(kicad_pcb
	(version 20260206)
	(generator "pcbnew")
	(generator_version "10.0")
	(general
		(thickness 1.6)
		(legacy_teardrops no)
	)
	(paper "A4")
	(layers
		(0 "F.Cu" signal "TOP")
		(4 "In1.Cu" signal "GND")
		(6 "In2.Cu" signal "VCC")
		(8 "In3.Cu" signal "VCC1")
		(10 "In4.Cu" signal "GND1")
		(12 "In5.Cu" signal "IN1")
		(14 "In6.Cu" signal "GND2")
		(16 "In7.Cu" signal "IN2")
		(18 "In8.Cu" signal "GND3")
		(20 "In9.Cu" signal "IN3")
		(22 "In10.Cu" signal "GND4")
		(24 "In11.Cu" signal "IN4")
		(26 "In12.Cu" signal "GND5")
		(28 "In13.Cu" signal "IN5")
		(30 "In14.Cu" signal "GND6")
		(32 "In15.Cu" signal "IN6")
		(34 "In16.Cu" signal "GND7")
		(2 "B.Cu" signal "BOTTOM")
		(9 "F.Adhes" user "F.Adhesive")
		(11 "B.Adhes" user "B.Adhesive")
		(13 "F.Paste" user "Package Geometry/Pastemask Top")
		(15 "B.Paste" user "Package Geometry/Pastemask Bottom")
		(5 "F.SilkS" user "Ref Des/Silkscreen Top")
		(7 "B.SilkS" user "Ref Des/Silkscreen Bottom")
		(1 "F.Mask" user "Board Geometry/Soldermask Top")
		(3 "B.Mask" user "Board Geometry/Soldermask Bottom")
		(17 "Dwgs.User" user "User.Drawings")
		(19 "Cmts.User" user "User.Comments")
		(21 "Eco1.User" user "User.Eco1")
		(23 "Eco2.User" user "User.Eco2")
		(25 "Edge.Cuts" user "Board Geometry/Outline")
		(27 "Margin" user)
		(31 "F.CrtYd" user "Package Geometry/Place Bound Top")
		(29 "B.CrtYd" user "Package Geometry/Place Bound Bottom")
		(35 "F.Fab" user "Ref Des/Assembly Top")
		(33 "B.Fab" user "Ref Des/Assembly Bottom")
	)
	(setup
		(pad_to_mask_clearance 0)
		(allow_soldermask_bridges_in_footprints no)
		(tenting
			(front yes)
			(back yes)
		)
		(covering
			(front no)
			(back no)
		)
		(plugging
			(front no)
			(back no)
		)
		(capping no)
		(filling no)
		(pcbplotparams
			(layerselection 0x00000000_00000000_55555555_5755f5ff)
			(plot_on_all_layers_selection 0x00000000_00000000_00000000_00000000)
			(disableapertmacros no)
			(usegerberextensions no)
			(usegerberattributes yes)
			(usegerberadvancedattributes yes)
			(creategerberjobfile yes)
			(dashed_line_dash_ratio 12)
			(dashed_line_gap_ratio 3)
			(svgprecision 4)
			(plotframeref no)
			(mode 1)
			(useauxorigin no)
			(pdf_front_fp_property_popups yes)
			(pdf_back_fp_property_popups yes)
			(pdf_metadata yes)
			(pdf_single_document no)
			(dxfpolygonmode yes)
			(dxfimperialunits yes)
			(dxfusepcbnewfont yes)
			(psnegative no)
			(psa4output no)
			(plot_black_and_white yes)
			(sketchpadsonfab no)
			(plotpadnumbers no)
			(hidednponfab no)
			(sketchdnponfab yes)
			(crossoutdnponfab yes)
			(subtractmaskfromsilk no)
			(outputformat 1)
			(mirror no)
			(drillshape 1)
			(scaleselection 1)
			(outputdirectory "")
		)
	)
	(gr_poly
		(pts
			(xy 134.780782 -293.609014) (xy 134.78129 -293.609014) (xy 134.788812 -293.607419) (xy 134.802509 -293.600452)
			(xy 134.808214 -293.595298) (xy 135.574786 -292.828726) (xy 135.579986 -292.82305) (xy 135.586978 -292.809346)
			(xy 135.588502 -292.801802) (xy 135.588502 -292.801294) (xy 135.589264 -292.793166) (xy 135.589264 -279.364948)
			(xy 135.58868 -279.354354) (xy 135.580055 -279.334995) (xy 135.564367 -279.320745) (xy 135.554466 -279.316942)
			(xy 135.545576 -279.314656) (xy 135.473714 -279.298897) (xy 135.331295 -279.261929) (xy 135.260842 -279.240742)
			(xy 135.17995 -279.215421) (xy 135.020549 -279.157727) (xy 134.864242 -279.092111) (xy 134.711421 -279.018739)
			(xy 134.562473 -278.937795) (xy 134.417771 -278.849484) (xy 134.27768 -278.754028) (xy 134.20979 -278.703278)
			(xy 134.144705 -278.653355) (xy 134.018899 -278.548067) (xy 133.898351 -278.436797) (xy 133.783345 -278.319808)
			(xy 133.674153 -278.197375) (xy 133.571032 -278.069787) (xy 133.474225 -277.937344) (xy 133.38396 -277.800359)
			(xy 133.300449 -277.659155) (xy 133.22389 -277.514063) (xy 133.154463 -277.365428) (xy 133.092332 -277.213597)
			(xy 133.037643 -277.058931) (xy 132.990525 -276.901792) (xy 132.951088 -276.742551) (xy 132.919427 -276.581585)
			(xy 132.895616 -276.419271) (xy 132.87971 -276.255993) (xy 132.871748 -276.092135) (xy 132.871747 -275.928084)
			(xy 132.879709 -275.764227) (xy 132.895614 -275.600948) (xy 132.919424 -275.438635) (xy 132.951084 -275.277668)
			(xy 132.990519 -275.118427) (xy 133.037637 -274.961288) (xy 133.092325 -274.806621) (xy 133.154455 -274.65479)
			(xy 133.223881 -274.506154) (xy 133.30044 -274.361062) (xy 133.383949 -274.219857) (xy 133.474214 -274.082872)
			(xy 133.57102 -273.950429) (xy 133.674141 -273.82284) (xy 133.783332 -273.700406) (xy 133.898337 -273.583416)
			(xy 134.018884 -273.472146) (xy 134.14469 -273.366857) (xy 134.20979 -273.316954) (xy 134.274046 -273.268886)
			(xy 134.406437 -273.178172) (xy 134.474458 -273.135598) (xy 134.545181 -273.09251) (xy 134.690191 -273.012484)
			(xy 134.838948 -272.939659) (xy 134.991095 -272.87421) (xy 135.146266 -272.816295) (xy 135.304089 -272.766054)
			(xy 135.464183 -272.723606) (xy 135.545068 -272.70583) (xy 135.546846 -272.705576) (xy 135.548116 -272.705068)
			(xy 135.55218 -272.703798) (xy 135.554466 -272.703036) (xy 135.564384 -272.699169) (xy 135.580116 -272.684865)
			(xy 135.588693 -272.665409) (xy 135.589264 -272.654776) (xy 135.589264 -255.810258) (xy 135.588941 -255.801978)
			(xy 135.583625 -255.786296) (xy 135.57885 -255.779524) (xy 135.576818 -255.777238) (xy 135.57504 -255.77546)
			(xy 135.571738 -255.77165) (xy 135.543798 -255.74371) (xy 135.53695 -255.736312) (xy 135.529212 -255.717714)
			(xy 135.528812 -255.707642) (xy 135.528812 -254.40132) (xy 135.528498 -254.393037) (xy 135.523193 -254.377346)
			(xy 135.518398 -254.370586) (xy 135.516366 -254.3683) (xy 135.514588 -254.366522) (xy 135.511286 -254.362712)
			(xy 133.280658 -252.132084) (xy 133.273374 -252.12548) (xy 133.255251 -252.117905) (xy 133.23561 -252.117736)
			(xy 133.226302 -252.120908) (xy 133.139688 -252.15469) (xy 133.13664 -252.15596) (xy 133.128388 -252.160297)
			(xy 133.115475 -252.173718) (xy 133.108201 -252.190865) (xy 133.10743 -252.200156) (xy 133.105916 -252.226678)
			(xy 133.096459 -252.278953) (xy 133.07984 -252.32941) (xy 133.056381 -252.377073) (xy 133.026534 -252.421018)
			(xy 132.990878 -252.460398) (xy 132.950102 -252.494448) (xy 132.904996 -252.52251) (xy 132.856431 -252.544042)
			(xy 132.805349 -252.558626) (xy 132.752738 -252.565981) (xy 132.726176 -252.566424) (xy 132.698925 -252.565937)
			(xy 132.644979 -252.558177) (xy 132.592687 -252.54282) (xy 132.543111 -252.520178) (xy 132.497263 -252.490711)
			(xy 132.456074 -252.45502) (xy 132.420384 -252.413831) (xy 132.390918 -252.367982) (xy 132.368277 -252.318406)
			(xy 132.352921 -252.266113) (xy 132.345163 -252.212167) (xy 132.344668 -252.184916) (xy 132.345132 -252.158359)
			(xy 132.352509 -252.10576) (xy 132.367109 -252.054691) (xy 132.388649 -252.006141) (xy 132.416713 -251.961047)
			(xy 132.45076 -251.92028) (xy 132.490131 -251.884628) (xy 132.534066 -251.854781) (xy 132.581715 -251.831314)
			(xy 132.632158 -251.814681) (xy 132.684419 -251.805204) (xy 132.710936 -251.803662) (xy 132.720376 -251.802962)
			(xy 132.737751 -251.795485) (xy 132.751194 -251.782177) (xy 132.755386 -251.77369) (xy 132.77469 -251.724414)
			(xy 132.790184 -251.68479) (xy 132.793349 -251.675486) (xy 132.793142 -251.655851) (xy 132.785601 -251.637721)
			(xy 132.779008 -251.630434) (xy 131.550918 -250.402344) (xy 131.547188 -250.398822) (xy 131.538614 -250.393192)
			(xy 131.5339 -250.391168) (xy 131.525264 -250.387612) (xy 130.501644 -250.387612) (xy 130.494833 -250.387825)
			(xy 130.481697 -250.391424) (xy 130.475736 -250.394724) (xy 130.454908 -250.40717) (xy 130.449409 -250.41065)
			(xy 130.440268 -250.419906) (xy 130.436874 -250.425458) (xy 130.422096 -250.449802) (xy 130.386456 -250.49422)
			(xy 130.344613 -250.532851) (xy 130.297497 -250.564838) (xy 130.246152 -250.589472) (xy 130.191718 -250.606206)
			(xy 130.135402 -250.614669) (xy 130.106928 -250.615196) (xy 130.077604 -250.61466) (xy 130.019646 -250.605684)
			(xy 129.963746 -250.587939) (xy 129.911223 -250.561844) (xy 129.863315 -250.528013) (xy 129.821152 -250.487246)
			(xy 129.785728 -250.440504) (xy 129.75788 -250.388889) (xy 129.747518 -250.36145) (xy 129.746502 -250.358402)
			(xy 129.742259 -250.349625) (xy 129.72845 -250.335889) (xy 129.710511 -250.328303) (xy 129.700782 -250.327668)
			(xy 129.156968 -250.327668) (xy 129.149096 -250.327964) (xy 129.134097 -250.332753) (xy 129.127504 -250.337066)
			(xy 129.123668 -250.339863) (xy 129.117023 -250.346642) (xy 129.114296 -250.350528) (xy 129.10947 -250.36018)
			(xy 129.108962 -250.362466) (xy 129.100656 -250.384514) (xy 129.07936 -250.426542) (xy 129.053044 -250.465624)
			(xy 129.037842 -250.483624) (xy 129.037334 -250.48464) (xy 129.030984 -250.491244) (xy 129.027936 -250.494292)
			(xy 129.00914 -250.513088) (xy 129.008632 -250.513596) (xy 129.00152 -250.5202) (xy 129.001012 -250.520708)
			(xy 128.993138 -250.527566) (xy 128.98882 -250.531122) (xy 128.986534 -250.533154) (xy 128.98247 -250.539504)
			(xy 128.976882 -250.55195) (xy 128.973072 -250.566174) (xy 128.970532 -250.576334) (xy 128.970532 -250.576588)
			(xy 128.968993 -250.582053) (xy 128.963872 -250.592184) (xy 128.960372 -250.596654) (xy 128.952814 -250.604858)
			(xy 128.932649 -250.614331) (xy 128.92151 -250.614942) (xy 128.74879 -250.614942) (xy 128.721039 -250.6144)
			(xy 128.666132 -250.606279) (xy 128.612979 -250.590295) (xy 128.562699 -250.566786) (xy 128.53924 -250.55195)
			(xy 128.522145 -250.540279) (xy 128.490322 -250.513808) (xy 128.47574 -250.499118) (xy 128.468628 -250.491752)
			(xy 128.440434 -250.479052) (xy 128.435926 -250.477322) (xy 128.426464 -250.475402) (xy 128.421638 -250.475242)
			(xy 128.358392 -250.475242) (xy 128.35011 -250.47556) (xy 128.334422 -250.480868) (xy 128.327658 -250.485656)
			(xy 128.32461 -250.48845) (xy 128.323086 -250.48972) (xy 128.32207 -250.490482) (xy 128.321816 -250.490736)
			(xy 128.321054 -250.491244) (xy 128.3208 -250.491498) (xy 128.317752 -250.493784) (xy 128.309878 -250.501658)
			(xy 128.2886 -250.522366) (xy 128.240817 -250.557604) (xy 128.188155 -250.585021) (xy 128.131884 -250.603958)
			(xy 128.073361 -250.613958) (xy 128.043686 -250.614942) (xy 128.030224 -250.614942) (xy 128.002279 -250.613848)
			(xy 127.947141 -250.604496) (xy 127.893957 -250.587202) (xy 127.843864 -250.562338) (xy 127.797932 -250.530435)
			(xy 127.757143 -250.492174) (xy 127.72237 -250.448374) (xy 127.707898 -250.424442) (xy 127.705104 -250.419362)
			(xy 127.704088 -250.41733) (xy 127.703072 -250.415552) (xy 127.698111 -250.406313) (xy 127.68909 -250.387379)
			(xy 127.685038 -250.377706) (xy 127.685038 -250.377452) (xy 127.681482 -250.368308) (xy 127.67945 -250.363482)
			(xy 127.675386 -250.352814) (xy 127.667766 -250.345194) (xy 127.662686 -250.340622) (xy 127.662178 -250.340622)
			(xy 127.651002 -250.334018) (xy 127.634238 -250.328176) (xy 127.620522 -250.327668) (xy 105.104946 -250.327668)
			(xy 105.094982 -250.328151) (xy 105.076552 -250.335732) (xy 105.069132 -250.3424) (xy 105.038906 -250.372626)
			(xy 105.031512 -250.379482) (xy 105.012913 -250.38723) (xy 105.002838 -250.387612) (xy 102.31882 -250.387612)
			(xy 102.308756 -250.387175) (xy 102.290171 -250.379441) (xy 102.282752 -250.372626) (xy 101.808788 -249.898662)
			(xy 101.801938 -249.891266) (xy 101.794203 -249.872667) (xy 101.793802 -249.862594) (xy 101.793802 -244.241574)
			(xy 101.79423 -244.231506) (xy 101.801951 -244.212909) (xy 101.808788 -244.205506) (xy 101.9175 -244.096794)
			(xy 101.924949 -244.088501) (xy 101.932465 -244.067544) (xy 101.931978 -244.056408) (xy 101.929946 -244.037612)
			(xy 101.929946 -244.037104) (xy 101.922834 -243.976652) (xy 101.921564 -243.970302) (xy 101.919272 -243.962056)
			(xy 101.910057 -243.947644) (xy 101.90353 -243.942108) (xy 101.90226 -243.941092) (xy 101.898958 -243.93906)
			(xy 101.886718 -243.931271) (xy 101.863323 -243.91411) (xy 101.852222 -243.90477) (xy 101.84384 -243.897658)
			(xy 101.832918 -243.894356) (xy 101.828003 -243.893113) (xy 101.817897 -243.892339) (xy 101.812852 -243.892832)
			(xy 101.749352 -243.900706) (xy 101.7397 -243.901976) (xy 101.721412 -243.911882) (xy 101.719888 -243.912898)
			(xy 101.71303 -243.917216) (xy 101.69906 -243.929916) (xy 101.696012 -243.933726) (xy 101.695504 -243.934234)
			(xy 101.677378 -243.957417) (xy 101.635197 -243.998448) (xy 101.587217 -244.032518) (xy 101.534575 -244.058817)
			(xy 101.47852 -244.076724) (xy 101.42038 -244.085812) (xy 101.390958 -244.08638) (xy 101.389942 -244.08638)
			(xy 101.362689 -244.08592) (xy 101.308738 -244.078168) (xy 101.256439 -244.062817) (xy 101.206857 -244.040178)
			(xy 101.161002 -244.010714) (xy 101.119807 -243.975023) (xy 101.084112 -243.933832) (xy 101.054642 -243.88798)
			(xy 101.031998 -243.838401) (xy 101.016641 -243.786103) (xy 101.008883 -243.732153) (xy 101.008883 -243.677647)
			(xy 101.016641 -243.623697) (xy 101.031998 -243.571399) (xy 101.054642 -243.52182) (xy 101.084112 -243.475968)
			(xy 101.119807 -243.434777) (xy 101.161002 -243.399086) (xy 101.206857 -243.369622) (xy 101.256439 -243.346983)
			(xy 101.308738 -243.331632) (xy 101.362689 -243.32388) (xy 101.389942 -243.323364) (xy 101.405436 -243.323364)
			(xy 101.436038 -243.325242) (xy 101.496101 -243.337532) (xy 101.55343 -243.359256) (xy 101.606555 -243.389856)
			(xy 101.630734 -243.408708) (xy 101.637338 -243.414042) (xy 101.67112 -243.42725) (xy 101.684074 -243.425726)
			(xy 101.704394 -243.423186) (xy 101.704902 -243.423186) (xy 101.743764 -243.417852) (xy 101.755702 -243.414296)
			(xy 101.756718 -243.413788) (xy 101.757988 -243.41328) (xy 101.786436 -243.395754) (xy 101.792278 -243.387626)
			(xy 101.808538 -243.366466) (xy 101.846018 -243.328481) (xy 101.866954 -243.311934) (xy 101.869748 -243.309902)
			(xy 101.875844 -243.303806) (xy 101.878384 -243.300758) (xy 101.886004 -243.28882) (xy 101.888798 -243.28247)
			(xy 101.889814 -243.275358) (xy 101.900228 -243.203476) (xy 101.900736 -243.193062) (xy 101.898958 -243.185696)
			(xy 101.897859 -243.181729) (xy 101.894546 -243.174194) (xy 101.892354 -243.17071) (xy 101.890576 -243.16817)
			(xy 101.88829 -243.165122) (xy 101.888036 -243.164614) (xy 101.883972 -243.15928) (xy 101.882448 -243.156994)
			(xy 101.882194 -243.156486) (xy 101.881686 -243.155724) (xy 101.881432 -243.15547) (xy 101.866041 -243.131704)
			(xy 101.841697 -243.080584) (xy 101.825184 -243.026426) (xy 101.816865 -242.97042) (xy 101.816408 -242.94211)
			(xy 101.816408 -242.934744) (xy 101.816662 -242.929664) (xy 101.817995 -242.902873) (xy 101.827237 -242.850034)
			(xy 101.84378 -242.799008) (xy 101.867297 -242.750797) (xy 101.897327 -242.70635) (xy 101.933279 -242.666541)
			(xy 101.953568 -242.648994) (xy 101.975023 -242.631741) (xy 102.021941 -242.602935) (xy 102.07251 -242.581166)
			(xy 102.125682 -242.566886) (xy 102.152958 -242.563142) (xy 102.153974 -242.563142) (xy 102.156514 -242.562888)
			(xy 102.158292 -242.562634) (xy 102.162864 -242.562126) (xy 102.166674 -242.561872) (xy 102.16769 -242.561618)
			(xy 102.199883 -242.559708) (xy 102.264111 -242.56545) (xy 102.295452 -242.573048) (xy 102.33025 -242.582446)
			(xy 102.340156 -242.586256) (xy 102.370636 -242.60175) (xy 102.380777 -242.607075) (xy 102.400474 -242.618768)
			(xy 102.410006 -242.625118) (xy 102.410514 -242.625118) (xy 102.431342 -242.640104) (xy 102.432866 -242.641374)
			(xy 102.437946 -242.644676) (xy 102.440994 -242.646708) (xy 102.451916 -242.652296) (xy 102.456865 -242.6544)
			(xy 102.467369 -242.656695) (xy 102.472744 -242.656868) (xy 102.477316 -242.656868) (xy 102.53472 -242.652042)
			(xy 102.539468 -242.65152) (xy 102.548673 -242.648969) (xy 102.553008 -242.646962) (xy 102.577392 -242.635024)
			(xy 102.583996 -242.628166) (xy 102.585774 -242.626388) (xy 102.604519 -242.607289) (xy 102.646411 -242.57399)
			(xy 102.692537 -242.546858) (xy 102.717092 -242.536218) (xy 102.73911 -242.527538) (xy 102.784767 -242.515063)
			(xy 102.831614 -242.508319) (xy 102.855268 -242.507516) (xy 102.863904 -242.507516) (xy 102.881684 -242.50777)
			(xy 102.891082 -242.508532) (xy 102.891336 -242.508532) (xy 102.918547 -242.511056) (xy 102.971895 -242.522904)
			(xy 103.023007 -242.542242) (xy 103.070837 -242.568674) (xy 103.114407 -242.60166) (xy 103.152826 -242.640524)
			(xy 103.169466 -242.662202) (xy 103.175816 -242.670838) (xy 103.212646 -242.69192) (xy 103.223822 -242.692936)
			(xy 103.289608 -242.698778) (xy 103.299514 -242.698778) (xy 103.308144 -242.697515) (xy 103.323866 -242.68999)
			(xy 103.330248 -242.684046) (xy 103.899462 -242.114832) (xy 103.906862 -242.107992) (xy 103.925461 -242.100275)
			(xy 103.93553 -242.099846) (xy 119.485918 -242.099846) (xy 119.494046 -242.099084) (xy 119.494554 -242.099084)
			(xy 119.502071 -242.09748) (xy 119.515753 -242.090498) (xy 119.521478 -242.085368) (xy 120.16486 -241.441986)
			(xy 120.172258 -241.43514) (xy 120.190857 -241.427414) (xy 120.200928 -241.427) (xy 122.431302 -241.427)
			(xy 122.43943 -241.426238) (xy 122.439938 -241.426238) (xy 122.447457 -241.424638) (xy 122.461148 -241.417664)
			(xy 122.466862 -241.412522) (xy 124.880624 -238.99876) (xy 124.886733 -238.992119) (xy 124.89426 -238.975733)
			(xy 124.895665 -238.957755) (xy 124.893578 -238.948976) (xy 124.867924 -238.873792) (xy 124.865797 -238.868183)
			(xy 124.859383 -238.85805) (xy 124.855224 -238.853726) (xy 124.853192 -238.851694) (xy 124.833888 -238.8362)
			(xy 124.827284 -238.830866) (xy 124.816108 -238.825786) (xy 124.811536 -238.825024) (xy 124.81052 -238.82477)
			(xy 124.808742 -238.824516) (xy 124.782289 -238.8197) (xy 124.730984 -238.803617) (xy 124.682443 -238.780495)
			(xy 124.637627 -238.75079) (xy 124.597421 -238.715092) (xy 124.562622 -238.674105) (xy 124.533917 -238.628642)
			(xy 124.511876 -238.5796) (xy 124.496933 -238.527952) (xy 124.489384 -238.474717) (xy 124.488956 -238.447834)
			(xy 124.489439 -238.42058) (xy 124.497192 -238.366627) (xy 124.512544 -238.314326) (xy 124.535182 -238.264742)
			(xy 124.564647 -238.218885) (xy 124.600338 -238.177688) (xy 124.641529 -238.141989) (xy 124.687381 -238.112516)
			(xy 124.73696 -238.089868) (xy 124.789258 -238.074507) (xy 124.84321 -238.066744) (xy 124.870464 -238.066326)
			(xy 124.897321 -238.066787) (xy 124.950505 -238.074324) (xy 125.002108 -238.089239) (xy 125.051112 -238.111238)
			(xy 125.096549 -238.139887) (xy 125.137523 -238.174621) (xy 125.173225 -238.214754) (xy 125.202951 -238.259494)
			(xy 125.226114 -238.307958) (xy 125.242257 -238.359191) (xy 125.247146 -238.385604) (xy 125.247146 -238.386112)
			(xy 125.248416 -238.392716) (xy 125.250702 -238.39805) (xy 125.257814 -238.409734) (xy 125.273308 -238.429038)
			(xy 125.273816 -238.429546) (xy 125.277626 -238.434372) (xy 125.289818 -238.443008) (xy 125.29693 -238.445548)
			(xy 125.363478 -238.468154) (xy 125.367425 -238.469415) (xy 125.375592 -238.470814) (xy 125.379734 -238.470948)
			(xy 125.399292 -238.470948) (xy 125.405397 -238.469036) (xy 125.416451 -238.462604) (xy 125.421136 -238.458248)
			(xy 126.727204 -237.15218) (xy 126.732397 -237.146501) (xy 126.739375 -237.132795) (xy 126.74092 -237.125256)
			(xy 126.74092 -237.124748) (xy 126.741682 -237.11662) (xy 126.741682 -220.293692) (xy 126.740158 -220.284802)
			(xy 126.738126 -220.27388) (xy 126.73076 -220.25991) (xy 126.724664 -220.254068) (xy 126.673356 -220.205046)
			(xy 126.66599 -220.197934) (xy 126.64821 -220.190822) (xy 126.633732 -220.190822) (xy 126.626874 -220.191076)
			(xy 126.620524 -220.191076) (xy 126.593288 -220.190571) (xy 126.539375 -220.182783) (xy 126.487118 -220.167406)
			(xy 126.437579 -220.144751) (xy 126.391767 -220.115279) (xy 126.350614 -220.079591) (xy 126.314955 -220.038411)
			(xy 126.285517 -219.992578) (xy 126.262898 -219.943024) (xy 126.247558 -219.890755) (xy 126.239809 -219.836836)
			(xy 126.239809 -219.782364) (xy 126.247558 -219.728445) (xy 126.262898 -219.676176) (xy 126.285517 -219.626622)
			(xy 126.314955 -219.580789) (xy 126.350614 -219.539609) (xy 126.391767 -219.503921) (xy 126.437579 -219.474449)
			(xy 126.487118 -219.451794) (xy 126.539375 -219.436417) (xy 126.593288 -219.428629) (xy 126.620524 -219.42806)
			(xy 126.626874 -219.42806) (xy 126.633732 -219.428314) (xy 126.64821 -219.428314) (xy 126.66599 -219.421202)
			(xy 126.673356 -219.41409) (xy 126.725934 -219.363798) (xy 126.727204 -219.362528) (xy 126.732402 -219.356852)
			(xy 126.739393 -219.343147) (xy 126.74092 -219.335604) (xy 126.74092 -219.335096) (xy 126.741682 -219.326968)
			(xy 126.741682 -219.205302) (xy 126.741415 -219.201003) (xy 126.739621 -219.192578) (xy 126.738126 -219.188538)
			(xy 126.736516 -219.184618) (xy 126.732172 -219.177342) (xy 126.72949 -219.17406) (xy 126.71933 -219.162122)
			(xy 126.711964 -219.157804) (xy 126.688281 -219.143) (xy 126.645116 -219.107561) (xy 126.607571 -219.066214)
			(xy 126.576446 -219.019842) (xy 126.552405 -218.969432) (xy 126.53596 -218.916058) (xy 126.527461 -218.860859)
			(xy 126.526798 -218.832938) (xy 126.527052 -218.82608) (xy 126.527052 -218.823032) (xy 126.527814 -218.806522)
			(xy 126.527814 -218.806014) (xy 126.529592 -218.785694) (xy 126.529846 -218.783662) (xy 126.529846 -218.783154)
			(xy 126.530862 -218.775026) (xy 126.530862 -218.77401) (xy 126.53137 -218.771216) (xy 126.531624 -218.7702)
			(xy 126.533402 -218.760802) (xy 126.533402 -218.759278) (xy 126.534164 -218.754706) (xy 126.534672 -218.753182)
			(xy 126.540133 -218.728903) (xy 126.55652 -218.681912) (xy 126.578882 -218.637454) (xy 126.606839 -218.596284)
			(xy 126.623064 -218.577414) (xy 126.63424 -218.564968) (xy 126.63678 -218.562428) (xy 126.646686 -218.55303)
			(xy 126.660462 -218.540337) (xy 126.690107 -218.517434) (xy 126.705868 -218.50731) (xy 126.706122 -218.507056)
			(xy 126.711202 -218.503754) (xy 126.715012 -218.499944) (xy 126.722886 -218.489784) (xy 126.734062 -218.470988)
			(xy 126.736602 -218.466162) (xy 126.73711 -218.465146) (xy 126.739146 -218.460375) (xy 126.741443 -218.450262)
			(xy 126.741682 -218.44508) (xy 126.741682 -198.833232) (xy 126.742117 -198.823167) (xy 126.749847 -198.804579)
			(xy 126.756668 -198.797164) (xy 127.685546 -197.868286) (xy 127.692943 -197.861437) (xy 127.711542 -197.853706)
			(xy 127.721614 -197.8533) (xy 143.622522 -197.8533) (xy 143.631173 -197.852903) (xy 143.647458 -197.847044)
			(xy 143.660867 -197.836103) (xy 143.665702 -197.828916) (xy 143.674084 -197.815454) (xy 143.675608 -197.808342)
			(xy 143.676116 -197.80631) (xy 143.676116 -197.806056) (xy 143.682501 -197.777741) (xy 143.702682 -197.723319)
			(xy 143.730866 -197.672579) (xy 143.766405 -197.626689) (xy 143.80848 -197.586706) (xy 143.856122 -197.553552)
			(xy 143.908232 -197.52799) (xy 143.963611 -197.51061) (xy 144.020983 -197.501811) (xy 144.050004 -197.501256)
			(xy 144.079125 -197.501806) (xy 144.13669 -197.510656) (xy 144.192243 -197.528149) (xy 144.244492 -197.553881)
			(xy 144.292226 -197.587252) (xy 144.334334 -197.627488) (xy 144.36984 -197.673656) (xy 144.39792 -197.724682)
			(xy 144.41792 -197.779382) (xy 144.424146 -197.807834) (xy 144.424654 -197.810374) (xy 144.427194 -197.819264)
			(xy 144.430723 -197.828028) (xy 144.44296 -197.8424) (xy 144.459545 -197.851415) (xy 144.46885 -197.853046)
			(xy 144.472914 -197.8533) (xy 148.339048 -197.8533) (xy 148.349315 -197.85277) (xy 148.368177 -197.84464)
			(xy 148.375624 -197.837552) (xy 148.427694 -197.783704) (xy 148.433467 -197.776547) (xy 148.439974 -197.759362)
			(xy 148.440394 -197.750176) (xy 148.440394 -197.744334) (xy 148.44014 -197.738746) (xy 148.44014 -197.72376)
			(xy 148.441125 -197.697215) (xy 148.449538 -197.644767) (xy 148.465151 -197.593995) (xy 148.487661 -197.545881)
			(xy 148.516633 -197.501359) (xy 148.551505 -197.46129) (xy 148.591601 -197.42645) (xy 148.613622 -197.411594)
			(xy 148.61794 -197.4088) (xy 148.62556 -197.40118) (xy 148.632147 -197.3938) (xy 148.639608 -197.375501)
			(xy 148.640038 -197.36562) (xy 148.640038 -197.355714) (xy 148.255482 -195.326) (xy 148.255482 -195.325492)
			(xy 148.242782 -195.2625) (xy 148.241096 -195.257503) (xy 148.23597 -195.248288) (xy 148.232622 -195.244212)
			(xy 148.22805 -195.238878) (xy 148.216874 -195.231258) (xy 148.20519 -195.227956) (xy 148.194522 -195.226432)
			(xy 148.190458 -195.226686) (xy 148.185632 -195.22694) (xy 148.1836 -195.227194) (xy 148.183346 -195.227194)
			(xy 148.182838 -195.227448) (xy 148.18233 -195.227448) (xy 148.18106 -195.227702) (xy 148.163507 -195.230795)
			(xy 148.128016 -195.234101) (xy 148.110194 -195.234306) (xy 148.107908 -195.234306) (xy 148.080655 -195.233843)
			(xy 148.026703 -195.226087) (xy 147.974404 -195.210732) (xy 147.924823 -195.18809) (xy 147.878969 -195.158622)
			(xy 147.837776 -195.122928) (xy 147.802082 -195.081735) (xy 147.772613 -195.035882) (xy 147.74997 -194.986301)
			(xy 147.734614 -194.934003) (xy 147.726857 -194.880051) (xy 147.7264 -194.852798) (xy 147.726852 -194.826115)
			(xy 147.7343 -194.77327) (xy 147.749036 -194.721978) (xy 147.770773 -194.673239) (xy 147.799088 -194.628003)
			(xy 147.833427 -194.587152) (xy 147.873123 -194.551482) (xy 147.917399 -194.521689) (xy 147.965394 -194.498355)
			(xy 148.016172 -194.481933) (xy 148.042376 -194.476878) (xy 148.04263 -194.476878) (xy 148.04644 -194.476116)
			(xy 148.057755 -194.47256) (xy 148.07564 -194.457026) (xy 148.084719 -194.435145) (xy 148.08454 -194.423284)
			(xy 146.90344 -188.18606) (xy 146.581368 -186.485276) (xy 146.579484 -186.478793) (xy 146.572788 -186.467077)
			(xy 146.56816 -186.462162) (xy 146.561302 -186.455304) (xy 146.54276 -186.445144) (xy 146.542252 -186.445144)
			(xy 146.486626 -186.41441) (xy 146.48173 -186.412036) (xy 146.471224 -186.409217) (xy 146.465798 -186.408822)
			(xy 146.45513 -186.40806) (xy 146.443954 -186.412632) (xy 146.421163 -186.421496) (xy 146.373888 -186.434009)
			(xy 146.325402 -186.440379) (xy 146.300952 -186.440826) (xy 146.294856 -186.440826) (xy 146.267786 -186.440079)
			(xy 146.214258 -186.431881) (xy 146.162428 -186.416195) (xy 146.113338 -186.393336) (xy 146.067973 -186.363764)
			(xy 146.027247 -186.328074) (xy 145.991977 -186.286982) (xy 145.962874 -186.241316) (xy 145.940522 -186.191992)
			(xy 145.92537 -186.140003) (xy 145.917723 -186.086394) (xy 145.917158 -186.059318) (xy 145.917643 -186.032065)
			(xy 145.925397 -185.978114) (xy 145.94075 -185.925815) (xy 145.96339 -185.876233) (xy 145.992855 -185.830378)
			(xy 146.028546 -185.789183) (xy 146.069736 -185.753486) (xy 146.115587 -185.724015) (xy 146.165166 -185.701368)
			(xy 146.217463 -185.686008) (xy 146.271413 -185.678246) (xy 146.298666 -185.67781) (xy 146.304508 -185.67781)
			(xy 146.314922 -185.676032) (xy 146.323812 -185.674508) (xy 146.331432 -185.67019) (xy 146.335131 -185.667978)
			(xy 146.341775 -185.662488) (xy 146.34464 -185.659268) (xy 146.37639 -185.621676) (xy 146.392138 -185.60288)
			(xy 146.397472 -185.59526) (xy 146.39925 -185.592466) (xy 146.40433 -185.58129) (xy 146.405712 -185.576594)
			(xy 146.406864 -185.566875) (xy 146.406616 -185.561986) (xy 146.382486 -185.434478) (xy 146.372834 -185.383678)
			(xy 146.371639 -185.379139) (xy 146.367805 -185.370573) (xy 146.365214 -185.36666) (xy 146.357848 -185.358024)
			(xy 146.348196 -185.349896) (xy 146.347688 -185.349642) (xy 146.331178 -185.338974) (xy 146.327368 -185.337704)
			(xy 146.324828 -185.336942) (xy 146.2992 -185.328095) (xy 146.25049 -185.304291) (xy 146.205566 -185.273942)
			(xy 146.165301 -185.237637) (xy 146.130479 -185.196083) (xy 146.101778 -185.150089) (xy 146.079754 -185.100548)
			(xy 146.064838 -185.048425) (xy 146.057319 -184.994734) (xy 146.056858 -184.967626) (xy 146.057398 -184.938308)
			(xy 146.06622 -184.880338) (xy 146.083653 -184.824352) (xy 146.109301 -184.771622) (xy 146.142581 -184.723344)
			(xy 146.182738 -184.680615) (xy 146.205448 -184.662064) (xy 146.207734 -184.660286) (xy 146.216624 -184.651396)
			(xy 146.222382 -184.643239) (xy 146.22772 -184.624021) (xy 146.227038 -184.614058) (xy 146.148044 -184.197244)
			(xy 143.340582 -169.37228) (xy 143.339312 -169.364914) (xy 143.338296 -169.359834) (xy 143.338042 -169.35704)
			(xy 140.85316 -156.236162) (xy 138.806428 -145.429478) (xy 138.797284 -145.372074) (xy 138.727688 -144.832832)
			(xy 138.727688 -144.832578) (xy 138.716258 -144.744948) (xy 138.170412 -140.594334) (xy 136.369806 -126.905512)
			(xy 136.368539 -126.898013) (xy 136.362212 -126.884191) (xy 136.35736 -126.878334) (xy 136.347454 -126.867412)
			(xy 136.34466 -126.86665) (xy 136.344152 -126.866396) (xy 136.343898 -126.866396) (xy 136.315704 -126.85903)
			(xy 136.305798 -126.858014) (xy 136.271254 -126.858014) (xy 136.266084 -126.858196) (xy 136.255972 -126.860365)
			(xy 136.251188 -126.862332) (xy 136.246616 -126.864364) (xy 136.242806 -126.866396) (xy 136.232646 -126.87427)
			(xy 136.226296 -126.88062) (xy 136.22401 -126.883668) (xy 136.205846 -126.906658) (xy 136.163661 -126.947316)
			(xy 136.115761 -126.981055) (xy 136.06327 -127.007083) (xy 136.00742 -127.024788) (xy 135.949521 -127.033755)
			(xy 135.920226 -127.03429) (xy 135.893191 -127.033822) (xy 135.839661 -127.026192) (xy 135.787744 -127.011083)
			(xy 135.73848 -126.988797) (xy 135.692855 -126.959779) (xy 135.651783 -126.924611) (xy 135.616087 -126.883998)
			(xy 135.586482 -126.838752) (xy 135.56356 -126.78978) (xy 135.54778 -126.738063) (xy 135.53946 -126.684636)
			(xy 135.538718 -126.657608) (xy 135.538718 -126.652782) (xy 135.539734 -126.623318) (xy 135.540496 -126.612396)
			(xy 135.536686 -126.601982) (xy 135.534678 -126.596886) (xy 135.528786 -126.587654) (xy 135.525002 -126.583694)
			(xy 135.522716 -126.581408) (xy 135.5217 -126.562358) (xy 135.521629 -126.553189) (xy 135.52724 -126.535747)
			(xy 135.532622 -126.528322) (xy 135.617204 -126.42088) (xy 135.617458 -126.420372) (xy 135.617712 -126.420118)
			(xy 135.619236 -126.41834) (xy 135.620506 -126.416562) (xy 135.62076 -126.416308) (xy 135.621776 -126.415038)
			(xy 135.622284 -126.414276) (xy 135.625586 -126.409704) (xy 135.629142 -126.40183) (xy 135.63077 -126.397367)
			(xy 135.632561 -126.388037) (xy 135.632698 -126.383288) (xy 135.632698 -126.361952) (xy 135.632843 -126.356513)
			(xy 135.635153 -126.345883) (xy 135.63727 -126.34087) (xy 135.643366 -126.327408) (xy 135.646984 -126.318746)
			(xy 135.648215 -126.300026) (xy 135.64259 -126.282129) (xy 135.637016 -126.274576) (xy 135.631428 -126.267464)
			(xy 135.627872 -126.262892) (xy 135.627364 -126.26213) (xy 135.626856 -126.261622) (xy 135.626094 -126.260606)
			(xy 135.609907 -126.240342) (xy 135.582584 -126.196259) (xy 135.561491 -126.148879) (xy 135.547015 -126.099077)
			(xy 135.539425 -126.047772) (xy 135.538718 -126.021846) (xy 135.538718 -126.018798) (xy 135.539054 -125.993414)
			(xy 135.545621 -125.943075) (xy 135.558797 -125.89405) (xy 135.568182 -125.870462) (xy 135.578721 -125.846317)
			(xy 135.605484 -125.800939) (xy 135.621522 -125.780038) (xy 135.625332 -125.775212) (xy 135.627872 -125.769878)
			(xy 135.630114 -125.764764) (xy 135.632554 -125.75387) (xy 135.632698 -125.748288) (xy 135.632698 -125.726952)
			(xy 135.632843 -125.721513) (xy 135.635153 -125.710883) (xy 135.63727 -125.70587) (xy 135.643366 -125.692408)
			(xy 135.646984 -125.683746) (xy 135.648215 -125.665026) (xy 135.64259 -125.647129) (xy 135.637016 -125.639576)
			(xy 135.631428 -125.632464) (xy 135.627872 -125.627892) (xy 135.627364 -125.62713) (xy 135.626856 -125.626622)
			(xy 135.626094 -125.625606) (xy 135.609907 -125.605342) (xy 135.582584 -125.561259) (xy 135.561491 -125.513879)
			(xy 135.547015 -125.464077) (xy 135.539425 -125.412772) (xy 135.538718 -125.386846) (xy 135.538718 -125.383798)
			(xy 135.539054 -125.358414) (xy 135.545621 -125.308075) (xy 135.558797 -125.25905) (xy 135.568182 -125.235462)
			(xy 135.578721 -125.211317) (xy 135.605484 -125.165939) (xy 135.621522 -125.145038) (xy 135.625332 -125.140212)
			(xy 135.627872 -125.134878) (xy 135.630114 -125.129764) (xy 135.632554 -125.11887) (xy 135.632698 -125.113288)
			(xy 135.632698 -125.091952) (xy 135.632843 -125.086513) (xy 135.635153 -125.075883) (xy 135.63727 -125.07087)
			(xy 135.643366 -125.057408) (xy 135.646984 -125.048746) (xy 135.648215 -125.030026) (xy 135.64259 -125.012129)
			(xy 135.637016 -125.004576) (xy 135.631428 -124.997464) (xy 135.627872 -124.992892) (xy 135.627364 -124.99213)
			(xy 135.62584 -124.990352) (xy 135.606948 -124.966484) (xy 135.576191 -124.913958) (xy 135.554153 -124.857219)
			(xy 135.541392 -124.797703) (xy 135.539226 -124.76734) (xy 135.538718 -124.748798) (xy 135.538718 -124.747782)
			(xy 135.539183 -124.720531) (xy 135.546942 -124.666583) (xy 135.5623 -124.614289) (xy 135.584944 -124.564713)
			(xy 135.614412 -124.518864) (xy 135.650106 -124.477675) (xy 135.691299 -124.441986) (xy 135.737151 -124.412522)
			(xy 135.78673 -124.389884) (xy 135.839026 -124.374532) (xy 135.892975 -124.366779) (xy 135.920226 -124.366274)
			(xy 135.930407 -124.366366) (xy 135.950739 -124.36751) (xy 135.960866 -124.36856) (xy 135.964168 -124.368814)
			(xy 135.969088 -124.368863) (xy 135.978807 -124.367332) (xy 135.983472 -124.365766) (xy 135.994394 -124.361702)
			(xy 136.012936 -124.342906) (xy 136.020742 -124.334228) (xy 136.028139 -124.31212) (xy 136.02716 -124.300488)
			(xy 135.995664 -124.060204) (xy 135.926322 -123.533408) (xy 135.899144 -123.326398) (xy 135.89774 -123.318379)
			(xy 135.890617 -123.30375) (xy 135.885174 -123.297696) (xy 135.873998 -123.286012) (xy 135.864854 -123.284488)
			(xy 135.863076 -123.284234) (xy 135.836344 -123.279705) (xy 135.784428 -123.264081) (xy 135.735246 -123.241265)
			(xy 135.689789 -123.211716) (xy 135.648973 -123.17603) (xy 135.61362 -123.134925) (xy 135.584442 -123.08923)
			(xy 135.562027 -123.039864) (xy 135.546825 -122.987822) (xy 135.539144 -122.934152) (xy 135.538718 -122.907044)
			(xy 135.539281 -122.876955) (xy 135.548725 -122.817521) (xy 135.567385 -122.760309) (xy 135.594799 -122.706737)
			(xy 135.630286 -122.658135) (xy 135.65124 -122.636534) (xy 135.654796 -122.632978) (xy 135.66394 -122.619262)
			(xy 135.666734 -122.615198) (xy 135.674354 -122.597418) (xy 135.67664 -122.59056) (xy 135.67664 -122.590052)
			(xy 135.678418 -122.577606) (xy 135.678418 -122.515884) (xy 135.678099 -122.507603) (xy 135.672785 -122.491919)
			(xy 135.668004 -122.48515) (xy 135.665972 -122.482864) (xy 135.664194 -122.481086) (xy 135.660892 -122.477276)
			(xy 135.657844 -122.474228) (xy 135.654796 -122.46991) (xy 135.651748 -122.466862) (xy 135.63073 -122.445228)
			(xy 135.595102 -122.396559) (xy 135.567574 -122.342893) (xy 135.548829 -122.285565) (xy 135.539335 -122.226001)
			(xy 135.538718 -122.195844) (xy 135.538795 -122.183106) (xy 135.540445 -122.157684) (xy 135.54202 -122.145044)
			(xy 135.545847 -122.119688) (xy 135.559415 -122.070236) (xy 135.579471 -122.023041) (xy 135.605657 -121.978951)
			(xy 135.621268 -121.958608) (xy 135.625332 -121.953528) (xy 135.628888 -121.945654) (xy 135.630657 -121.941025)
			(xy 135.632566 -121.931304) (xy 135.632698 -121.92635) (xy 135.632698 -121.905014) (xy 135.63473 -121.891044)
			(xy 135.635492 -121.887234) (xy 135.635492 -121.833894) (xy 135.635407 -121.829483) (xy 135.633879 -121.820794)
			(xy 135.632444 -121.816622) (xy 135.62965 -121.808748) (xy 135.626094 -121.804176) (xy 135.609734 -121.783717)
			(xy 135.582177 -121.739165) (xy 135.560966 -121.691266) (xy 135.546498 -121.640918) (xy 135.539046 -121.589066)
			(xy 135.538464 -121.562876) (xy 135.538718 -121.553224) (xy 135.538718 -121.55297) (xy 135.538972 -121.544588)
			(xy 135.539734 -121.516648) (xy 135.539916 -121.512699) (xy 135.541323 -121.504919) (xy 135.542528 -121.501154)
			(xy 135.54329 -121.498614) (xy 135.545576 -121.487184) (xy 135.546846 -121.48185) (xy 135.546846 -121.481596)
			(xy 135.547354 -121.47931) (xy 135.548624 -121.473722) (xy 135.55582 -121.445438) (xy 135.577636 -121.39131)
			(xy 135.607452 -121.341141) (xy 135.625586 -121.318274) (xy 135.626094 -121.317766) (xy 135.626856 -121.31675)
			(xy 135.63219 -121.296938) (xy 135.613394 -121.15292) (xy 135.609076 -121.146824) (xy 135.601774 -121.136302)
			(xy 135.588431 -121.114438) (xy 135.582406 -121.103136) (xy 135.569895 -121.078254) (xy 135.55141 -121.02572)
			(xy 135.545576 -120.998488) (xy 135.545322 -120.996964) (xy 135.54255 -120.981481) (xy 135.539244 -120.9502)
			(xy 135.538718 -120.93448) (xy 135.538718 -120.915684) (xy 135.540069 -120.885399) (xy 135.551178 -120.825808)
			(xy 135.560816 -120.797066) (xy 135.562086 -120.794018) (xy 135.56361 -120.7897) (xy 135.565134 -120.78589)
			(xy 135.486394 -120.188482) (xy 135.484616 -120.180354) (xy 134.999984 -118.581424) (xy 134.677658 -117.517926)
			(xy 134.674261 -117.508259) (xy 134.661152 -117.492535) (xy 134.652258 -117.487446) (xy 134.644415 -117.483773)
			(xy 134.627269 -117.481433) (xy 134.61873 -117.482874) (xy 134.614412 -117.484144) (xy 134.610642 -117.485288)
			(xy 134.603495 -117.488606) (xy 134.600188 -117.490748) (xy 134.594854 -117.494558) (xy 134.590028 -117.5004)
			(xy 134.582408 -117.50929) (xy 134.5819 -117.509798) (xy 134.580884 -117.511068) (xy 134.56158 -117.531642)
			(xy 134.553706 -117.539262) (xy 134.553452 -117.539516) (xy 134.550658 -117.542056) (xy 134.529913 -117.560251)
			(xy 134.484154 -117.591088) (xy 134.434427 -117.615005) (xy 134.381771 -117.631501) (xy 134.327286 -117.640231)
			(xy 134.299706 -117.641116) (xy 134.293356 -117.641116) (xy 134.263447 -117.640509) (xy 134.204366 -117.631131)
			(xy 134.147469 -117.61266) (xy 134.094147 -117.585545) (xy 134.069582 -117.568472) (xy 134.0612 -117.562122)
			(xy 134.056374 -117.558312) (xy 134.047738 -117.552978) (xy 134.046722 -117.55247) (xy 134.041395 -117.550014)
			(xy 134.029979 -117.547331) (xy 134.024116 -117.547136) (xy 134.003034 -117.547136) (xy 133.997596 -117.546989)
			(xy 133.986968 -117.544672) (xy 133.981952 -117.542564) (xy 133.96849 -117.536468) (xy 133.959829 -117.532851)
			(xy 133.941112 -117.531626) (xy 133.923221 -117.537258) (xy 133.915658 -117.542818) (xy 133.908546 -117.548406)
			(xy 133.903974 -117.551962) (xy 133.903212 -117.55247) (xy 133.88257 -117.569111) (xy 133.837558 -117.597127)
			(xy 133.789099 -117.618642) (xy 133.738128 -117.633239) (xy 133.685627 -117.640638) (xy 133.659118 -117.641116)
			(xy 133.658864 -117.641116) (xy 133.644894 -117.640862) (xy 133.641592 -117.640862) (xy 133.612764 -117.639028)
			(xy 133.556112 -117.627751) (xy 133.501808 -117.608062) (xy 133.451094 -117.580411) (xy 133.405128 -117.545428)
			(xy 133.364962 -117.503916) (xy 133.331515 -117.456822) (xy 133.305551 -117.405223) (xy 133.287663 -117.350299)
			(xy 133.27826 -117.293307) (xy 133.277356 -117.264434) (xy 133.277356 -117.259608) (xy 133.278372 -117.230144)
			(xy 133.278372 -117.22989) (xy 133.279134 -117.219222) (xy 133.275324 -117.208808) (xy 133.273312 -117.203714)
			(xy 133.267413 -117.19449) (xy 133.26364 -117.19052) (xy 133.261354 -117.188234) (xy 133.260338 -117.169184)
			(xy 133.260262 -117.160012) (xy 133.26586 -117.142561) (xy 133.27126 -117.135148) (xy 133.355842 -117.027706)
			(xy 133.356096 -117.027198) (xy 133.35635 -117.026944) (xy 133.357874 -117.025166) (xy 133.359144 -117.023388)
			(xy 133.359398 -117.023134) (xy 133.360414 -117.021864) (xy 133.360922 -117.021102) (xy 133.364224 -117.01653)
			(xy 133.36778 -117.008656) (xy 133.369409 -117.004193) (xy 133.371203 -116.994863) (xy 133.371336 -116.990114)
			(xy 133.371336 -116.968778) (xy 133.371478 -116.963338) (xy 133.373785 -116.952706) (xy 133.375908 -116.947696)
			(xy 133.382004 -116.934234) (xy 133.38563 -116.925572) (xy 133.386871 -116.906847) (xy 133.381246 -116.888944)
			(xy 133.375654 -116.881402) (xy 133.370066 -116.87429) (xy 133.36651 -116.869718) (xy 133.366002 -116.868956)
			(xy 133.365494 -116.868448) (xy 133.364732 -116.867432) (xy 133.348542 -116.847169) (xy 133.321214 -116.803088)
			(xy 133.300115 -116.755708) (xy 133.285635 -116.705905) (xy 133.27804 -116.654599) (xy 133.277356 -116.628672)
			(xy 133.277356 -116.625624) (xy 133.277691 -116.60024) (xy 133.284254 -116.5499) (xy 133.297429 -116.500874)
			(xy 133.30682 -116.477288) (xy 133.317364 -116.453146) (xy 133.344136 -116.407775) (xy 133.36016 -116.386864)
			(xy 133.36397 -116.382038) (xy 133.36651 -116.376704) (xy 133.368743 -116.371588) (xy 133.371166 -116.360694)
			(xy 133.371336 -116.355114) (xy 133.371336 -116.333778) (xy 133.371478 -116.328338) (xy 133.373785 -116.317706)
			(xy 133.375908 -116.312696) (xy 133.382004 -116.299234) (xy 133.38563 -116.290572) (xy 133.386871 -116.271847)
			(xy 133.381246 -116.253944) (xy 133.375654 -116.246402) (xy 133.370066 -116.23929) (xy 133.36651 -116.234718)
			(xy 133.366002 -116.233956) (xy 133.364478 -116.232178) (xy 133.345582 -116.208312) (xy 133.314819 -116.155787)
			(xy 133.292775 -116.099048) (xy 133.280009 -116.039531) (xy 133.277864 -116.009166) (xy 133.277356 -115.990624)
			(xy 133.277356 -115.989608) (xy 133.277841 -115.962355) (xy 133.285597 -115.908405) (xy 133.300951 -115.856107)
			(xy 133.323591 -115.806527) (xy 133.353056 -115.760673) (xy 133.388747 -115.719479) (xy 133.429937 -115.683783)
			(xy 133.475788 -115.654312) (xy 133.525366 -115.631666) (xy 133.577662 -115.616306) (xy 133.631611 -115.608544)
			(xy 133.658864 -115.6081) (xy 133.659118 -115.6081) (xy 133.684735 -115.608511) (xy 133.735508 -115.615366)
			(xy 133.784905 -115.628963) (xy 133.832033 -115.649057) (xy 133.876044 -115.675286) (xy 133.896354 -115.690904)
			(xy 133.90118 -115.694714) (xy 133.908546 -115.698016) (xy 133.913286 -115.699881) (xy 133.923266 -115.701917)
			(xy 133.928358 -115.70208) (xy 133.949694 -115.70208) (xy 133.953501 -115.702145) (xy 133.961028 -115.703289)
			(xy 133.96468 -115.704366) (xy 133.968744 -115.705636) (xy 133.986016 -115.71351) (xy 133.994825 -115.716835)
			(xy 134.013623 -115.717537) (xy 134.031405 -115.711401) (xy 134.038848 -115.705636) (xy 134.041388 -115.70335)
			(xy 134.041642 -115.703096) (xy 134.044182 -115.701064) (xy 134.055358 -115.691666) (xy 134.069074 -115.680998)
			(xy 134.069582 -115.680998) (xy 134.071106 -115.679728) (xy 134.072122 -115.67922) (xy 134.07644 -115.675918)
			(xy 134.083552 -115.66779) (xy 134.103364 -115.630706) (xy 134.102094 -115.619784) (xy 130.313938 -103.121714)
			(xy 130.313176 -103.119174) (xy 130.312922 -103.118412) (xy 130.311906 -103.115364) (xy 128.365504 -96.693736)
			(xy 128.3589 -96.685862) (xy 128.342092 -96.665157) (xy 128.313816 -96.619941) (xy 128.292108 -96.57123)
			(xy 128.277393 -96.519971) (xy 128.269956 -96.467163) (xy 128.269492 -96.440498) (xy 128.269492 -96.43999)
			(xy 128.269564 -96.429554) (xy 128.270709 -96.408715) (xy 128.271778 -96.398334) (xy 128.271778 -96.397318)
			(xy 128.272794 -96.388174) (xy 125.095 -85.904324) (xy 125.086959 -85.877051) (xy 125.073614 -85.821773)
			(xy 125.06833 -85.793834) (xy 125.060789 -85.749516) (xy 125.052772 -85.65997) (xy 125.052328 -85.615018)
			(xy 125.052328 -85.60689) (xy 125.24232 -62.60338) (xy 125.24232 -61.016134) (xy 125.24105 -61.015372)
			(xy 125.234192 -61.011562) (xy 125.203712 -61.003942) (xy 125.175766 -60.996502) (xy 125.122349 -60.974344)
			(xy 125.07289 -60.944377) (xy 125.028522 -60.907287) (xy 124.990261 -60.863924) (xy 124.958984 -60.815282)
			(xy 124.935409 -60.762476) (xy 124.920075 -60.706717) (xy 124.916184 -60.67806) (xy 124.91466 -60.66409)
			(xy 124.91339 -60.633356) (xy 124.913928 -60.604023) (xy 124.922899 -60.546045) (xy 124.940625 -60.49012)
			(xy 124.966688 -60.43756) (xy 125.000476 -60.3896) (xy 125.041196 -60.347366) (xy 125.087892 -60.311851)
			(xy 125.139466 -60.283888) (xy 125.166882 -60.273438) (xy 125.173232 -60.271152) (xy 125.173994 -60.270898)
			(xy 125.179328 -60.267088) (xy 125.189234 -60.25769) (xy 125.193298 -60.25261) (xy 125.206506 -60.235592)
			(xy 125.210923 -60.229165) (xy 125.215985 -60.214422) (xy 125.216412 -60.206636) (xy 125.216412 -60.202572)
			(xy 125.188726 -59.71159) (xy 125.188726 -59.710574) (xy 125.106938 -58.806334) (xy 125.104922 -58.795539)
			(xy 125.093206 -58.776989) (xy 125.084332 -58.77052) (xy 125.084078 -58.77052) (xy 125.061491 -58.755341)
			(xy 125.020452 -58.719602) (xy 124.984903 -58.678399) (xy 124.955565 -58.632566) (xy 124.933031 -58.583031)
			(xy 124.917759 -58.530799) (xy 124.910058 -58.476928) (xy 124.90958 -58.449718) (xy 124.90958 -58.449464)
			(xy 124.910038 -58.423442) (xy 124.917145 -58.371886) (xy 124.931194 -58.321773) (xy 124.951925 -58.274036)
			(xy 124.978952 -58.22956) (xy 125.011775 -58.189171) (xy 125.030484 -58.17108) (xy 125.034294 -58.167524)
			(xy 125.040644 -58.157872) (xy 125.042676 -58.152538) (xy 125.044519 -58.147151) (xy 125.046054 -58.135871)
			(xy 125.045724 -58.130186) (xy 125.042676 -58.097166) (xy 125.033786 -58.000138) (xy 124.97435 -57.343548)
			(xy 124.97251 -57.321115) (xy 124.970606 -57.27614) (xy 124.97054 -57.253632) (xy 124.97054 -57.238138)
			(xy 124.97054 -57.237122) (xy 124.987812 -56.129936) (xy 124.987812 -56.12638) (xy 124.785374 -52.520342)
			(xy 124.740416 -51.716686) (xy 124.739854 -51.712541) (xy 124.737562 -51.704498) (xy 124.735844 -51.700684)
			(xy 124.73178 -51.692302) (xy 124.723906 -51.68519) (xy 124.723652 -51.684936) (xy 124.718318 -51.68011)
			(xy 124.648976 -51.645566) (xy 124.643651 -51.643101) (xy 124.632235 -51.640401) (xy 124.62637 -51.640232)
			(xy 124.59843 -51.640232) (xy 124.585222 -51.64201) (xy 124.578872 -51.643788) (xy 124.572776 -51.647344)
			(xy 124.550503 -51.660227) (xy 124.503228 -51.680542) (xy 124.453649 -51.694309) (xy 124.402669 -51.70128)
			(xy 124.376942 -51.7017) (xy 124.376688 -51.7017) (xy 124.350514 -51.701339) (xy 124.29864 -51.694333)
			(xy 124.27331 -51.68773) (xy 124.243235 -51.678628) (xy 124.186338 -51.651975) (xy 124.134575 -51.616362)
			(xy 124.111512 -51.59502) (xy 124.094627 -51.578354) (xy 124.064693 -51.541544) (xy 124.051822 -51.521614)
			(xy 124.049282 -51.51755) (xy 124.04638 -51.513902) (xy 124.039483 -51.507631) (xy 124.035566 -51.505104)
			(xy 124.030994 -51.502056) (xy 124.020326 -51.4985) (xy 123.966732 -51.492912) (xy 123.966224 -51.492912)
			(xy 123.93803 -51.490372) (xy 123.934401 -51.490113) (xy 123.927135 -51.490503) (xy 123.923552 -51.491134)
			(xy 123.917456 -51.492404) (xy 123.90628 -51.496214) (xy 123.897136 -51.50104) (xy 123.891294 -51.507136)
			(xy 123.873223 -51.525501) (xy 123.832994 -51.557692) (xy 123.788794 -51.584168) (xy 123.741429 -51.604447)
			(xy 123.691764 -51.618159) (xy 123.640704 -51.625053) (xy 123.614942 -51.6255) (xy 123.614688 -51.6255)
			(xy 123.599702 -51.625246) (xy 123.571233 -51.623596) (xy 123.51522 -51.612902) (xy 123.461423 -51.593992)
			(xy 123.411038 -51.567288) (xy 123.365187 -51.533385) (xy 123.324891 -51.493036) (xy 123.291047 -51.447141)
			(xy 123.264409 -51.396722) (xy 123.254516 -51.369976) (xy 123.254262 -51.369468) (xy 123.251722 -51.361848)
			(xy 123.247253 -51.347688) (xy 123.240262 -51.318825) (xy 123.237752 -51.30419) (xy 123.237752 -51.303682)
			(xy 123.235212 -51.284124) (xy 123.235212 -51.283362) (xy 123.233434 -51.267614) (xy 123.23318 -51.262026)
			(xy 123.23318 -51.243738) (xy 123.234196 -51.214528) (xy 123.234958 -51.203606) (xy 123.231148 -51.193192)
			(xy 123.229144 -51.188093) (xy 123.223258 -51.178856) (xy 123.219464 -51.174904) (xy 123.217178 -51.172618)
			(xy 123.216162 -51.153568) (xy 123.216089 -51.144398) (xy 123.221693 -51.126951) (xy 123.227084 -51.119532)
			(xy 123.311666 -51.01209) (xy 123.31192 -51.011582) (xy 123.312174 -51.011328) (xy 123.313698 -51.00955)
			(xy 123.314968 -51.007772) (xy 123.315222 -51.007518) (xy 123.316238 -51.006248) (xy 123.316746 -51.005486)
			(xy 123.320048 -51.000914) (xy 123.323604 -50.99304) (xy 123.325231 -50.988576) (xy 123.327021 -50.979247)
			(xy 123.32716 -50.974498) (xy 123.32716 -50.953162) (xy 123.327304 -50.947723) (xy 123.329615 -50.937093)
			(xy 123.331732 -50.93208) (xy 123.337828 -50.918618) (xy 123.34145 -50.909956) (xy 123.342685 -50.891234)
			(xy 123.337059 -50.873335) (xy 123.331478 -50.865786) (xy 123.32589 -50.858674) (xy 123.322334 -50.854102)
			(xy 123.321826 -50.85334) (xy 123.321318 -50.852832) (xy 123.320556 -50.851816) (xy 123.304366 -50.831553)
			(xy 123.277038 -50.787472) (xy 123.25594 -50.740092) (xy 123.24146 -50.690289) (xy 123.233868 -50.638983)
			(xy 123.23318 -50.613056) (xy 123.23318 -50.610008) (xy 123.233378 -50.590636) (xy 123.237199 -50.552082)
			(xy 123.2408 -50.533046) (xy 123.246912 -50.505527) (xy 123.266148 -50.452542) (xy 123.292968 -50.402962)
			(xy 123.326789 -50.357866) (xy 123.366875 -50.318236) (xy 123.412354 -50.284933) (xy 123.462237 -50.258681)
			(xy 123.515439 -50.240052) (xy 123.570802 -50.229451) (xy 123.59894 -50.227738) (xy 123.602496 -50.227738)
			(xy 123.606814 -50.227484) (xy 123.616466 -50.227484) (xy 123.617736 -50.22723) (xy 123.620784 -50.22723)
			(xy 123.64806 -50.22811) (xy 123.701951 -50.236708) (xy 123.754065 -50.252902) (xy 123.803339 -50.276359)
			(xy 123.848766 -50.306601) (xy 123.889417 -50.34301) (xy 123.907296 -50.363628) (xy 123.908058 -50.364644)
			(xy 123.914154 -50.37201) (xy 123.92406 -50.378614) (xy 123.927616 -50.380392) (xy 123.946412 -50.389282)
			(xy 123.958858 -50.393346) (xy 123.96724 -50.394108) (xy 124.018802 -50.394108) (xy 124.030994 -50.392584)
			(xy 124.04725 -50.38852) (xy 124.052076 -50.386234) (xy 124.063252 -50.3809) (xy 124.068078 -50.378614)
			(xy 124.077476 -50.371502) (xy 124.08154 -50.366676) (xy 124.081794 -50.366422) (xy 124.084842 -50.362866)
			(xy 124.092795 -50.353641) (xy 124.109696 -50.336099) (xy 124.118624 -50.327814) (xy 124.13985 -50.308999)
			(xy 124.186829 -50.277213) (xy 124.237999 -50.252742) (xy 124.292231 -50.236126) (xy 124.348327 -50.227732)
			(xy 124.376688 -50.22723) (xy 124.407676 -50.2285) (xy 124.411994 -50.229008) (xy 124.413264 -50.229262)
			(xy 124.437146 -50.231927) (xy 124.484024 -50.242496) (xy 124.506736 -50.250344) (xy 124.515118 -50.253392)
			(xy 124.542042 -50.253392) (xy 124.55017 -50.25263) (xy 124.550678 -50.25263) (xy 124.558201 -50.251037)
			(xy 124.571902 -50.244074) (xy 124.577602 -50.238914) (xy 124.584968 -50.231548) (xy 124.591064 -50.226468)
			(xy 124.634752 -50.194972) (xy 124.638903 -50.191327) (xy 124.645697 -50.182618) (xy 124.648214 -50.1777)
			(xy 124.650246 -50.172366) (xy 124.651404 -50.168531) (xy 124.652674 -50.160622) (xy 124.652786 -50.156618)
			(xy 124.652786 -50.153316) (xy 124.650754 -50.120804) (xy 124.650754 -50.120042) (xy 124.648468 -50.080926)
			(xy 124.646436 -50.046128) (xy 124.645831 -50.041702) (xy 124.643277 -50.033143) (xy 124.641356 -50.02911)
			(xy 124.637038 -50.020474) (xy 124.631958 -50.016156) (xy 124.62891 -50.013616) (xy 124.606558 -49.994566)
			(xy 124.603186 -49.9916) (xy 124.597435 -49.984703) (xy 124.595128 -49.98085) (xy 124.595128 -49.980596)
			(xy 124.593096 -49.97704) (xy 124.589723 -49.972193) (xy 124.581127 -49.9641) (xy 124.576078 -49.961038)
			(xy 124.570236 -49.957736) (xy 124.557028 -49.95418) (xy 124.544836 -49.954434) (xy 124.542296 -49.954434)
			(xy 124.50953 -49.956212) (xy 124.492512 -49.956212) (xy 124.459492 -49.95418) (xy 124.447387 -49.952817)
			(xy 124.423366 -49.948748) (xy 124.411486 -49.946052) (xy 124.395496 -49.942102) (xy 124.364209 -49.931803)
			(xy 124.349002 -49.925478) (xy 124.325988 -49.91521) (xy 124.282661 -49.889476) (xy 124.262642 -49.87417)
			(xy 124.259594 -49.871884) (xy 124.25807 -49.870614) (xy 124.246386 -49.864772) (xy 124.235464 -49.862232)
			(xy 124.208286 -49.862232) (xy 124.202846 -49.86209) (xy 124.192214 -49.859783) (xy 124.187204 -49.85766)
			(xy 124.173742 -49.851564) (xy 124.165079 -49.847937) (xy 124.146353 -49.846695) (xy 124.128447 -49.852315)
			(xy 124.12091 -49.857914) (xy 124.113798 -49.863502) (xy 124.109226 -49.867058) (xy 124.108464 -49.867566)
			(xy 124.087822 -49.884204) (xy 124.042808 -49.912215) (xy 123.994349 -49.933724) (xy 123.943378 -49.948315)
			(xy 123.890878 -49.955707) (xy 123.86437 -49.956212) (xy 123.854464 -49.956212) (xy 123.825744 -49.954968)
			(xy 123.769147 -49.944909) (xy 123.714704 -49.926457) (xy 123.663654 -49.900032) (xy 123.640088 -49.883568)
			(xy 123.631452 -49.877472) (xy 123.626372 -49.873154) (xy 123.619006 -49.868582) (xy 123.616974 -49.867566)
			(xy 123.611649 -49.865101) (xy 123.600233 -49.862401) (xy 123.594368 -49.862232) (xy 123.573286 -49.862232)
			(xy 123.567846 -49.86209) (xy 123.557214 -49.859783) (xy 123.552204 -49.85766) (xy 123.538742 -49.851564)
			(xy 123.530079 -49.847937) (xy 123.511353 -49.846695) (xy 123.493447 -49.852315) (xy 123.48591 -49.857914)
			(xy 123.478798 -49.863502) (xy 123.474226 -49.867058) (xy 123.473464 -49.867566) (xy 123.452822 -49.884204)
			(xy 123.407808 -49.912215) (xy 123.359349 -49.933724) (xy 123.308378 -49.948315) (xy 123.255878 -49.955707)
			(xy 123.22937 -49.956212) (xy 123.219464 -49.956212) (xy 123.190744 -49.954968) (xy 123.134147 -49.944909)
			(xy 123.079704 -49.926457) (xy 123.028654 -49.900032) (xy 123.005088 -49.883568) (xy 122.996452 -49.877472)
			(xy 122.991372 -49.873154) (xy 122.984006 -49.868582) (xy 122.981974 -49.867566) (xy 122.976649 -49.865101)
			(xy 122.965233 -49.862401) (xy 122.959368 -49.862232) (xy 122.938286 -49.862232) (xy 122.932846 -49.86209)
			(xy 122.922214 -49.859783) (xy 122.917204 -49.85766) (xy 122.903742 -49.851564) (xy 122.895079 -49.847937)
			(xy 122.876353 -49.846695) (xy 122.858447 -49.852315) (xy 122.85091 -49.857914) (xy 122.843798 -49.863502)
			(xy 122.839226 -49.867058) (xy 122.838464 -49.867566) (xy 122.817822 -49.884204) (xy 122.772808 -49.912215)
			(xy 122.724349 -49.933724) (xy 122.673378 -49.948315) (xy 122.620878 -49.955707) (xy 122.59437 -49.956212)
			(xy 122.594116 -49.956212) (xy 122.566862 -49.95575) (xy 122.512909 -49.947995) (xy 122.460609 -49.93264)
			(xy 122.411026 -49.909998) (xy 122.36517 -49.88053) (xy 122.323975 -49.844836) (xy 122.28828 -49.803642)
			(xy 122.25881 -49.757788) (xy 122.236166 -49.708206) (xy 122.220809 -49.655907) (xy 122.213051 -49.601954)
			(xy 122.213051 -49.547446) (xy 122.220809 -49.493493) (xy 122.236166 -49.441194) (xy 122.25881 -49.391612)
			(xy 122.28828 -49.345758) (xy 122.323975 -49.304564) (xy 122.36517 -49.26887) (xy 122.411026 -49.239402)
			(xy 122.460609 -49.21676) (xy 122.512909 -49.201405) (xy 122.566862 -49.19365) (xy 122.594116 -49.193196)
			(xy 122.59437 -49.193196) (xy 122.619988 -49.193603) (xy 122.670764 -49.200453) (xy 122.720164 -49.214045)
			(xy 122.767297 -49.234135) (xy 122.811313 -49.26036) (xy 122.831606 -49.276) (xy 122.836432 -49.27981)
			(xy 122.843798 -49.283112) (xy 122.848537 -49.284982) (xy 122.858517 -49.287027) (xy 122.86361 -49.287176)
			(xy 122.884946 -49.287176) (xy 122.890385 -49.28732) (xy 122.901016 -49.289629) (xy 122.906028 -49.291748)
			(xy 122.91949 -49.297844) (xy 122.928152 -49.301464) (xy 122.946872 -49.302696) (xy 122.96477 -49.297069)
			(xy 122.972322 -49.291494) (xy 122.979434 -49.285906) (xy 122.984006 -49.28235) (xy 122.984768 -49.281842)
			(xy 123.005409 -49.2652) (xy 123.050421 -49.23718) (xy 123.098879 -49.215662) (xy 123.14985 -49.201062)
			(xy 123.202352 -49.19366) (xy 123.228862 -49.193196) (xy 123.238768 -49.193196) (xy 123.269556 -49.194565)
			(xy 123.330112 -49.205999) (xy 123.388045 -49.227009) (xy 123.441852 -49.257051) (xy 123.466352 -49.275746)
			(xy 123.471432 -49.27981) (xy 123.479306 -49.283366) (xy 123.483934 -49.285139) (xy 123.493655 -49.287057)
			(xy 123.49861 -49.287176) (xy 123.519946 -49.287176) (xy 123.525385 -49.28732) (xy 123.536016 -49.289629)
			(xy 123.541028 -49.291748) (xy 123.55449 -49.297844) (xy 123.563152 -49.301464) (xy 123.581872 -49.302696)
			(xy 123.59977 -49.297069) (xy 123.607322 -49.291494) (xy 123.614434 -49.285906) (xy 123.619006 -49.28235)
			(xy 123.619768 -49.281842) (xy 123.640409 -49.2652) (xy 123.685421 -49.23718) (xy 123.733879 -49.215662)
			(xy 123.78485 -49.201062) (xy 123.837352 -49.19366) (xy 123.863862 -49.193196) (xy 123.873768 -49.193196)
			(xy 123.904556 -49.194565) (xy 123.965112 -49.205999) (xy 124.023045 -49.227009) (xy 124.076852 -49.257051)
			(xy 124.101352 -49.275746) (xy 124.106432 -49.27981) (xy 124.11329 -49.282858) (xy 124.120656 -49.285398)
			(xy 124.121164 -49.285398) (xy 124.133864 -49.287176) (xy 124.154946 -49.287176) (xy 124.160385 -49.28732)
			(xy 124.171016 -49.289629) (xy 124.176028 -49.291748) (xy 124.187458 -49.297082) (xy 124.187966 -49.297082)
			(xy 124.19711 -49.301654) (xy 124.20854 -49.301908) (xy 124.214045 -49.30179) (xy 124.224809 -49.29949)
			(xy 124.229876 -49.297336) (xy 124.234956 -49.29505) (xy 124.243846 -49.290478) (xy 124.248418 -49.286414)
			(xy 124.271028 -49.267584) (xy 124.320913 -49.236387) (xy 124.374994 -49.213213) (xy 124.403358 -49.205388)
			(xy 124.422789 -49.200586) (xy 124.462369 -49.194606) (xy 124.482352 -49.19345) (xy 124.485654 -49.19345)
			(xy 124.49302 -49.193196) (xy 124.493274 -49.193196) (xy 124.503688 -49.192942) (xy 124.512832 -49.189132)
			(xy 124.517198 -49.187077) (xy 124.525127 -49.18158) (xy 124.52858 -49.17821) (xy 124.54763 -49.15789)
			(xy 124.57938 -49.1236) (xy 124.585999 -49.115773) (xy 124.592954 -49.096511) (xy 124.592842 -49.086262)
			(xy 124.47016 -46.901862) (xy 124.324364 -44.305728) (xy 124.32411 -44.301664) (xy 123.793758 -40.375586)
			(xy 123.789988 -40.346131) (xy 123.785539 -40.28691) (xy 123.784868 -40.257222) (xy 123.778772 -39.8653)
			(xy 123.77674 -39.725346) (xy 123.776256 -39.720384) (xy 123.773574 -39.710785) (xy 123.771406 -39.706296)
			(xy 123.771406 -39.706042) (xy 123.752172 -39.666102) (xy 123.72005 -39.583471) (xy 123.695393 -39.498315)
			(xy 123.678396 -39.411305) (xy 123.669193 -39.323129) (xy 123.668028 -39.278814) (xy 123.660408 -38.78453)
			(xy 123.660408 -38.766496) (xy 123.660848 -38.726361) (xy 123.667378 -38.646355) (xy 123.680324 -38.567135)
			(xy 123.6996 -38.489212) (xy 123.71197 -38.451028) (xy 123.714141 -38.44365) (xy 123.714522 -38.428283)
			(xy 123.712732 -38.420802) (xy 123.711462 -38.417246) (xy 123.697115 -38.377312) (xy 123.674458 -38.295531)
			(xy 123.658823 -38.212122) (xy 123.650321 -38.127687) (xy 123.649232 -38.085268) (xy 123.641612 -37.59073)
			(xy 123.641612 -37.574474) (xy 123.641958 -37.535464) (xy 123.647996 -37.457678) (xy 123.660104 -37.380604)
			(xy 123.66879 -37.342572) (xy 123.670822 -37.334444) (xy 123.663456 -37.260276) (xy 123.658122 -37.250878)
			(xy 123.634093 -37.207234) (xy 123.593919 -37.116056) (xy 123.563109 -37.021304) (xy 123.55195 -36.972748)
			(xy 123.549664 -36.96208) (xy 123.548648 -36.957) (xy 123.547886 -36.952682) (xy 123.54564 -36.945435)
			(xy 123.537497 -36.93264) (xy 123.531884 -36.927536) (xy 123.53163 -36.927282) (xy 123.529344 -36.92525)
			(xy 123.505722 -36.9062) (xy 123.4948 -36.900104) (xy 123.48718 -36.89731) (xy 123.47956 -36.896802)
			(xy 123.478544 -36.896802) (xy 123.452002 -36.895089) (xy 123.399737 -36.885228) (xy 123.349349 -36.868202)
			(xy 123.325382 -36.85667) (xy 123.314707 -36.851212) (xy 123.293991 -36.839137) (xy 123.28398 -36.83254)
			(xy 123.275504 -36.826768) (xy 123.259111 -36.814443) (xy 123.251214 -36.807902) (xy 123.229456 -36.788959)
			(xy 123.191339 -36.745657) (xy 123.160165 -36.697117) (xy 123.136643 -36.644442) (xy 123.121306 -36.58883)
			(xy 123.117356 -36.560252) (xy 123.115578 -36.545266) (xy 123.114562 -36.515548) (xy 123.115041 -36.487999)
			(xy 123.122951 -36.433472) (xy 123.138615 -36.380647) (xy 123.161706 -36.330622) (xy 123.191746 -36.284433)
			(xy 123.228111 -36.24304) (xy 123.270046 -36.207302) (xy 123.316681 -36.177961) (xy 123.367049 -36.155625)
			(xy 123.393454 -36.147756) (xy 123.395486 -36.147502) (xy 123.398026 -36.14674) (xy 123.400058 -36.146232)
			(xy 123.40082 -36.145978) (xy 123.401582 -36.145978) (xy 123.403868 -36.145216) (xy 123.40717 -36.144454)
			(xy 123.411275 -36.142944) (xy 123.418937 -36.13873) (xy 123.42241 -36.136072) (xy 123.425312 -36.133629)
			(xy 123.430416 -36.128018) (xy 123.43257 -36.124896) (xy 123.439936 -36.112196) (xy 123.440444 -36.11118)
			(xy 123.46813 -36.060634) (xy 123.469654 -36.05784) (xy 123.471893 -36.052725) (xy 123.474326 -36.041831)
			(xy 123.47448 -36.03625) (xy 123.47448 -36.016184) (xy 123.47321 -36.011866) (xy 123.472956 -36.011104)
			(xy 123.472956 -36.01085) (xy 123.47194 -36.007802) (xy 123.471432 -36.006278) (xy 123.468384 -35.99688)
			(xy 123.468384 -35.996118) (xy 123.466352 -35.988752) (xy 123.46559 -35.986466) (xy 123.464828 -35.984688)
			(xy 123.463304 -35.9791) (xy 123.462542 -35.976052) (xy 123.462034 -35.974528) (xy 123.462034 -35.974274)
			(xy 123.460764 -35.969956) (xy 123.460002 -35.967162) (xy 123.457716 -35.958526) (xy 123.457716 -35.958272)
			(xy 123.456192 -35.952938) (xy 123.456192 -35.95243) (xy 123.454668 -35.946588) (xy 123.451874 -35.935158)
			(xy 123.44477 -35.904051) (xy 123.434096 -35.841137) (xy 123.430538 -35.809428) (xy 123.42876 -35.791648)
			(xy 123.42495 -35.752532) (xy 123.405138 -35.55365) (xy 123.404023 -35.547859) (xy 123.399538 -35.536954)
			(xy 123.396248 -35.53206) (xy 123.391168 -35.525964) (xy 123.389898 -35.524694) (xy 123.381262 -35.517582)
			(xy 123.356116 -35.518852) (xy 123.353576 -35.518852) (xy 123.34113 -35.51936) (xy 123.31573 -35.519868)
			(xy 123.303284 -35.519868) (xy 123.256889 -35.518987) (xy 123.164557 -35.509663) (xy 123.073491 -35.491798)
			(xy 122.984481 -35.465544) (xy 122.898296 -35.431131) (xy 122.815684 -35.388854) (xy 122.776234 -35.36442)
			(xy 122.774202 -35.364928) (xy 122.770138 -35.36569) (xy 122.753139 -35.368564) (xy 122.718797 -35.371616)
			(xy 122.701558 -35.371786) (xy 122.70105 -35.371786) (xy 122.673795 -35.371326) (xy 122.61984 -35.363575)
			(xy 122.567538 -35.348223) (xy 122.517953 -35.325583) (xy 122.472095 -35.296116) (xy 122.430898 -35.260422)
			(xy 122.395201 -35.219228) (xy 122.365731 -35.173372) (xy 122.343087 -35.123789) (xy 122.327731 -35.071487)
			(xy 122.319976 -35.017533) (xy 122.319542 -34.990278) (xy 122.319542 -34.987484) (xy 122.320111 -34.963282)
			(xy 122.326626 -34.91531) (xy 122.339167 -34.86855) (xy 122.34799 -34.846006) (xy 122.348498 -34.844482)
			(xy 122.350276 -34.840164) (xy 122.35688 -34.824162) (xy 122.35815 -34.818574) (xy 122.353578 -34.802826)
			(xy 122.340851 -34.757528) (xy 122.32297 -34.665145) (xy 122.313865 -34.571489) (xy 122.313192 -34.524442)
			(xy 122.313192 -34.515552) (xy 122.313794 -34.478339) (xy 122.319857 -34.404154) (xy 122.331438 -34.330628)
			(xy 122.339608 -34.294318) (xy 122.350972 -34.248369) (xy 122.381245 -34.158681) (xy 122.40006 -34.115248)
			(xy 122.401838 -34.111184) (xy 122.40641 -34.091118) (xy 122.40641 -34.090102) (xy 122.401838 -34.070036)
			(xy 122.40006 -34.065972) (xy 122.38333 -34.027502) (xy 122.355636 -33.948309) (xy 122.334694 -33.86707)
			(xy 122.320653 -33.784357) (xy 122.313611 -33.700758) (xy 122.313192 -33.65881) (xy 122.313247 -33.64267)
			(xy 122.314264 -33.610406) (xy 122.315224 -33.594294) (xy 122.317822 -33.559685) (xy 122.327231 -33.490916)
			(xy 122.33402 -33.45688) (xy 122.339048 -33.433201) (xy 122.351118 -33.386317) (xy 122.35815 -33.363154)
			(xy 122.356372 -33.35528) (xy 122.354086 -33.349692) (xy 122.344572 -33.328076) (xy 122.330351 -33.28304)
			(xy 122.321799 -33.236592) (xy 122.32005 -33.21304) (xy 122.32005 -33.208722) (xy 122.319542 -33.19018)
			(xy 122.319542 -33.18256) (xy 122.320536 -33.155664) (xy 122.329154 -33.102538) (xy 122.345154 -33.05115)
			(xy 122.368218 -33.002522) (xy 122.397889 -32.95762) (xy 122.433578 -32.917333) (xy 122.474576 -32.882464)
			(xy 122.520068 -32.853704) (xy 122.569151 -32.831625) (xy 122.62085 -32.816664) (xy 122.67414 -32.809119)
			(xy 122.70105 -32.808672) (xy 122.701304 -32.808672) (xy 122.715775 -32.808786) (xy 122.744635 -32.810949)
			(xy 122.758962 -32.81299) (xy 122.76778 -32.813979) (xy 122.785185 -32.810594) (xy 122.792998 -32.806386)
			(xy 122.832038 -32.783272) (xy 122.913542 -32.7434) (xy 122.998328 -32.711092) (xy 123.085698 -32.686614)
			(xy 123.174928 -32.670168) (xy 123.265283 -32.66189) (xy 123.31065 -32.661352) (xy 123.310904 -32.661352)
			(xy 123.356244 -32.661878) (xy 123.446548 -32.670131) (xy 123.535731 -32.686541) (xy 123.623058 -32.710973)
			(xy 123.707808 -32.743226) (xy 123.789284 -32.783033) (xy 123.828302 -32.806132) (xy 123.836027 -32.810399)
			(xy 123.853308 -32.813912) (xy 123.862084 -32.81299) (xy 123.87679 -32.81091) (xy 123.906414 -32.808747)
			(xy 123.921266 -32.808672) (xy 123.922028 -32.808672) (xy 123.951746 -32.80936) (xy 124.010434 -32.818797)
			(xy 124.038868 -32.827468) (xy 124.052584 -32.83204) (xy 124.064014 -32.831024) (xy 124.071895 -32.83001)
			(xy 124.086508 -32.823793) (xy 124.092716 -32.818832) (xy 124.112274 -32.804608) (xy 124.154946 -32.773366)
			(xy 124.157992 -32.770887) (xy 124.16335 -32.765145) (xy 124.165614 -32.761936) (xy 124.166122 -32.761428)
			(xy 124.168154 -32.75838) (xy 124.167646 -32.737552) (xy 124.167646 -32.737044) (xy 124.167392 -32.722566)
			(xy 124.167392 -32.720788) (xy 124.167646 -32.696912) (xy 124.16949 -32.647678) (xy 124.181693 -32.549908)
			(xy 124.203489 -32.45382) (xy 124.234665 -32.360354) (xy 124.25426 -32.31515) (xy 124.256038 -32.311086)
			(xy 124.26061 -32.29102) (xy 124.26061 -32.290004) (xy 124.256038 -32.269938) (xy 124.25426 -32.265874)
			(xy 124.234701 -32.220657) (xy 124.203551 -32.127187) (xy 124.181755 -32.031104) (xy 124.169525 -31.933342)
			(xy 124.167646 -31.884112) (xy 124.167392 -31.860236) (xy 124.167392 -31.858458) (xy 124.167646 -31.843218)
			(xy 124.167646 -31.840424) (xy 124.168154 -31.821628) (xy 124.16568 -31.817673) (xy 124.159541 -31.81065)
			(xy 124.155962 -31.807658) (xy 124.11075 -31.774638) (xy 124.110242 -31.774638) (xy 124.090938 -31.760668)
			(xy 124.085476 -31.757157) (xy 124.073258 -31.752775) (xy 124.066808 -31.752032) (xy 124.0663 -31.752032)
			(xy 124.062236 -31.751778) (xy 124.042678 -31.751778) (xy 124.035058 -31.754064) (xy 124.007449 -31.762246)
			(xy 123.950562 -31.771175) (xy 123.921774 -31.771844) (xy 123.914662 -31.771844) (xy 123.889008 -31.770574)
			(xy 123.851924 -31.765748) (xy 123.847352 -31.764986) (xy 123.84532 -31.764478) (xy 123.805324 -31.789227)
			(xy 123.721519 -31.831935) (xy 123.634061 -31.866555) (xy 123.543729 -31.892777) (xy 123.451328 -31.910369)
			(xy 123.357681 -31.919173) (xy 123.31065 -31.919672) (xy 123.26581 -31.919189) (xy 123.17649 -31.911153)
			(xy 123.088252 -31.895133) (xy 123.001808 -31.871259) (xy 122.917856 -31.839722) (xy 122.837073 -31.800777)
			(xy 122.798332 -31.778194) (xy 122.79249 -31.774638) (xy 122.766074 -31.767272) (xy 122.76074 -31.767272)
			(xy 122.753628 -31.768288) (xy 122.749564 -31.768796) (xy 122.74804 -31.768796) (xy 122.709432 -31.771844)
			(xy 122.70105 -31.771844) (xy 122.673794 -31.771385) (xy 122.619836 -31.763634) (xy 122.56753 -31.748282)
			(xy 122.517941 -31.725643) (xy 122.472079 -31.696177) (xy 122.430877 -31.660484) (xy 122.395175 -31.61929)
			(xy 122.365698 -31.573435) (xy 122.343048 -31.523851) (xy 122.327685 -31.471549) (xy 122.319922 -31.417592)
			(xy 122.319542 -31.390336) (xy 122.319542 -31.387542) (xy 122.320107 -31.363339) (xy 122.326615 -31.315365)
			(xy 122.33915 -31.268602) (xy 122.34799 -31.246064) (xy 122.348498 -31.24454) (xy 122.350276 -31.240222)
			(xy 122.35688 -31.22422) (xy 122.35815 -31.218632) (xy 122.353578 -31.202884) (xy 122.341082 -31.158531)
			(xy 122.323375 -31.068096) (xy 122.314096 -30.976412) (xy 122.313192 -30.930342) (xy 122.313192 -30.919166)
			(xy 122.313769 -30.877633) (xy 122.320975 -30.794876) (xy 122.335033 -30.713005) (xy 122.355847 -30.632585)
			(xy 122.383272 -30.554173) (xy 122.399806 -30.516068) (xy 122.402854 -30.506416) (xy 122.40641 -30.491176)
			(xy 122.40641 -30.49016) (xy 122.402854 -30.47492) (xy 122.399806 -30.465268) (xy 122.383127 -30.426865)
			(xy 122.355521 -30.347814) (xy 122.334644 -30.266726) (xy 122.320645 -30.184172) (xy 122.313622 -30.100734)
			(xy 122.313192 -30.058868) (xy 122.313192 -30.05836) (xy 122.313404 -30.02972) (xy 122.316708 -29.972534)
			(xy 122.319796 -29.94406) (xy 122.324515 -29.906605) (xy 122.338883 -29.832485) (xy 122.348498 -29.795978)
			(xy 122.358404 -29.76245) (xy 122.356626 -29.755084) (xy 122.344921 -29.729287) (xy 122.3284 -29.675101)
			(xy 122.32006 -29.61907) (xy 122.319542 -29.590746) (xy 122.319542 -29.590238) (xy 122.320003 -29.562985)
			(xy 122.327756 -29.509032) (xy 122.343109 -29.456733) (xy 122.36575 -29.407151) (xy 122.395218 -29.361297)
			(xy 122.430912 -29.320104) (xy 122.472106 -29.28441) (xy 122.517962 -29.254944) (xy 122.567544 -29.232305)
			(xy 122.619844 -29.216953) (xy 122.673797 -29.209202) (xy 122.70105 -29.20873) (xy 122.701812 -29.20873)
			(xy 122.719507 -29.208943) (xy 122.754743 -29.212254) (xy 122.77217 -29.215334) (xy 122.776234 -29.216096)
			(xy 122.776996 -29.21635) (xy 122.816937 -29.191701) (xy 122.90061 -29.149164) (xy 122.987908 -29.114675)
			(xy 123.07806 -29.088539) (xy 123.170268 -29.070987) (xy 123.263718 -29.062174) (xy 123.31065 -29.061664)
			(xy 123.357554 -29.062194) (xy 123.450948 -29.070984) (xy 123.543106 -29.088501) (xy 123.633212 -29.114589)
			(xy 123.720473 -29.14902) (xy 123.804116 -29.191488) (xy 123.84405 -29.216096) (xy 123.845066 -29.215842)
			(xy 123.848622 -29.215334) (xy 123.866301 -29.212222) (xy 123.902047 -29.208918) (xy 123.919996 -29.20873)
			(xy 123.921012 -29.20873) (xy 123.946404 -29.209148) (xy 123.996737 -29.215905) (xy 124.021342 -29.222192)
			(xy 124.02312 -29.2227) (xy 124.02439 -29.222954) (xy 124.0282 -29.22397) (xy 124.038614 -29.227526)
			(xy 124.040646 -29.228034) (xy 124.05106 -29.232098) (xy 124.066808 -29.230828) (xy 124.077222 -29.228034)
			(xy 124.083064 -29.225748) (xy 124.088906 -29.221684) (xy 124.099574 -29.214064) (xy 124.100336 -29.213556)
			(xy 124.137928 -29.18587) (xy 124.13869 -29.185362) (xy 124.154946 -29.173678) (xy 124.163328 -29.16555)
			(xy 124.166884 -29.161232) (xy 124.168154 -29.158692) (xy 124.167646 -29.13761) (xy 124.167646 -29.137356)
			(xy 124.167392 -29.122624) (xy 124.167392 -29.120846) (xy 124.167646 -29.09697) (xy 124.169492 -29.047737)
			(xy 124.181699 -28.949968) (xy 124.203499 -28.853882) (xy 124.234678 -28.760417) (xy 124.25426 -28.715208)
			(xy 124.256038 -28.711144) (xy 124.26061 -28.691078) (xy 124.26061 -28.690062) (xy 124.257054 -28.674822)
			(xy 124.254006 -28.66517) (xy 124.237327 -28.626767) (xy 124.209721 -28.547716) (xy 124.188844 -28.466628)
			(xy 124.174845 -28.384074) (xy 124.167822 -28.300636) (xy 124.167392 -28.25877) (xy 124.167392 -28.258262)
			(xy 124.167603 -28.229622) (xy 124.170908 -28.172436) (xy 124.173996 -28.143962) (xy 124.178708 -28.106568)
			(xy 124.193078 -28.032575) (xy 124.202698 -27.996134) (xy 124.202698 -27.995626) (xy 124.20981 -27.972004)
			(xy 124.20981 -27.971496) (xy 124.212604 -27.962352) (xy 124.210826 -27.954986) (xy 124.20854 -27.95016)
			(xy 124.198957 -27.928472) (xy 124.184623 -27.883272) (xy 124.175994 -27.836647) (xy 124.17425 -27.813)
			(xy 124.17425 -27.808682) (xy 124.173742 -27.79014) (xy 124.173742 -27.78252) (xy 124.174739 -27.755626)
			(xy 124.183361 -27.702504) (xy 124.199364 -27.651121) (xy 124.222431 -27.602498) (xy 124.252103 -27.5576)
			(xy 124.287792 -27.517319) (xy 124.328788 -27.482454) (xy 124.374279 -27.453697) (xy 124.423359 -27.431621)
			(xy 124.475055 -27.416662) (xy 124.528341 -27.409118) (xy 124.55525 -27.408632) (xy 124.571975 -27.408812)
			(xy 124.605297 -27.411739) (xy 124.621798 -27.414474) (xy 124.63145 -27.415998) (xy 124.678948 -27.387804)
			(xy 124.69622 -27.378152) (xy 124.70003 -27.368754) (xy 124.719842 -27.295348) (xy 124.719588 -27.281632)
			(xy 124.71781 -27.275028) (xy 124.713492 -27.259534) (xy 124.710444 -27.2542) (xy 124.69875 -27.232664)
			(xy 124.680333 -27.187249) (xy 124.667874 -27.139852) (xy 124.661577 -27.091251) (xy 124.661168 -27.066748)
			(xy 124.661168 -27.057604) (xy 124.661422 -27.05354) (xy 124.661422 -27.052778) (xy 124.663708 -27.022552)
			(xy 124.666812 -26.998918) (xy 124.678158 -26.952619) (xy 124.695201 -26.908102) (xy 124.706126 -26.886916)
			(xy 124.718957 -26.8638) (xy 124.750029 -26.821026) (xy 124.786711 -26.782953) (xy 124.807218 -26.766266)
			(xy 124.80925 -26.764742) (xy 124.816362 -26.757884) (xy 124.829316 -26.742136) (xy 124.831856 -26.736802)
			(xy 124.834396 -26.725118) (xy 124.830332 -26.647394) (xy 124.829824 -26.634948) (xy 124.811536 -26.603452)
			(xy 124.806964 -26.59888) (xy 124.795788 -26.58745) (xy 124.789438 -26.583132) (xy 124.767541 -26.567858)
			(xy 124.727834 -26.532169) (xy 124.693486 -26.491296) (xy 124.665168 -26.446036) (xy 124.643432 -26.397273)
			(xy 124.628701 -26.345956) (xy 124.621264 -26.293088) (xy 124.620782 -26.266394) (xy 124.621268 -26.239143)
			(xy 124.629024 -26.185195) (xy 124.644379 -26.1329) (xy 124.667021 -26.083323) (xy 124.696487 -26.037473)
			(xy 124.732178 -25.996282) (xy 124.773369 -25.960591) (xy 124.819219 -25.931125) (xy 124.868796 -25.908483)
			(xy 124.921091 -25.893128) (xy 124.975039 -25.885372) (xy 125.029541 -25.885372) (xy 125.083489 -25.893128)
			(xy 125.135784 -25.908483) (xy 125.185361 -25.931125) (xy 125.231211 -25.960591) (xy 125.272402 -25.996282)
			(xy 125.308093 -26.037473) (xy 125.337559 -26.083323) (xy 125.360201 -26.1329) (xy 125.375556 -26.185195)
			(xy 125.383312 -26.239143) (xy 125.383798 -26.266394) (xy 125.383246 -26.295552) (xy 125.374374 -26.353189)
			(xy 125.356836 -26.408805) (xy 125.33104 -26.461105) (xy 125.297587 -26.508871) (xy 125.257256 -26.550991)
			(xy 125.234446 -26.569162) (xy 125.231652 -26.571194) (xy 125.225048 -26.577798) (xy 125.220476 -26.58364)
			(xy 125.216402 -26.589981) (xy 125.211749 -26.604309) (xy 125.211332 -26.611834) (xy 125.215142 -26.69667)
			(xy 125.219968 -26.706068) (xy 125.220984 -26.708354) (xy 125.233684 -26.72969) (xy 125.238002 -26.734008)
			(xy 125.249178 -26.745438) (xy 125.255528 -26.749756) (xy 125.277385 -26.764969) (xy 125.317031 -26.800525)
			(xy 125.351343 -26.841253) (xy 125.379651 -26.886359) (xy 125.401405 -26.934967) (xy 125.416183 -26.98613)
			(xy 125.423695 -27.038852) (xy 125.424184 -27.065478) (xy 125.424184 -27.07005) (xy 125.423339 -27.100326)
			(xy 125.413255 -27.160045) (xy 125.404118 -27.188922) (xy 125.400816 -27.198828) (xy 125.401324 -27.20848)
			(xy 125.401774 -27.21357) (xy 125.404452 -27.223429) (xy 125.406658 -27.228038) (xy 125.419866 -27.2542)
			(xy 125.419866 -27.254708) (xy 125.436122 -27.286458) (xy 125.444504 -27.297126) (xy 125.45187 -27.303476)
			(xy 125.463808 -27.307286) (xy 125.503607 -27.320228) (xy 125.558934 -27.342846) (xy 132.62356 -27.342846)
			(xy 132.62356 -26.479246) (xy 132.62405 -26.449262) (xy 132.631878 -26.389806) (xy 132.647399 -26.331881)
			(xy 132.670348 -26.276477) (xy 132.700332 -26.224543) (xy 132.736838 -26.176967) (xy 132.779243 -26.134562)
			(xy 132.826819 -26.098056) (xy 132.878753 -26.068072) (xy 132.934157 -26.045123) (xy 132.992082 -26.029602)
			(xy 133.051538 -26.021774) (xy 133.111506 -26.021774) (xy 133.170962 -26.029602) (xy 133.228887 -26.045123)
			(xy 133.284291 -26.068072) (xy 133.336225 -26.098056) (xy 133.383801 -26.134562) (xy 133.426206 -26.176967)
			(xy 133.462712 -26.224543) (xy 133.492696 -26.276477) (xy 133.515645 -26.331881) (xy 133.523416 -26.360882)
			(xy 135.18972 -26.360882) (xy 135.193791 -26.30526) (xy 135.205917 -26.250823) (xy 135.22584 -26.198732)
			(xy 135.253136 -26.150097) (xy 135.287222 -26.105954) (xy 135.327371 -26.067245) (xy 135.372729 -26.034794)
			(xy 135.422329 -26.009293) (xy 135.475113 -25.991286) (xy 135.529956 -25.981156) (xy 135.58569 -25.979119)
			(xy 135.641127 -25.985219) (xy 135.695084 -25.999325) (xy 135.746413 -26.021137) (xy 135.794019 -26.050191)
			(xy 135.836887 -26.085866) (xy 135.874104 -26.127403) (xy 135.904877 -26.173916) (xy 135.928549 -26.224413)
			(xy 135.944617 -26.27782) (xy 135.950785 -26.319734) (xy 140.942058 -26.319734) (xy 140.946129 -26.264112)
			(xy 140.958255 -26.209675) (xy 140.978178 -26.157584) (xy 141.005474 -26.108949) (xy 141.03956 -26.064806)
			(xy 141.079709 -26.026097) (xy 141.125067 -25.993646) (xy 141.174667 -25.968145) (xy 141.227451 -25.950138)
			(xy 141.282294 -25.940008) (xy 141.338028 -25.937971) (xy 141.393465 -25.944071) (xy 141.447422 -25.958177)
			(xy 141.498751 -25.979989) (xy 141.546357 -26.009043) (xy 141.576022 -26.03373) (xy 147.368004 -26.03373)
			(xy 147.372075 -25.978108) (xy 147.384201 -25.923671) (xy 147.404124 -25.87158) (xy 147.43142 -25.822945)
			(xy 147.465506 -25.778802) (xy 147.505655 -25.740093) (xy 147.551013 -25.707642) (xy 147.600613 -25.682141)
			(xy 147.653397 -25.664134) (xy 147.70824 -25.654004) (xy 147.763974 -25.651967) (xy 147.819411 -25.658067)
			(xy 147.873368 -25.672173) (xy 147.924697 -25.693985) (xy 147.972303 -25.723039) (xy 148.015171 -25.758714)
			(xy 148.052388 -25.800251) (xy 148.083161 -25.846764) (xy 148.106833 -25.897261) (xy 148.122901 -25.950668)
			(xy 148.131021 -26.005844) (xy 148.13153 -26.03373) (xy 148.131021 -26.061616) (xy 148.122901 -26.116792)
			(xy 148.106833 -26.170199) (xy 148.083161 -26.220696) (xy 148.052388 -26.267209) (xy 148.015171 -26.308746)
			(xy 147.972303 -26.344421) (xy 147.924697 -26.373475) (xy 147.873368 -26.395287) (xy 147.819411 -26.409393)
			(xy 147.763974 -26.415493) (xy 147.70824 -26.413456) (xy 147.653397 -26.403326) (xy 147.600613 -26.385319)
			(xy 147.551013 -26.359818) (xy 147.505655 -26.327367) (xy 147.465506 -26.288658) (xy 147.43142 -26.244515)
			(xy 147.404124 -26.19588) (xy 147.384201 -26.143789) (xy 147.372075 -26.089352) (xy 147.368004 -26.03373)
			(xy 141.576022 -26.03373) (xy 141.589225 -26.044718) (xy 141.626442 -26.086255) (xy 141.657215 -26.132768)
			(xy 141.680887 -26.183265) (xy 141.696955 -26.236672) (xy 141.705075 -26.291848) (xy 141.705584 -26.319734)
			(xy 141.705075 -26.34762) (xy 141.696955 -26.402796) (xy 141.680887 -26.456203) (xy 141.657215 -26.5067)
			(xy 141.626442 -26.553213) (xy 141.589225 -26.59475) (xy 141.546357 -26.630425) (xy 141.498751 -26.659479)
			(xy 141.447422 -26.681291) (xy 141.393465 -26.695397) (xy 141.338028 -26.701497) (xy 141.282294 -26.69946)
			(xy 141.227451 -26.68933) (xy 141.174667 -26.671323) (xy 141.125067 -26.645822) (xy 141.079709 -26.613371)
			(xy 141.03956 -26.574662) (xy 141.005474 -26.530519) (xy 140.978178 -26.481884) (xy 140.958255 -26.429793)
			(xy 140.946129 -26.375356) (xy 140.942058 -26.319734) (xy 135.950785 -26.319734) (xy 135.952737 -26.332996)
			(xy 135.953246 -26.360882) (xy 135.952737 -26.388768) (xy 135.944617 -26.443944) (xy 135.928549 -26.497351)
			(xy 135.904877 -26.547848) (xy 135.874104 -26.594361) (xy 135.836887 -26.635898) (xy 135.794019 -26.671573)
			(xy 135.746413 -26.700627) (xy 135.695084 -26.722439) (xy 135.641127 -26.736545) (xy 135.58569 -26.742645)
			(xy 135.529956 -26.740608) (xy 135.475113 -26.730478) (xy 135.422329 -26.712471) (xy 135.372729 -26.68697)
			(xy 135.327371 -26.654519) (xy 135.287222 -26.61581) (xy 135.253136 -26.571667) (xy 135.22584 -26.523032)
			(xy 135.205917 -26.470941) (xy 135.193791 -26.416504) (xy 135.18972 -26.360882) (xy 133.523416 -26.360882)
			(xy 133.531166 -26.389806) (xy 133.538994 -26.449262) (xy 133.539484 -26.479246) (xy 133.539484 -26.971244)
			(xy 136.95121 -26.971244) (xy 136.955281 -26.915622) (xy 136.967407 -26.861185) (xy 136.98733 -26.809094)
			(xy 137.014626 -26.760459) (xy 137.048712 -26.716316) (xy 137.088861 -26.677607) (xy 137.134219 -26.645156)
			(xy 137.183819 -26.619655) (xy 137.236603 -26.601648) (xy 137.291446 -26.591518) (xy 137.34718 -26.589481)
			(xy 137.402617 -26.595581) (xy 137.456574 -26.609687) (xy 137.507903 -26.631499) (xy 137.555509 -26.660553)
			(xy 137.598377 -26.696228) (xy 137.635594 -26.737765) (xy 137.666367 -26.784278) (xy 137.690039 -26.834775)
			(xy 137.706107 -26.888182) (xy 137.714227 -26.943358) (xy 137.714736 -26.971244) (xy 137.714227 -26.99913)
			(xy 137.706107 -27.054306) (xy 137.690039 -27.107713) (xy 137.666367 -27.15821) (xy 137.635594 -27.204723)
			(xy 137.598377 -27.24626) (xy 137.555509 -27.281935) (xy 137.507903 -27.310989) (xy 137.456574 -27.332801)
			(xy 137.402617 -27.346907) (xy 137.34718 -27.353007) (xy 137.291446 -27.35097) (xy 137.236603 -27.34084)
			(xy 137.183819 -27.322833) (xy 137.134219 -27.297332) (xy 137.088861 -27.264881) (xy 137.048712 -27.226172)
			(xy 137.014626 -27.182029) (xy 136.98733 -27.133394) (xy 136.967407 -27.081303) (xy 136.955281 -27.026866)
			(xy 136.95121 -26.971244) (xy 133.539484 -26.971244) (xy 133.539484 -27.342846) (xy 133.538994 -27.37283)
			(xy 133.531166 -27.432286) (xy 133.515645 -27.490211) (xy 133.492696 -27.545615) (xy 133.462712 -27.597549)
			(xy 133.426206 -27.645125) (xy 133.383801 -27.68753) (xy 133.336225 -27.724036) (xy 133.284291 -27.75402)
			(xy 133.228887 -27.776969) (xy 133.170962 -27.79249) (xy 133.111506 -27.800318) (xy 133.051538 -27.800318)
			(xy 132.992082 -27.79249) (xy 132.934157 -27.776969) (xy 132.878753 -27.75402) (xy 132.826819 -27.724036)
			(xy 132.779243 -27.68753) (xy 132.736838 -27.645125) (xy 132.700332 -27.597549) (xy 132.670348 -27.545615)
			(xy 132.647399 -27.490211) (xy 132.631878 -27.432286) (xy 132.62405 -27.37283) (xy 132.62356 -27.342846)
			(xy 125.558934 -27.342846) (xy 125.581079 -27.351899) (xy 125.655623 -27.389954) (xy 125.691392 -27.41168)
			(xy 125.700028 -27.41168) (xy 125.712228 -27.410168) (xy 125.736758 -27.408515) (xy 125.74905 -27.408378)
			(xy 125.768354 -27.408886) (xy 125.778006 -27.409648) (xy 125.805013 -27.412184) (xy 125.85797 -27.423923)
			(xy 125.908731 -27.443041) (xy 125.956274 -27.469154) (xy 125.999642 -27.501735) (xy 126.037959 -27.540128)
			(xy 126.054612 -27.56154) (xy 126.056644 -27.56408) (xy 126.101039 -27.571476) (xy 126.188377 -27.59324)
			(xy 126.273399 -27.622784) (xy 126.355414 -27.659866) (xy 126.433756 -27.704186) (xy 126.507786 -27.755384)
			(xy 126.576902 -27.813042) (xy 126.609094 -27.844496) (xy 127.520192 -28.755594) (xy 127.554451 -28.790557)
			(xy 127.61667 -28.866131) (xy 127.644398 -28.90647) (xy 127.67437 -28.951428) (xy 127.680212 -28.95854)
			(xy 127.835914 -29.114242) (xy 134.94766 -29.114242) (xy 134.94766 -28.250642) (xy 134.94815 -28.220674)
			(xy 134.955973 -28.161252) (xy 134.971486 -28.103359) (xy 134.994422 -28.047986) (xy 135.024389 -27.99608)
			(xy 135.060876 -27.94853) (xy 135.103256 -27.90615) (xy 135.150806 -27.869663) (xy 135.202712 -27.839696)
			(xy 135.258085 -27.81676) (xy 135.315978 -27.801247) (xy 135.3754 -27.793424) (xy 135.435336 -27.793424)
			(xy 135.494758 -27.801247) (xy 135.552651 -27.81676) (xy 135.608024 -27.839696) (xy 135.65993 -27.869663)
			(xy 135.70748 -27.90615) (xy 135.74986 -27.94853) (xy 135.786347 -27.99608) (xy 135.816314 -28.047986)
			(xy 135.83925 -28.103359) (xy 135.854763 -28.161252) (xy 135.862586 -28.220674) (xy 135.863076 -28.250642)
			(xy 135.863076 -28.469082) (xy 139.852652 -28.469082) (xy 139.856723 -28.41346) (xy 139.868849 -28.359023)
			(xy 139.888772 -28.306932) (xy 139.916068 -28.258297) (xy 139.950154 -28.214154) (xy 139.990303 -28.175445)
			(xy 140.035661 -28.142994) (xy 140.085261 -28.117493) (xy 140.138045 -28.099486) (xy 140.192888 -28.089356)
			(xy 140.248622 -28.087319) (xy 140.304059 -28.093419) (xy 140.358016 -28.107525) (xy 140.409345 -28.129337)
			(xy 140.425401 -28.139136) (xy 144.498058 -28.139136) (xy 144.502129 -28.083514) (xy 144.514255 -28.029077)
			(xy 144.534178 -27.976986) (xy 144.561474 -27.928351) (xy 144.59556 -27.884208) (xy 144.635709 -27.845499)
			(xy 144.681067 -27.813048) (xy 144.730667 -27.787547) (xy 144.783451 -27.76954) (xy 144.838294 -27.75941)
			(xy 144.894028 -27.757373) (xy 144.949465 -27.763473) (xy 145.003422 -27.777579) (xy 145.054751 -27.799391)
			(xy 145.102357 -27.828445) (xy 145.145225 -27.86412) (xy 145.182442 -27.905657) (xy 145.213215 -27.95217)
			(xy 145.236887 -28.002667) (xy 145.252955 -28.056074) (xy 145.261075 -28.11125) (xy 145.261584 -28.139136)
			(xy 145.768058 -28.139136) (xy 145.772129 -28.083514) (xy 145.784255 -28.029077) (xy 145.804178 -27.976986)
			(xy 145.831474 -27.928351) (xy 145.86556 -27.884208) (xy 145.905709 -27.845499) (xy 145.951067 -27.813048)
			(xy 146.000667 -27.787547) (xy 146.053451 -27.76954) (xy 146.108294 -27.75941) (xy 146.164028 -27.757373)
			(xy 146.219465 -27.763473) (xy 146.273422 -27.777579) (xy 146.324751 -27.799391) (xy 146.372357 -27.828445)
			(xy 146.415225 -27.86412) (xy 146.452442 -27.905657) (xy 146.483215 -27.95217) (xy 146.506887 -28.002667)
			(xy 146.522955 -28.056074) (xy 146.531075 -28.11125) (xy 146.531584 -28.139136) (xy 146.531075 -28.167022)
			(xy 146.522955 -28.222198) (xy 146.506887 -28.275605) (xy 146.483215 -28.326102) (xy 146.452442 -28.372615)
			(xy 146.415225 -28.414152) (xy 146.372357 -28.449827) (xy 146.324751 -28.478881) (xy 146.273422 -28.500693)
			(xy 146.219465 -28.514799) (xy 146.164028 -28.520899) (xy 146.108294 -28.518862) (xy 146.053451 -28.508732)
			(xy 146.000667 -28.490725) (xy 145.951067 -28.465224) (xy 145.905709 -28.432773) (xy 145.86556 -28.394064)
			(xy 145.831474 -28.349921) (xy 145.804178 -28.301286) (xy 145.784255 -28.249195) (xy 145.772129 -28.194758)
			(xy 145.768058 -28.139136) (xy 145.261584 -28.139136) (xy 145.261075 -28.167022) (xy 145.252955 -28.222198)
			(xy 145.236887 -28.275605) (xy 145.213215 -28.326102) (xy 145.182442 -28.372615) (xy 145.145225 -28.414152)
			(xy 145.102357 -28.449827) (xy 145.054751 -28.478881) (xy 145.003422 -28.500693) (xy 144.949465 -28.514799)
			(xy 144.894028 -28.520899) (xy 144.838294 -28.518862) (xy 144.783451 -28.508732) (xy 144.730667 -28.490725)
			(xy 144.681067 -28.465224) (xy 144.635709 -28.432773) (xy 144.59556 -28.394064) (xy 144.561474 -28.349921)
			(xy 144.534178 -28.301286) (xy 144.514255 -28.249195) (xy 144.502129 -28.194758) (xy 144.498058 -28.139136)
			(xy 140.425401 -28.139136) (xy 140.456951 -28.158391) (xy 140.499819 -28.194066) (xy 140.537036 -28.235603)
			(xy 140.567809 -28.282116) (xy 140.591481 -28.332613) (xy 140.607549 -28.38602) (xy 140.615669 -28.441196)
			(xy 140.616178 -28.469082) (xy 140.615669 -28.496968) (xy 140.607549 -28.552144) (xy 140.591481 -28.605551)
			(xy 140.567809 -28.656048) (xy 140.537036 -28.702561) (xy 140.499819 -28.744098) (xy 140.456951 -28.779773)
			(xy 140.409345 -28.808827) (xy 140.358016 -28.830639) (xy 140.304059 -28.844745) (xy 140.248622 -28.850845)
			(xy 140.192888 -28.848808) (xy 140.138045 -28.838678) (xy 140.085261 -28.820671) (xy 140.035661 -28.79517)
			(xy 139.990303 -28.762719) (xy 139.950154 -28.72401) (xy 139.916068 -28.679867) (xy 139.888772 -28.631232)
			(xy 139.868849 -28.579141) (xy 139.856723 -28.524704) (xy 139.852652 -28.469082) (xy 135.863076 -28.469082)
			(xy 135.863076 -29.114242) (xy 135.862586 -29.14421) (xy 135.854763 -29.203632) (xy 135.83925 -29.261525)
			(xy 135.816314 -29.316898) (xy 135.786347 -29.368804) (xy 135.74986 -29.416354) (xy 135.70748 -29.458734)
			(xy 135.65993 -29.495221) (xy 135.608024 -29.525188) (xy 135.552651 -29.548124) (xy 135.494758 -29.563637)
			(xy 135.435336 -29.57146) (xy 135.3754 -29.57146) (xy 135.315978 -29.563637) (xy 135.258085 -29.548124)
			(xy 135.202712 -29.525188) (xy 135.150806 -29.495221) (xy 135.103256 -29.458734) (xy 135.060876 -29.416354)
			(xy 135.024389 -29.368804) (xy 134.994422 -29.316898) (xy 134.971486 -29.261525) (xy 134.955973 -29.203632)
			(xy 134.94815 -29.14421) (xy 134.94766 -29.114242) (xy 127.835914 -29.114242) (xy 127.93345 -29.211778)
			(xy 127.936859 -29.215065) (xy 127.944655 -29.220438) (xy 127.948944 -29.222446) (xy 127.95377 -29.224224)
			(xy 127.955802 -29.224732) (xy 127.971804 -29.230066) (xy 127.972058 -29.230066) (xy 127.974852 -29.231082)
			(xy 127.996442 -29.239718) (xy 127.999744 -29.241242) (xy 128.00965 -29.24556) (xy 128.016 -29.248862)
			(xy 128.016508 -29.249116) (xy 128.032002 -29.257244) (xy 128.037844 -29.260546) (xy 128.038098 -29.260546)
			(xy 128.042416 -29.263086) (xy 128.044448 -29.264356) (xy 128.067115 -29.278776) (xy 128.108537 -29.312987)
			(xy 128.144743 -29.352675) (xy 128.175019 -29.397055) (xy 128.198762 -29.445245) (xy 128.215503 -29.496293)
			(xy 128.22491 -29.549185) (xy 128.226312 -29.576014) (xy 128.227074 -29.590238) (xy 128.505204 -30.007052)
			(xy 128.628394 -30.19171) (xy 128.631442 -30.196282) (xy 128.732534 -30.297374) (xy 129.355694 -30.92069)
			(xy 137.589768 -30.92069) (xy 137.589768 -30.05709) (xy 137.590258 -30.027122) (xy 137.598081 -29.9677)
			(xy 137.613594 -29.909807) (xy 137.63653 -29.854434) (xy 137.666497 -29.802528) (xy 137.702984 -29.754978)
			(xy 137.745364 -29.712598) (xy 137.792914 -29.676111) (xy 137.84482 -29.646144) (xy 137.900193 -29.623208)
			(xy 137.958086 -29.607695) (xy 138.017508 -29.599872) (xy 138.077444 -29.599872) (xy 138.136866 -29.607695)
			(xy 138.194759 -29.623208) (xy 138.250132 -29.646144) (xy 138.302038 -29.676111) (xy 138.349588 -29.712598)
			(xy 138.391968 -29.754978) (xy 138.428455 -29.802528) (xy 138.458422 -29.854434) (xy 138.481358 -29.909807)
			(xy 138.496871 -29.9677) (xy 138.504694 -30.027122) (xy 138.505184 -30.05709) (xy 138.505184 -30.376876)
			(xy 142.989046 -30.376876) (xy 142.989602 -30.34796) (xy 142.998321 -30.29079) (xy 143.01557 -30.235591)
			(xy 143.040955 -30.183629) (xy 143.073892 -30.136094) (xy 143.113629 -30.094077) (xy 143.136112 -30.075886)
			(xy 143.144917 -30.068277) (xy 143.155101 -30.047378) (xy 143.15567 -30.035754) (xy 143.15567 -29.955998)
			(xy 143.155128 -29.944366) (xy 143.144942 -29.923456) (xy 143.136112 -29.915866) (xy 143.113615 -29.897691)
			(xy 143.07388 -29.855668) (xy 143.040942 -29.80813) (xy 143.015556 -29.756166) (xy 142.998303 -29.700965)
			(xy 142.989578 -29.643793) (xy 142.989046 -29.614876) (xy 142.989532 -29.587625) (xy 142.997288 -29.533677)
			(xy 143.012643 -29.481382) (xy 143.035285 -29.431805) (xy 143.064751 -29.385955) (xy 143.100442 -29.344764)
			(xy 143.141633 -29.309073) (xy 143.187483 -29.279607) (xy 143.23706 -29.256965) (xy 143.289355 -29.24161)
			(xy 143.343303 -29.233854) (xy 143.397805 -29.233854) (xy 143.451753 -29.24161) (xy 143.504048 -29.256965)
			(xy 143.553625 -29.279607) (xy 143.599475 -29.309073) (xy 143.640666 -29.344764) (xy 143.676357 -29.385955)
			(xy 143.705823 -29.431805) (xy 143.728465 -29.481382) (xy 143.74382 -29.533677) (xy 143.751576 -29.587625)
			(xy 143.752062 -29.614876) (xy 143.751541 -29.643793) (xy 143.742814 -29.700965) (xy 143.725558 -29.756164)
			(xy 143.700167 -29.808126) (xy 143.667223 -29.85566) (xy 143.627482 -29.897676) (xy 143.604996 -29.915866)
			(xy 143.596214 -29.923497) (xy 143.586017 -29.94438) (xy 143.585438 -29.955998) (xy 143.585438 -30.035754)
			(xy 143.585947 -30.04739) (xy 143.596156 -30.0683) (xy 143.604996 -30.075886) (xy 143.627472 -30.094086)
			(xy 143.667208 -30.136104) (xy 143.700148 -30.183637) (xy 143.725538 -30.235596) (xy 143.742795 -30.290792)
			(xy 143.751526 -30.347961) (xy 143.752062 -30.376876) (xy 146.029172 -30.376876) (xy 146.029718 -30.34796)
			(xy 146.038437 -30.290789) (xy 146.055688 -30.235589) (xy 146.081074 -30.183627) (xy 146.114015 -30.136092)
			(xy 146.153753 -30.094076) (xy 146.176238 -30.075886) (xy 146.185048 -30.068282) (xy 146.195228 -30.047379)
			(xy 146.195796 -30.035754) (xy 146.195796 -29.955998) (xy 146.195245 -29.944368) (xy 146.185065 -29.923458)
			(xy 146.176238 -29.915866) (xy 146.153746 -29.897685) (xy 146.11401 -29.855664) (xy 146.081071 -29.808127)
			(xy 146.055683 -29.756164) (xy 146.03843 -29.700964) (xy 146.029704 -29.643793) (xy 146.029172 -29.614876)
			(xy 146.029658 -29.587625) (xy 146.037414 -29.533677) (xy 146.052769 -29.481382) (xy 146.075411 -29.431805)
			(xy 146.104877 -29.385955) (xy 146.140568 -29.344764) (xy 146.181759 -29.309073) (xy 146.227609 -29.279607)
			(xy 146.277186 -29.256965) (xy 146.329481 -29.24161) (xy 146.383429 -29.233854) (xy 146.437931 -29.233854)
			(xy 146.491879 -29.24161) (xy 146.544174 -29.256965) (xy 146.593751 -29.279607) (xy 146.639601 -29.309073)
			(xy 146.680792 -29.344764) (xy 146.716483 -29.385955) (xy 146.745949 -29.431805) (xy 146.768591 -29.481382)
			(xy 146.783946 -29.533677) (xy 146.791702 -29.587625) (xy 146.792188 -29.614876) (xy 146.791657 -29.643792)
			(xy 146.782931 -29.700963) (xy 146.765676 -29.756162) (xy 146.740287 -29.808124) (xy 146.707345 -29.855658)
			(xy 146.667606 -29.897676) (xy 146.645122 -29.915866) (xy 146.636327 -29.923484) (xy 146.62614 -29.944377)
			(xy 146.625564 -29.955998) (xy 146.625564 -30.035754) (xy 146.626064 -30.047391) (xy 146.636278 -30.068302)
			(xy 146.645122 -30.075886) (xy 146.667603 -30.094079) (xy 146.707338 -30.136099) (xy 146.740276 -30.183634)
			(xy 146.765665 -30.235595) (xy 146.782922 -30.290791) (xy 146.791652 -30.34796) (xy 146.792188 -30.376876)
			(xy 146.791702 -30.404127) (xy 146.783946 -30.458075) (xy 146.768591 -30.51037) (xy 146.745949 -30.559947)
			(xy 146.716483 -30.605797) (xy 146.680792 -30.646988) (xy 146.639601 -30.682679) (xy 146.593751 -30.712145)
			(xy 146.544174 -30.734787) (xy 146.491879 -30.750142) (xy 146.437931 -30.757898) (xy 146.383429 -30.757898)
			(xy 146.329481 -30.750142) (xy 146.277186 -30.734787) (xy 146.227609 -30.712145) (xy 146.181759 -30.682679)
			(xy 146.140568 -30.646988) (xy 146.104877 -30.605797) (xy 146.075411 -30.559947) (xy 146.052769 -30.51037)
			(xy 146.037414 -30.458075) (xy 146.029658 -30.404127) (xy 146.029172 -30.376876) (xy 143.752062 -30.376876)
			(xy 143.751576 -30.404127) (xy 143.74382 -30.458075) (xy 143.728465 -30.51037) (xy 143.705823 -30.559947)
			(xy 143.676357 -30.605797) (xy 143.640666 -30.646988) (xy 143.599475 -30.682679) (xy 143.553625 -30.712145)
			(xy 143.504048 -30.734787) (xy 143.451753 -30.750142) (xy 143.397805 -30.757898) (xy 143.343303 -30.757898)
			(xy 143.289355 -30.750142) (xy 143.23706 -30.734787) (xy 143.187483 -30.712145) (xy 143.141633 -30.682679)
			(xy 143.100442 -30.646988) (xy 143.064751 -30.605797) (xy 143.035285 -30.559947) (xy 143.012643 -30.51037)
			(xy 142.997288 -30.458075) (xy 142.989532 -30.404127) (xy 142.989046 -30.376876) (xy 138.505184 -30.376876)
			(xy 138.505184 -30.92069) (xy 138.504694 -30.950658) (xy 138.496871 -31.01008) (xy 138.481358 -31.067973)
			(xy 138.458422 -31.123346) (xy 138.428455 -31.175252) (xy 138.391968 -31.222802) (xy 138.349588 -31.265182)
			(xy 138.302038 -31.301669) (xy 138.250132 -31.331636) (xy 138.194759 -31.354572) (xy 138.136866 -31.370085)
			(xy 138.077444 -31.377908) (xy 138.017508 -31.377908) (xy 137.958086 -31.370085) (xy 137.900193 -31.354572)
			(xy 137.84482 -31.331636) (xy 137.792914 -31.301669) (xy 137.745364 -31.265182) (xy 137.702984 -31.222802)
			(xy 137.666497 -31.175252) (xy 137.63653 -31.123346) (xy 137.613594 -31.067973) (xy 137.598081 -31.01008)
			(xy 137.590258 -30.950658) (xy 137.589768 -30.92069) (xy 129.355694 -30.92069) (xy 129.748026 -31.31312)
			(xy 129.781719 -31.347612) (xy 129.843002 -31.422062) (xy 129.896813 -31.502079) (xy 129.942651 -31.586917)
			(xy 129.961894 -31.631128) (xy 130.26644 -32.353504) (xy 130.343402 -32.536384) (xy 130.418336 -32.714184)
			(xy 134.94766 -32.714184) (xy 134.94766 -31.850584) (xy 134.94815 -31.820616) (xy 134.955973 -31.761194)
			(xy 134.971486 -31.703301) (xy 134.994422 -31.647928) (xy 135.024389 -31.596022) (xy 135.060876 -31.548472)
			(xy 135.103256 -31.506092) (xy 135.150806 -31.469605) (xy 135.202712 -31.439638) (xy 135.258085 -31.416702)
			(xy 135.315978 -31.401189) (xy 135.3754 -31.393366) (xy 135.435336 -31.393366) (xy 135.494758 -31.401189)
			(xy 135.552651 -31.416702) (xy 135.608024 -31.439638) (xy 135.65993 -31.469605) (xy 135.70748 -31.506092)
			(xy 135.74986 -31.548472) (xy 135.764754 -31.567882) (xy 143.098772 -31.567882) (xy 143.102843 -31.51226)
			(xy 143.114969 -31.457823) (xy 143.134892 -31.405732) (xy 143.162188 -31.357097) (xy 143.196274 -31.312954)
			(xy 143.236423 -31.274245) (xy 143.281781 -31.241794) (xy 143.331381 -31.216293) (xy 143.384165 -31.198286)
			(xy 143.439008 -31.188156) (xy 143.494742 -31.186119) (xy 143.550179 -31.192219) (xy 143.604136 -31.206325)
			(xy 143.655465 -31.228137) (xy 143.703071 -31.257191) (xy 143.745939 -31.292866) (xy 143.783156 -31.334403)
			(xy 143.813929 -31.380916) (xy 143.837601 -31.431413) (xy 143.853669 -31.48482) (xy 143.861789 -31.539996)
			(xy 143.862298 -31.567882) (xy 143.861789 -31.595768) (xy 143.853669 -31.650944) (xy 143.837601 -31.704351)
			(xy 143.830609 -31.719266) (xy 144.385536 -31.719266) (xy 144.389607 -31.663644) (xy 144.401733 -31.609207)
			(xy 144.421656 -31.557116) (xy 144.448952 -31.508481) (xy 144.483038 -31.464338) (xy 144.523187 -31.425629)
			(xy 144.568545 -31.393178) (xy 144.618145 -31.367677) (xy 144.670929 -31.34967) (xy 144.725772 -31.33954)
			(xy 144.781506 -31.337503) (xy 144.836943 -31.343603) (xy 144.8909 -31.357709) (xy 144.942229 -31.379521)
			(xy 144.989835 -31.408575) (xy 145.032703 -31.44425) (xy 145.06992 -31.485787) (xy 145.100693 -31.5323)
			(xy 145.124365 -31.582797) (xy 145.140433 -31.636204) (xy 145.144583 -31.664402) (xy 145.661124 -31.664402)
			(xy 145.665195 -31.60878) (xy 145.677321 -31.554343) (xy 145.697244 -31.502252) (xy 145.72454 -31.453617)
			(xy 145.758626 -31.409474) (xy 145.798775 -31.370765) (xy 145.844133 -31.338314) (xy 145.893733 -31.312813)
			(xy 145.946517 -31.294806) (xy 146.00136 -31.284676) (xy 146.057094 -31.282639) (xy 146.112531 -31.288739)
			(xy 146.166488 -31.302845) (xy 146.217817 -31.324657) (xy 146.265423 -31.353711) (xy 146.308291 -31.389386)
			(xy 146.345508 -31.430923) (xy 146.376281 -31.477436) (xy 146.399953 -31.527933) (xy 146.416021 -31.58134)
			(xy 146.424141 -31.636516) (xy 146.42465 -31.664402) (xy 146.424141 -31.692288) (xy 146.416021 -31.747464)
			(xy 146.407081 -31.777178) (xy 146.926298 -31.777178) (xy 146.930369 -31.721556) (xy 146.942495 -31.667119)
			(xy 146.962418 -31.615028) (xy 146.989714 -31.566393) (xy 147.0238 -31.52225) (xy 147.063949 -31.483541)
			(xy 147.109307 -31.45109) (xy 147.158907 -31.425589) (xy 147.211691 -31.407582) (xy 147.266534 -31.397452)
			(xy 147.322268 -31.395415) (xy 147.377705 -31.401515) (xy 147.431662 -31.415621) (xy 147.482991 -31.437433)
			(xy 147.530597 -31.466487) (xy 147.573465 -31.502162) (xy 147.610682 -31.543699) (xy 147.641455 -31.590212)
			(xy 147.665127 -31.640709) (xy 147.681195 -31.694116) (xy 147.689315 -31.749292) (xy 147.689824 -31.777178)
			(xy 147.689315 -31.805064) (xy 147.681195 -31.86024) (xy 147.665127 -31.913647) (xy 147.641455 -31.964144)
			(xy 147.610682 -32.010657) (xy 147.573465 -32.052194) (xy 147.530597 -32.087869) (xy 147.482991 -32.116923)
			(xy 147.431662 -32.138735) (xy 147.377705 -32.152841) (xy 147.322268 -32.158941) (xy 147.266534 -32.156904)
			(xy 147.211691 -32.146774) (xy 147.158907 -32.128767) (xy 147.109307 -32.103266) (xy 147.063949 -32.070815)
			(xy 147.0238 -32.032106) (xy 146.989714 -31.987963) (xy 146.962418 -31.939328) (xy 146.942495 -31.887237)
			(xy 146.930369 -31.8328) (xy 146.926298 -31.777178) (xy 146.407081 -31.777178) (xy 146.399953 -31.800871)
			(xy 146.376281 -31.851368) (xy 146.345508 -31.897881) (xy 146.308291 -31.939418) (xy 146.265423 -31.975093)
			(xy 146.217817 -32.004147) (xy 146.166488 -32.025959) (xy 146.112531 -32.040065) (xy 146.057094 -32.046165)
			(xy 146.00136 -32.044128) (xy 145.946517 -32.033998) (xy 145.893733 -32.015991) (xy 145.844133 -31.99049)
			(xy 145.798775 -31.958039) (xy 145.758626 -31.91933) (xy 145.72454 -31.875187) (xy 145.697244 -31.826552)
			(xy 145.677321 -31.774461) (xy 145.665195 -31.720024) (xy 145.661124 -31.664402) (xy 145.144583 -31.664402)
			(xy 145.148553 -31.69138) (xy 145.149062 -31.719266) (xy 145.148553 -31.747152) (xy 145.140433 -31.802328)
			(xy 145.124365 -31.855735) (xy 145.100693 -31.906232) (xy 145.06992 -31.952745) (xy 145.032703 -31.994282)
			(xy 144.989835 -32.029957) (xy 144.942229 -32.059011) (xy 144.8909 -32.080823) (xy 144.836943 -32.094929)
			(xy 144.781506 -32.101029) (xy 144.725772 -32.098992) (xy 144.670929 -32.088862) (xy 144.618145 -32.070855)
			(xy 144.568545 -32.045354) (xy 144.523187 -32.012903) (xy 144.483038 -31.974194) (xy 144.448952 -31.930051)
			(xy 144.421656 -31.881416) (xy 144.401733 -31.829325) (xy 144.389607 -31.774888) (xy 144.385536 -31.719266)
			(xy 143.830609 -31.719266) (xy 143.813929 -31.754848) (xy 143.783156 -31.801361) (xy 143.745939 -31.842898)
			(xy 143.703071 -31.878573) (xy 143.655465 -31.907627) (xy 143.604136 -31.929439) (xy 143.550179 -31.943545)
			(xy 143.494742 -31.949645) (xy 143.439008 -31.947608) (xy 143.384165 -31.937478) (xy 143.331381 -31.919471)
			(xy 143.281781 -31.89397) (xy 143.236423 -31.861519) (xy 143.196274 -31.82281) (xy 143.162188 -31.778667)
			(xy 143.134892 -31.730032) (xy 143.114969 -31.677941) (xy 143.102843 -31.623504) (xy 143.098772 -31.567882)
			(xy 135.764754 -31.567882) (xy 135.786347 -31.596022) (xy 135.816314 -31.647928) (xy 135.83925 -31.703301)
			(xy 135.854763 -31.761194) (xy 135.862586 -31.820616) (xy 135.863076 -31.850584) (xy 135.863076 -32.714184)
			(xy 135.862586 -32.744152) (xy 135.854763 -32.803574) (xy 135.83925 -32.861467) (xy 135.816314 -32.91684)
			(xy 135.786347 -32.968746) (xy 135.74986 -33.016296) (xy 135.70748 -33.058676) (xy 135.65993 -33.095163)
			(xy 135.608024 -33.12513) (xy 135.552651 -33.148066) (xy 135.494758 -33.163579) (xy 135.435336 -33.171402)
			(xy 135.3754 -33.171402) (xy 135.315978 -33.163579) (xy 135.258085 -33.148066) (xy 135.202712 -33.12513)
			(xy 135.150806 -33.095163) (xy 135.103256 -33.058676) (xy 135.060876 -33.016296) (xy 135.024389 -32.968746)
			(xy 134.994422 -32.91684) (xy 134.971486 -32.861467) (xy 134.955973 -32.803574) (xy 134.94815 -32.744152)
			(xy 134.94766 -32.714184) (xy 130.418336 -32.714184) (xy 130.457194 -32.806386) (xy 130.4593 -32.810987)
			(xy 130.46506 -32.819304) (xy 130.468624 -32.822896) (xy 130.475736 -32.830008) (xy 130.485896 -32.833818)
			(xy 130.509938 -32.843539) (xy 130.555366 -32.868547) (xy 130.596993 -32.899473) (xy 130.634052 -32.935747)
			(xy 130.665861 -32.976703) (xy 130.691835 -33.021587) (xy 130.711496 -33.069573) (xy 130.724482 -33.119778)
			(xy 130.727958 -33.145476) (xy 130.729482 -33.160208) (xy 130.730752 -33.19018) (xy 130.730752 -33.190688)
			(xy 130.730359 -33.216591) (xy 130.723425 -33.267928) (xy 130.709602 -33.317853) (xy 130.699764 -33.341818)
			(xy 130.699764 -33.342072) (xy 130.696141 -33.351641) (xy 130.696004 -33.372084) (xy 130.69951 -33.381696)
			(xy 131.179402 -34.520886) (xy 137.589768 -34.520886) (xy 137.589768 -33.657286) (xy 137.590258 -33.627318)
			(xy 137.598081 -33.567896) (xy 137.613594 -33.510003) (xy 137.63653 -33.45463) (xy 137.666497 -33.402724)
			(xy 137.702984 -33.355174) (xy 137.745364 -33.312794) (xy 137.792914 -33.276307) (xy 137.84482 -33.24634)
			(xy 137.900193 -33.223404) (xy 137.958086 -33.207891) (xy 138.017508 -33.200068) (xy 138.077444 -33.200068)
			(xy 138.136866 -33.207891) (xy 138.194759 -33.223404) (xy 138.250132 -33.24634) (xy 138.302038 -33.276307)
			(xy 138.349588 -33.312794) (xy 138.391968 -33.355174) (xy 138.428455 -33.402724) (xy 138.458422 -33.45463)
			(xy 138.481358 -33.510003) (xy 138.496871 -33.567896) (xy 138.504694 -33.627318) (xy 138.505184 -33.657286)
			(xy 138.505184 -34.520886) (xy 138.504694 -34.550854) (xy 138.496871 -34.610276) (xy 138.481358 -34.668169)
			(xy 138.458422 -34.723542) (xy 138.428455 -34.775448) (xy 138.391968 -34.822998) (xy 138.349588 -34.865378)
			(xy 138.302038 -34.901865) (xy 138.250132 -34.931832) (xy 138.194759 -34.954768) (xy 138.136866 -34.970281)
			(xy 138.077444 -34.978104) (xy 138.017508 -34.978104) (xy 137.958086 -34.970281) (xy 137.900193 -34.954768)
			(xy 137.84482 -34.931832) (xy 137.792914 -34.901865) (xy 137.745364 -34.865378) (xy 137.702984 -34.822998)
			(xy 137.666497 -34.775448) (xy 137.63653 -34.723542) (xy 137.613594 -34.668169) (xy 137.598081 -34.610276)
			(xy 137.590258 -34.550854) (xy 137.589768 -34.520886) (xy 131.179402 -34.520886) (xy 131.492803 -35.264852)
			(xy 146.0025 -35.264852) (xy 146.006571 -35.20923) (xy 146.018697 -35.154793) (xy 146.03862 -35.102702)
			(xy 146.065916 -35.054067) (xy 146.100002 -35.009924) (xy 146.140151 -34.971215) (xy 146.185509 -34.938764)
			(xy 146.235109 -34.913263) (xy 146.287893 -34.895256) (xy 146.342736 -34.885126) (xy 146.39847 -34.883089)
			(xy 146.453907 -34.889189) (xy 146.507864 -34.903295) (xy 146.559193 -34.925107) (xy 146.606799 -34.954161)
			(xy 146.649667 -34.989836) (xy 146.686884 -35.031373) (xy 146.717657 -35.077886) (xy 146.741329 -35.128383)
			(xy 146.757397 -35.18179) (xy 146.765517 -35.236966) (xy 146.766026 -35.264852) (xy 146.765517 -35.292738)
			(xy 146.757397 -35.347914) (xy 146.741329 -35.401321) (xy 146.717657 -35.451818) (xy 146.686884 -35.498331)
			(xy 146.649667 -35.539868) (xy 146.606799 -35.575543) (xy 146.559193 -35.604597) (xy 146.507864 -35.626409)
			(xy 146.453907 -35.640515) (xy 146.39847 -35.646615) (xy 146.342736 -35.644578) (xy 146.287893 -35.634448)
			(xy 146.235109 -35.616441) (xy 146.185509 -35.59094) (xy 146.140151 -35.558489) (xy 146.100002 -35.51978)
			(xy 146.065916 -35.475637) (xy 146.03862 -35.427002) (xy 146.018697 -35.374911) (xy 146.006571 -35.320474)
			(xy 146.0025 -35.264852) (xy 131.492803 -35.264852) (xy 131.750565 -35.876738) (xy 134.817356 -35.876738)
			(xy 134.821427 -35.821116) (xy 134.833553 -35.766679) (xy 134.853476 -35.714588) (xy 134.880772 -35.665953)
			(xy 134.914858 -35.62181) (xy 134.955007 -35.583101) (xy 135.000365 -35.55065) (xy 135.049965 -35.525149)
			(xy 135.102749 -35.507142) (xy 135.157592 -35.497012) (xy 135.213326 -35.494975) (xy 135.268763 -35.501075)
			(xy 135.32272 -35.515181) (xy 135.374049 -35.536993) (xy 135.421655 -35.566047) (xy 135.464523 -35.601722)
			(xy 135.50174 -35.643259) (xy 135.532513 -35.689772) (xy 135.556185 -35.740269) (xy 135.572253 -35.793676)
			(xy 135.580373 -35.848852) (xy 135.580882 -35.876738) (xy 138.888976 -35.876738) (xy 138.893047 -35.821116)
			(xy 138.905173 -35.766679) (xy 138.925096 -35.714588) (xy 138.952392 -35.665953) (xy 138.986478 -35.62181)
			(xy 139.026627 -35.583101) (xy 139.071985 -35.55065) (xy 139.121585 -35.525149) (xy 139.174369 -35.507142)
			(xy 139.229212 -35.497012) (xy 139.284946 -35.494975) (xy 139.340383 -35.501075) (xy 139.39434 -35.515181)
			(xy 139.445669 -35.536993) (xy 139.493275 -35.566047) (xy 139.536143 -35.601722) (xy 139.57336 -35.643259)
			(xy 139.604133 -35.689772) (xy 139.627805 -35.740269) (xy 139.643873 -35.793676) (xy 139.651993 -35.848852)
			(xy 139.652502 -35.876738) (xy 139.651993 -35.904624) (xy 139.643873 -35.9598) (xy 139.627805 -36.013207)
			(xy 139.604133 -36.063704) (xy 139.57336 -36.110217) (xy 139.536143 -36.151754) (xy 139.493275 -36.187429)
			(xy 139.445669 -36.216483) (xy 139.39434 -36.238295) (xy 139.340383 -36.252401) (xy 139.284946 -36.258501)
			(xy 139.229212 -36.256464) (xy 139.174369 -36.246334) (xy 139.121585 -36.228327) (xy 139.071985 -36.202826)
			(xy 139.026627 -36.170375) (xy 138.986478 -36.131666) (xy 138.952392 -36.087523) (xy 138.925096 -36.038888)
			(xy 138.905173 -35.986797) (xy 138.893047 -35.93236) (xy 138.888976 -35.876738) (xy 135.580882 -35.876738)
			(xy 135.580373 -35.904624) (xy 135.572253 -35.9598) (xy 135.556185 -36.013207) (xy 135.532513 -36.063704)
			(xy 135.50174 -36.110217) (xy 135.464523 -36.151754) (xy 135.421655 -36.187429) (xy 135.374049 -36.216483)
			(xy 135.32272 -36.238295) (xy 135.268763 -36.252401) (xy 135.213326 -36.258501) (xy 135.157592 -36.256464)
			(xy 135.102749 -36.246334) (xy 135.049965 -36.228327) (xy 135.000365 -36.202826) (xy 134.955007 -36.170375)
			(xy 134.914858 -36.131666) (xy 134.880772 -36.087523) (xy 134.853476 -36.038888) (xy 134.833553 -35.986797)
			(xy 134.821427 -35.93236) (xy 134.817356 -35.876738) (xy 131.750565 -35.876738) (xy 132.017314 -36.50996)
			(xy 136.713974 -36.50996) (xy 136.718045 -36.454338) (xy 136.730171 -36.399901) (xy 136.750094 -36.34781)
			(xy 136.77739 -36.299175) (xy 136.811476 -36.255032) (xy 136.851625 -36.216323) (xy 136.896983 -36.183872)
			(xy 136.946583 -36.158371) (xy 136.999367 -36.140364) (xy 137.05421 -36.130234) (xy 137.109944 -36.128197)
			(xy 137.165381 -36.134297) (xy 137.219338 -36.148403) (xy 137.270667 -36.170215) (xy 137.318273 -36.199269)
			(xy 137.361141 -36.234944) (xy 137.398358 -36.276481) (xy 137.429131 -36.322994) (xy 137.452803 -36.373491)
			(xy 137.468871 -36.426898) (xy 137.472796 -36.453572) (xy 140.028674 -36.453572) (xy 140.032745 -36.39795)
			(xy 140.044871 -36.343513) (xy 140.064794 -36.291422) (xy 140.09209 -36.242787) (xy 140.126176 -36.198644)
			(xy 140.166325 -36.159935) (xy 140.211683 -36.127484) (xy 140.261283 -36.101983) (xy 140.314067 -36.083976)
			(xy 140.36891 -36.073846) (xy 140.424644 -36.071809) (xy 140.480081 -36.077909) (xy 140.534038 -36.092015)
			(xy 140.585367 -36.113827) (xy 140.632973 -36.142881) (xy 140.675841 -36.178556) (xy 140.713058 -36.220093)
			(xy 140.743831 -36.266606) (xy 140.753367 -36.286948) (xy 147.30044 -36.286948) (xy 147.304511 -36.231326)
			(xy 147.316637 -36.176889) (xy 147.33656 -36.124798) (xy 147.363856 -36.076163) (xy 147.397942 -36.03202)
			(xy 147.438091 -35.993311) (xy 147.483449 -35.96086) (xy 147.533049 -35.935359) (xy 147.585833 -35.917352)
			(xy 147.640676 -35.907222) (xy 147.69641 -35.905185) (xy 147.751847 -35.911285) (xy 147.805804 -35.925391)
			(xy 147.857133 -35.947203) (xy 147.904739 -35.976257) (xy 147.947607 -36.011932) (xy 147.984824 -36.053469)
			(xy 148.015597 -36.099982) (xy 148.039269 -36.150479) (xy 148.055337 -36.203886) (xy 148.063457 -36.259062)
			(xy 148.063966 -36.286948) (xy 148.063457 -36.314834) (xy 148.055337 -36.37001) (xy 148.039269 -36.423417)
			(xy 148.015597 -36.473914) (xy 147.984824 -36.520427) (xy 147.947607 -36.561964) (xy 147.904739 -36.597639)
			(xy 147.857133 -36.626693) (xy 147.805804 -36.648505) (xy 147.751847 -36.662611) (xy 147.69641 -36.668711)
			(xy 147.640676 -36.666674) (xy 147.585833 -36.656544) (xy 147.533049 -36.638537) (xy 147.483449 -36.613036)
			(xy 147.438091 -36.580585) (xy 147.397942 -36.541876) (xy 147.363856 -36.497733) (xy 147.33656 -36.449098)
			(xy 147.316637 -36.397007) (xy 147.304511 -36.34257) (xy 147.30044 -36.286948) (xy 140.753367 -36.286948)
			(xy 140.767503 -36.317103) (xy 140.783571 -36.37051) (xy 140.791691 -36.425686) (xy 140.7922 -36.453572)
			(xy 140.791691 -36.481458) (xy 140.783571 -36.536634) (xy 140.767503 -36.590041) (xy 140.743831 -36.640538)
			(xy 140.713058 -36.687051) (xy 140.675841 -36.728588) (xy 140.632973 -36.764263) (xy 140.585367 -36.793317)
			(xy 140.534038 -36.815129) (xy 140.480081 -36.829235) (xy 140.424644 -36.835335) (xy 140.36891 -36.833298)
			(xy 140.314067 -36.823168) (xy 140.261283 -36.805161) (xy 140.211683 -36.77966) (xy 140.166325 -36.747209)
			(xy 140.126176 -36.7085) (xy 140.09209 -36.664357) (xy 140.064794 -36.615722) (xy 140.044871 -36.563631)
			(xy 140.032745 -36.509194) (xy 140.028674 -36.453572) (xy 137.472796 -36.453572) (xy 137.476991 -36.482074)
			(xy 137.4775 -36.50996) (xy 137.476991 -36.537846) (xy 137.468871 -36.593022) (xy 137.452803 -36.646429)
			(xy 137.429131 -36.696926) (xy 137.398358 -36.743439) (xy 137.361141 -36.784976) (xy 137.318273 -36.820651)
			(xy 137.270667 -36.849705) (xy 137.219338 -36.871517) (xy 137.165381 -36.885623) (xy 137.109944 -36.891723)
			(xy 137.05421 -36.889686) (xy 136.999367 -36.879556) (xy 136.946583 -36.861549) (xy 136.896983 -36.836048)
			(xy 136.851625 -36.803597) (xy 136.811476 -36.764888) (xy 136.77739 -36.720745) (xy 136.750094 -36.67211)
			(xy 136.730171 -36.620019) (xy 136.718045 -36.565582) (xy 136.713974 -36.50996) (xy 132.017314 -36.50996)
			(xy 132.35051 -37.300916) (xy 132.371277 -37.351976) (xy 132.402714 -37.45763) (xy 132.406127 -37.47516)
			(xy 133.859268 -37.47516) (xy 133.863339 -37.419538) (xy 133.875465 -37.365101) (xy 133.895388 -37.31301)
			(xy 133.922684 -37.264375) (xy 133.95677 -37.220232) (xy 133.996919 -37.181523) (xy 134.042277 -37.149072)
			(xy 134.091877 -37.123571) (xy 134.144661 -37.105564) (xy 134.199504 -37.095434) (xy 134.255238 -37.093397)
			(xy 134.310675 -37.099497) (xy 134.364632 -37.113603) (xy 134.415961 -37.135415) (xy 134.463567 -37.164469)
			(xy 134.506435 -37.200144) (xy 134.543652 -37.241681) (xy 134.574425 -37.288194) (xy 134.598097 -37.338691)
			(xy 134.614165 -37.392098) (xy 134.622285 -37.447274) (xy 134.622794 -37.47516) (xy 134.622285 -37.503046)
			(xy 134.614165 -37.558222) (xy 134.598097 -37.611629) (xy 134.574425 -37.662126) (xy 134.574272 -37.662358)
			(xy 136.048494 -37.662358) (xy 136.052565 -37.606736) (xy 136.064691 -37.552299) (xy 136.084614 -37.500208)
			(xy 136.11191 -37.451573) (xy 136.145996 -37.40743) (xy 136.186145 -37.368721) (xy 136.231503 -37.33627)
			(xy 136.281103 -37.310769) (xy 136.333887 -37.292762) (xy 136.38873 -37.282632) (xy 136.444464 -37.280595)
			(xy 136.499901 -37.286695) (xy 136.553858 -37.300801) (xy 136.605187 -37.322613) (xy 136.652793 -37.351667)
			(xy 136.695661 -37.387342) (xy 136.732878 -37.428879) (xy 136.763651 -37.475392) (xy 136.787323 -37.525889)
			(xy 136.803391 -37.579296) (xy 136.811511 -37.634472) (xy 136.81202 -37.662358) (xy 136.811511 -37.690244)
			(xy 136.803391 -37.74542) (xy 136.794757 -37.774118) (xy 147.564854 -37.774118) (xy 147.568925 -37.718496)
			(xy 147.581051 -37.664059) (xy 147.600974 -37.611968) (xy 147.62827 -37.563333) (xy 147.662356 -37.51919)
			(xy 147.702505 -37.480481) (xy 147.747863 -37.44803) (xy 147.797463 -37.422529) (xy 147.850247 -37.404522)
			(xy 147.90509 -37.394392) (xy 147.960824 -37.392355) (xy 148.016261 -37.398455) (xy 148.070218 -37.412561)
			(xy 148.121547 -37.434373) (xy 148.169153 -37.463427) (xy 148.212021 -37.499102) (xy 148.249238 -37.540639)
			(xy 148.280011 -37.587152) (xy 148.303683 -37.637649) (xy 148.319751 -37.691056) (xy 148.327871 -37.746232)
			(xy 148.32838 -37.774118) (xy 148.327871 -37.802004) (xy 148.319751 -37.85718) (xy 148.303683 -37.910587)
			(xy 148.280011 -37.961084) (xy 148.249238 -38.007597) (xy 148.212021 -38.049134) (xy 148.169153 -38.084809)
			(xy 148.121547 -38.113863) (xy 148.070218 -38.135675) (xy 148.016261 -38.149781) (xy 147.960824 -38.155881)
			(xy 147.90509 -38.153844) (xy 147.850247 -38.143714) (xy 147.797463 -38.125707) (xy 147.747863 -38.100206)
			(xy 147.702505 -38.067755) (xy 147.662356 -38.029046) (xy 147.62827 -37.984903) (xy 147.600974 -37.936268)
			(xy 147.581051 -37.884177) (xy 147.568925 -37.82974) (xy 147.564854 -37.774118) (xy 136.794757 -37.774118)
			(xy 136.787323 -37.798827) (xy 136.763651 -37.849324) (xy 136.732878 -37.895837) (xy 136.695661 -37.937374)
			(xy 136.652793 -37.973049) (xy 136.605187 -38.002103) (xy 136.553858 -38.023915) (xy 136.499901 -38.038021)
			(xy 136.444464 -38.044121) (xy 136.38873 -38.042084) (xy 136.333887 -38.031954) (xy 136.281103 -38.013947)
			(xy 136.231503 -37.988446) (xy 136.186145 -37.955995) (xy 136.145996 -37.917286) (xy 136.11191 -37.873143)
			(xy 136.084614 -37.824508) (xy 136.064691 -37.772417) (xy 136.052565 -37.71798) (xy 136.048494 -37.662358)
			(xy 134.574272 -37.662358) (xy 134.543652 -37.708639) (xy 134.506435 -37.750176) (xy 134.463567 -37.785851)
			(xy 134.415961 -37.814905) (xy 134.364632 -37.836717) (xy 134.310675 -37.850823) (xy 134.255238 -37.856923)
			(xy 134.199504 -37.854886) (xy 134.144661 -37.844756) (xy 134.091877 -37.826749) (xy 134.042277 -37.801248)
			(xy 133.996919 -37.768797) (xy 133.95677 -37.730088) (xy 133.922684 -37.685945) (xy 133.895388 -37.63731)
			(xy 133.875465 -37.585219) (xy 133.863339 -37.530782) (xy 133.859268 -37.47516) (xy 132.406127 -37.47516)
			(xy 132.413248 -37.511736) (xy 132.420608 -37.555369) (xy 132.428493 -37.643511) (xy 132.428996 -37.687758)
			(xy 132.428996 -37.688266) (xy 132.428742 -37.704268) (xy 132.428742 -37.704522) (xy 132.411687 -38.729948)
			(xy 139.80112 -38.729948) (xy 139.80112 -38.675452) (xy 139.808876 -38.621511) (xy 139.824229 -38.569223)
			(xy 139.846867 -38.519652) (xy 139.876329 -38.473807) (xy 139.912016 -38.432621) (xy 139.9532 -38.396934)
			(xy 139.999045 -38.36747) (xy 140.048615 -38.344831) (xy 140.100903 -38.329477) (xy 140.154844 -38.321721)
			(xy 140.182092 -38.321234) (xy 140.210397 -38.321714) (xy 140.266386 -38.330066) (xy 140.320526 -38.346602)
			(xy 140.371628 -38.370958) (xy 140.418567 -38.402601) (xy 140.460314 -38.440834) (xy 140.495952 -38.484818)
			(xy 140.510768 -38.50894) (xy 140.518441 -38.520923) (xy 140.539044 -38.540521) (xy 140.56426 -38.553665)
			(xy 140.592126 -38.559331) (xy 140.620472 -38.557077) (xy 140.647093 -38.547079) (xy 140.669915 -38.530116)
			(xy 140.678916 -38.5191) (xy 140.697098 -38.49622) (xy 140.739262 -38.455757) (xy 140.787099 -38.42219)
			(xy 140.839491 -38.396303) (xy 140.895216 -38.378702) (xy 140.952973 -38.369797) (xy 140.982192 -38.36924)
			(xy 141.009449 -38.369606) (xy 141.063407 -38.377363) (xy 141.115713 -38.392721) (xy 141.1653 -38.415366)
			(xy 141.21116 -38.444837) (xy 141.252359 -38.480535) (xy 141.288058 -38.521733) (xy 141.317531 -38.567593)
			(xy 141.340176 -38.61718) (xy 141.355535 -38.669485) (xy 141.363293 -38.723443) (xy 141.363293 -38.777957)
			(xy 141.355535 -38.831915) (xy 141.340176 -38.88422) (xy 141.317531 -38.933807) (xy 141.288058 -38.979667)
			(xy 141.252359 -39.020865) (xy 141.21116 -39.056563) (xy 141.1653 -39.086034) (xy 141.115713 -39.108679)
			(xy 141.063407 -39.124037) (xy 141.009449 -39.131794) (xy 140.982192 -39.132256) (xy 140.953887 -39.131793)
			(xy 140.897896 -39.123439) (xy 140.843755 -39.106901) (xy 140.792654 -39.082541) (xy 140.745714 -39.050896)
			(xy 140.703968 -39.01266) (xy 140.668332 -38.968674) (xy 140.653516 -38.94455) (xy 140.645864 -38.932553)
			(xy 140.625256 -38.912955) (xy 140.600036 -38.899813) (xy 140.572166 -38.89415) (xy 140.543817 -38.896407)
			(xy 140.517194 -38.906407) (xy 140.49437 -38.923373) (xy 140.485368 -38.93439) (xy 140.467192 -38.957275)
			(xy 140.425028 -38.997739) (xy 140.37719 -39.031306) (xy 140.324796 -39.057191) (xy 140.269069 -39.074791)
			(xy 140.211312 -39.083695) (xy 140.182092 -39.08425) (xy 140.154844 -39.083679) (xy 140.100903 -39.075923)
			(xy 140.048615 -39.060569) (xy 139.999045 -39.03793) (xy 139.9532 -39.008466) (xy 139.912016 -38.972779)
			(xy 139.876329 -38.931593) (xy 139.846867 -38.885748) (xy 139.824229 -38.836177) (xy 139.808876 -38.783889)
			(xy 139.80112 -38.729948) (xy 132.411687 -38.729948) (xy 132.404104 -39.18585) (xy 132.402749 -39.233199)
			(xy 132.392193 -39.327338) (xy 132.383022 -39.37381) (xy 132.257886 -39.97198) (xy 141.995904 -39.97198)
			(xy 141.999975 -39.916358) (xy 142.012101 -39.861921) (xy 142.032024 -39.80983) (xy 142.05932 -39.761195)
			(xy 142.093406 -39.717052) (xy 142.133555 -39.678343) (xy 142.178913 -39.645892) (xy 142.228513 -39.620391)
			(xy 142.281297 -39.602384) (xy 142.33614 -39.592254) (xy 142.391874 -39.590217) (xy 142.447311 -39.596317)
			(xy 142.501268 -39.610423) (xy 142.552597 -39.632235) (xy 142.600203 -39.661289) (xy 142.643071 -39.696964)
			(xy 142.680288 -39.738501) (xy 142.711061 -39.785014) (xy 142.734733 -39.835511) (xy 142.750801 -39.888918)
			(xy 142.758921 -39.944094) (xy 142.75943 -39.97198) (xy 142.758921 -39.999866) (xy 142.750801 -40.055042)
			(xy 142.734733 -40.108449) (xy 142.711061 -40.158946) (xy 142.680288 -40.205459) (xy 142.643071 -40.246996)
			(xy 142.600203 -40.282671) (xy 142.552597 -40.311725) (xy 142.501268 -40.333537) (xy 142.447311 -40.347643)
			(xy 142.391874 -40.353743) (xy 142.33614 -40.351706) (xy 142.281297 -40.341576) (xy 142.228513 -40.323569)
			(xy 142.178913 -40.298068) (xy 142.133555 -40.265617) (xy 142.093406 -40.226908) (xy 142.05932 -40.182765)
			(xy 142.032024 -40.13413) (xy 142.012101 -40.082039) (xy 141.999975 -40.027602) (xy 141.995904 -39.97198)
			(xy 132.257886 -39.97198) (xy 132.203952 -40.22979) (xy 132.093716 -40.756078) (xy 132.093108 -40.760903)
			(xy 132.093498 -40.770619) (xy 132.094478 -40.775382) (xy 132.094732 -40.776398) (xy 132.09669 -40.783451)
			(xy 132.104053 -40.796095) (xy 132.10921 -40.80129) (xy 132.172202 -40.860218) (xy 132.181854 -40.86733)
			(xy 132.190863 -40.871874) (xy 132.210867 -40.874353) (xy 132.220716 -40.872156) (xy 132.227066 -40.870378)
			(xy 132.251021 -40.864512) (xy 132.299942 -40.858264) (xy 132.324602 -40.857932) (xy 132.32511 -40.857932)
			(xy 132.353632 -40.858454) (xy 132.410048 -40.866898) (xy 132.464594 -40.883597) (xy 132.516067 -40.908184)
			(xy 132.563335 -40.940118) (xy 132.584698 -40.959024) (xy 132.585714 -40.96004) (xy 132.588 -40.961818)
			(xy 132.597398 -40.966898) (xy 132.611622 -40.974518) (xy 132.621528 -40.976804) (xy 132.69087 -40.976804)
			(xy 132.696712 -40.97655) (xy 132.715348 -40.956912) (xy 132.757089 -40.922436) (xy 132.803177 -40.89403)
			(xy 132.852734 -40.872236) (xy 132.904819 -40.857468) (xy 132.958441 -40.850006) (xy 132.98551 -40.84955)
			(xy 133.013507 -40.85005) (xy 133.06893 -40.85802) (xy 133.122655 -40.873796) (xy 133.173587 -40.897058)
			(xy 133.220692 -40.927331) (xy 133.263008 -40.963999) (xy 133.299675 -41.006316) (xy 133.329947 -41.053421)
			(xy 133.353207 -41.104355) (xy 133.368982 -41.15808) (xy 133.376951 -41.213503) (xy 133.376951 -41.269497)
			(xy 133.368982 -41.32492) (xy 133.353207 -41.378645) (xy 133.329947 -41.429579) (xy 133.299675 -41.476684)
			(xy 133.263008 -41.519001) (xy 133.220692 -41.555669) (xy 133.173587 -41.585942) (xy 133.122655 -41.609204)
			(xy 133.06893 -41.62498) (xy 133.013507 -41.63295) (xy 132.98551 -41.633394) (xy 132.958441 -41.632938)
			(xy 132.904817 -41.625485) (xy 132.85273 -41.610721) (xy 132.803173 -41.588925) (xy 132.757088 -41.560513)
			(xy 132.715354 -41.526027) (xy 132.696712 -41.506394) (xy 132.69087 -41.50614) (xy 132.62737 -41.50614)
			(xy 132.615432 -41.507664) (xy 132.609336 -41.509188) (xy 132.597144 -41.514268) (xy 132.592318 -41.517062)
			(xy 132.588 -41.520872) (xy 132.587238 -41.521634) (xy 132.565785 -41.540955) (xy 132.518168 -41.573597)
			(xy 132.466202 -41.598744) (xy 132.411057 -41.615832) (xy 132.353976 -41.624473) (xy 132.32511 -41.625012)
			(xy 132.324856 -41.625012) (xy 132.298517 -41.624579) (xy 132.246335 -41.617373) (xy 132.195631 -41.60309)
			(xy 132.14736 -41.581997) (xy 132.102433 -41.554494) (xy 132.081778 -41.538144) (xy 132.08127 -41.537636)
			(xy 132.076047 -41.533659) (xy 132.064084 -41.528263) (xy 132.057648 -41.526968) (xy 132.045456 -41.524936)
			(xy 131.950714 -41.55821) (xy 131.94265 -41.561432) (xy 131.929158 -41.572344) (xy 131.920076 -41.587131)
			(xy 131.917948 -41.595548) (xy 131.834636 -41.993566) (xy 131.789678 -42.207942) (xy 131.559804 -43.305222)
			(xy 134.407402 -43.305222) (xy 134.40788 -43.277852) (xy 134.415695 -43.223674) (xy 134.431181 -43.171171)
			(xy 134.45402 -43.121424) (xy 134.483742 -43.075456) (xy 134.501382 -43.054524) (xy 134.501636 -43.05427)
			(xy 134.507203 -43.047171) (xy 134.513461 -43.030263) (xy 134.513828 -43.02125) (xy 134.513828 -42.954194)
			(xy 134.513468 -42.945178) (xy 134.507222 -42.928261) (xy 134.501636 -42.921174) (xy 134.501382 -42.921174)
			(xy 134.501382 -42.92092) (xy 134.483736 -42.899994) (xy 134.454026 -42.854019) (xy 134.431192 -42.80427)
			(xy 134.415702 -42.751768) (xy 134.407875 -42.697592) (xy 134.407402 -42.670222) (xy 134.407939 -42.641484)
			(xy 134.416558 -42.584657) (xy 134.433605 -42.529766) (xy 134.458694 -42.478054) (xy 134.491256 -42.430691)
			(xy 134.510526 -42.409364) (xy 134.51713 -42.402506) (xy 134.524242 -42.384472) (xy 134.524242 -42.295572)
			(xy 134.51713 -42.277538) (xy 134.510526 -42.27068) (xy 134.491277 -42.249334) (xy 134.458711 -42.201975)
			(xy 134.433618 -42.150267) (xy 134.416566 -42.095379) (xy 134.407941 -42.038554) (xy 134.407939 -41.981078)
			(xy 134.416559 -41.924253) (xy 134.433606 -41.869363) (xy 134.458695 -41.817653) (xy 134.491257 -41.770291)
			(xy 134.510526 -41.748964) (xy 134.51713 -41.742106) (xy 134.524242 -41.724072) (xy 134.524242 -41.635172)
			(xy 134.51713 -41.617138) (xy 134.510526 -41.61028) (xy 134.491264 -41.588946) (xy 134.458697 -41.541585)
			(xy 134.433603 -41.489876) (xy 134.41655 -41.434987) (xy 134.407925 -41.37816) (xy 134.407402 -41.349422)
			(xy 134.407888 -41.322171) (xy 134.415644 -41.268223) (xy 134.430999 -41.215928) (xy 134.453641 -41.166351)
			(xy 134.483107 -41.120501) (xy 134.518798 -41.07931) (xy 134.559989 -41.043619) (xy 134.605839 -41.014153)
			(xy 134.655416 -40.991511) (xy 134.707711 -40.976156) (xy 134.761659 -40.9684) (xy 134.816161 -40.9684)
			(xy 134.839282 -40.971724) (xy 142.69415 -40.971724) (xy 142.698221 -40.916102) (xy 142.710347 -40.861665)
			(xy 142.73027 -40.809574) (xy 142.757566 -40.760939) (xy 142.791652 -40.716796) (xy 142.831801 -40.678087)
			(xy 142.877159 -40.645636) (xy 142.926759 -40.620135) (xy 142.979543 -40.602128) (xy 143.034386 -40.591998)
			(xy 143.09012 -40.589961) (xy 143.145557 -40.596061) (xy 143.199514 -40.610167) (xy 143.250843 -40.631979)
			(xy 143.298449 -40.661033) (xy 143.341317 -40.696708) (xy 143.378534 -40.738245) (xy 143.409307 -40.784758)
			(xy 143.432979 -40.835255) (xy 143.449047 -40.888662) (xy 143.457167 -40.943838) (xy 143.457676 -40.971724)
			(xy 143.457167 -40.99961) (xy 143.449047 -41.054786) (xy 143.432979 -41.108193) (xy 143.409307 -41.15869)
			(xy 143.378534 -41.205203) (xy 143.341317 -41.24674) (xy 143.298449 -41.282415) (xy 143.250843 -41.311469)
			(xy 143.199514 -41.333281) (xy 143.145557 -41.347387) (xy 143.09012 -41.353487) (xy 143.034386 -41.35145)
			(xy 142.979543 -41.34132) (xy 142.926759 -41.323313) (xy 142.877159 -41.297812) (xy 142.831801 -41.265361)
			(xy 142.791652 -41.226652) (xy 142.757566 -41.182509) (xy 142.73027 -41.133874) (xy 142.710347 -41.081783)
			(xy 142.698221 -41.027346) (xy 142.69415 -40.971724) (xy 134.839282 -40.971724) (xy 134.870109 -40.976156)
			(xy 134.922404 -40.991511) (xy 134.971981 -41.014153) (xy 135.017831 -41.043619) (xy 135.059022 -41.07931)
			(xy 135.094713 -41.120501) (xy 135.124179 -41.166351) (xy 135.146821 -41.215928) (xy 135.162176 -41.268223)
			(xy 135.169932 -41.322171) (xy 135.170418 -41.349422) (xy 135.169903 -41.378161) (xy 135.161277 -41.434989)
			(xy 135.144225 -41.489879) (xy 135.119132 -41.541591) (xy 135.086565 -41.588953) (xy 135.067294 -41.61028)
			(xy 135.06069 -41.617138) (xy 135.053578 -41.635172) (xy 135.053578 -41.724072) (xy 135.06069 -41.742106)
			(xy 135.067294 -41.748964) (xy 135.086586 -41.770272) (xy 135.119149 -41.817638) (xy 135.144238 -41.869353)
			(xy 135.161286 -41.924247) (xy 135.169906 -41.981076) (xy 135.169903 -42.038556) (xy 135.161278 -42.095385)
			(xy 135.144226 -42.150277) (xy 135.119133 -42.201989) (xy 135.086566 -42.249353) (xy 135.067294 -42.27068)
			(xy 135.06069 -42.277538) (xy 135.053578 -42.295572) (xy 135.053578 -42.384472) (xy 135.06069 -42.402506)
			(xy 135.067294 -42.409364) (xy 135.086564 -42.430692) (xy 135.119132 -42.478053) (xy 135.144226 -42.529764)
			(xy 135.161277 -42.584655) (xy 135.169898 -42.641483) (xy 135.170418 -42.670222) (xy 135.169985 -42.697594)
			(xy 135.162162 -42.751775) (xy 135.146666 -42.804279) (xy 135.126108 -42.849038) (xy 136.992104 -42.849038)
			(xy 136.996175 -42.793416) (xy 137.008301 -42.738979) (xy 137.028224 -42.686888) (xy 137.05552 -42.638253)
			(xy 137.089606 -42.59411) (xy 137.129755 -42.555401) (xy 137.175113 -42.52295) (xy 137.224713 -42.497449)
			(xy 137.277497 -42.479442) (xy 137.33234 -42.469312) (xy 137.388074 -42.467275) (xy 137.443511 -42.473375)
			(xy 137.497468 -42.487481) (xy 137.548797 -42.509293) (xy 137.596403 -42.538347) (xy 137.639271 -42.574022)
			(xy 137.676488 -42.615559) (xy 137.707261 -42.662072) (xy 137.730933 -42.712569) (xy 137.747001 -42.765976)
			(xy 137.755121 -42.821152) (xy 137.755482 -42.84091) (xy 143.03324 -42.84091) (xy 143.037311 -42.785288)
			(xy 143.049437 -42.730851) (xy 143.06936 -42.67876) (xy 143.096656 -42.630125) (xy 143.130742 -42.585982)
			(xy 143.170891 -42.547273) (xy 143.216249 -42.514822) (xy 143.265849 -42.489321) (xy 143.318633 -42.471314)
			(xy 143.373476 -42.461184) (xy 143.42921 -42.459147) (xy 143.484647 -42.465247) (xy 143.538604 -42.479353)
			(xy 143.589933 -42.501165) (xy 143.637539 -42.530219) (xy 143.680407 -42.565894) (xy 143.717624 -42.607431)
			(xy 143.748397 -42.653944) (xy 143.772069 -42.704441) (xy 143.788137 -42.757848) (xy 143.796257 -42.813024)
			(xy 143.796766 -42.84091) (xy 143.796257 -42.868796) (xy 143.788137 -42.923972) (xy 143.772069 -42.977379)
			(xy 143.748397 -43.027876) (xy 143.717624 -43.074389) (xy 143.680407 -43.115926) (xy 143.637539 -43.151601)
			(xy 143.589933 -43.180655) (xy 143.538604 -43.202467) (xy 143.484647 -43.216573) (xy 143.42921 -43.222673)
			(xy 143.373476 -43.220636) (xy 143.318633 -43.210506) (xy 143.265849 -43.192499) (xy 143.216249 -43.166998)
			(xy 143.170891 -43.134547) (xy 143.130742 -43.095838) (xy 143.096656 -43.051695) (xy 143.06936 -43.00306)
			(xy 143.049437 -42.950969) (xy 143.037311 -42.896532) (xy 143.03324 -42.84091) (xy 137.755482 -42.84091)
			(xy 137.75563 -42.849038) (xy 137.755121 -42.876924) (xy 137.747001 -42.9321) (xy 137.730933 -42.985507)
			(xy 137.707261 -43.036004) (xy 137.676488 -43.082517) (xy 137.639271 -43.124054) (xy 137.596403 -43.159729)
			(xy 137.548797 -43.188783) (xy 137.497468 -43.210595) (xy 137.443511 -43.224701) (xy 137.388074 -43.230801)
			(xy 137.33234 -43.228764) (xy 137.277497 -43.218634) (xy 137.224713 -43.200627) (xy 137.175113 -43.175126)
			(xy 137.129755 -43.142675) (xy 137.089606 -43.103966) (xy 137.05552 -43.059823) (xy 137.028224 -43.011188)
			(xy 137.008301 -42.959097) (xy 136.996175 -42.90466) (xy 136.992104 -42.849038) (xy 135.126108 -42.849038)
			(xy 135.123817 -42.854026) (xy 135.094084 -42.89999) (xy 135.076438 -42.92092) (xy 135.076184 -42.921174)
			(xy 135.0706 -42.928263) (xy 135.064352 -42.945178) (xy 135.063992 -42.954194) (xy 135.063992 -43.02125)
			(xy 135.064374 -43.030264) (xy 135.070604 -43.047181) (xy 135.076184 -43.05427) (xy 135.076438 -43.05427)
			(xy 135.076438 -43.054524) (xy 135.094061 -43.075469) (xy 135.123774 -43.121439) (xy 135.146613 -43.171183)
			(xy 135.162108 -43.223681) (xy 135.169941 -43.277854) (xy 135.170418 -43.305222) (xy 135.169932 -43.332473)
			(xy 135.162176 -43.386421) (xy 135.146821 -43.438716) (xy 135.124179 -43.488293) (xy 135.094713 -43.534143)
			(xy 135.059022 -43.575334) (xy 135.017831 -43.611025) (xy 134.971981 -43.640491) (xy 134.922404 -43.663133)
			(xy 134.870109 -43.678488) (xy 134.816161 -43.686244) (xy 134.761659 -43.686244) (xy 134.707711 -43.678488)
			(xy 134.655416 -43.663133) (xy 134.605839 -43.640491) (xy 134.559989 -43.611025) (xy 134.518798 -43.575334)
			(xy 134.483107 -43.534143) (xy 134.453641 -43.488293) (xy 134.430999 -43.438716) (xy 134.415644 -43.386421)
			(xy 134.407888 -43.332473) (xy 134.407402 -43.305222) (xy 131.559804 -43.305222) (xy 131.54533 -43.37431)
			(xy 131.544822 -43.37685) (xy 131.490151 -43.73626) (xy 136.313162 -43.73626) (xy 136.317233 -43.680638)
			(xy 136.329359 -43.626201) (xy 136.349282 -43.57411) (xy 136.376578 -43.525475) (xy 136.410664 -43.481332)
			(xy 136.450813 -43.442623) (xy 136.496171 -43.410172) (xy 136.545771 -43.384671) (xy 136.598555 -43.366664)
			(xy 136.653398 -43.356534) (xy 136.709132 -43.354497) (xy 136.764569 -43.360597) (xy 136.818526 -43.374703)
			(xy 136.869855 -43.396515) (xy 136.917461 -43.425569) (xy 136.960329 -43.461244) (xy 136.997546 -43.502781)
			(xy 137.028319 -43.549294) (xy 137.051991 -43.599791) (xy 137.068059 -43.653198) (xy 137.076179 -43.708374)
			(xy 137.076688 -43.73626) (xy 137.076179 -43.764146) (xy 137.068059 -43.819322) (xy 137.05675 -43.85691)
			(xy 140.819884 -43.85691) (xy 140.823955 -43.801288) (xy 140.836081 -43.746851) (xy 140.856004 -43.69476)
			(xy 140.8833 -43.646125) (xy 140.917386 -43.601982) (xy 140.957535 -43.563273) (xy 141.002893 -43.530822)
			(xy 141.052493 -43.505321) (xy 141.105277 -43.487314) (xy 141.16012 -43.477184) (xy 141.215854 -43.475147)
			(xy 141.271291 -43.481247) (xy 141.325248 -43.495353) (xy 141.376577 -43.517165) (xy 141.424183 -43.546219)
			(xy 141.467051 -43.581894) (xy 141.504268 -43.623431) (xy 141.535041 -43.669944) (xy 141.558713 -43.720441)
			(xy 141.574781 -43.773848) (xy 141.582901 -43.829024) (xy 141.58341 -43.85691) (xy 141.582901 -43.884796)
			(xy 141.574781 -43.939972) (xy 141.558713 -43.993379) (xy 141.535041 -44.043876) (xy 141.504268 -44.090389)
			(xy 141.467051 -44.131926) (xy 141.424183 -44.167601) (xy 141.376577 -44.196655) (xy 141.325248 -44.218467)
			(xy 141.271291 -44.232573) (xy 141.215854 -44.238673) (xy 141.16012 -44.236636) (xy 141.105277 -44.226506)
			(xy 141.052493 -44.208499) (xy 141.002893 -44.182998) (xy 140.957535 -44.150547) (xy 140.917386 -44.111838)
			(xy 140.8833 -44.067695) (xy 140.856004 -44.01906) (xy 140.836081 -43.966969) (xy 140.823955 -43.912532)
			(xy 140.819884 -43.85691) (xy 137.05675 -43.85691) (xy 137.051991 -43.872729) (xy 137.028319 -43.923226)
			(xy 136.997546 -43.969739) (xy 136.960329 -44.011276) (xy 136.917461 -44.046951) (xy 136.869855 -44.076005)
			(xy 136.818526 -44.097817) (xy 136.764569 -44.111923) (xy 136.709132 -44.118023) (xy 136.653398 -44.115986)
			(xy 136.598555 -44.105856) (xy 136.545771 -44.087849) (xy 136.496171 -44.062348) (xy 136.450813 -44.029897)
			(xy 136.410664 -43.991188) (xy 136.376578 -43.947045) (xy 136.349282 -43.89841) (xy 136.329359 -43.846319)
			(xy 136.317233 -43.791882) (xy 136.313162 -43.73626) (xy 131.490151 -43.73626) (xy 131.280509 -45.114464)
			(xy 136.165588 -45.114464) (xy 136.169659 -45.058842) (xy 136.181785 -45.004405) (xy 136.201708 -44.952314)
			(xy 136.229004 -44.903679) (xy 136.26309 -44.859536) (xy 136.303239 -44.820827) (xy 136.348597 -44.788376)
			(xy 136.398197 -44.762875) (xy 136.450981 -44.744868) (xy 136.505824 -44.734738) (xy 136.561558 -44.732701)
			(xy 136.616995 -44.738801) (xy 136.670952 -44.752907) (xy 136.722281 -44.774719) (xy 136.769887 -44.803773)
			(xy 136.812755 -44.839448) (xy 136.842737 -44.87291) (xy 143.03324 -44.87291) (xy 143.037311 -44.817288)
			(xy 143.049437 -44.762851) (xy 143.06936 -44.71076) (xy 143.096656 -44.662125) (xy 143.130742 -44.617982)
			(xy 143.170891 -44.579273) (xy 143.216249 -44.546822) (xy 143.265849 -44.521321) (xy 143.318633 -44.503314)
			(xy 143.373476 -44.493184) (xy 143.42921 -44.491147) (xy 143.484647 -44.497247) (xy 143.538604 -44.511353)
			(xy 143.589933 -44.533165) (xy 143.637539 -44.562219) (xy 143.680407 -44.597894) (xy 143.717624 -44.639431)
			(xy 143.748397 -44.685944) (xy 143.772069 -44.736441) (xy 143.788137 -44.789848) (xy 143.796257 -44.845024)
			(xy 143.796766 -44.87291) (xy 143.796257 -44.900796) (xy 143.788137 -44.955972) (xy 143.772069 -45.009379)
			(xy 143.748397 -45.059876) (xy 143.717624 -45.106389) (xy 143.680407 -45.147926) (xy 143.637539 -45.183601)
			(xy 143.589933 -45.212655) (xy 143.538604 -45.234467) (xy 143.484647 -45.248573) (xy 143.42921 -45.254673)
			(xy 143.373476 -45.252636) (xy 143.318633 -45.242506) (xy 143.265849 -45.224499) (xy 143.216249 -45.198998)
			(xy 143.170891 -45.166547) (xy 143.130742 -45.127838) (xy 143.096656 -45.083695) (xy 143.06936 -45.03506)
			(xy 143.049437 -44.982969) (xy 143.037311 -44.928532) (xy 143.03324 -44.87291) (xy 136.842737 -44.87291)
			(xy 136.849972 -44.880985) (xy 136.880745 -44.927498) (xy 136.904417 -44.977995) (xy 136.920485 -45.031402)
			(xy 136.928605 -45.086578) (xy 136.929114 -45.114464) (xy 136.928605 -45.14235) (xy 136.920485 -45.197526)
			(xy 136.904417 -45.250933) (xy 136.880745 -45.30143) (xy 136.849972 -45.347943) (xy 136.84433 -45.35424)
			(xy 140.803882 -45.35424) (xy 140.807953 -45.298618) (xy 140.820079 -45.244181) (xy 140.840002 -45.19209)
			(xy 140.867298 -45.143455) (xy 140.901384 -45.099312) (xy 140.941533 -45.060603) (xy 140.986891 -45.028152)
			(xy 141.036491 -45.002651) (xy 141.089275 -44.984644) (xy 141.144118 -44.974514) (xy 141.199852 -44.972477)
			(xy 141.255289 -44.978577) (xy 141.309246 -44.992683) (xy 141.360575 -45.014495) (xy 141.408181 -45.043549)
			(xy 141.451049 -45.079224) (xy 141.488266 -45.120761) (xy 141.519039 -45.167274) (xy 141.542711 -45.217771)
			(xy 141.558779 -45.271178) (xy 141.566899 -45.326354) (xy 141.567408 -45.35424) (xy 141.566899 -45.382126)
			(xy 141.558779 -45.437302) (xy 141.542711 -45.490709) (xy 141.519039 -45.541206) (xy 141.488266 -45.587719)
			(xy 141.451049 -45.629256) (xy 141.408181 -45.664931) (xy 141.360575 -45.693985) (xy 141.309246 -45.715797)
			(xy 141.255289 -45.729903) (xy 141.199852 -45.736003) (xy 141.144118 -45.733966) (xy 141.089275 -45.723836)
			(xy 141.036491 -45.705829) (xy 140.986891 -45.680328) (xy 140.941533 -45.647877) (xy 140.901384 -45.609168)
			(xy 140.867298 -45.565025) (xy 140.840002 -45.51639) (xy 140.820079 -45.464299) (xy 140.807953 -45.409862)
			(xy 140.803882 -45.35424) (xy 136.84433 -45.35424) (xy 136.812755 -45.38948) (xy 136.769887 -45.425155)
			(xy 136.722281 -45.454209) (xy 136.670952 -45.476021) (xy 136.616995 -45.490127) (xy 136.561558 -45.496227)
			(xy 136.505824 -45.49419) (xy 136.450981 -45.48406) (xy 136.398197 -45.466053) (xy 136.348597 -45.440552)
			(xy 136.303239 -45.408101) (xy 136.26309 -45.369392) (xy 136.229004 -45.325249) (xy 136.201708 -45.276614)
			(xy 136.181785 -45.224523) (xy 136.169659 -45.170086) (xy 136.165588 -45.114464) (xy 131.280509 -45.114464)
			(xy 131.133304 -46.082204) (xy 134.15264 -46.082204) (xy 134.153059 -46.054949) (xy 134.160817 -46.000994)
			(xy 134.176175 -45.948692) (xy 134.19882 -45.899109) (xy 134.228292 -45.853254) (xy 134.263991 -45.81206)
			(xy 134.305189 -45.776366) (xy 134.351048 -45.746899) (xy 134.400634 -45.724259) (xy 134.452937 -45.708908)
			(xy 134.506893 -45.701156) (xy 134.534148 -45.700696) (xy 134.561052 -45.701122) (xy 134.614323 -45.7087)
			(xy 134.666003 -45.723686) (xy 134.715064 -45.745782) (xy 134.760536 -45.77455) (xy 134.801517 -45.80942)
			(xy 134.837193 -45.8497) (xy 134.85241 -45.871892) (xy 134.859522 -45.882814) (xy 134.882382 -45.894752)
			(xy 134.99465 -45.89272) (xy 135.017002 -45.879766) (xy 135.02386 -45.86859) (xy 135.038754 -45.84497)
			(xy 135.074438 -45.802019) (xy 135.116001 -45.764727) (xy 135.162555 -45.733892) (xy 135.213107 -45.710171)
			(xy 135.266577 -45.694073) (xy 135.321822 -45.685939) (xy 135.349742 -45.685456) (xy 135.376736 -45.685893)
			(xy 135.430185 -45.693505) (xy 135.482029 -45.70857) (xy 135.531233 -45.73079) (xy 135.576816 -45.75972)
			(xy 135.597646 -45.776896) (xy 135.605774 -45.784008) (xy 135.626348 -45.790104) (xy 135.711692 -45.779182)
			(xy 135.722238 -45.777414) (xy 135.74052 -45.766355) (xy 135.746998 -45.757846) (xy 135.762359 -45.736621)
			(xy 135.797945 -45.698168) (xy 135.838461 -45.664949) (xy 135.883142 -45.63759) (xy 135.931149 -45.616605)
			(xy 135.981577 -45.602391) (xy 136.033476 -45.595214) (xy 136.059672 -45.594778) (xy 136.086925 -45.595267)
			(xy 136.140877 -45.603021) (xy 136.193176 -45.618374) (xy 136.242758 -45.641014) (xy 136.288613 -45.67048)
			(xy 136.329808 -45.706172) (xy 136.365503 -45.747364) (xy 136.394973 -45.793217) (xy 136.417616 -45.842797)
			(xy 136.432973 -45.895095) (xy 136.440731 -45.949047) (xy 136.440731 -46.003553) (xy 136.432973 -46.057505)
			(xy 136.417616 -46.109803) (xy 136.394973 -46.159383) (xy 136.365503 -46.205236) (xy 136.329808 -46.246428)
			(xy 136.288613 -46.28212) (xy 136.242758 -46.311586) (xy 136.193176 -46.334226) (xy 136.140877 -46.349579)
			(xy 136.086925 -46.357333) (xy 136.059672 -46.357794) (xy 136.032679 -46.357337) (xy 135.979231 -46.349728)
			(xy 135.927388 -46.334667) (xy 135.878183 -46.312452) (xy 135.832599 -46.283528) (xy 135.811768 -46.266354)
			(xy 135.80364 -46.259242) (xy 135.783066 -46.253146) (xy 135.697722 -46.264068) (xy 135.687182 -46.265861)
			(xy 135.668899 -46.276903) (xy 135.662416 -46.285404) (xy 135.644798 -46.3097) (xy 135.603206 -46.352962)
			(xy 135.579612 -46.37151) (xy 135.571738 -46.377352) (xy 135.561324 -46.394878) (xy 135.548116 -46.485302)
			(xy 135.552942 -46.504606) (xy 135.558784 -46.51248) (xy 135.558784 -46.512734) (xy 135.576288 -46.537477)
			(xy 135.60409 -46.591331) (xy 135.623026 -46.648903) (xy 135.630229 -46.693836) (xy 140.776452 -46.693836)
			(xy 140.776938 -46.666585) (xy 140.784694 -46.612637) (xy 140.800049 -46.560342) (xy 140.822691 -46.510765)
			(xy 140.852157 -46.464915) (xy 140.887848 -46.423724) (xy 140.929039 -46.388033) (xy 140.974889 -46.358567)
			(xy 141.024466 -46.335925) (xy 141.076761 -46.32057) (xy 141.130709 -46.312814) (xy 141.185211 -46.312814)
			(xy 141.239159 -46.32057) (xy 141.291454 -46.335925) (xy 141.341031 -46.358567) (xy 141.386881 -46.388033)
			(xy 141.428072 -46.423724) (xy 141.463763 -46.464915) (xy 141.493229 -46.510765) (xy 141.515871 -46.560342)
			(xy 141.531226 -46.612637) (xy 141.538982 -46.666585) (xy 141.539468 -46.693836) (xy 141.539 -46.720264)
			(xy 141.53169 -46.772611) (xy 141.517215 -46.823446) (xy 141.495853 -46.871793) (xy 141.482318 -46.894496)
			(xy 141.482064 -46.89475) (xy 141.476728 -46.904768) (xy 141.47447 -46.927318) (xy 141.477746 -46.938184)
			(xy 141.503908 -47.01286) (xy 141.508267 -47.023389) (xy 141.524373 -47.039472) (xy 141.534896 -47.043848)
			(xy 141.53515 -47.043848) (xy 141.55966 -47.052915) (xy 141.606112 -47.076858) (xy 141.648864 -47.106915)
			(xy 141.687116 -47.142522) (xy 141.720152 -47.183015) (xy 141.747356 -47.227637) (xy 141.768217 -47.275552)
			(xy 141.782347 -47.325865) (xy 141.789481 -47.377636) (xy 141.789912 -47.403766) (xy 141.789426 -47.431017)
			(xy 141.787903 -47.441612) (xy 143.061942 -47.441612) (xy 143.066013 -47.38599) (xy 143.078139 -47.331553)
			(xy 143.098062 -47.279462) (xy 143.125358 -47.230827) (xy 143.159444 -47.186684) (xy 143.199593 -47.147975)
			(xy 143.244951 -47.115524) (xy 143.294551 -47.090023) (xy 143.347335 -47.072016) (xy 143.402178 -47.061886)
			(xy 143.457912 -47.059849) (xy 143.513349 -47.065949) (xy 143.567306 -47.080055) (xy 143.618635 -47.101867)
			(xy 143.666241 -47.130921) (xy 143.709109 -47.166596) (xy 143.746326 -47.208133) (xy 143.777099 -47.254646)
			(xy 143.800771 -47.305143) (xy 143.816839 -47.35855) (xy 143.824959 -47.413726) (xy 143.825468 -47.441612)
			(xy 143.824959 -47.469498) (xy 143.816839 -47.524674) (xy 143.800771 -47.578081) (xy 143.777099 -47.628578)
			(xy 143.746326 -47.675091) (xy 143.709109 -47.716628) (xy 143.666241 -47.752303) (xy 143.618635 -47.781357)
			(xy 143.567306 -47.803169) (xy 143.513349 -47.817275) (xy 143.457912 -47.823375) (xy 143.402178 -47.821338)
			(xy 143.347335 -47.811208) (xy 143.294551 -47.793201) (xy 143.244951 -47.7677) (xy 143.199593 -47.735249)
			(xy 143.159444 -47.69654) (xy 143.125358 -47.652397) (xy 143.098062 -47.603762) (xy 143.078139 -47.551671)
			(xy 143.066013 -47.497234) (xy 143.061942 -47.441612) (xy 141.787903 -47.441612) (xy 141.78167 -47.484965)
			(xy 141.766315 -47.53726) (xy 141.743673 -47.586837) (xy 141.714207 -47.632687) (xy 141.678516 -47.673878)
			(xy 141.637325 -47.709569) (xy 141.591475 -47.739035) (xy 141.541898 -47.761677) (xy 141.489603 -47.777032)
			(xy 141.435655 -47.784788) (xy 141.381153 -47.784788) (xy 141.327205 -47.777032) (xy 141.27491 -47.761677)
			(xy 141.225333 -47.739035) (xy 141.179483 -47.709569) (xy 141.138292 -47.673878) (xy 141.102601 -47.632687)
			(xy 141.073135 -47.586837) (xy 141.050493 -47.53726) (xy 141.035138 -47.484965) (xy 141.027382 -47.431017)
			(xy 141.026896 -47.403766) (xy 141.02737 -47.377338) (xy 141.034679 -47.324991) (xy 141.049152 -47.274156)
			(xy 141.070511 -47.225809) (xy 141.084046 -47.203106) (xy 141.0843 -47.202852) (xy 141.089635 -47.192833)
			(xy 141.091896 -47.170283) (xy 141.088618 -47.159418) (xy 141.062456 -47.084742) (xy 141.058067 -47.074229)
			(xy 141.041982 -47.058139) (xy 141.031468 -47.053754) (xy 141.031214 -47.053754) (xy 141.006697 -47.044705)
			(xy 140.960246 -47.020758) (xy 140.917495 -46.990699) (xy 140.879245 -46.955088) (xy 140.846209 -46.914593)
			(xy 140.819007 -46.86997) (xy 140.798146 -46.822053) (xy 140.784017 -46.771738) (xy 140.776883 -46.719966)
			(xy 140.776452 -46.693836) (xy 135.630229 -46.693836) (xy 135.632619 -46.708745) (xy 135.633206 -46.739048)
			(xy 135.632767 -46.766301) (xy 135.625004 -46.82025) (xy 135.609642 -46.872546) (xy 135.586996 -46.922123)
			(xy 135.557524 -46.967974) (xy 135.521828 -47.009163) (xy 135.480633 -47.044854) (xy 135.434779 -47.07432)
			(xy 135.385199 -47.09696) (xy 135.332901 -47.112314) (xy 135.278951 -47.12007) (xy 135.251698 -47.120556)
			(xy 135.225665 -47.120102) (xy 135.174082 -47.113016) (xy 135.123941 -47.098988) (xy 135.07617 -47.078278)
			(xy 135.031655 -47.051271) (xy 135.01116 -47.035212) (xy 135.003392 -47.029487) (xy 134.98499 -47.023736)
			(xy 134.975346 -47.024036) (xy 134.89559 -47.030386) (xy 134.87781 -47.039022) (xy 134.87146 -47.046388)
			(xy 134.853272 -47.066027) (xy 134.812366 -47.10055) (xy 134.767038 -47.12902) (xy 134.718178 -47.150878)
			(xy 134.666744 -47.165697) (xy 134.613743 -47.173186) (xy 134.58698 -47.173642) (xy 134.55973 -47.173141)
			(xy 134.505784 -47.165383) (xy 134.453492 -47.150027) (xy 134.403917 -47.127386) (xy 134.358068 -47.09792)
			(xy 134.316879 -47.062231) (xy 134.281188 -47.021043) (xy 134.251721 -46.975195) (xy 134.229078 -46.925621)
			(xy 134.21372 -46.873329) (xy 134.20596 -46.819384) (xy 134.205472 -46.792134) (xy 134.206004 -46.76336)
			(xy 134.214654 -46.706467) (xy 134.231749 -46.651517) (xy 134.256901 -46.599757) (xy 134.289539 -46.55236)
			(xy 134.30885 -46.531022) (xy 134.316216 -46.523148) (xy 134.323328 -46.503336) (xy 134.315962 -46.40707)
			(xy 134.306056 -46.388274) (xy 134.297674 -46.38167) (xy 134.27548 -46.363457) (xy 134.236273 -46.321518)
			(xy 134.203789 -46.274179) (xy 134.178763 -46.222509) (xy 134.161758 -46.167674) (xy 134.153158 -46.11091)
			(xy 134.15264 -46.082204) (xy 131.133304 -46.082204) (xy 130.794886 -48.30699) (xy 140.654022 -48.30699)
			(xy 140.658093 -48.251368) (xy 140.670219 -48.196931) (xy 140.690142 -48.14484) (xy 140.717438 -48.096205)
			(xy 140.751524 -48.052062) (xy 140.791673 -48.013353) (xy 140.837031 -47.980902) (xy 140.886631 -47.955401)
			(xy 140.939415 -47.937394) (xy 140.994258 -47.927264) (xy 141.049992 -47.925227) (xy 141.105429 -47.931327)
			(xy 141.159386 -47.945433) (xy 141.210715 -47.967245) (xy 141.258321 -47.996299) (xy 141.301189 -48.031974)
			(xy 141.338406 -48.073511) (xy 141.369179 -48.120024) (xy 141.392851 -48.170521) (xy 141.408919 -48.223928)
			(xy 141.417039 -48.279104) (xy 141.417548 -48.30699) (xy 141.417039 -48.334876) (xy 141.408919 -48.390052)
			(xy 141.392851 -48.443459) (xy 141.369179 -48.493956) (xy 141.338406 -48.540469) (xy 141.301189 -48.582006)
			(xy 141.258321 -48.617681) (xy 141.210715 -48.646735) (xy 141.159386 -48.668547) (xy 141.105429 -48.682653)
			(xy 141.049992 -48.688753) (xy 140.994258 -48.686716) (xy 140.939415 -48.676586) (xy 140.886631 -48.658579)
			(xy 140.837031 -48.633078) (xy 140.791673 -48.600627) (xy 140.751524 -48.561918) (xy 140.717438 -48.517775)
			(xy 140.690142 -48.46914) (xy 140.670219 -48.417049) (xy 140.658093 -48.362612) (xy 140.654022 -48.30699)
			(xy 130.794886 -48.30699) (xy 130.72704 -48.753014) (xy 137.268456 -48.753014) (xy 137.272527 -48.697392)
			(xy 137.284653 -48.642955) (xy 137.304576 -48.590864) (xy 137.331872 -48.542229) (xy 137.365958 -48.498086)
			(xy 137.406107 -48.459377) (xy 137.451465 -48.426926) (xy 137.501065 -48.401425) (xy 137.553849 -48.383418)
			(xy 137.608692 -48.373288) (xy 137.664426 -48.371251) (xy 137.719863 -48.377351) (xy 137.77382 -48.391457)
			(xy 137.825149 -48.413269) (xy 137.872755 -48.442323) (xy 137.915623 -48.477998) (xy 137.95284 -48.519535)
			(xy 137.983613 -48.566048) (xy 138.007285 -48.616545) (xy 138.023353 -48.669952) (xy 138.031473 -48.725128)
			(xy 138.031982 -48.753014) (xy 138.031473 -48.7809) (xy 138.023353 -48.836076) (xy 138.007285 -48.889483)
			(xy 138.005889 -48.89246) (xy 139.314172 -48.89246) (xy 139.318243 -48.836838) (xy 139.330369 -48.782401)
			(xy 139.350292 -48.73031) (xy 139.377588 -48.681675) (xy 139.411674 -48.637532) (xy 139.451823 -48.598823)
			(xy 139.497181 -48.566372) (xy 139.546781 -48.540871) (xy 139.599565 -48.522864) (xy 139.654408 -48.512734)
			(xy 139.710142 -48.510697) (xy 139.765579 -48.516797) (xy 139.819536 -48.530903) (xy 139.870865 -48.552715)
			(xy 139.918471 -48.581769) (xy 139.961339 -48.617444) (xy 139.998556 -48.658981) (xy 140.029329 -48.705494)
			(xy 140.053001 -48.755991) (xy 140.069069 -48.809398) (xy 140.077189 -48.864574) (xy 140.077698 -48.89246)
			(xy 140.077189 -48.920346) (xy 140.074751 -48.93691) (xy 143.03324 -48.93691) (xy 143.037311 -48.881288)
			(xy 143.049437 -48.826851) (xy 143.06936 -48.77476) (xy 143.096656 -48.726125) (xy 143.130742 -48.681982)
			(xy 143.170891 -48.643273) (xy 143.216249 -48.610822) (xy 143.265849 -48.585321) (xy 143.318633 -48.567314)
			(xy 143.373476 -48.557184) (xy 143.42921 -48.555147) (xy 143.484647 -48.561247) (xy 143.538604 -48.575353)
			(xy 143.589933 -48.597165) (xy 143.637539 -48.626219) (xy 143.680407 -48.661894) (xy 143.717624 -48.703431)
			(xy 143.748397 -48.749944) (xy 143.772069 -48.800441) (xy 143.788137 -48.853848) (xy 143.796257 -48.909024)
			(xy 143.796766 -48.93691) (xy 143.796257 -48.964796) (xy 143.788137 -49.019972) (xy 143.772069 -49.073379)
			(xy 143.748397 -49.123876) (xy 143.717624 -49.170389) (xy 143.680407 -49.211926) (xy 143.637539 -49.247601)
			(xy 143.589933 -49.276655) (xy 143.538604 -49.298467) (xy 143.484647 -49.312573) (xy 143.42921 -49.318673)
			(xy 143.373476 -49.316636) (xy 143.318633 -49.306506) (xy 143.265849 -49.288499) (xy 143.216249 -49.262998)
			(xy 143.170891 -49.230547) (xy 143.130742 -49.191838) (xy 143.096656 -49.147695) (xy 143.06936 -49.09906)
			(xy 143.049437 -49.046969) (xy 143.037311 -48.992532) (xy 143.03324 -48.93691) (xy 140.074751 -48.93691)
			(xy 140.069069 -48.975522) (xy 140.053001 -49.028929) (xy 140.029329 -49.079426) (xy 139.998556 -49.125939)
			(xy 139.961339 -49.167476) (xy 139.918471 -49.203151) (xy 139.870865 -49.232205) (xy 139.819536 -49.254017)
			(xy 139.765579 -49.268123) (xy 139.710142 -49.274223) (xy 139.654408 -49.272186) (xy 139.599565 -49.262056)
			(xy 139.546781 -49.244049) (xy 139.497181 -49.218548) (xy 139.451823 -49.186097) (xy 139.411674 -49.147388)
			(xy 139.377588 -49.103245) (xy 139.350292 -49.05461) (xy 139.330369 -49.002519) (xy 139.318243 -48.948082)
			(xy 139.314172 -48.89246) (xy 138.005889 -48.89246) (xy 137.983613 -48.93998) (xy 137.95284 -48.986493)
			(xy 137.915623 -49.02803) (xy 137.872755 -49.063705) (xy 137.825149 -49.092759) (xy 137.77382 -49.114571)
			(xy 137.719863 -49.128677) (xy 137.664426 -49.134777) (xy 137.608692 -49.13274) (xy 137.553849 -49.12261)
			(xy 137.501065 -49.104603) (xy 137.451465 -49.079102) (xy 137.406107 -49.046651) (xy 137.365958 -49.007942)
			(xy 137.331872 -48.963799) (xy 137.304576 -48.915164) (xy 137.284653 -48.863073) (xy 137.272527 -48.808636)
			(xy 137.268456 -48.753014) (xy 130.72704 -48.753014) (xy 130.544521 -49.95291) (xy 143.03324 -49.95291)
			(xy 143.037311 -49.897288) (xy 143.049437 -49.842851) (xy 143.06936 -49.79076) (xy 143.096656 -49.742125)
			(xy 143.130742 -49.697982) (xy 143.170891 -49.659273) (xy 143.216249 -49.626822) (xy 143.265849 -49.601321)
			(xy 143.318633 -49.583314) (xy 143.373476 -49.573184) (xy 143.42921 -49.571147) (xy 143.484647 -49.577247)
			(xy 143.538604 -49.591353) (xy 143.589933 -49.613165) (xy 143.637539 -49.642219) (xy 143.680407 -49.677894)
			(xy 143.717624 -49.719431) (xy 143.748397 -49.765944) (xy 143.772069 -49.816441) (xy 143.788137 -49.869848)
			(xy 143.796257 -49.925024) (xy 143.796766 -49.95291) (xy 143.796257 -49.980796) (xy 143.788137 -50.035972)
			(xy 143.772069 -50.089379) (xy 143.748397 -50.139876) (xy 143.717624 -50.186389) (xy 143.680407 -50.227926)
			(xy 143.637539 -50.263601) (xy 143.589933 -50.292655) (xy 143.538604 -50.314467) (xy 143.484647 -50.328573)
			(xy 143.42921 -50.334673) (xy 143.373476 -50.332636) (xy 143.318633 -50.322506) (xy 143.265849 -50.304499)
			(xy 143.216249 -50.278998) (xy 143.170891 -50.246547) (xy 143.130742 -50.207838) (xy 143.096656 -50.163695)
			(xy 143.06936 -50.11506) (xy 143.049437 -50.062969) (xy 143.037311 -50.008532) (xy 143.03324 -49.95291)
			(xy 130.544521 -49.95291) (xy 130.531616 -50.037746) (xy 130.531616 -50.038254) (xy 130.527806 -50.06213)
			(xy 130.527552 -50.063908) (xy 130.52679 -50.068988) (xy 130.421888 -50.758598) (xy 130.382178 -51.019456)
			(xy 140.849602 -51.019456) (xy 140.853673 -50.963834) (xy 140.865799 -50.909397) (xy 140.885722 -50.857306)
			(xy 140.913018 -50.808671) (xy 140.947104 -50.764528) (xy 140.987253 -50.725819) (xy 141.032611 -50.693368)
			(xy 141.082211 -50.667867) (xy 141.134995 -50.64986) (xy 141.189838 -50.63973) (xy 141.245572 -50.637693)
			(xy 141.301009 -50.643793) (xy 141.354966 -50.657899) (xy 141.406295 -50.679711) (xy 141.453901 -50.708765)
			(xy 141.496769 -50.74444) (xy 141.533986 -50.785977) (xy 141.564759 -50.83249) (xy 141.588431 -50.882987)
			(xy 141.604499 -50.936394) (xy 141.612619 -50.99157) (xy 141.613128 -51.019456) (xy 141.612619 -51.047342)
			(xy 141.604499 -51.102518) (xy 141.588431 -51.155925) (xy 141.564759 -51.206422) (xy 141.539903 -51.243992)
			(xy 149.233128 -51.243992) (xy 149.233583 -51.216621) (xy 149.241402 -51.162441) (xy 149.256894 -51.109938)
			(xy 149.279738 -51.060191) (xy 149.309465 -51.014225) (xy 149.327108 -50.993294) (xy 149.327362 -50.99304)
			(xy 149.332945 -50.985951) (xy 149.339192 -50.969036) (xy 149.339554 -50.96002) (xy 149.339554 -50.892964)
			(xy 149.339224 -50.883944) (xy 149.332959 -50.867027) (xy 149.327362 -50.859944) (xy 149.327108 -50.859944)
			(xy 149.327108 -50.85969) (xy 149.309452 -50.838772) (xy 149.279742 -50.792795) (xy 149.25691 -50.743044)
			(xy 149.241423 -50.69054) (xy 149.233599 -50.636362) (xy 149.233128 -50.608992) (xy 149.233548 -50.581737)
			(xy 149.241307 -50.527783) (xy 149.256666 -50.475482) (xy 149.279312 -50.4259) (xy 149.308784 -50.380045)
			(xy 149.344482 -50.338851) (xy 149.38568 -50.303158) (xy 149.431538 -50.273691) (xy 149.481123 -50.25105)
			(xy 149.533426 -50.235698) (xy 149.587381 -50.227945) (xy 149.614636 -50.227484) (xy 149.643553 -50.228017)
			(xy 149.700725 -50.236738) (xy 149.755925 -50.253991) (xy 149.807887 -50.27938) (xy 149.855421 -50.312323)
			(xy 149.897437 -50.352064) (xy 149.915626 -50.37455) (xy 149.923223 -50.383368) (xy 149.944132 -50.393544)
			(xy 149.955758 -50.394108) (xy 150.035514 -50.394108) (xy 150.047145 -50.39356) (xy 150.068054 -50.383377)
			(xy 150.075646 -50.37455) (xy 150.093855 -50.352082) (xy 150.135872 -50.312348) (xy 150.183404 -50.279409)
			(xy 150.235362 -50.254018) (xy 150.290555 -50.236758) (xy 150.347721 -50.228023) (xy 150.376636 -50.227484)
			(xy 150.403888 -50.227944) (xy 150.457836 -50.235706) (xy 150.510131 -50.251065) (xy 150.559708 -50.27371)
			(xy 150.605557 -50.303179) (xy 150.646747 -50.338873) (xy 150.682438 -50.380065) (xy 150.711904 -50.425917)
			(xy 150.734545 -50.475496) (xy 150.7499 -50.527791) (xy 150.757658 -50.58174) (xy 150.758144 -50.608992)
			(xy 150.757689 -50.635307) (xy 150.750454 -50.687436) (xy 150.736134 -50.73808) (xy 150.714999 -50.786279)
			(xy 150.68745 -50.831122) (xy 150.654008 -50.871761) (xy 150.634954 -50.889916) (xy 150.627551 -50.897437)
			(xy 150.619026 -50.916717) (xy 150.618444 -50.927254) (xy 150.618444 -51.00193) (xy 150.618984 -51.012479)
			(xy 150.62751 -51.031775) (xy 150.634954 -51.039268) (xy 150.654046 -51.057387) (xy 150.687498 -51.098026)
			(xy 150.715051 -51.142874) (xy 150.736182 -51.191082) (xy 150.750492 -51.241735) (xy 150.757709 -51.293874)
			(xy 150.758144 -51.320192) (xy 150.757615 -51.347441) (xy 150.74986 -51.401386) (xy 150.734508 -51.453677)
			(xy 150.711871 -51.503252) (xy 150.682408 -51.549101) (xy 150.646722 -51.59029) (xy 150.605536 -51.625982)
			(xy 150.559691 -51.655449) (xy 150.510119 -51.678093) (xy 150.457829 -51.693451) (xy 150.403885 -51.701212)
			(xy 150.376636 -51.7017) (xy 150.348972 -51.70116) (xy 150.294224 -51.693165) (xy 150.241203 -51.677354)
			(xy 150.191019 -51.654055) (xy 150.144723 -51.623758) (xy 150.103284 -51.587097) (xy 150.06757 -51.544839)
			(xy 150.052532 -51.521614) (xy 150.04589 -51.511942) (xy 150.026032 -51.499497) (xy 150.014432 -51.497738)
			(xy 149.934422 -51.489864) (xy 149.922784 -51.489249) (xy 149.900947 -51.497317) (xy 149.892512 -51.505358)
			(xy 149.892258 -51.505612) (xy 149.874182 -51.524198) (xy 149.833849 -51.556776) (xy 149.789473 -51.583588)
			(xy 149.741874 -51.604139) (xy 149.691929 -51.618052) (xy 149.640559 -51.625069) (xy 149.614636 -51.6255)
			(xy 149.587384 -51.625011) (xy 149.533433 -51.617259) (xy 149.481135 -51.601907) (xy 149.431555 -51.579268)
			(xy 149.385701 -51.549803) (xy 149.344508 -51.514112) (xy 149.308814 -51.472921) (xy 149.279345 -51.42707)
			(xy 149.256703 -51.377491) (xy 149.241347 -51.325194) (xy 149.233591 -51.271244) (xy 149.233128 -51.243992)
			(xy 141.539903 -51.243992) (xy 141.533986 -51.252935) (xy 141.496769 -51.294472) (xy 141.453901 -51.330147)
			(xy 141.406295 -51.359201) (xy 141.354966 -51.381013) (xy 141.301009 -51.395119) (xy 141.245572 -51.401219)
			(xy 141.189838 -51.399182) (xy 141.134995 -51.389052) (xy 141.082211 -51.371045) (xy 141.032611 -51.345544)
			(xy 140.987253 -51.313093) (xy 140.947104 -51.274384) (xy 140.913018 -51.230241) (xy 140.885722 -51.181606)
			(xy 140.865799 -51.129515) (xy 140.853673 -51.075078) (xy 140.849602 -51.019456) (xy 130.382178 -51.019456)
			(xy 130.374136 -51.072288) (xy 130.341878 -51.283616) (xy 130.341878 -51.284378) (xy 130.341624 -51.286156)
			(xy 130.227792 -52.035456) (xy 143.041368 -52.035456) (xy 143.045439 -51.979834) (xy 143.057565 -51.925397)
			(xy 143.077488 -51.873306) (xy 143.104784 -51.824671) (xy 143.13887 -51.780528) (xy 143.179019 -51.741819)
			(xy 143.224377 -51.709368) (xy 143.273977 -51.683867) (xy 143.326761 -51.66586) (xy 143.381604 -51.65573)
			(xy 143.437338 -51.653693) (xy 143.492775 -51.659793) (xy 143.546732 -51.673899) (xy 143.598061 -51.695711)
			(xy 143.645667 -51.724765) (xy 143.688535 -51.76044) (xy 143.725752 -51.801977) (xy 143.756525 -51.84849)
			(xy 143.780197 -51.898987) (xy 143.796265 -51.952394) (xy 143.804385 -52.00757) (xy 143.804894 -52.035456)
			(xy 143.804385 -52.063342) (xy 143.796265 -52.118518) (xy 143.780197 -52.171925) (xy 143.756525 -52.222422)
			(xy 143.725752 -52.268935) (xy 143.688535 -52.310472) (xy 143.645667 -52.346147) (xy 143.598061 -52.375201)
			(xy 143.546732 -52.397013) (xy 143.492775 -52.411119) (xy 143.437338 -52.417219) (xy 143.381604 -52.415182)
			(xy 143.326761 -52.405052) (xy 143.273977 -52.387045) (xy 143.224377 -52.361544) (xy 143.179019 -52.329093)
			(xy 143.13887 -52.290384) (xy 143.104784 -52.246241) (xy 143.077488 -52.197606) (xy 143.057565 -52.145515)
			(xy 143.045439 -52.091078) (xy 143.041368 -52.035456) (xy 130.227792 -52.035456) (xy 130.21691 -52.107084)
			(xy 130.216402 -52.113688) (xy 130.211576 -52.414424) (xy 130.210814 -52.467256) (xy 130.21086 -52.473381)
			(xy 130.213566 -52.485323) (xy 130.216148 -52.490878) (xy 130.228086 -52.514754) (xy 130.235198 -52.523644)
			(xy 130.239516 -52.526946) (xy 130.26165 -52.545193) (xy 130.300721 -52.587189) (xy 130.333085 -52.634548)
			(xy 130.358014 -52.686209) (xy 130.374949 -52.741013) (xy 130.383512 -52.797731) (xy 130.384042 -52.826412)
			(xy 130.383026 -52.855876) (xy 130.381248 -52.871116) (xy 130.381248 -52.87137) (xy 130.379326 -52.886157)
			(xy 130.373476 -52.9154) (xy 130.369564 -52.92979) (xy 130.362388 -52.953812) (xy 130.3426 -52.999876)
			(xy 130.316958 -53.042957) (xy 130.301746 -53.062886) (xy 130.298952 -53.066442) (xy 130.292348 -53.078888)
			(xy 130.289808 -53.090064) (xy 130.289808 -53.117242) (xy 130.289664 -53.122681) (xy 130.287355 -53.133312)
			(xy 130.285236 -53.138324) (xy 130.27914 -53.151786) (xy 130.27552 -53.160448) (xy 130.274288 -53.179169)
			(xy 130.279911 -53.197068) (xy 130.28549 -53.204618) (xy 130.291078 -53.21173) (xy 130.294634 -53.216302)
			(xy 130.295142 -53.217064) (xy 130.29565 -53.217572) (xy 130.296412 -53.218588) (xy 130.312599 -53.238852)
			(xy 130.339922 -53.282935) (xy 130.361016 -53.330315) (xy 130.375492 -53.380117) (xy 130.383083 -53.431422)
			(xy 130.383788 -53.457348) (xy 130.383788 -53.460396) (xy 130.383452 -53.48578) (xy 130.376887 -53.536119)
			(xy 130.363711 -53.585145) (xy 130.354324 -53.608732) (xy 130.354324 -53.608986) (xy 130.35407 -53.609494)
			(xy 130.3528 -53.612288) (xy 130.352292 -53.613304) (xy 130.35026 -53.61813) (xy 130.334258 -53.649372)
			(xy 130.328927 -53.658668) (xy 130.317363 -53.676713) (xy 130.311144 -53.68544) (xy 130.305048 -53.693822)
			(xy 130.300476 -53.699664) (xy 130.296158 -53.706522) (xy 130.295142 -53.708554) (xy 130.292681 -53.71388)
			(xy 130.289989 -53.725296) (xy 130.289808 -53.73116) (xy 130.289808 -53.752242) (xy 130.289664 -53.757681)
			(xy 130.287355 -53.768312) (xy 130.285236 -53.773324) (xy 130.27914 -53.786786) (xy 130.27552 -53.795448)
			(xy 130.274288 -53.814169) (xy 130.279911 -53.832068) (xy 130.28549 -53.839618) (xy 130.291078 -53.84673)
			(xy 130.294634 -53.851302) (xy 130.295142 -53.852064) (xy 130.29565 -53.852572) (xy 130.296412 -53.853588)
			(xy 130.312599 -53.873852) (xy 130.339922 -53.917935) (xy 130.361016 -53.965315) (xy 130.375492 -54.015117)
			(xy 130.383083 -54.066422) (xy 130.383788 -54.092348) (xy 130.383788 -54.095396) (xy 130.383452 -54.12078)
			(xy 130.376887 -54.171119) (xy 130.363711 -54.220145) (xy 130.354324 -54.243732) (xy 130.354324 -54.243986)
			(xy 130.35407 -54.244494) (xy 130.3528 -54.247288) (xy 130.352292 -54.248304) (xy 130.35026 -54.25313)
			(xy 130.334258 -54.284372) (xy 130.328927 -54.293668) (xy 130.317363 -54.311713) (xy 130.311144 -54.32044)
			(xy 130.305048 -54.328822) (xy 130.300476 -54.334664) (xy 130.296158 -54.341522) (xy 130.295142 -54.343554)
			(xy 130.292681 -54.34888) (xy 130.289989 -54.360296) (xy 130.289808 -54.36616) (xy 130.289808 -54.387242)
			(xy 130.289664 -54.392681) (xy 130.287355 -54.403312) (xy 130.285236 -54.408324) (xy 130.27914 -54.421786)
			(xy 130.27552 -54.430448) (xy 130.274288 -54.449169) (xy 130.279911 -54.467068) (xy 130.28549 -54.474618)
			(xy 130.291078 -54.48173) (xy 130.294634 -54.486302) (xy 130.295142 -54.487064) (xy 130.296666 -54.488842)
			(xy 130.315559 -54.51271) (xy 130.346316 -54.565236) (xy 130.368354 -54.621975) (xy 130.381115 -54.681491)
			(xy 130.38328 -54.711854) (xy 130.383788 -54.730396) (xy 130.383788 -54.731412) (xy 130.383272 -54.759821)
			(xy 130.378588 -54.791102) (xy 132.276596 -54.791102) (xy 132.277064 -54.763732) (xy 132.284882 -54.709553)
			(xy 132.30037 -54.65705) (xy 132.323212 -54.607303) (xy 132.352935 -54.561336) (xy 132.370576 -54.540404)
			(xy 132.37083 -54.54015) (xy 132.376405 -54.533056) (xy 132.382658 -54.516145) (xy 132.383022 -54.50713)
			(xy 132.383022 -54.440074) (xy 132.382673 -54.431056) (xy 132.376419 -54.41414) (xy 132.37083 -54.407054)
			(xy 132.370576 -54.407054) (xy 132.370576 -54.4068) (xy 132.352935 -54.385867) (xy 132.323207 -54.3399)
			(xy 132.300358 -54.290154) (xy 132.28486 -54.237652) (xy 132.27703 -54.183473) (xy 132.27703 -54.12873)
			(xy 132.284859 -54.074551) (xy 132.300357 -54.022049) (xy 132.323205 -53.972302) (xy 132.352933 -53.926336)
			(xy 132.370576 -53.905404) (xy 132.37083 -53.90515) (xy 132.376405 -53.898056) (xy 132.382658 -53.881145)
			(xy 132.383022 -53.87213) (xy 132.383022 -53.805074) (xy 132.382673 -53.796056) (xy 132.376419 -53.77914)
			(xy 132.37083 -53.772054) (xy 132.370576 -53.772054) (xy 132.370576 -53.7718) (xy 132.352935 -53.750867)
			(xy 132.323207 -53.7049) (xy 132.300358 -53.655154) (xy 132.28486 -53.602652) (xy 132.27703 -53.548473)
			(xy 132.27703 -53.49373) (xy 132.284859 -53.439551) (xy 132.300357 -53.387049) (xy 132.323205 -53.337302)
			(xy 132.352933 -53.291336) (xy 132.370576 -53.270404) (xy 132.37083 -53.27015) (xy 132.376405 -53.263056)
			(xy 132.382658 -53.246145) (xy 132.383022 -53.23713) (xy 132.383022 -53.170074) (xy 132.382673 -53.161056)
			(xy 132.376419 -53.14414) (xy 132.37083 -53.137054) (xy 132.370576 -53.137054) (xy 132.370576 -53.1368)
			(xy 132.35292 -53.115882) (xy 132.323211 -53.069905) (xy 132.300379 -53.020154) (xy 132.284892 -52.96765)
			(xy 132.277068 -52.913472) (xy 132.276596 -52.886102) (xy 132.277082 -52.858851) (xy 132.284838 -52.804903)
			(xy 132.300193 -52.752608) (xy 132.322835 -52.703031) (xy 132.352301 -52.657181) (xy 132.387992 -52.61599)
			(xy 132.429183 -52.580299) (xy 132.475033 -52.550833) (xy 132.52461 -52.528191) (xy 132.576905 -52.512836)
			(xy 132.630853 -52.50508) (xy 132.685355 -52.50508) (xy 132.739303 -52.512836) (xy 132.791598 -52.528191)
			(xy 132.830698 -52.546048) (xy 137.779796 -52.546048) (xy 137.779796 -52.491552) (xy 137.787551 -52.43761)
			(xy 137.802904 -52.385321) (xy 137.825541 -52.335749) (xy 137.855002 -52.289903) (xy 137.890687 -52.248716)
			(xy 137.931871 -52.213026) (xy 137.977714 -52.18356) (xy 138.027284 -52.160918) (xy 138.079571 -52.14556)
			(xy 138.133512 -52.137799) (xy 138.16076 -52.13731) (xy 138.18813 -52.137797) (xy 138.242308 -52.145609)
			(xy 138.294811 -52.161093) (xy 138.344558 -52.183931) (xy 138.390526 -52.213651) (xy 138.411458 -52.23129)
			(xy 138.411712 -52.231544) (xy 138.418787 -52.237147) (xy 138.435713 -52.243383) (xy 138.444732 -52.243736)
			(xy 138.511788 -52.243736) (xy 138.520803 -52.243365) (xy 138.53772 -52.237126) (xy 138.544808 -52.231544)
			(xy 138.544808 -52.23129) (xy 138.545062 -52.23129) (xy 138.565995 -52.213649) (xy 138.611963 -52.183925)
			(xy 138.661709 -52.161079) (xy 138.714211 -52.145583) (xy 138.768389 -52.137754) (xy 138.823131 -52.137754)
			(xy 138.877309 -52.145583) (xy 138.929811 -52.161079) (xy 138.979557 -52.183925) (xy 139.025525 -52.213649)
			(xy 139.046458 -52.23129) (xy 139.046712 -52.231544) (xy 139.053787 -52.237147) (xy 139.070713 -52.243383)
			(xy 139.079732 -52.243736) (xy 139.146788 -52.243736) (xy 139.155803 -52.243365) (xy 139.17272 -52.237126)
			(xy 139.179808 -52.231544) (xy 139.179808 -52.23129) (xy 139.180062 -52.23129) (xy 139.200996 -52.213654)
			(xy 139.246969 -52.183942) (xy 139.296716 -52.161105) (xy 139.349216 -52.145614) (xy 139.403391 -52.137785)
			(xy 139.43076 -52.13731) (xy 139.458016 -52.137734) (xy 139.511974 -52.145487) (xy 139.564279 -52.16084)
			(xy 139.613867 -52.183482) (xy 139.659727 -52.21295) (xy 139.700926 -52.248645) (xy 139.736626 -52.289841)
			(xy 139.766099 -52.335698) (xy 139.788746 -52.385283) (xy 139.804105 -52.437587) (xy 139.811863 -52.491544)
			(xy 139.811863 -52.546056) (xy 139.805919 -52.587398) (xy 140.855444 -52.587398) (xy 140.859515 -52.531776)
			(xy 140.871641 -52.477339) (xy 140.891564 -52.425248) (xy 140.91886 -52.376613) (xy 140.952946 -52.33247)
			(xy 140.993095 -52.293761) (xy 141.038453 -52.26131) (xy 141.088053 -52.235809) (xy 141.140837 -52.217802)
			(xy 141.19568 -52.207672) (xy 141.251414 -52.205635) (xy 141.306851 -52.211735) (xy 141.360808 -52.225841)
			(xy 141.412137 -52.247653) (xy 141.459743 -52.276707) (xy 141.502611 -52.312382) (xy 141.539828 -52.353919)
			(xy 141.570601 -52.400432) (xy 141.594273 -52.450929) (xy 141.610341 -52.504336) (xy 141.617937 -52.555949)
			(xy 148.684002 -52.555949) (xy 148.684002 -52.501451) (xy 148.691758 -52.447509) (xy 148.707111 -52.395219)
			(xy 148.729749 -52.345646) (xy 148.759212 -52.2998) (xy 148.794899 -52.258613) (xy 148.836084 -52.222924)
			(xy 148.881929 -52.193459) (xy 148.9315 -52.170818) (xy 148.983789 -52.155462) (xy 149.037731 -52.147704)
			(xy 149.06498 -52.147216) (xy 149.09235 -52.14769) (xy 149.146529 -52.155505) (xy 149.199032 -52.170992)
			(xy 149.248779 -52.193832) (xy 149.294746 -52.223555) (xy 149.315678 -52.241196) (xy 149.315932 -52.24145)
			(xy 149.32303 -52.24702) (xy 149.339938 -52.253276) (xy 149.348952 -52.253642) (xy 149.416008 -52.253642)
			(xy 149.425027 -52.253301) (xy 149.441944 -52.247044) (xy 149.449028 -52.24145) (xy 149.449028 -52.241196)
			(xy 149.449282 -52.241196) (xy 149.47021 -52.223551) (xy 149.516184 -52.19384) (xy 149.565932 -52.171006)
			(xy 149.618434 -52.155516) (xy 149.672611 -52.147689) (xy 149.69998 -52.147216) (xy 149.727236 -52.14763)
			(xy 149.781192 -52.155385) (xy 149.833496 -52.17074) (xy 149.883081 -52.193383) (xy 149.92894 -52.222852)
			(xy 149.970138 -52.258548) (xy 150.005836 -52.299744) (xy 150.035308 -52.345601) (xy 150.057953 -52.395186)
			(xy 150.073311 -52.447488) (xy 150.081069 -52.501444) (xy 150.081069 -52.555956) (xy 150.073311 -52.609912)
			(xy 150.057953 -52.662214) (xy 150.035308 -52.711799) (xy 150.005836 -52.757656) (xy 149.970138 -52.798852)
			(xy 149.92894 -52.834548) (xy 149.883081 -52.864017) (xy 149.833496 -52.88666) (xy 149.781192 -52.902015)
			(xy 149.727236 -52.90977) (xy 149.69998 -52.910232) (xy 149.672609 -52.909794) (xy 149.618428 -52.901972)
			(xy 149.565924 -52.886477) (xy 149.516177 -52.863629) (xy 149.470212 -52.833897) (xy 149.449282 -52.816252)
			(xy 149.449028 -52.815998) (xy 149.441938 -52.810417) (xy 149.425024 -52.804167) (xy 149.416008 -52.803806)
			(xy 149.348952 -52.803806) (xy 149.339938 -52.804187) (xy 149.32302 -52.810418) (xy 149.315932 -52.815998)
			(xy 149.315932 -52.816252) (xy 149.315678 -52.816252) (xy 149.294721 -52.833861) (xy 149.248756 -52.863579)
			(xy 149.199015 -52.886421) (xy 149.146519 -52.901919) (xy 149.092348 -52.909754) (xy 149.06498 -52.910232)
			(xy 149.037731 -52.909696) (xy 148.983789 -52.901938) (xy 148.9315 -52.886582) (xy 148.881929 -52.863941)
			(xy 148.836084 -52.834476) (xy 148.794899 -52.798787) (xy 148.759212 -52.7576) (xy 148.729749 -52.711754)
			(xy 148.707111 -52.662181) (xy 148.691758 -52.609891) (xy 148.684002 -52.555949) (xy 141.617937 -52.555949)
			(xy 141.618461 -52.559512) (xy 141.61897 -52.587398) (xy 141.618461 -52.615284) (xy 141.610341 -52.67046)
			(xy 141.594273 -52.723867) (xy 141.570601 -52.774364) (xy 141.539828 -52.820877) (xy 141.502611 -52.862414)
			(xy 141.459743 -52.898089) (xy 141.412137 -52.927143) (xy 141.360808 -52.948955) (xy 141.306851 -52.963061)
			(xy 141.251414 -52.969161) (xy 141.19568 -52.967124) (xy 141.140837 -52.956994) (xy 141.088053 -52.938987)
			(xy 141.038453 -52.913486) (xy 140.993095 -52.881035) (xy 140.952946 -52.842326) (xy 140.91886 -52.798183)
			(xy 140.891564 -52.749548) (xy 140.871641 -52.697457) (xy 140.859515 -52.64302) (xy 140.855444 -52.587398)
			(xy 139.805919 -52.587398) (xy 139.804105 -52.600013) (xy 139.788746 -52.652317) (xy 139.766099 -52.701902)
			(xy 139.736626 -52.747759) (xy 139.700926 -52.788955) (xy 139.659727 -52.82465) (xy 139.613867 -52.854118)
			(xy 139.564279 -52.87676) (xy 139.511974 -52.892113) (xy 139.458016 -52.899866) (xy 139.43076 -52.900326)
			(xy 139.40339 -52.899843) (xy 139.349211 -52.892032) (xy 139.296707 -52.876548) (xy 139.24696 -52.853709)
			(xy 139.200993 -52.823987) (xy 139.180062 -52.806346) (xy 139.179808 -52.806092) (xy 139.172724 -52.800502)
			(xy 139.155805 -52.794258) (xy 139.146788 -52.7939) (xy 139.079732 -52.7939) (xy 139.070717 -52.794272)
			(xy 139.0538 -52.800509) (xy 139.046712 -52.806092) (xy 139.046458 -52.806346) (xy 139.025525 -52.823987)
			(xy 138.979557 -52.853711) (xy 138.929811 -52.876557) (xy 138.877309 -52.892053) (xy 138.823131 -52.899882)
			(xy 138.768389 -52.899882) (xy 138.714211 -52.892053) (xy 138.661709 -52.876557) (xy 138.611963 -52.853711)
			(xy 138.565995 -52.823987) (xy 138.545062 -52.806346) (xy 138.544808 -52.806092) (xy 138.537724 -52.800502)
			(xy 138.520805 -52.794258) (xy 138.511788 -52.7939) (xy 138.444732 -52.7939) (xy 138.435717 -52.794272)
			(xy 138.4188 -52.800509) (xy 138.411712 -52.806092) (xy 138.411712 -52.806346) (xy 138.411458 -52.806346)
			(xy 138.390508 -52.823963) (xy 138.344541 -52.85368) (xy 138.294798 -52.876521) (xy 138.242301 -52.892017)
			(xy 138.188128 -52.89985) (xy 138.16076 -52.900326) (xy 138.133512 -52.899801) (xy 138.079571 -52.89204)
			(xy 138.027284 -52.876682) (xy 137.977714 -52.85404) (xy 137.931871 -52.824574) (xy 137.890687 -52.788884)
			(xy 137.855002 -52.747697) (xy 137.825541 -52.701851) (xy 137.802904 -52.652279) (xy 137.787551 -52.59999)
			(xy 137.779796 -52.546048) (xy 132.830698 -52.546048) (xy 132.841175 -52.550833) (xy 132.887025 -52.580299)
			(xy 132.928216 -52.61599) (xy 132.963907 -52.657181) (xy 132.993373 -52.703031) (xy 133.016015 -52.752608)
			(xy 133.03137 -52.804903) (xy 133.039126 -52.858851) (xy 133.039612 -52.886102) (xy 133.039144 -52.913472)
			(xy 133.031326 -52.967651) (xy 133.015837 -53.020154) (xy 132.992996 -53.069901) (xy 132.963273 -53.115868)
			(xy 132.945632 -53.1368) (xy 132.945378 -53.137054) (xy 132.939802 -53.144148) (xy 132.93355 -53.161059)
			(xy 132.933186 -53.170074) (xy 132.933186 -53.23713) (xy 132.933531 -53.246148) (xy 132.939787 -53.263065)
			(xy 132.945378 -53.27015) (xy 132.945632 -53.27015) (xy 132.945632 -53.270404) (xy 132.963276 -53.291334)
			(xy 132.993004 -53.337302) (xy 133.015852 -53.387048) (xy 133.03135 -53.439551) (xy 133.039179 -53.49373)
			(xy 133.039179 -53.548473) (xy 133.031349 -53.602652) (xy 133.015851 -53.655155) (xy 132.993003 -53.704901)
			(xy 132.963275 -53.750868) (xy 132.946702 -53.77053) (xy 133.310884 -53.77053) (xy 133.311392 -53.741612)
			(xy 133.320119 -53.684439) (xy 133.337376 -53.629239) (xy 133.36277 -53.577276) (xy 133.395717 -53.529743)
			(xy 133.435462 -53.487728) (xy 133.45795 -53.46954) (xy 133.466738 -53.461914) (xy 133.47693 -53.441027)
			(xy 133.477508 -53.429408) (xy 133.477508 -53.349652) (xy 133.476979 -53.338019) (xy 133.466783 -53.31711)
			(xy 133.45795 -53.30952) (xy 133.435466 -53.29133) (xy 133.395733 -53.249309) (xy 133.362795 -53.201773)
			(xy 133.337408 -53.149812) (xy 133.320151 -53.094615) (xy 133.31142 -53.037446) (xy 133.310884 -53.00853)
			(xy 133.311383 -52.981278) (xy 133.319136 -52.927329) (xy 133.334488 -52.875032) (xy 133.357126 -52.825453)
			(xy 133.38659 -52.7796) (xy 133.42228 -52.738407) (xy 133.463469 -52.702713) (xy 133.509319 -52.673244)
			(xy 133.558897 -52.650601) (xy 133.611192 -52.635244) (xy 133.66514 -52.627486) (xy 133.692392 -52.627022)
			(xy 133.718706 -52.627488) (xy 133.770835 -52.634722) (xy 133.821478 -52.649041) (xy 133.869677 -52.670174)
			(xy 133.914521 -52.69772) (xy 133.95516 -52.73116) (xy 133.973316 -52.750212) (xy 133.980828 -52.757625)
			(xy 134.000115 -52.766142) (xy 134.010654 -52.766722) (xy 134.08533 -52.766722) (xy 134.095876 -52.766162)
			(xy 134.115171 -52.757648) (xy 134.122668 -52.750212) (xy 134.1408 -52.731133) (xy 134.181434 -52.697677)
			(xy 134.22628 -52.670121) (xy 134.274485 -52.648987) (xy 134.325137 -52.634675) (xy 134.377274 -52.627457)
			(xy 134.403592 -52.627022) (xy 134.430846 -52.627463) (xy 134.484799 -52.63522) (xy 134.537099 -52.650576)
			(xy 134.586682 -52.67322) (xy 134.632536 -52.70269) (xy 134.67373 -52.738386) (xy 134.709423 -52.779582)
			(xy 134.738891 -52.825438) (xy 134.761532 -52.875021) (xy 134.776885 -52.927322) (xy 134.784639 -52.981276)
			(xy 134.7851 -53.00853) (xy 134.784611 -53.036196) (xy 134.78238 -53.051456) (xy 143.041368 -53.051456)
			(xy 143.045439 -52.995834) (xy 143.057565 -52.941397) (xy 143.077488 -52.889306) (xy 143.104784 -52.840671)
			(xy 143.13887 -52.796528) (xy 143.179019 -52.757819) (xy 143.224377 -52.725368) (xy 143.273977 -52.699867)
			(xy 143.326761 -52.68186) (xy 143.381604 -52.67173) (xy 143.437338 -52.669693) (xy 143.492775 -52.675793)
			(xy 143.546732 -52.689899) (xy 143.598061 -52.711711) (xy 143.645667 -52.740765) (xy 143.688535 -52.77644)
			(xy 143.725752 -52.817977) (xy 143.756525 -52.86449) (xy 143.780197 -52.914987) (xy 143.796265 -52.968394)
			(xy 143.804385 -53.02357) (xy 143.804894 -53.051456) (xy 143.804385 -53.079342) (xy 143.796265 -53.134518)
			(xy 143.780197 -53.187925) (xy 143.756525 -53.238422) (xy 143.725752 -53.284935) (xy 143.688535 -53.326472)
			(xy 143.645667 -53.362147) (xy 143.598061 -53.391201) (xy 143.546732 -53.413013) (xy 143.492775 -53.427119)
			(xy 143.437338 -53.433219) (xy 143.381604 -53.431182) (xy 143.326761 -53.421052) (xy 143.273977 -53.403045)
			(xy 143.224377 -53.377544) (xy 143.179019 -53.345093) (xy 143.13887 -53.306384) (xy 143.104784 -53.262241)
			(xy 143.077488 -53.213606) (xy 143.057565 -53.161515) (xy 143.045439 -53.107078) (xy 143.041368 -53.051456)
			(xy 134.78238 -53.051456) (xy 134.776608 -53.090946) (xy 134.760787 -53.143968) (xy 134.73748 -53.194152)
			(xy 134.707175 -53.240448) (xy 134.670507 -53.281885) (xy 134.628242 -53.317597) (xy 134.605014 -53.332634)
			(xy 134.595316 -53.339245) (xy 134.582884 -53.359125) (xy 134.581138 -53.370734) (xy 134.573264 -53.450744)
			(xy 134.572608 -53.462383) (xy 134.580704 -53.484222) (xy 134.588758 -53.492654) (xy 134.589012 -53.492908)
			(xy 134.607581 -53.511) (xy 134.640161 -53.55133) (xy 134.666975 -53.595702) (xy 134.68753 -53.643298)
			(xy 134.701446 -53.69324) (xy 134.708466 -53.744608) (xy 134.7089 -53.77053) (xy 134.70845 -53.797782)
			(xy 134.700689 -53.851732) (xy 134.68533 -53.904028) (xy 134.662685 -53.953606) (xy 134.633215 -53.999456)
			(xy 134.597519 -54.040646) (xy 134.556326 -54.076337) (xy 134.510472 -54.105803) (xy 134.460892 -54.128443)
			(xy 134.408595 -54.143797) (xy 134.354644 -54.151553) (xy 134.327392 -54.152038) (xy 134.300021 -54.151592)
			(xy 134.24584 -54.143771) (xy 134.193336 -54.128279) (xy 134.14359 -54.105432) (xy 134.097624 -54.075702)
			(xy 134.076694 -54.058058) (xy 134.07644 -54.057804) (xy 134.069346 -54.052228) (xy 134.052435 -54.045975)
			(xy 134.04342 -54.045612) (xy 133.976364 -54.045612) (xy 133.967345 -54.045949) (xy 133.950428 -54.05221)
			(xy 133.943344 -54.057804) (xy 133.943344 -54.058058) (xy 133.94309 -54.058058) (xy 133.922167 -54.075709)
			(xy 133.876192 -54.10542) (xy 133.826443 -54.128255) (xy 133.77394 -54.143743) (xy 133.719762 -54.151567)
			(xy 133.692392 -54.152038) (xy 133.665142 -54.15153) (xy 133.611197 -54.143773) (xy 133.558904 -54.128418)
			(xy 133.509329 -54.105778) (xy 133.46348 -54.076314) (xy 133.422291 -54.040625) (xy 133.386599 -53.999438)
			(xy 133.357132 -53.953591) (xy 133.334489 -53.904017) (xy 133.319132 -53.851725) (xy 133.311372 -53.79778)
			(xy 133.310884 -53.77053) (xy 132.946702 -53.77053) (xy 132.945632 -53.7718) (xy 132.945378 -53.772054)
			(xy 132.939802 -53.779148) (xy 132.93355 -53.796059) (xy 132.933186 -53.805074) (xy 132.933186 -53.87213)
			(xy 132.933531 -53.881148) (xy 132.939787 -53.898065) (xy 132.945378 -53.90515) (xy 132.945632 -53.90515)
			(xy 132.945632 -53.905404) (xy 132.963276 -53.926334) (xy 132.993004 -53.972302) (xy 133.015852 -54.022048)
			(xy 133.03135 -54.074551) (xy 133.039179 -54.12873) (xy 133.039179 -54.183473) (xy 133.031349 -54.237652)
			(xy 133.015851 -54.290155) (xy 133.002058 -54.320186) (xy 135.230616 -54.320186) (xy 135.23107 -54.292815)
			(xy 135.23889 -54.238636) (xy 135.254382 -54.186132) (xy 135.277226 -54.136385) (xy 135.306954 -54.090419)
			(xy 135.324596 -54.069488) (xy 135.32485 -54.069234) (xy 135.330434 -54.062146) (xy 135.336681 -54.04523)
			(xy 135.337042 -54.036214) (xy 135.337042 -53.969158) (xy 135.33667 -53.960142) (xy 135.330434 -53.943225)
			(xy 135.32485 -53.936138) (xy 135.324596 -53.936138) (xy 135.324596 -53.935884) (xy 135.306982 -53.914932)
			(xy 135.277267 -53.868964) (xy 135.254426 -53.819222) (xy 135.238929 -53.766726) (xy 135.231094 -53.712554)
			(xy 135.230616 -53.685186) (xy 135.231102 -53.657935) (xy 135.238858 -53.603987) (xy 135.254213 -53.551692)
			(xy 135.276855 -53.502115) (xy 135.306321 -53.456265) (xy 135.342012 -53.415074) (xy 135.383203 -53.379383)
			(xy 135.429053 -53.349917) (xy 135.47863 -53.327275) (xy 135.530925 -53.31192) (xy 135.584873 -53.304164)
			(xy 135.639375 -53.304164) (xy 135.693323 -53.31192) (xy 135.745618 -53.327275) (xy 135.795195 -53.349917)
			(xy 135.841045 -53.379383) (xy 135.882236 -53.415074) (xy 135.917927 -53.456265) (xy 135.94382 -53.496556)
			(xy 148.233541 -53.496556) (xy 148.233541 -53.442044) (xy 148.241299 -53.388088) (xy 148.256658 -53.335785)
			(xy 148.279304 -53.286201) (xy 148.308777 -53.240344) (xy 148.344476 -53.199149) (xy 148.385674 -53.163454)
			(xy 148.431534 -53.133986) (xy 148.481121 -53.111344) (xy 148.533425 -53.095991) (xy 148.587382 -53.088238)
			(xy 148.614638 -53.087778) (xy 148.642008 -53.088261) (xy 148.696187 -53.096072) (xy 148.748691 -53.111556)
			(xy 148.798438 -53.134394) (xy 148.844405 -53.164117) (xy 148.865336 -53.181758) (xy 148.86559 -53.182012)
			(xy 148.872674 -53.187602) (xy 148.889593 -53.193846) (xy 148.89861 -53.194204) (xy 148.965666 -53.194204)
			(xy 148.974681 -53.19383) (xy 148.991598 -53.187594) (xy 148.998686 -53.182012) (xy 148.998686 -53.181758)
			(xy 148.99894 -53.181758) (xy 149.019878 -53.164127) (xy 149.06585 -53.134415) (xy 149.115596 -53.111578)
			(xy 149.168095 -53.096085) (xy 149.222269 -53.088254) (xy 149.249638 -53.087778) (xy 149.276886 -53.088295)
			(xy 149.330828 -53.096055) (xy 149.383116 -53.111413) (xy 149.432687 -53.134056) (xy 149.478531 -53.163522)
			(xy 149.519715 -53.199212) (xy 149.555401 -53.2404) (xy 149.584863 -53.286247) (xy 149.6075 -53.335819)
			(xy 149.622853 -53.388109) (xy 149.630608 -53.442052) (xy 149.630608 -53.496548) (xy 149.622853 -53.550491)
			(xy 149.6075 -53.602781) (xy 149.584863 -53.652353) (xy 149.555401 -53.6982) (xy 149.519715 -53.739388)
			(xy 149.478531 -53.775078) (xy 149.432687 -53.804544) (xy 149.383116 -53.827187) (xy 149.330828 -53.842545)
			(xy 149.276886 -53.850305) (xy 149.249638 -53.850794) (xy 149.222269 -53.850307) (xy 149.16809 -53.842495)
			(xy 149.115587 -53.82701) (xy 149.06584 -53.804173) (xy 149.019872 -53.774453) (xy 148.99894 -53.756814)
			(xy 148.998686 -53.75656) (xy 148.991611 -53.750957) (xy 148.974685 -53.744721) (xy 148.965666 -53.744368)
			(xy 148.89861 -53.744368) (xy 148.889594 -53.744737) (xy 148.872678 -53.750977) (xy 148.86559 -53.75656)
			(xy 148.86559 -53.756814) (xy 148.865336 -53.756814) (xy 148.844403 -53.774452) (xy 148.79843 -53.804163)
			(xy 148.748683 -53.826999) (xy 148.696183 -53.842491) (xy 148.642007 -53.85032) (xy 148.614638 -53.850794)
			(xy 148.587382 -53.850362) (xy 148.533425 -53.842609) (xy 148.481121 -53.827256) (xy 148.431534 -53.804614)
			(xy 148.385674 -53.775146) (xy 148.344476 -53.739451) (xy 148.308777 -53.698256) (xy 148.279304 -53.652399)
			(xy 148.256658 -53.602815) (xy 148.241299 -53.550512) (xy 148.233541 -53.496556) (xy 135.94382 -53.496556)
			(xy 135.947393 -53.502115) (xy 135.970035 -53.551692) (xy 135.98539 -53.603987) (xy 135.993146 -53.657935)
			(xy 135.993632 -53.685186) (xy 135.993174 -53.712557) (xy 135.985357 -53.766737) (xy 135.969867 -53.819241)
			(xy 135.947023 -53.868987) (xy 135.917295 -53.914953) (xy 135.899652 -53.935884) (xy 135.899398 -53.936138)
			(xy 135.893831 -53.943238) (xy 135.887573 -53.960144) (xy 135.887206 -53.969158) (xy 135.887206 -54.036214)
			(xy 135.887555 -54.045232) (xy 135.893808 -54.062149) (xy 135.899398 -54.069234) (xy 135.899652 -54.069234)
			(xy 135.899652 -54.069488) (xy 135.917291 -54.09042) (xy 135.947005 -54.136392) (xy 135.969842 -54.186139)
			(xy 135.985332 -54.23864) (xy 135.993159 -54.292817) (xy 135.993632 -54.320186) (xy 135.993146 -54.347437)
			(xy 135.98539 -54.401385) (xy 135.970035 -54.45368) (xy 135.947393 -54.503257) (xy 135.917927 -54.549107)
			(xy 135.882236 -54.590298) (xy 135.841045 -54.625989) (xy 135.795195 -54.655455) (xy 135.745618 -54.678097)
			(xy 135.693323 -54.693452) (xy 135.639375 -54.701208) (xy 135.584873 -54.701208) (xy 135.530925 -54.693452)
			(xy 135.47863 -54.678097) (xy 135.429053 -54.655455) (xy 135.383203 -54.625989) (xy 135.342012 -54.590298)
			(xy 135.306321 -54.549107) (xy 135.276855 -54.503257) (xy 135.254213 -54.45368) (xy 135.238858 -54.401385)
			(xy 135.231102 -54.347437) (xy 135.230616 -54.320186) (xy 133.002058 -54.320186) (xy 132.993003 -54.339901)
			(xy 132.963275 -54.385868) (xy 132.945632 -54.4068) (xy 132.945378 -54.407054) (xy 132.939802 -54.414148)
			(xy 132.93355 -54.431059) (xy 132.933186 -54.440074) (xy 132.933186 -54.50713) (xy 132.933531 -54.516148)
			(xy 132.939787 -54.533065) (xy 132.945378 -54.54015) (xy 132.945632 -54.54015) (xy 132.945632 -54.540404)
			(xy 132.963291 -54.56132) (xy 132.992999 -54.607297) (xy 133.015831 -54.657049) (xy 133.031317 -54.709553)
			(xy 133.03914 -54.763732) (xy 133.039257 -54.770528) (xy 136.171178 -54.770528) (xy 136.171641 -54.743157)
			(xy 136.179457 -54.688977) (xy 136.194946 -54.636474) (xy 136.217788 -54.586727) (xy 136.247515 -54.540761)
			(xy 136.265158 -54.51983) (xy 136.265412 -54.519576) (xy 136.271016 -54.512501) (xy 136.277252 -54.495575)
			(xy 136.277604 -54.486556) (xy 136.277604 -54.4195) (xy 136.277246 -54.410483) (xy 136.270999 -54.393566)
			(xy 136.265412 -54.38648) (xy 136.265158 -54.38648) (xy 136.265158 -54.386226) (xy 136.247511 -54.365301)
			(xy 136.217801 -54.319325) (xy 136.194968 -54.269576) (xy 136.179478 -54.217074) (xy 136.171651 -54.162898)
			(xy 136.171178 -54.135528) (xy 136.171664 -54.108277) (xy 136.17942 -54.054329) (xy 136.194775 -54.002034)
			(xy 136.217417 -53.952457) (xy 136.246883 -53.906607) (xy 136.282574 -53.865416) (xy 136.323765 -53.829725)
			(xy 136.369615 -53.800259) (xy 136.419192 -53.777617) (xy 136.471487 -53.762262) (xy 136.525435 -53.754506)
			(xy 136.579937 -53.754506) (xy 136.633885 -53.762262) (xy 136.68618 -53.777617) (xy 136.735757 -53.800259)
			(xy 136.781607 -53.829725) (xy 136.822798 -53.865416) (xy 136.858489 -53.906607) (xy 136.887955 -53.952457)
			(xy 136.89303 -53.96357) (xy 140.872208 -53.96357) (xy 140.876279 -53.907948) (xy 140.888405 -53.853511)
			(xy 140.908328 -53.80142) (xy 140.935624 -53.752785) (xy 140.96971 -53.708642) (xy 141.009859 -53.669933)
			(xy 141.055217 -53.637482) (xy 141.104817 -53.611981) (xy 141.157601 -53.593974) (xy 141.212444 -53.583844)
			(xy 141.268178 -53.581807) (xy 141.323615 -53.587907) (xy 141.377572 -53.602013) (xy 141.428901 -53.623825)
			(xy 141.476507 -53.652879) (xy 141.519375 -53.688554) (xy 141.556592 -53.730091) (xy 141.587365 -53.776604)
			(xy 141.611037 -53.827101) (xy 141.627105 -53.880508) (xy 141.635225 -53.935684) (xy 141.635734 -53.96357)
			(xy 141.635225 -53.991456) (xy 141.627105 -54.046632) (xy 141.611037 -54.100039) (xy 141.587365 -54.150536)
			(xy 141.556592 -54.197049) (xy 141.519375 -54.238586) (xy 141.476507 -54.274261) (xy 141.428901 -54.303315)
			(xy 141.377572 -54.325127) (xy 141.323615 -54.339233) (xy 141.268178 -54.345333) (xy 141.212444 -54.343296)
			(xy 141.157601 -54.333166) (xy 141.104817 -54.315159) (xy 141.055217 -54.289658) (xy 141.009859 -54.257207)
			(xy 140.96971 -54.218498) (xy 140.935624 -54.174355) (xy 140.908328 -54.12572) (xy 140.888405 -54.073629)
			(xy 140.876279 -54.019192) (xy 140.872208 -53.96357) (xy 136.89303 -53.96357) (xy 136.910597 -54.002034)
			(xy 136.925952 -54.054329) (xy 136.933708 -54.108277) (xy 136.934194 -54.135528) (xy 136.933746 -54.162899)
			(xy 136.925924 -54.217079) (xy 136.910431 -54.269582) (xy 136.887585 -54.319329) (xy 136.857857 -54.365295)
			(xy 136.840214 -54.386226) (xy 136.83996 -54.38648) (xy 136.834371 -54.393565) (xy 136.828127 -54.410483)
			(xy 136.827768 -54.4195) (xy 136.827768 -54.486556) (xy 136.828153 -54.49557) (xy 136.834382 -54.512487)
			(xy 136.83996 -54.519576) (xy 136.840214 -54.519576) (xy 136.840214 -54.51983) (xy 136.857836 -54.540776)
			(xy 136.88755 -54.586745) (xy 136.910389 -54.636489) (xy 136.925884 -54.688987) (xy 136.933717 -54.74316)
			(xy 136.934194 -54.770528) (xy 136.933708 -54.797779) (xy 136.925952 -54.851727) (xy 136.910597 -54.904022)
			(xy 136.887955 -54.953599) (xy 136.865169 -54.989055) (xy 146.001145 -54.989055) (xy 146.001145 -54.934545)
			(xy 146.008903 -54.88059) (xy 146.024261 -54.828288) (xy 146.046906 -54.778704) (xy 146.076378 -54.732848)
			(xy 146.112076 -54.691654) (xy 146.153274 -54.655959) (xy 146.199132 -54.626491) (xy 146.248718 -54.60385)
			(xy 146.301021 -54.588496) (xy 146.354977 -54.580743) (xy 146.382232 -54.580282) (xy 146.410324 -54.580751)
			(xy 146.465903 -54.588983) (xy 146.519672 -54.605279) (xy 146.57047 -54.629286) (xy 146.617196 -54.660484)
			(xy 146.658841 -54.6982) (xy 146.694502 -54.741616) (xy 146.709384 -54.765448) (xy 146.714718 -54.774338)
			(xy 146.731736 -54.78653) (xy 146.824954 -54.80685) (xy 146.845528 -54.802532) (xy 146.854164 -54.79669)
			(xy 146.878235 -54.780702) (xy 146.930164 -54.755357) (xy 146.98532 -54.738128) (xy 147.042442 -54.729409)
			(xy 147.071334 -54.728872) (xy 147.098585 -54.729346) (xy 147.152532 -54.737107) (xy 147.204826 -54.752465)
			(xy 147.254402 -54.775109) (xy 147.300251 -54.804577) (xy 147.341441 -54.840269) (xy 147.377132 -54.88146)
			(xy 147.406598 -54.92731) (xy 147.42924 -54.976887) (xy 147.444596 -55.029181) (xy 147.452355 -55.083129)
			(xy 147.452842 -55.11038) (xy 147.452378 -55.13775) (xy 147.444562 -55.19193) (xy 147.429073 -55.244434)
			(xy 147.406231 -55.294181) (xy 147.376504 -55.340147) (xy 147.358862 -55.361078) (xy 147.358608 -55.361332)
			(xy 147.353045 -55.368435) (xy 147.346784 -55.385339) (xy 147.346416 -55.394352) (xy 147.346416 -55.461408)
			(xy 147.346766 -55.470426) (xy 147.353018 -55.487343) (xy 147.358608 -55.494428) (xy 147.358862 -55.494428)
			(xy 147.358862 -55.494682) (xy 147.376484 -55.51563) (xy 147.40621 -55.561595) (xy 147.429057 -55.611339)
			(xy 147.444555 -55.663839) (xy 147.452386 -55.718015) (xy 147.452388 -55.772755) (xy 147.444562 -55.826932)
			(xy 147.429068 -55.879433) (xy 147.406225 -55.929178) (xy 147.376502 -55.975146) (xy 147.358862 -55.996078)
			(xy 147.358608 -55.996332) (xy 147.353045 -56.003435) (xy 147.346784 -56.020339) (xy 147.346416 -56.029352)
			(xy 147.346416 -56.096408) (xy 147.346766 -56.105426) (xy 147.353018 -56.122343) (xy 147.358608 -56.129428)
			(xy 147.358862 -56.129428) (xy 147.358862 -56.129682) (xy 147.3765 -56.150615) (xy 147.406213 -56.196587)
			(xy 147.42905 -56.246334) (xy 147.444541 -56.298835) (xy 147.452369 -56.353011) (xy 147.452842 -56.38038)
			(xy 147.452356 -56.407631) (xy 147.4446 -56.461579) (xy 147.429245 -56.513874) (xy 147.406603 -56.563451)
			(xy 147.377137 -56.609301) (xy 147.341446 -56.650492) (xy 147.300255 -56.686183) (xy 147.254405 -56.715649)
			(xy 147.204828 -56.738291) (xy 147.152533 -56.753646) (xy 147.098585 -56.761402) (xy 147.044083 -56.761402)
			(xy 146.990135 -56.753646) (xy 146.93784 -56.738291) (xy 146.888263 -56.715649) (xy 146.842413 -56.686183)
			(xy 146.801222 -56.650492) (xy 146.765531 -56.609301) (xy 146.736065 -56.563451) (xy 146.713423 -56.513874)
			(xy 146.698068 -56.461579) (xy 146.690312 -56.407631) (xy 146.689826 -56.38038) (xy 146.690274 -56.353009)
			(xy 146.698095 -56.298829) (xy 146.713588 -56.246325) (xy 146.736434 -56.196579) (xy 146.766163 -56.150613)
			(xy 146.783806 -56.129682) (xy 146.78406 -56.129428) (xy 146.789648 -56.122343) (xy 146.795892 -56.105425)
			(xy 146.796252 -56.096408) (xy 146.796252 -56.029352) (xy 146.795881 -56.020336) (xy 146.789644 -56.003419)
			(xy 146.78406 -55.996332) (xy 146.783806 -55.996332) (xy 146.783806 -55.996078) (xy 146.766147 -55.975161)
			(xy 146.736424 -55.92919) (xy 146.713581 -55.879441) (xy 146.698087 -55.826937) (xy 146.690261 -55.772756)
			(xy 146.690263 -55.718014) (xy 146.698094 -55.663834) (xy 146.713592 -55.611331) (xy 146.736439 -55.561584)
			(xy 146.766165 -55.515615) (xy 146.783806 -55.494682) (xy 146.78406 -55.494428) (xy 146.789648 -55.487343)
			(xy 146.795892 -55.470425) (xy 146.796252 -55.461408) (xy 146.796252 -55.394352) (xy 146.795881 -55.385336)
			(xy 146.789644 -55.368419) (xy 146.78406 -55.361332) (xy 146.783806 -55.360824) (xy 146.772863 -55.348089)
			(xy 146.753021 -55.320998) (xy 146.744182 -55.306722) (xy 146.738848 -55.297832) (xy 146.72183 -55.28564)
			(xy 146.628612 -55.26532) (xy 146.608038 -55.269638) (xy 146.599402 -55.27548) (xy 146.575338 -55.291479)
			(xy 146.523407 -55.316823) (xy 146.468249 -55.334049) (xy 146.411125 -55.342764) (xy 146.382232 -55.343298)
			(xy 146.354977 -55.342857) (xy 146.301021 -55.335104) (xy 146.248718 -55.31975) (xy 146.199132 -55.297109)
			(xy 146.153274 -55.267641) (xy 146.112076 -55.231946) (xy 146.076378 -55.190752) (xy 146.046906 -55.144896)
			(xy 146.024261 -55.095312) (xy 146.008903 -55.04301) (xy 146.001145 -54.989055) (xy 136.865169 -54.989055)
			(xy 136.858489 -54.999449) (xy 136.822798 -55.04064) (xy 136.781607 -55.076331) (xy 136.735757 -55.105797)
			(xy 136.68618 -55.128439) (xy 136.633885 -55.143794) (xy 136.579937 -55.15155) (xy 136.525435 -55.15155)
			(xy 136.471487 -55.143794) (xy 136.419192 -55.128439) (xy 136.369615 -55.105797) (xy 136.323765 -55.076331)
			(xy 136.282574 -55.04064) (xy 136.246883 -54.999449) (xy 136.217417 -54.953599) (xy 136.194775 -54.904022)
			(xy 136.17942 -54.851727) (xy 136.171664 -54.797779) (xy 136.171178 -54.770528) (xy 133.039257 -54.770528)
			(xy 133.039612 -54.791102) (xy 133.039126 -54.818353) (xy 133.03137 -54.872301) (xy 133.016015 -54.924596)
			(xy 132.993373 -54.974173) (xy 132.963907 -55.020023) (xy 132.928216 -55.061214) (xy 132.887025 -55.096905)
			(xy 132.841175 -55.126371) (xy 132.791598 -55.149013) (xy 132.739303 -55.164368) (xy 132.685355 -55.172124)
			(xy 132.630853 -55.172124) (xy 132.576905 -55.164368) (xy 132.52461 -55.149013) (xy 132.475033 -55.126371)
			(xy 132.429183 -55.096905) (xy 132.387992 -55.061214) (xy 132.352301 -55.020023) (xy 132.322835 -54.974173)
			(xy 132.300193 -54.924596) (xy 132.284838 -54.872301) (xy 132.277082 -54.818353) (xy 132.276596 -54.791102)
			(xy 130.378588 -54.791102) (xy 130.374858 -54.816013) (xy 130.358202 -54.870335) (xy 130.333674 -54.921586)
			(xy 130.301816 -54.968632) (xy 130.263333 -55.010433) (xy 130.219075 -55.046063) (xy 130.194812 -55.06085)
			(xy 130.194558 -55.061104) (xy 130.184099 -55.067926) (xy 130.170899 -55.089093) (xy 130.169412 -55.10149)
			(xy 130.159776 -55.722266) (xy 141.934182 -55.722266) (xy 141.938253 -55.666644) (xy 141.950379 -55.612207)
			(xy 141.970302 -55.560116) (xy 141.997598 -55.511481) (xy 142.031684 -55.467338) (xy 142.071833 -55.428629)
			(xy 142.117191 -55.396178) (xy 142.166791 -55.370677) (xy 142.219575 -55.35267) (xy 142.274418 -55.34254)
			(xy 142.330152 -55.340503) (xy 142.385589 -55.346603) (xy 142.439546 -55.360709) (xy 142.490875 -55.382521)
			(xy 142.538481 -55.411575) (xy 142.549632 -55.420855) (xy 144.324745 -55.420855) (xy 144.324745 -55.366345)
			(xy 144.332503 -55.31239) (xy 144.347861 -55.260088) (xy 144.370506 -55.210504) (xy 144.399978 -55.164648)
			(xy 144.435676 -55.123454) (xy 144.476874 -55.087759) (xy 144.522732 -55.058291) (xy 144.572318 -55.03565)
			(xy 144.624621 -55.020296) (xy 144.678577 -55.012543) (xy 144.705832 -55.012082) (xy 144.732146 -55.012534)
			(xy 144.784275 -55.019773) (xy 144.834918 -55.034095) (xy 144.883117 -55.055231) (xy 144.92796 -55.082779)
			(xy 144.968599 -55.11622) (xy 144.986756 -55.135272) (xy 144.994296 -55.142652) (xy 145.013562 -55.15119)
			(xy 145.024094 -55.151782) (xy 145.09877 -55.151782) (xy 145.10932 -55.151256) (xy 145.128616 -55.142719)
			(xy 145.136108 -55.135272) (xy 145.154261 -55.116214) (xy 145.194892 -55.082758) (xy 145.239733 -55.0552)
			(xy 145.287934 -55.034062) (xy 145.338582 -55.019745) (xy 145.390716 -55.012521) (xy 145.417032 -55.012082)
			(xy 145.444281 -55.01259) (xy 145.498224 -55.02035) (xy 145.550513 -55.035708) (xy 145.600085 -55.05835)
			(xy 145.64593 -55.087817) (xy 145.687116 -55.123507) (xy 145.722803 -55.164695) (xy 145.752265 -55.210543)
			(xy 145.774903 -55.260117) (xy 145.790256 -55.312408) (xy 145.798012 -55.366351) (xy 145.798012 -55.420849)
			(xy 145.790256 -55.474792) (xy 145.774903 -55.527083) (xy 145.752265 -55.576657) (xy 145.722803 -55.622505)
			(xy 145.687116 -55.663693) (xy 145.64593 -55.699383) (xy 145.600085 -55.72885) (xy 145.550513 -55.751492)
			(xy 145.498224 -55.76685) (xy 145.444281 -55.77461) (xy 145.417032 -55.775098) (xy 145.390716 -55.774677)
			(xy 145.338586 -55.767432) (xy 145.287942 -55.753104) (xy 145.239744 -55.731963) (xy 145.194901 -55.704409)
			(xy 145.154263 -55.670963) (xy 145.136108 -55.651908) (xy 145.128584 -55.644509) (xy 145.109306 -55.635983)
			(xy 145.09877 -55.635398) (xy 145.024094 -55.635398) (xy 145.013542 -55.635911) (xy 144.994247 -55.644457)
			(xy 144.986756 -55.651908) (xy 144.968616 -55.670979) (xy 144.927983 -55.704435) (xy 144.883139 -55.731992)
			(xy 144.834936 -55.753127) (xy 144.784285 -55.767441) (xy 144.732149 -55.774662) (xy 144.705832 -55.775098)
			(xy 144.678577 -55.774657) (xy 144.624621 -55.766904) (xy 144.572318 -55.75155) (xy 144.522732 -55.728909)
			(xy 144.476874 -55.699441) (xy 144.435676 -55.663746) (xy 144.399978 -55.622552) (xy 144.370506 -55.576696)
			(xy 144.347861 -55.527112) (xy 144.332503 -55.47481) (xy 144.324745 -55.420855) (xy 142.549632 -55.420855)
			(xy 142.581349 -55.44725) (xy 142.618566 -55.488787) (xy 142.649339 -55.5353) (xy 142.673011 -55.585797)
			(xy 142.689079 -55.639204) (xy 142.697199 -55.69438) (xy 142.697708 -55.722266) (xy 142.697199 -55.750152)
			(xy 142.689079 -55.805328) (xy 142.673011 -55.858735) (xy 142.649339 -55.909232) (xy 142.618566 -55.955745)
			(xy 142.581349 -55.997282) (xy 142.538481 -56.032957) (xy 142.490875 -56.062011) (xy 142.439546 -56.083823)
			(xy 142.385589 -56.097929) (xy 142.330152 -56.104029) (xy 142.274418 -56.101992) (xy 142.219575 -56.091862)
			(xy 142.166791 -56.073855) (xy 142.117191 -56.048354) (xy 142.071833 -56.015903) (xy 142.031684 -55.977194)
			(xy 141.997598 -55.933051) (xy 141.970302 -55.884416) (xy 141.950379 -55.832325) (xy 141.938253 -55.777888)
			(xy 141.934182 -55.722266) (xy 130.159776 -55.722266) (xy 130.148838 -56.426862) (xy 130.14895 -56.434073)
			(xy 130.152696 -56.447993) (xy 130.156204 -56.454294) (xy 130.169158 -56.475122) (xy 130.172686 -56.480478)
			(xy 130.181946 -56.489347) (xy 130.187446 -56.492648) (xy 130.1877 -56.492902) (xy 130.210036 -56.505809)
			(xy 130.251335 -56.536723) (xy 130.288093 -56.572918) (xy 130.319642 -56.613735) (xy 130.345406 -56.658428)
			(xy 130.364916 -56.706184) (xy 130.377815 -56.756132) (xy 130.381248 -56.7817) (xy 130.382264 -56.791098)
			(xy 130.383788 -56.826404) (xy 130.383379 -56.851951) (xy 130.376562 -56.902589) (xy 130.36305 -56.951864)
			(xy 130.343086 -56.998897) (xy 130.340692 -57.002934) (xy 137.663682 -57.002934) (xy 137.664204 -56.974843)
			(xy 137.672426 -56.919268) (xy 137.688712 -56.865499) (xy 137.712711 -56.814702) (xy 137.743901 -56.767975)
			(xy 137.78161 -56.726329) (xy 137.825019 -56.690665) (xy 137.848848 -56.675782) (xy 137.857738 -56.670448)
			(xy 137.86993 -56.65343) (xy 137.89025 -56.560212) (xy 137.885932 -56.539638) (xy 137.88009 -56.531002)
			(xy 137.864087 -56.50694) (xy 137.838746 -56.455008) (xy 137.821521 -56.399849) (xy 137.812806 -56.342725)
			(xy 137.812272 -56.313832) (xy 137.812785 -56.286581) (xy 137.820537 -56.232633) (xy 137.835888 -56.180337)
			(xy 137.858525 -56.130758) (xy 137.887988 -56.084906) (xy 137.923677 -56.043714) (xy 137.964864 -56.008019)
			(xy 138.010713 -55.97855) (xy 138.060288 -55.955906) (xy 138.112582 -55.940548) (xy 138.166529 -55.932789)
			(xy 138.19378 -55.932324) (xy 138.22115 -55.932796) (xy 138.275329 -55.940611) (xy 138.327832 -55.956099)
			(xy 138.377579 -55.978939) (xy 138.423546 -56.008663) (xy 138.444478 -56.026304) (xy 138.444732 -56.026558)
			(xy 138.451829 -56.032129) (xy 138.468738 -56.038384) (xy 138.477752 -56.03875) (xy 138.544808 -56.03875)
			(xy 138.553827 -56.038407) (xy 138.570744 -56.032151) (xy 138.577828 -56.026558) (xy 138.577828 -56.026304)
			(xy 138.578082 -56.026304) (xy 138.599015 -56.008663) (xy 138.644983 -55.978939) (xy 138.694729 -55.956093)
			(xy 138.747231 -55.940597) (xy 138.801409 -55.932768) (xy 138.856151 -55.932768) (xy 138.910329 -55.940597)
			(xy 138.962831 -55.956093) (xy 139.012577 -55.978939) (xy 139.058545 -56.008663) (xy 139.079478 -56.026304)
			(xy 139.079732 -56.026558) (xy 139.086829 -56.032129) (xy 139.103738 -56.038384) (xy 139.112752 -56.03875)
			(xy 139.179808 -56.03875) (xy 139.188827 -56.038407) (xy 139.205744 -56.032151) (xy 139.212828 -56.026558)
			(xy 139.212828 -56.026304) (xy 139.213082 -56.026304) (xy 139.234011 -56.008661) (xy 139.279984 -55.978949)
			(xy 139.329733 -55.956114) (xy 139.382234 -55.940624) (xy 139.436411 -55.932797) (xy 139.46378 -55.932324)
			(xy 139.491036 -55.932722) (xy 139.544994 -55.940477) (xy 139.597298 -55.955832) (xy 139.646885 -55.978476)
			(xy 139.692745 -56.007946) (xy 139.733943 -56.043642) (xy 139.769642 -56.084839) (xy 139.799115 -56.130697)
			(xy 139.821761 -56.180283) (xy 139.837119 -56.232587) (xy 139.844877 -56.286544) (xy 139.844877 -56.297068)
			(xy 140.186662 -56.297068) (xy 140.190733 -56.241446) (xy 140.202859 -56.187009) (xy 140.222782 -56.134918)
			(xy 140.250078 -56.086283) (xy 140.284164 -56.04214) (xy 140.324313 -56.003431) (xy 140.369671 -55.97098)
			(xy 140.419271 -55.945479) (xy 140.472055 -55.927472) (xy 140.526898 -55.917342) (xy 140.582632 -55.915305)
			(xy 140.638069 -55.921405) (xy 140.692026 -55.935511) (xy 140.743355 -55.957323) (xy 140.790961 -55.986377)
			(xy 140.833829 -56.022052) (xy 140.871046 -56.063589) (xy 140.901819 -56.110102) (xy 140.925491 -56.160599)
			(xy 140.941559 -56.214006) (xy 140.949679 -56.269182) (xy 140.950188 -56.297068) (xy 140.949679 -56.324954)
			(xy 140.941559 -56.38013) (xy 140.925491 -56.433537) (xy 140.901819 -56.484034) (xy 140.871046 -56.530547)
			(xy 140.833829 -56.572084) (xy 140.790961 -56.607759) (xy 140.743355 -56.636813) (xy 140.692026 -56.658625)
			(xy 140.638069 -56.672731) (xy 140.582632 -56.678831) (xy 140.526898 -56.676794) (xy 140.472055 -56.666664)
			(xy 140.419271 -56.648657) (xy 140.369671 -56.623156) (xy 140.324313 -56.590705) (xy 140.284164 -56.551996)
			(xy 140.250078 -56.507853) (xy 140.222782 -56.459218) (xy 140.202859 -56.407127) (xy 140.190733 -56.35269)
			(xy 140.186662 -56.297068) (xy 139.844877 -56.297068) (xy 139.844877 -56.341056) (xy 139.837119 -56.395013)
			(xy 139.821761 -56.447317) (xy 139.799115 -56.496903) (xy 139.769642 -56.542761) (xy 139.733943 -56.583958)
			(xy 139.692745 -56.619654) (xy 139.646885 -56.649124) (xy 139.597298 -56.671768) (xy 139.544994 -56.687123)
			(xy 139.491036 -56.694878) (xy 139.46378 -56.69534) (xy 139.436409 -56.6949) (xy 139.382228 -56.687078)
			(xy 139.329724 -56.671584) (xy 139.279977 -56.648736) (xy 139.234012 -56.619005) (xy 139.213082 -56.60136)
			(xy 139.212828 -56.601106) (xy 139.205737 -56.595526) (xy 139.188824 -56.589275) (xy 139.179808 -56.588914)
			(xy 139.112752 -56.588914) (xy 139.103737 -56.589293) (xy 139.08682 -56.595525) (xy 139.079732 -56.601106)
			(xy 139.079732 -56.60136) (xy 139.079478 -56.60136) (xy 139.058545 -56.619001) (xy 139.012577 -56.648725)
			(xy 138.962831 -56.671571) (xy 138.910329 -56.687067) (xy 138.856151 -56.694896) (xy 138.801409 -56.694896)
			(xy 138.747231 -56.687067) (xy 138.694729 -56.671571) (xy 138.644983 -56.648725) (xy 138.599015 -56.619001)
			(xy 138.578082 -56.60136) (xy 138.577828 -56.601106) (xy 138.570737 -56.595526) (xy 138.553824 -56.589275)
			(xy 138.544808 -56.588914) (xy 138.477752 -56.588914) (xy 138.468737 -56.589293) (xy 138.45182 -56.595525)
			(xy 138.444732 -56.601106) (xy 138.444224 -56.60136) (xy 138.431492 -56.612307) (xy 138.404399 -56.632146)
			(xy 138.390122 -56.640984) (xy 138.381232 -56.646318) (xy 138.36904 -56.663336) (xy 138.34872 -56.756554)
			(xy 138.353038 -56.777128) (xy 138.35888 -56.785764) (xy 138.374865 -56.809838) (xy 138.400211 -56.861765)
			(xy 138.417441 -56.91692) (xy 138.426161 -56.974042) (xy 138.426698 -57.002934) (xy 138.426212 -57.030185)
			(xy 138.418456 -57.084133) (xy 138.403101 -57.136428) (xy 138.380459 -57.186005) (xy 138.350993 -57.231855)
			(xy 138.315302 -57.273046) (xy 138.274111 -57.308737) (xy 138.228261 -57.338203) (xy 138.178684 -57.360845)
			(xy 138.126389 -57.3762) (xy 138.072441 -57.383956) (xy 138.017939 -57.383956) (xy 137.963991 -57.3762)
			(xy 137.911696 -57.360845) (xy 137.862119 -57.338203) (xy 137.816269 -57.308737) (xy 137.775078 -57.273046)
			(xy 137.739387 -57.231855) (xy 137.709921 -57.186005) (xy 137.687279 -57.136428) (xy 137.671924 -57.084133)
			(xy 137.664168 -57.030185) (xy 137.663682 -57.002934) (xy 130.340692 -57.002934) (xy 130.317025 -57.042845)
			(xy 130.301492 -57.063132) (xy 130.297682 -57.067958) (xy 130.295142 -57.073546) (xy 130.292348 -57.07888)
			(xy 130.289808 -57.090056) (xy 130.289808 -57.117996) (xy 130.289695 -57.123093) (xy 130.287646 -57.133078)
			(xy 130.285744 -57.137808) (xy 130.278886 -57.153556) (xy 130.278632 -57.154318) (xy 130.276092 -57.159906)
			(xy 130.275076 -57.167526) (xy 130.275076 -57.179718) (xy 130.276346 -57.189624) (xy 130.282442 -57.201816)
			(xy 130.287014 -57.207404) (xy 130.287776 -57.208166) (xy 130.2893 -57.209944) (xy 130.29057 -57.211468)
			(xy 130.292094 -57.212992) (xy 130.29438 -57.215786) (xy 130.30073 -57.22366) (xy 130.305048 -57.229248)
			(xy 130.308858 -57.234328) (xy 130.326493 -57.259123) (xy 130.354494 -57.313138) (xy 130.373566 -57.370913)
			(xy 130.383224 -57.430983) (xy 130.383788 -57.461404) (xy 130.383788 -57.461658) (xy 130.383411 -57.48528)
			(xy 146.70608 -57.48528) (xy 146.710151 -57.429658) (xy 146.722277 -57.375221) (xy 146.7422 -57.32313)
			(xy 146.769496 -57.274495) (xy 146.803582 -57.230352) (xy 146.843731 -57.191643) (xy 146.889089 -57.159192)
			(xy 146.938689 -57.133691) (xy 146.991473 -57.115684) (xy 147.046316 -57.105554) (xy 147.10205 -57.103517)
			(xy 147.157487 -57.109617) (xy 147.211444 -57.123723) (xy 147.262773 -57.145535) (xy 147.310379 -57.174589)
			(xy 147.353247 -57.210264) (xy 147.390464 -57.251801) (xy 147.421237 -57.298314) (xy 147.444909 -57.348811)
			(xy 147.460977 -57.402218) (xy 147.469097 -57.457394) (xy 147.469606 -57.48528) (xy 147.469097 -57.513166)
			(xy 147.460977 -57.568342) (xy 147.444909 -57.621749) (xy 147.421237 -57.672246) (xy 147.390464 -57.718759)
			(xy 147.353247 -57.760296) (xy 147.310379 -57.795971) (xy 147.262773 -57.825025) (xy 147.211444 -57.846837)
			(xy 147.157487 -57.860943) (xy 147.10205 -57.867043) (xy 147.046316 -57.865006) (xy 146.991473 -57.854876)
			(xy 146.938689 -57.836869) (xy 146.889089 -57.811368) (xy 146.843731 -57.778917) (xy 146.803582 -57.740208)
			(xy 146.769496 -57.696065) (xy 146.7422 -57.64743) (xy 146.722277 -57.595339) (xy 146.710151 -57.540902)
			(xy 146.70608 -57.48528) (xy 130.383411 -57.48528) (xy 130.383386 -57.486821) (xy 130.376766 -57.53671)
			(xy 130.363635 -57.585293) (xy 130.344222 -57.631724) (xy 130.318865 -57.675195) (xy 130.303778 -57.695338)
			(xy 130.30327 -57.695846) (xy 130.296412 -57.70626) (xy 130.293383 -57.711966) (xy 130.290044 -57.724442)
			(xy 130.289808 -57.730898) (xy 130.289808 -57.752996) (xy 130.289695 -57.758093) (xy 130.287646 -57.768078)
			(xy 130.285744 -57.772808) (xy 130.278886 -57.788556) (xy 130.278632 -57.789318) (xy 130.276092 -57.794906)
			(xy 130.275076 -57.802526) (xy 130.275076 -57.814718) (xy 130.276346 -57.824624) (xy 130.282442 -57.836816)
			(xy 130.287014 -57.842404) (xy 130.287776 -57.843166) (xy 130.2893 -57.844944) (xy 130.29057 -57.846468)
			(xy 130.292094 -57.847992) (xy 130.29438 -57.850786) (xy 130.30073 -57.85866) (xy 130.305048 -57.864248)
			(xy 130.308858 -57.869328) (xy 130.326493 -57.894123) (xy 130.354494 -57.948138) (xy 130.373566 -58.005913)
			(xy 130.383224 -58.065983) (xy 130.383788 -58.096404) (xy 130.383788 -58.096658) (xy 130.383386 -58.121821)
			(xy 130.376766 -58.17171) (xy 130.363635 -58.220293) (xy 130.344222 -58.266724) (xy 130.318865 -58.310195)
			(xy 130.303778 -58.330338) (xy 130.30327 -58.330846) (xy 130.296412 -58.34126) (xy 130.293383 -58.346966)
			(xy 130.290044 -58.359442) (xy 130.289808 -58.365898) (xy 130.289808 -58.387234) (xy 130.289665 -58.392673)
			(xy 130.287357 -58.403305) (xy 130.285236 -58.408316) (xy 130.27914 -58.421778) (xy 130.275519 -58.430441)
			(xy 130.274284 -58.449163) (xy 130.279905 -58.467064) (xy 130.28549 -58.47461) (xy 130.291078 -58.481722)
			(xy 130.294634 -58.486294) (xy 130.295142 -58.487056) (xy 130.312784 -58.508939) (xy 130.342116 -58.556887)
			(xy 130.353562 -58.58256) (xy 130.360799 -58.60019) (xy 130.372121 -58.636581) (xy 130.376168 -58.655204)
			(xy 130.380087 -58.679334) (xy 138.095482 -58.679334) (xy 138.095911 -58.653019) (xy 138.103155 -58.600889)
			(xy 138.117482 -58.550246) (xy 138.138621 -58.502047) (xy 138.166174 -58.457204) (xy 138.199618 -58.416566)
			(xy 138.218672 -58.39841) (xy 138.226067 -58.390883) (xy 138.234596 -58.371607) (xy 138.235182 -58.361072)
			(xy 138.235182 -58.286396) (xy 138.234674 -58.275844) (xy 138.226124 -58.256548) (xy 138.218672 -58.249058)
			(xy 138.199598 -58.230921) (xy 138.166143 -58.190287) (xy 138.138588 -58.145443) (xy 138.117453 -58.097238)
			(xy 138.103139 -58.046588) (xy 138.095918 -57.994451) (xy 138.095482 -57.968134) (xy 138.095968 -57.940883)
			(xy 138.103724 -57.886935) (xy 138.119079 -57.83464) (xy 138.141721 -57.785063) (xy 138.171187 -57.739213)
			(xy 138.206878 -57.698022) (xy 138.248069 -57.662331) (xy 138.293919 -57.632865) (xy 138.343496 -57.610223)
			(xy 138.395791 -57.594868) (xy 138.449739 -57.587112) (xy 138.504241 -57.587112) (xy 138.558189 -57.594868)
			(xy 138.610484 -57.610223) (xy 138.660061 -57.632865) (xy 138.705911 -57.662331) (xy 138.747102 -57.698022)
			(xy 138.782793 -57.739213) (xy 138.812259 -57.785063) (xy 138.834901 -57.83464) (xy 138.850256 -57.886935)
			(xy 138.858012 -57.940883) (xy 138.858498 -57.968134) (xy 138.858054 -57.994449) (xy 138.850814 -58.046578)
			(xy 138.843547 -58.072274) (xy 142.093694 -58.072274) (xy 142.097765 -58.016652) (xy 142.109891 -57.962215)
			(xy 142.129814 -57.910124) (xy 142.15711 -57.861489) (xy 142.191196 -57.817346) (xy 142.231345 -57.778637)
			(xy 142.276703 -57.746186) (xy 142.326303 -57.720685) (xy 142.379087 -57.702678) (xy 142.43393 -57.692548)
			(xy 142.489664 -57.690511) (xy 142.545101 -57.696611) (xy 142.599058 -57.710717) (xy 142.650387 -57.732529)
			(xy 142.697993 -57.761583) (xy 142.740861 -57.797258) (xy 142.778078 -57.838795) (xy 142.808851 -57.885308)
			(xy 142.832523 -57.935805) (xy 142.848591 -57.989212) (xy 142.856711 -58.044388) (xy 142.85722 -58.072274)
			(xy 142.85715 -58.076084) (xy 147.458174 -58.076084) (xy 147.462245 -58.020462) (xy 147.474371 -57.966025)
			(xy 147.494294 -57.913934) (xy 147.52159 -57.865299) (xy 147.555676 -57.821156) (xy 147.595825 -57.782447)
			(xy 147.641183 -57.749996) (xy 147.690783 -57.724495) (xy 147.743567 -57.706488) (xy 147.79841 -57.696358)
			(xy 147.854144 -57.694321) (xy 147.909581 -57.700421) (xy 147.963538 -57.714527) (xy 148.014867 -57.736339)
			(xy 148.062473 -57.765393) (xy 148.105341 -57.801068) (xy 148.142558 -57.842605) (xy 148.158894 -57.867296)
			(xy 149.743158 -57.867296) (xy 149.747229 -57.811674) (xy 149.759355 -57.757237) (xy 149.779278 -57.705146)
			(xy 149.806574 -57.656511) (xy 149.84066 -57.612368) (xy 149.880809 -57.573659) (xy 149.926167 -57.541208)
			(xy 149.975767 -57.515707) (xy 150.028551 -57.4977) (xy 150.083394 -57.48757) (xy 150.139128 -57.485533)
			(xy 150.194565 -57.491633) (xy 150.248522 -57.505739) (xy 150.299851 -57.527551) (xy 150.347457 -57.556605)
			(xy 150.390325 -57.59228) (xy 150.427542 -57.633817) (xy 150.458315 -57.68033) (xy 150.481987 -57.730827)
			(xy 150.498055 -57.784234) (xy 150.506175 -57.83941) (xy 150.506684 -57.867296) (xy 150.506175 -57.895182)
			(xy 150.498055 -57.950358) (xy 150.481987 -58.003765) (xy 150.458315 -58.054262) (xy 150.427542 -58.100775)
			(xy 150.390325 -58.142312) (xy 150.347457 -58.177987) (xy 150.299851 -58.207041) (xy 150.248522 -58.228853)
			(xy 150.194565 -58.242959) (xy 150.139128 -58.249059) (xy 150.083394 -58.247022) (xy 150.028551 -58.236892)
			(xy 149.975767 -58.218885) (xy 149.926167 -58.193384) (xy 149.880809 -58.160933) (xy 149.84066 -58.122224)
			(xy 149.806574 -58.078081) (xy 149.779278 -58.029446) (xy 149.759355 -57.977355) (xy 149.747229 -57.922918)
			(xy 149.743158 -57.867296) (xy 148.158894 -57.867296) (xy 148.173331 -57.889118) (xy 148.197003 -57.939615)
			(xy 148.213071 -57.993022) (xy 148.221191 -58.048198) (xy 148.2217 -58.076084) (xy 148.221191 -58.10397)
			(xy 148.213071 -58.159146) (xy 148.197003 -58.212553) (xy 148.173331 -58.26305) (xy 148.142558 -58.309563)
			(xy 148.105341 -58.3511) (xy 148.062473 -58.386775) (xy 148.014867 -58.415829) (xy 147.963538 -58.437641)
			(xy 147.909581 -58.451747) (xy 147.854144 -58.457847) (xy 147.79841 -58.45581) (xy 147.743567 -58.44568)
			(xy 147.690783 -58.427673) (xy 147.641183 -58.402172) (xy 147.595825 -58.369721) (xy 147.555676 -58.331012)
			(xy 147.52159 -58.286869) (xy 147.494294 -58.238234) (xy 147.474371 -58.186143) (xy 147.462245 -58.131706)
			(xy 147.458174 -58.076084) (xy 142.85715 -58.076084) (xy 142.856711 -58.10016) (xy 142.848591 -58.155336)
			(xy 142.832523 -58.208743) (xy 142.808851 -58.25924) (xy 142.778078 -58.305753) (xy 142.740861 -58.34729)
			(xy 142.697993 -58.382965) (xy 142.650387 -58.412019) (xy 142.599058 -58.433831) (xy 142.545101 -58.447937)
			(xy 142.489664 -58.454037) (xy 142.43393 -58.452) (xy 142.379087 -58.44187) (xy 142.326303 -58.423863)
			(xy 142.276703 -58.398362) (xy 142.231345 -58.365911) (xy 142.191196 -58.327202) (xy 142.15711 -58.283059)
			(xy 142.129814 -58.234424) (xy 142.109891 -58.182333) (xy 142.097765 -58.127896) (xy 142.093694 -58.072274)
			(xy 138.843547 -58.072274) (xy 138.836491 -58.097221) (xy 138.815354 -58.14542) (xy 138.787804 -58.190263)
			(xy 138.754361 -58.230902) (xy 138.735308 -58.249058) (xy 138.727924 -58.256594) (xy 138.719389 -58.275863)
			(xy 138.718798 -58.286396) (xy 138.718798 -58.361072) (xy 138.719329 -58.371621) (xy 138.727863 -58.390917)
			(xy 138.735308 -58.39841) (xy 138.754363 -58.416566) (xy 138.78782 -58.457196) (xy 138.815379 -58.502036)
			(xy 138.836517 -58.550237) (xy 138.839623 -58.561224) (xy 148.662388 -58.561224) (xy 148.666459 -58.505602)
			(xy 148.678585 -58.451165) (xy 148.698508 -58.399074) (xy 148.725804 -58.350439) (xy 148.75989 -58.306296)
			(xy 148.800039 -58.267587) (xy 148.845397 -58.235136) (xy 148.894997 -58.209635) (xy 148.947781 -58.191628)
			(xy 149.002624 -58.181498) (xy 149.058358 -58.179461) (xy 149.113795 -58.185561) (xy 149.167752 -58.199667)
			(xy 149.219081 -58.221479) (xy 149.266687 -58.250533) (xy 149.309555 -58.286208) (xy 149.346772 -58.327745)
			(xy 149.377545 -58.374258) (xy 149.401217 -58.424755) (xy 149.417285 -58.478162) (xy 149.425405 -58.533338)
			(xy 149.425914 -58.561224) (xy 149.425405 -58.58911) (xy 149.417285 -58.644286) (xy 149.401217 -58.697693)
			(xy 149.377545 -58.74819) (xy 149.346772 -58.794703) (xy 149.309555 -58.83624) (xy 149.266687 -58.871915)
			(xy 149.219081 -58.900969) (xy 149.167752 -58.922781) (xy 149.113795 -58.936887) (xy 149.058358 -58.942987)
			(xy 149.002624 -58.94095) (xy 148.947781 -58.93082) (xy 148.894997 -58.912813) (xy 148.845397 -58.887312)
			(xy 148.800039 -58.854861) (xy 148.75989 -58.816152) (xy 148.725804 -58.772009) (xy 148.698508 -58.723374)
			(xy 148.678585 -58.671283) (xy 148.666459 -58.616846) (xy 148.662388 -58.561224) (xy 138.839623 -58.561224)
			(xy 138.850835 -58.600884) (xy 138.858059 -58.653018) (xy 138.858498 -58.679334) (xy 138.858012 -58.706585)
			(xy 138.850256 -58.760533) (xy 138.834901 -58.812828) (xy 138.812259 -58.862405) (xy 138.782793 -58.908255)
			(xy 138.747102 -58.949446) (xy 138.705911 -58.985137) (xy 138.660061 -59.014603) (xy 138.610484 -59.037245)
			(xy 138.558189 -59.0526) (xy 138.504241 -59.060356) (xy 138.449739 -59.060356) (xy 138.395791 -59.0526)
			(xy 138.343496 -59.037245) (xy 138.293919 -59.014603) (xy 138.248069 -58.985137) (xy 138.206878 -58.949446)
			(xy 138.171187 -58.908255) (xy 138.141721 -58.862405) (xy 138.119079 -58.812828) (xy 138.103724 -58.760533)
			(xy 138.095968 -58.706585) (xy 138.095482 -58.679334) (xy 130.380087 -58.679334) (xy 130.380994 -58.684922)
			(xy 130.382155 -58.694918) (xy 130.383555 -58.714994) (xy 130.383788 -58.725054) (xy 130.383788 -58.740294)
			(xy 130.383534 -58.744358) (xy 130.383534 -58.748168) (xy 130.382772 -58.7629) (xy 130.382772 -58.763916)
			(xy 130.382264 -58.770266) (xy 130.37947 -58.789316) (xy 130.377553 -58.800939) (xy 130.372467 -58.823941)
			(xy 130.36931 -58.83529) (xy 130.36931 -58.836306) (xy 130.367786 -58.841386) (xy 130.363976 -58.854086)
			(xy 130.360928 -58.861452) (xy 130.350545 -58.888652) (xy 130.322739 -58.939803) (xy 130.305556 -58.963306)
			(xy 130.301492 -58.968894) (xy 130.321825 -59.174634) (xy 147.193252 -59.174634) (xy 147.197323 -59.119012)
			(xy 147.209449 -59.064575) (xy 147.229372 -59.012484) (xy 147.256668 -58.963849) (xy 147.290754 -58.919706)
			(xy 147.330903 -58.880997) (xy 147.376261 -58.848546) (xy 147.425861 -58.823045) (xy 147.478645 -58.805038)
			(xy 147.533488 -58.794908) (xy 147.589222 -58.792871) (xy 147.644659 -58.798971) (xy 147.698616 -58.813077)
			(xy 147.749945 -58.834889) (xy 147.797551 -58.863943) (xy 147.840419 -58.899618) (xy 147.877636 -58.941155)
			(xy 147.908409 -58.987668) (xy 147.932081 -59.038165) (xy 147.948149 -59.091572) (xy 147.956269 -59.146748)
			(xy 147.956778 -59.174634) (xy 147.956269 -59.20252) (xy 147.948149 -59.257696) (xy 147.932081 -59.311103)
			(xy 147.908409 -59.3616) (xy 147.877636 -59.408113) (xy 147.840419 -59.44965) (xy 147.797551 -59.485325)
			(xy 147.749945 -59.514379) (xy 147.698616 -59.536191) (xy 147.644659 -59.550297) (xy 147.589222 -59.556397)
			(xy 147.533488 -59.55436) (xy 147.478645 -59.54423) (xy 147.425861 -59.526223) (xy 147.376261 -59.500722)
			(xy 147.330903 -59.468271) (xy 147.290754 -59.429562) (xy 147.256668 -59.385419) (xy 147.229372 -59.336784)
			(xy 147.209449 -59.284693) (xy 147.197323 -59.230256) (xy 147.193252 -59.174634) (xy 130.321825 -59.174634)
			(xy 130.350768 -59.467496) (xy 130.399536 -59.962034) (xy 130.402838 -60.006484) (xy 130.403142 -60.019254)
			(xy 138.235861 -60.019254) (xy 138.235861 -59.964746) (xy 138.243619 -59.910792) (xy 138.258977 -59.858491)
			(xy 138.281623 -59.808909) (xy 138.311094 -59.763054) (xy 138.346792 -59.721861) (xy 138.38799 -59.686168)
			(xy 138.433848 -59.656702) (xy 138.483432 -59.634062) (xy 138.535735 -59.61871) (xy 138.58969 -59.610958)
			(xy 138.616944 -59.610498) (xy 138.644313 -59.610997) (xy 138.698491 -59.618807) (xy 138.750993 -59.634289)
			(xy 138.800741 -59.657123) (xy 138.846709 -59.68684) (xy 138.867642 -59.704478) (xy 138.867896 -59.704732)
			(xy 138.874977 -59.710327) (xy 138.891898 -59.716567) (xy 138.900916 -59.716924) (xy 138.967972 -59.716924)
			(xy 138.976987 -59.716548) (xy 138.993904 -59.710313) (xy 139.000992 -59.704732) (xy 139.000992 -59.704478)
			(xy 139.001246 -59.704478) (xy 139.022179 -59.686837) (xy 139.068147 -59.657113) (xy 139.117893 -59.634267)
			(xy 139.170395 -59.618771) (xy 139.224573 -59.610942) (xy 139.279315 -59.610942) (xy 139.333493 -59.618771)
			(xy 139.385995 -59.634267) (xy 139.435741 -59.657113) (xy 139.481709 -59.686837) (xy 139.502642 -59.704478)
			(xy 139.502896 -59.704732) (xy 139.509977 -59.710327) (xy 139.526898 -59.716567) (xy 139.535916 -59.716924)
			(xy 139.602972 -59.716924) (xy 139.611987 -59.716548) (xy 139.628904 -59.710313) (xy 139.635992 -59.704732)
			(xy 139.635992 -59.704478) (xy 139.636246 -59.704478) (xy 139.657185 -59.686847) (xy 139.703156 -59.657135)
			(xy 139.752902 -59.634298) (xy 139.805401 -59.618805) (xy 139.859575 -59.610974) (xy 139.886944 -59.610498)
			(xy 139.914194 -59.610975) (xy 139.968137 -59.618737) (xy 140.020428 -59.634096) (xy 140.07 -59.65674)
			(xy 140.115846 -59.686208) (xy 140.157031 -59.7219) (xy 140.192719 -59.763089) (xy 140.222181 -59.808938)
			(xy 140.24482 -59.858514) (xy 140.260173 -59.910806) (xy 140.267928 -59.96475) (xy 140.267928 -60.01925)
			(xy 140.260173 -60.073194) (xy 140.24482 -60.125486) (xy 140.222181 -60.175062) (xy 140.192719 -60.220911)
			(xy 140.157031 -60.2621) (xy 140.115846 -60.297792) (xy 140.07 -60.32726) (xy 140.020428 -60.349904)
			(xy 139.968137 -60.365263) (xy 139.914194 -60.373025) (xy 139.886944 -60.373514) (xy 139.859575 -60.373019)
			(xy 139.805397 -60.365207) (xy 139.752894 -60.349725) (xy 139.703147 -60.32689) (xy 139.657179 -60.297172)
			(xy 139.636246 -60.279534) (xy 139.635992 -60.27928) (xy 139.628914 -60.273682) (xy 139.61199 -60.267443)
			(xy 139.602972 -60.267088) (xy 139.535916 -60.267088) (xy 139.5269 -60.267455) (xy 139.509983 -60.273696)
			(xy 139.502896 -60.27928) (xy 139.502642 -60.279534) (xy 139.481709 -60.297175) (xy 139.435741 -60.326899)
			(xy 139.385995 -60.349745) (xy 139.333493 -60.365241) (xy 139.279315 -60.37307) (xy 139.224573 -60.37307)
			(xy 139.170395 -60.365241) (xy 139.117893 -60.349745) (xy 139.068147 -60.326899) (xy 139.022179 -60.297175)
			(xy 139.001246 -60.279534) (xy 139.000992 -60.27928) (xy 138.993914 -60.273682) (xy 138.97699 -60.267443)
			(xy 138.967972 -60.267088) (xy 138.900916 -60.267088) (xy 138.8919 -60.267455) (xy 138.874983 -60.273696)
			(xy 138.867896 -60.27928) (xy 138.867896 -60.279534) (xy 138.867642 -60.279534) (xy 138.846709 -60.297172)
			(xy 138.800736 -60.326883) (xy 138.750989 -60.349719) (xy 138.698488 -60.36521) (xy 138.644313 -60.373039)
			(xy 138.616944 -60.373514) (xy 138.58969 -60.373042) (xy 138.535735 -60.36529) (xy 138.483432 -60.349938)
			(xy 138.433847 -60.327298) (xy 138.38799 -60.297832) (xy 138.346792 -60.262139) (xy 138.311094 -60.220946)
			(xy 138.281623 -60.175091) (xy 138.258977 -60.125509) (xy 138.243619 -60.073208) (xy 138.235861 -60.019254)
			(xy 130.403142 -60.019254) (xy 130.404108 -60.059824) (xy 130.404108 -60.633356) (xy 149.897082 -60.633356)
			(xy 149.901153 -60.577734) (xy 149.913279 -60.523297) (xy 149.933202 -60.471206) (xy 149.960498 -60.422571)
			(xy 149.994584 -60.378428) (xy 150.034733 -60.339719) (xy 150.080091 -60.307268) (xy 150.129691 -60.281767)
			(xy 150.182475 -60.26376) (xy 150.237318 -60.25363) (xy 150.293052 -60.251593) (xy 150.348489 -60.257693)
			(xy 150.402446 -60.271799) (xy 150.453775 -60.293611) (xy 150.501381 -60.322665) (xy 150.544249 -60.35834)
			(xy 150.581466 -60.399877) (xy 150.612239 -60.44639) (xy 150.635911 -60.496887) (xy 150.651979 -60.550294)
			(xy 150.660099 -60.60547) (xy 150.660608 -60.633356) (xy 150.660099 -60.661242) (xy 150.651979 -60.716418)
			(xy 150.635911 -60.769825) (xy 150.612239 -60.820322) (xy 150.581466 -60.866835) (xy 150.544249 -60.908372)
			(xy 150.501381 -60.944047) (xy 150.453775 -60.973101) (xy 150.402446 -60.994913) (xy 150.348489 -61.009019)
			(xy 150.293052 -61.015119) (xy 150.237318 -61.013082) (xy 150.182475 -61.002952) (xy 150.129691 -60.984945)
			(xy 150.080091 -60.959444) (xy 150.034733 -60.926993) (xy 149.994584 -60.888284) (xy 149.960498 -60.844141)
			(xy 149.933202 -60.795506) (xy 149.913279 -60.743415) (xy 149.901153 -60.688978) (xy 149.897082 -60.633356)
			(xy 130.404108 -60.633356) (xy 130.404108 -61.487812) (xy 148.404578 -61.487812) (xy 148.408649 -61.43219)
			(xy 148.420775 -61.377753) (xy 148.440698 -61.325662) (xy 148.467994 -61.277027) (xy 148.50208 -61.232884)
			(xy 148.542229 -61.194175) (xy 148.587587 -61.161724) (xy 148.637187 -61.136223) (xy 148.689971 -61.118216)
			(xy 148.744814 -61.108086) (xy 148.800548 -61.106049) (xy 148.855985 -61.112149) (xy 148.909942 -61.126255)
			(xy 148.961271 -61.148067) (xy 149.008877 -61.177121) (xy 149.051745 -61.212796) (xy 149.088962 -61.254333)
			(xy 149.119735 -61.300846) (xy 149.143407 -61.351343) (xy 149.159475 -61.40475) (xy 149.167595 -61.459926)
			(xy 149.168104 -61.487812) (xy 149.167595 -61.515698) (xy 149.159475 -61.570874) (xy 149.143407 -61.624281)
			(xy 149.119735 -61.674778) (xy 149.088962 -61.721291) (xy 149.051745 -61.762828) (xy 149.008877 -61.798503)
			(xy 148.961271 -61.827557) (xy 148.909942 -61.849369) (xy 148.855985 -61.863475) (xy 148.800548 -61.869575)
			(xy 148.744814 -61.867538) (xy 148.689971 -61.857408) (xy 148.637187 -61.839401) (xy 148.587587 -61.8139)
			(xy 148.542229 -61.781449) (xy 148.50208 -61.74274) (xy 148.467994 -61.698597) (xy 148.440698 -61.649962)
			(xy 148.420775 -61.597871) (xy 148.408649 -61.543434) (xy 148.404578 -61.487812) (xy 130.404108 -61.487812)
			(xy 130.404108 -61.85916) (xy 130.404108 -61.859668) (xy 130.402005 -62.121034) (xy 146.342352 -62.121034)
			(xy 146.346423 -62.065412) (xy 146.358549 -62.010975) (xy 146.378472 -61.958884) (xy 146.405768 -61.910249)
			(xy 146.439854 -61.866106) (xy 146.480003 -61.827397) (xy 146.525361 -61.794946) (xy 146.574961 -61.769445)
			(xy 146.627745 -61.751438) (xy 146.682588 -61.741308) (xy 146.738322 -61.739271) (xy 146.793759 -61.745371)
			(xy 146.847716 -61.759477) (xy 146.899045 -61.781289) (xy 146.946651 -61.810343) (xy 146.989519 -61.846018)
			(xy 147.026736 -61.887555) (xy 147.057509 -61.934068) (xy 147.081181 -61.984565) (xy 147.097249 -62.037972)
			(xy 147.105369 -62.093148) (xy 147.105878 -62.121034) (xy 147.105369 -62.14892) (xy 147.097249 -62.204096)
			(xy 147.081181 -62.257503) (xy 147.057509 -62.308) (xy 147.026736 -62.354513) (xy 146.989519 -62.39605)
			(xy 146.946651 -62.431725) (xy 146.899045 -62.460779) (xy 146.847716 -62.482591) (xy 146.793759 -62.496697)
			(xy 146.738322 -62.502797) (xy 146.682588 -62.50076) (xy 146.627745 -62.49063) (xy 146.574961 -62.472623)
			(xy 146.525361 -62.447122) (xy 146.480003 -62.414671) (xy 146.439854 -62.375962) (xy 146.405768 -62.331819)
			(xy 146.378472 -62.283184) (xy 146.358549 -62.231093) (xy 146.346423 -62.176656) (xy 146.342352 -62.121034)
			(xy 130.402005 -62.121034) (xy 130.398012 -62.61735) (xy 130.397518 -62.678767) (xy 149.766272 -62.678767)
			(xy 149.774026 -62.624819) (xy 149.789379 -62.572524) (xy 149.812017 -62.522946) (xy 149.841481 -62.477094)
			(xy 149.87717 -62.435901) (xy 149.918358 -62.400207) (xy 149.964206 -62.370738) (xy 150.013782 -62.348094)
			(xy 150.066076 -62.332736) (xy 150.120023 -62.324976) (xy 150.147274 -62.324488) (xy 150.170828 -62.324873)
			(xy 150.217573 -62.330727) (xy 150.240492 -62.336172) (xy 150.254259 -62.339155) (xy 150.282405 -62.338311)
			(xy 150.309251 -62.329815) (xy 150.332757 -62.314312) (xy 150.351138 -62.292981) (xy 150.362997 -62.267442)
			(xy 150.367433 -62.239635) (xy 150.364108 -62.211674) (xy 150.35911 -62.198504) (xy 150.349797 -62.175115)
			(xy 150.336673 -62.126514) (xy 150.330051 -62.076609) (xy 150.329646 -62.051438) (xy 150.330114 -62.024181)
			(xy 150.337867 -61.970221) (xy 150.353221 -61.917915) (xy 150.375863 -61.868325) (xy 150.405332 -61.822463)
			(xy 150.441028 -61.781262) (xy 150.482225 -61.745561) (xy 150.528083 -61.716086) (xy 150.57767 -61.693438)
			(xy 150.629975 -61.678078) (xy 150.683933 -61.670318) (xy 150.738447 -61.670316) (xy 150.792406 -61.678073)
			(xy 150.844712 -61.693431) (xy 150.894299 -61.716077) (xy 150.940159 -61.745549) (xy 150.981358 -61.781248)
			(xy 151.017056 -61.822447) (xy 151.046527 -61.868308) (xy 151.069172 -61.917896) (xy 151.084528 -61.970202)
			(xy 151.092284 -62.024161) (xy 151.092282 -62.078675) (xy 151.084521 -62.132633) (xy 151.069159 -62.184938)
			(xy 151.04651 -62.234524) (xy 151.017034 -62.280382) (xy 150.981332 -62.321577) (xy 150.94013 -62.357273)
			(xy 150.894268 -62.386741) (xy 150.844678 -62.409382) (xy 150.792371 -62.424734) (xy 150.738411 -62.432486)
			(xy 150.711154 -62.432946) (xy 150.687599 -62.432573) (xy 150.640855 -62.426711) (xy 150.617936 -62.421262)
			(xy 150.60417 -62.418261) (xy 150.576018 -62.419098) (xy 150.549165 -62.427592) (xy 150.525652 -62.443096)
			(xy 150.507268 -62.464433) (xy 150.49541 -62.489979) (xy 150.490979 -62.517793) (xy 150.494313 -62.545759)
			(xy 150.499318 -62.55893) (xy 150.508643 -62.582314) (xy 150.521762 -62.630918) (xy 150.528379 -62.680824)
			(xy 150.528782 -62.705996) (xy 150.528327 -62.733247) (xy 150.520571 -62.787195) (xy 150.505216 -62.83949)
			(xy 150.482576 -62.889067) (xy 150.453111 -62.934918) (xy 150.41742 -62.976109) (xy 150.37623 -63.011801)
			(xy 150.330381 -63.041269) (xy 150.280804 -63.063911) (xy 150.22851 -63.079267) (xy 150.174563 -63.087025)
			(xy 150.12006 -63.087027) (xy 150.066112 -63.079272) (xy 150.013817 -63.063919) (xy 149.964239 -63.041279)
			(xy 149.918388 -63.011815) (xy 149.877196 -62.976125) (xy 149.841503 -62.934936) (xy 149.812035 -62.889087)
			(xy 149.789392 -62.839511) (xy 149.774034 -62.787217) (xy 149.766275 -62.73327) (xy 149.766272 -62.678767)
			(xy 130.397518 -62.678767) (xy 130.393217 -63.213549) (xy 138.220988 -63.213549) (xy 138.220988 -63.159051)
			(xy 138.228743 -63.105109) (xy 138.244096 -63.052819) (xy 138.266733 -63.003246) (xy 138.296195 -62.957399)
			(xy 138.331881 -62.916211) (xy 138.373065 -62.88052) (xy 138.418909 -62.851054) (xy 138.468479 -62.828411)
			(xy 138.520768 -62.813052) (xy 138.574709 -62.805291) (xy 138.601958 -62.804802) (xy 138.629327 -62.805292)
			(xy 138.683505 -62.813104) (xy 138.736008 -62.828588) (xy 138.785756 -62.851424) (xy 138.831723 -62.881143)
			(xy 138.852656 -62.898782) (xy 138.85291 -62.899036) (xy 138.859987 -62.904637) (xy 138.876911 -62.910874)
			(xy 138.88593 -62.911228) (xy 138.952986 -62.911228) (xy 138.962001 -62.910858) (xy 138.978918 -62.904619)
			(xy 138.986006 -62.899036) (xy 138.986006 -62.898782) (xy 138.98626 -62.898782) (xy 139.007193 -62.881141)
			(xy 139.053161 -62.851417) (xy 139.102907 -62.828571) (xy 139.155409 -62.813075) (xy 139.209587 -62.805246)
			(xy 139.264329 -62.805246) (xy 139.318507 -62.813075) (xy 139.371009 -62.828571) (xy 139.420755 -62.851417)
			(xy 139.466723 -62.881141) (xy 139.487656 -62.898782) (xy 139.48791 -62.899036) (xy 139.494987 -62.904637)
			(xy 139.511911 -62.910874) (xy 139.52093 -62.911228) (xy 139.587986 -62.911228) (xy 139.597001 -62.910858)
			(xy 139.613918 -62.904619) (xy 139.621006 -62.899036) (xy 139.621006 -62.898782) (xy 139.62126 -62.898782)
			(xy 139.642194 -62.881145) (xy 139.688167 -62.851434) (xy 139.737914 -62.828598) (xy 139.790414 -62.813106)
			(xy 139.844589 -62.805277) (xy 139.871958 -62.804802) (xy 139.899214 -62.805242) (xy 139.953171 -62.812994)
			(xy 140.005475 -62.828347) (xy 140.055062 -62.850988) (xy 140.100921 -62.880456) (xy 140.14212 -62.91615)
			(xy 140.177819 -62.957345) (xy 140.207292 -63.003201) (xy 140.229938 -63.052786) (xy 140.23976 -63.086234)
			(xy 143.487646 -63.086234) (xy 143.491717 -63.030612) (xy 143.503843 -62.976175) (xy 143.523766 -62.924084)
			(xy 143.551062 -62.875449) (xy 143.585148 -62.831306) (xy 143.625297 -62.792597) (xy 143.670655 -62.760146)
			(xy 143.720255 -62.734645) (xy 143.773039 -62.716638) (xy 143.827882 -62.706508) (xy 143.883616 -62.704471)
			(xy 143.939053 -62.710571) (xy 143.99301 -62.724677) (xy 144.044339 -62.746489) (xy 144.091945 -62.775543)
			(xy 144.134813 -62.811218) (xy 144.17203 -62.852755) (xy 144.202803 -62.899268) (xy 144.226475 -62.949765)
			(xy 144.242543 -63.003172) (xy 144.250663 -63.058348) (xy 144.251172 -63.086234) (xy 144.250663 -63.11412)
			(xy 144.242543 -63.169296) (xy 144.226475 -63.222703) (xy 144.202803 -63.2732) (xy 144.20265 -63.273432)
			(xy 145.676872 -63.273432) (xy 145.680943 -63.21781) (xy 145.693069 -63.163373) (xy 145.712992 -63.111282)
			(xy 145.740288 -63.062647) (xy 145.774374 -63.018504) (xy 145.814523 -62.979795) (xy 145.859881 -62.947344)
			(xy 145.909481 -62.921843) (xy 145.962265 -62.903836) (xy 146.017108 -62.893706) (xy 146.072842 -62.891669)
			(xy 146.128279 -62.897769) (xy 146.182236 -62.911875) (xy 146.233565 -62.933687) (xy 146.281171 -62.962741)
			(xy 146.324039 -62.998416) (xy 146.361256 -63.039953) (xy 146.392029 -63.086466) (xy 146.415701 -63.136963)
			(xy 146.431769 -63.19037) (xy 146.439889 -63.245546) (xy 146.440398 -63.273432) (xy 146.439889 -63.301318)
			(xy 146.431769 -63.356494) (xy 146.415701 -63.409901) (xy 146.392029 -63.460398) (xy 146.361256 -63.506911)
			(xy 146.324039 -63.548448) (xy 146.281171 -63.584123) (xy 146.233565 -63.613177) (xy 146.182236 -63.634989)
			(xy 146.128279 -63.649095) (xy 146.072842 -63.655195) (xy 146.017108 -63.653158) (xy 145.962265 -63.643028)
			(xy 145.909481 -63.625021) (xy 145.859881 -63.59952) (xy 145.814523 -63.567069) (xy 145.774374 -63.52836)
			(xy 145.740288 -63.484217) (xy 145.712992 -63.435582) (xy 145.693069 -63.383491) (xy 145.680943 -63.329054)
			(xy 145.676872 -63.273432) (xy 144.20265 -63.273432) (xy 144.17203 -63.319713) (xy 144.134813 -63.36125)
			(xy 144.091945 -63.396925) (xy 144.044339 -63.425979) (xy 143.99301 -63.447791) (xy 143.939053 -63.461897)
			(xy 143.883616 -63.467997) (xy 143.827882 -63.46596) (xy 143.773039 -63.45583) (xy 143.720255 -63.437823)
			(xy 143.670655 -63.412322) (xy 143.625297 -63.379871) (xy 143.585148 -63.341162) (xy 143.551062 -63.297019)
			(xy 143.523766 -63.248384) (xy 143.503843 -63.196293) (xy 143.491717 -63.141856) (xy 143.487646 -63.086234)
			(xy 140.23976 -63.086234) (xy 140.245297 -63.105088) (xy 140.253055 -63.159044) (xy 140.253055 -63.213556)
			(xy 140.245297 -63.267512) (xy 140.229938 -63.319814) (xy 140.207292 -63.369399) (xy 140.177819 -63.415255)
			(xy 140.14212 -63.45645) (xy 140.100921 -63.492144) (xy 140.055062 -63.521612) (xy 140.005475 -63.544253)
			(xy 139.953171 -63.559606) (xy 139.899214 -63.567358) (xy 139.871958 -63.567818) (xy 139.844588 -63.567338)
			(xy 139.790409 -63.559527) (xy 139.737905 -63.544042) (xy 139.688158 -63.521203) (xy 139.642191 -63.491479)
			(xy 139.62126 -63.473838) (xy 139.621006 -63.473584) (xy 139.613923 -63.467992) (xy 139.597003 -63.461749)
			(xy 139.587986 -63.461392) (xy 139.52093 -63.461392) (xy 139.511915 -63.461765) (xy 139.494998 -63.468002)
			(xy 139.48791 -63.473584) (xy 139.487656 -63.473838) (xy 139.466723 -63.491479) (xy 139.420755 -63.521203)
			(xy 139.371009 -63.544049) (xy 139.318507 -63.559545) (xy 139.264329 -63.567374) (xy 139.209587 -63.567374)
			(xy 139.155409 -63.559545) (xy 139.102907 -63.544049) (xy 139.053161 -63.521203) (xy 139.007193 -63.491479)
			(xy 138.98626 -63.473838) (xy 138.986006 -63.473584) (xy 138.978923 -63.467992) (xy 138.962003 -63.461749)
			(xy 138.952986 -63.461392) (xy 138.88593 -63.461392) (xy 138.876915 -63.461765) (xy 138.859998 -63.468002)
			(xy 138.85291 -63.473584) (xy 138.85291 -63.473838) (xy 138.852656 -63.473838) (xy 138.831719 -63.491471)
			(xy 138.785747 -63.521182) (xy 138.736001 -63.544019) (xy 138.683501 -63.559512) (xy 138.629327 -63.567343)
			(xy 138.601958 -63.567818) (xy 138.574709 -63.567309) (xy 138.520768 -63.559548) (xy 138.468479 -63.544189)
			(xy 138.418909 -63.521546) (xy 138.373065 -63.49208) (xy 138.331881 -63.456389) (xy 138.296195 -63.415201)
			(xy 138.266733 -63.369354) (xy 138.244096 -63.319781) (xy 138.228743 -63.267491) (xy 138.220988 -63.213549)
			(xy 130.393217 -63.213549) (xy 130.391916 -63.375286) (xy 130.391916 -65.100962) (xy 136.232644 -65.100962)
			(xy 136.236715 -65.04534) (xy 136.248841 -64.990903) (xy 136.268764 -64.938812) (xy 136.29606 -64.890177)
			(xy 136.330146 -64.846034) (xy 136.370295 -64.807325) (xy 136.415653 -64.774874) (xy 136.465253 -64.749373)
			(xy 136.518037 -64.731366) (xy 136.57288 -64.721236) (xy 136.628614 -64.719199) (xy 136.684051 -64.725299)
			(xy 136.738008 -64.739405) (xy 136.789337 -64.761217) (xy 136.836943 -64.790271) (xy 136.879811 -64.825946)
			(xy 136.917028 -64.867483) (xy 136.947801 -64.913996) (xy 136.971473 -64.964493) (xy 136.987541 -65.0179)
			(xy 136.995661 -65.073076) (xy 136.99617 -65.100962) (xy 136.995748 -65.124076) (xy 148.207474 -65.124076)
			(xy 148.211545 -65.068454) (xy 148.223671 -65.014017) (xy 148.243594 -64.961926) (xy 148.27089 -64.913291)
			(xy 148.304976 -64.869148) (xy 148.345125 -64.830439) (xy 148.390483 -64.797988) (xy 148.440083 -64.772487)
			(xy 148.492867 -64.75448) (xy 148.54771 -64.74435) (xy 148.603444 -64.742313) (xy 148.658881 -64.748413)
			(xy 148.712838 -64.762519) (xy 148.764167 -64.784331) (xy 148.811773 -64.813385) (xy 148.854641 -64.84906)
			(xy 148.891858 -64.890597) (xy 148.922631 -64.93711) (xy 148.946303 -64.987607) (xy 148.962371 -65.041014)
			(xy 148.970491 -65.09619) (xy 148.971 -65.124076) (xy 148.970491 -65.151962) (xy 148.962371 -65.207138)
			(xy 148.946303 -65.260545) (xy 148.922631 -65.311042) (xy 148.891858 -65.357555) (xy 148.854641 -65.399092)
			(xy 148.811773 -65.434767) (xy 148.764167 -65.463821) (xy 148.712838 -65.485633) (xy 148.658881 -65.499739)
			(xy 148.603444 -65.505839) (xy 148.54771 -65.503802) (xy 148.492867 -65.493672) (xy 148.440083 -65.475665)
			(xy 148.390483 -65.450164) (xy 148.345125 -65.417713) (xy 148.304976 -65.379004) (xy 148.27089 -65.334861)
			(xy 148.243594 -65.286226) (xy 148.223671 -65.234135) (xy 148.211545 -65.179698) (xy 148.207474 -65.124076)
			(xy 136.995748 -65.124076) (xy 136.995661 -65.128848) (xy 136.987541 -65.184024) (xy 136.971473 -65.237431)
			(xy 136.947801 -65.287928) (xy 136.917028 -65.334441) (xy 136.879811 -65.375978) (xy 136.836943 -65.411653)
			(xy 136.789337 -65.440707) (xy 136.738008 -65.462519) (xy 136.684051 -65.476625) (xy 136.628614 -65.482725)
			(xy 136.57288 -65.480688) (xy 136.518037 -65.470558) (xy 136.465253 -65.452551) (xy 136.415653 -65.42705)
			(xy 136.370295 -65.394599) (xy 136.330146 -65.35589) (xy 136.29606 -65.311747) (xy 136.268764 -65.263112)
			(xy 136.248841 -65.211021) (xy 136.236715 -65.156584) (xy 136.232644 -65.100962) (xy 130.391916 -65.100962)
			(xy 130.391916 -65.466468) (xy 130.391916 -65.466976) (xy 130.391154 -65.523872) (xy 130.3909 -65.554098)
			(xy 130.391641 -65.56677) (xy 130.403758 -65.589039) (xy 130.414014 -65.596516) (xy 130.421126 -65.600326)
			(xy 130.432379 -65.604596) (xy 130.456374 -65.60325) (xy 130.4671 -65.597786) (xy 130.475482 -65.592706)
			(xy 130.491992 -65.574926) (xy 130.49504 -65.569592) (xy 130.495294 -65.569084) (xy 130.509937 -65.544108)
			(xy 130.545579 -65.498486) (xy 130.58769 -65.458757) (xy 130.635308 -65.425829) (xy 130.687346 -65.400456)
			(xy 130.742614 -65.383216) (xy 130.799849 -65.374503) (xy 130.828796 -65.374012) (xy 130.856048 -65.374475)
			(xy 130.909996 -65.382231) (xy 130.962292 -65.397586) (xy 131.01187 -65.420227) (xy 131.057721 -65.449693)
			(xy 131.098912 -65.485385) (xy 131.134604 -65.526576) (xy 131.164071 -65.572427) (xy 131.186713 -65.622005)
			(xy 131.202068 -65.6743) (xy 131.209825 -65.728248) (xy 131.209825 -65.782752) (xy 131.202068 -65.8367)
			(xy 131.186713 -65.888995) (xy 131.164071 -65.938573) (xy 131.134604 -65.984424) (xy 131.098912 -66.025615)
			(xy 131.057721 -66.061307) (xy 131.01187 -66.090773) (xy 130.962292 -66.113414) (xy 130.909996 -66.128769)
			(xy 130.856048 -66.136525) (xy 130.828796 -66.137028) (xy 130.799607 -66.136473) (xy 130.741911 -66.127582)
			(xy 130.686242 -66.110007) (xy 130.633899 -66.084159) (xy 130.586104 -66.050641) (xy 130.564636 -66.030856)
			(xy 130.55727 -66.023744) (xy 130.541522 -66.017648) (xy 130.53568 -66.01587) (xy 130.522472 -66.012568)
			(xy 130.516787 -66.011901) (xy 130.505378 -66.012801) (xy 130.499866 -66.014346) (xy 130.44805 -66.034666)
			(xy 130.447542 -66.034666) (xy 130.416554 -66.046858) (xy 130.407221 -66.050978) (xy 130.39258 -66.065164)
			(xy 130.384576 -66.083912) (xy 130.384042 -66.094102) (xy 130.384042 -66.094356) (xy 130.378454 -66.54292)
			(xy 130.377184 -66.646806) (xy 130.37566 -66.766186) (xy 130.37566 -66.789554) (xy 130.376168 -66.794126)
			(xy 130.376422 -66.796158) (xy 130.37693 -66.800476) (xy 130.379476 -66.81171) (xy 130.392966 -66.830355)
			(xy 130.402838 -66.83629) (xy 130.410966 -66.840354) (xy 130.41884 -66.843148) (xy 130.494278 -66.87058)
			(xy 130.498225 -66.871842) (xy 130.506392 -66.873244) (xy 130.510534 -66.873374) (xy 130.517646 -66.873374)
			(xy 130.523512 -66.87321) (xy 130.534932 -66.870517) (xy 130.540252 -66.86804) (xy 130.545078 -66.865754)
			(xy 130.551936 -66.860166) (xy 130.555238 -66.85661) (xy 130.555746 -66.855594) (xy 130.556762 -66.854578)
			(xy 130.557524 -66.853816) (xy 130.565704 -66.844432) (xy 130.583116 -66.826637) (xy 130.592322 -66.818256)
			(xy 130.613448 -66.799848) (xy 130.660085 -66.768789) (xy 130.710766 -66.744891) (xy 130.764399 -66.72867)
			(xy 130.81983 -66.720475) (xy 130.847846 -66.719958) (xy 130.873459 -66.720393) (xy 130.92422 -66.727283)
			(xy 130.973606 -66.740892) (xy 131.020731 -66.760977) (xy 131.064751 -66.787178) (xy 131.085082 -66.802762)
			(xy 131.086098 -66.80327) (xy 131.088892 -66.805556) (xy 131.0894 -66.806064) (xy 131.093351 -66.808498)
			(xy 131.101909 -66.81208) (xy 131.106418 -66.813176) (xy 131.11607 -66.814192) (xy 131.138676 -66.814192)
			(xy 131.144117 -66.814329) (xy 131.154754 -66.816626) (xy 131.159758 -66.818764) (xy 131.17322 -66.82486)
			(xy 131.181881 -66.828473) (xy 131.200596 -66.829695) (xy 131.218485 -66.824063) (xy 131.226052 -66.81851)
			(xy 131.233164 -66.812922) (xy 131.237736 -66.809366) (xy 131.238498 -66.808858) (xy 131.259141 -66.792221)
			(xy 131.304155 -66.76421) (xy 131.352614 -66.742702) (xy 131.403584 -66.728109) (xy 131.456084 -66.720713)
			(xy 131.482592 -66.720212) (xy 131.482846 -66.720212) (xy 131.510095 -66.720701) (xy 131.564036 -66.728463)
			(xy 131.616324 -66.743823) (xy 131.665894 -66.766467) (xy 131.711737 -66.795934) (xy 131.75292 -66.831626)
			(xy 131.788605 -66.872815) (xy 131.818065 -66.918664) (xy 131.8407 -66.968238) (xy 131.856051 -67.020528)
			(xy 131.863803 -67.074471) (xy 131.864354 -67.10172) (xy 131.863879 -67.128799) (xy 131.856219 -67.182411)
			(xy 131.841054 -67.234402) (xy 131.81869 -67.283726) (xy 131.789577 -67.329392) (xy 131.754299 -67.370483)
			(xy 131.713565 -67.406172) (xy 131.668194 -67.435743) (xy 131.619097 -67.458602) (xy 131.567261 -67.474288)
			(xy 131.513728 -67.482488) (xy 131.486656 -67.483228) (xy 131.482338 -67.483228) (xy 131.452429 -67.482619)
			(xy 131.39335 -67.47324) (xy 131.336454 -67.454766) (xy 131.283133 -67.427651) (xy 131.258564 -67.410584)
			(xy 131.250182 -67.404234) (xy 131.245356 -67.400424) (xy 131.23672 -67.39509) (xy 131.235704 -67.394582)
			(xy 131.230379 -67.392117) (xy 131.218963 -67.389415) (xy 131.213098 -67.389248) (xy 131.192016 -67.389248)
			(xy 131.186576 -67.389109) (xy 131.175941 -67.386809) (xy 131.170934 -67.384676) (xy 131.157472 -67.37858)
			(xy 131.148811 -67.374966) (xy 131.130098 -67.373747) (xy 131.112212 -67.379384) (xy 131.10464 -67.38493)
			(xy 131.100068 -67.388486) (xy 131.099052 -67.389502) (xy 131.078067 -67.407155) (xy 131.031995 -67.436895)
			(xy 130.982146 -67.459746) (xy 130.929542 -67.475238) (xy 130.875265 -67.483053) (xy 130.847846 -67.483482)
			(xy 130.847338 -67.483482) (xy 130.822759 -67.483085) (xy 130.774012 -67.476746) (xy 130.72648 -67.464209)
			(xy 130.703574 -67.455288) (xy 130.66903 -67.439032) (xy 130.656127 -67.432007) (xy 130.631332 -67.416244)
			(xy 130.6195 -67.407536) (xy 130.606656 -67.397713) (xy 130.582495 -67.37622) (xy 130.57124 -67.36461)
			(xy 130.570732 -67.364102) (xy 130.55473 -67.346576) (xy 130.551174 -67.342258) (xy 130.54711 -67.338956)
			(xy 130.539236 -67.333876) (xy 130.529838 -67.329304) (xy 130.52478 -67.327098) (xy 130.514017 -67.324669)
			(xy 130.508502 -67.324478) (xy 130.494532 -67.324478) (xy 130.490652 -67.32458) (xy 130.482995 -67.325855)
			(xy 130.479292 -67.327018) (xy 130.452368 -67.335908) (xy 130.45186 -67.335908) (xy 130.400552 -67.353688)
			(xy 130.392489 -67.357109) (xy 130.379118 -67.368404) (xy 130.37028 -67.383512) (xy 130.368294 -67.392042)
			(xy 130.367786 -67.39509) (xy 130.366615 -67.488054) (xy 134.879332 -67.488054) (xy 134.883403 -67.432432)
			(xy 134.895529 -67.377995) (xy 134.915452 -67.325904) (xy 134.942748 -67.277269) (xy 134.976834 -67.233126)
			(xy 135.016983 -67.194417) (xy 135.062341 -67.161966) (xy 135.111941 -67.136465) (xy 135.164725 -67.118458)
			(xy 135.219568 -67.108328) (xy 135.275302 -67.106291) (xy 135.330739 -67.112391) (xy 135.384696 -67.126497)
			(xy 135.436025 -67.148309) (xy 135.483631 -67.177363) (xy 135.526499 -67.213038) (xy 135.563716 -67.254575)
			(xy 135.594489 -67.301088) (xy 135.618161 -67.351585) (xy 135.634229 -67.404992) (xy 135.642349 -67.460168)
			(xy 135.642858 -67.488054) (xy 135.642349 -67.51594) (xy 135.639164 -67.537584) (xy 136.17143 -67.537584)
			(xy 136.175501 -67.481962) (xy 136.187627 -67.427525) (xy 136.20755 -67.375434) (xy 136.234846 -67.326799)
			(xy 136.268932 -67.282656) (xy 136.309081 -67.243947) (xy 136.354439 -67.211496) (xy 136.404039 -67.185995)
			(xy 136.456823 -67.167988) (xy 136.511666 -67.157858) (xy 136.5674 -67.155821) (xy 136.622837 -67.161921)
			(xy 136.676794 -67.176027) (xy 136.728123 -67.197839) (xy 136.775729 -67.226893) (xy 136.818597 -67.262568)
			(xy 136.855814 -67.304105) (xy 136.886587 -67.350618) (xy 136.910259 -67.401115) (xy 136.926327 -67.454522)
			(xy 136.934447 -67.509698) (xy 136.934956 -67.537584) (xy 136.934447 -67.56547) (xy 136.930402 -67.592956)
			(xy 137.445494 -67.592956) (xy 137.449565 -67.537334) (xy 137.461691 -67.482897) (xy 137.481614 -67.430806)
			(xy 137.50891 -67.382171) (xy 137.542996 -67.338028) (xy 137.583145 -67.299319) (xy 137.628503 -67.266868)
			(xy 137.678103 -67.241367) (xy 137.730887 -67.22336) (xy 137.78573 -67.21323) (xy 137.841464 -67.211193)
			(xy 137.896901 -67.217293) (xy 137.950858 -67.231399) (xy 138.002187 -67.253211) (xy 138.049793 -67.282265)
			(xy 138.092661 -67.31794) (xy 138.129878 -67.359477) (xy 138.160651 -67.40599) (xy 138.184323 -67.456487)
			(xy 138.200391 -67.509894) (xy 138.208508 -67.565052) (xy 140.546793 -67.565052) (xy 140.546793 -67.510548)
			(xy 140.55455 -67.4566) (xy 140.569907 -67.404304) (xy 140.59255 -67.354726) (xy 140.622018 -67.308876)
			(xy 140.657712 -67.267687) (xy 140.698905 -67.231996) (xy 140.744758 -67.202532) (xy 140.794338 -67.179894)
			(xy 140.846635 -67.164543) (xy 140.900584 -67.156791) (xy 140.927836 -67.15633) (xy 140.955207 -67.156768)
			(xy 141.009388 -67.164591) (xy 141.061892 -67.180087) (xy 141.111638 -67.202935) (xy 141.157603 -67.232666)
			(xy 141.178534 -67.25031) (xy 141.178788 -67.250564) (xy 141.185868 -67.256159) (xy 141.20279 -67.262399)
			(xy 141.211808 -67.262756) (xy 141.278864 -67.262756) (xy 141.28788 -67.262391) (xy 141.304798 -67.25615)
			(xy 141.311884 -67.250564) (xy 141.311884 -67.25031) (xy 141.312138 -67.25031) (xy 141.333084 -67.232688)
			(xy 141.379053 -67.202973) (xy 141.428797 -67.180134) (xy 141.481294 -67.164639) (xy 141.535468 -67.156806)
			(xy 141.562836 -67.15633) (xy 141.590088 -67.156742) (xy 141.644037 -67.164504) (xy 141.696333 -67.179864)
			(xy 141.745911 -67.202509) (xy 141.791761 -67.231979) (xy 141.832951 -67.267674) (xy 141.868642 -67.308868)
			(xy 141.898108 -67.354721) (xy 141.920749 -67.404301) (xy 141.936104 -67.456598) (xy 141.94386 -67.510548)
			(xy 141.94386 -67.565052) (xy 141.936104 -67.619002) (xy 141.920749 -67.671299) (xy 141.898108 -67.720879)
			(xy 141.868642 -67.766732) (xy 141.832951 -67.807926) (xy 141.791761 -67.843621) (xy 141.745911 -67.873091)
			(xy 141.696333 -67.895736) (xy 141.644037 -67.911096) (xy 141.590088 -67.918858) (xy 141.562836 -67.919346)
			(xy 141.535466 -67.918872) (xy 141.481287 -67.911058) (xy 141.428783 -67.895572) (xy 141.379036 -67.872731)
			(xy 141.333069 -67.843007) (xy 141.312138 -67.825366) (xy 141.311884 -67.825112) (xy 141.304805 -67.819514)
			(xy 141.287883 -67.813274) (xy 141.278864 -67.81292) (xy 141.211808 -67.81292) (xy 141.202791 -67.813276)
			(xy 141.185874 -67.819524) (xy 141.178788 -67.825112) (xy 141.178788 -67.825366) (xy 141.178534 -67.825366)
			(xy 141.157596 -67.842997) (xy 141.111625 -67.872711) (xy 141.061879 -67.895549) (xy 141.00938 -67.911042)
			(xy 140.955205 -67.918872) (xy 140.927836 -67.919346) (xy 140.900584 -67.918809) (xy 140.846635 -67.911057)
			(xy 140.794338 -67.895706) (xy 140.744758 -67.873068) (xy 140.698905 -67.843604) (xy 140.657712 -67.807913)
			(xy 140.622018 -67.766724) (xy 140.59255 -67.720874) (xy 140.569907 -67.671296) (xy 140.55455 -67.619)
			(xy 140.546793 -67.565052) (xy 138.208508 -67.565052) (xy 138.208511 -67.56507) (xy 138.20902 -67.592956)
			(xy 138.208511 -67.620842) (xy 138.200391 -67.676018) (xy 138.184323 -67.729425) (xy 138.160651 -67.779922)
			(xy 138.129878 -67.826435) (xy 138.092661 -67.867972) (xy 138.049793 -67.903647) (xy 138.002187 -67.932701)
			(xy 137.950858 -67.954513) (xy 137.896901 -67.968619) (xy 137.841464 -67.974719) (xy 137.78573 -67.972682)
			(xy 137.730887 -67.962552) (xy 137.678103 -67.944545) (xy 137.628503 -67.919044) (xy 137.583145 -67.886593)
			(xy 137.542996 -67.847884) (xy 137.50891 -67.803741) (xy 137.481614 -67.755106) (xy 137.461691 -67.703015)
			(xy 137.449565 -67.648578) (xy 137.445494 -67.592956) (xy 136.930402 -67.592956) (xy 136.926327 -67.620646)
			(xy 136.910259 -67.674053) (xy 136.886587 -67.72455) (xy 136.855814 -67.771063) (xy 136.818597 -67.8126)
			(xy 136.775729 -67.848275) (xy 136.728123 -67.877329) (xy 136.676794 -67.899141) (xy 136.622837 -67.913247)
			(xy 136.5674 -67.919347) (xy 136.511666 -67.91731) (xy 136.456823 -67.90718) (xy 136.404039 -67.889173)
			(xy 136.354439 -67.863672) (xy 136.309081 -67.831221) (xy 136.268932 -67.792512) (xy 136.234846 -67.748369)
			(xy 136.20755 -67.699734) (xy 136.187627 -67.647643) (xy 136.175501 -67.593206) (xy 136.17143 -67.537584)
			(xy 135.639164 -67.537584) (xy 135.634229 -67.571116) (xy 135.618161 -67.624523) (xy 135.594489 -67.67502)
			(xy 135.563716 -67.721533) (xy 135.526499 -67.76307) (xy 135.483631 -67.798745) (xy 135.436025 -67.827799)
			(xy 135.384696 -67.849611) (xy 135.330739 -67.863717) (xy 135.275302 -67.869817) (xy 135.219568 -67.86778)
			(xy 135.164725 -67.85765) (xy 135.111941 -67.839643) (xy 135.062341 -67.814142) (xy 135.016983 -67.781691)
			(xy 134.976834 -67.742982) (xy 134.942748 -67.698839) (xy 134.915452 -67.650204) (xy 134.895529 -67.598113)
			(xy 134.883403 -67.543676) (xy 134.879332 -67.488054) (xy 130.366615 -67.488054) (xy 130.352772 -68.586604)
			(xy 132.725414 -68.586604) (xy 132.725879 -68.559234) (xy 132.733697 -68.505054) (xy 132.749186 -68.452551)
			(xy 132.772028 -68.402804) (xy 132.801753 -68.356838) (xy 132.819394 -68.335906) (xy 132.819648 -68.335652)
			(xy 132.825225 -68.328559) (xy 132.831476 -68.311647) (xy 132.83184 -68.302632) (xy 132.83184 -68.235576)
			(xy 132.831507 -68.226556) (xy 132.825244 -68.209639) (xy 132.819648 -68.202556) (xy 132.819394 -68.202556)
			(xy 132.819394 -68.202302) (xy 132.801741 -68.181381) (xy 132.772032 -68.135405) (xy 132.749199 -68.085655)
			(xy 132.733711 -68.033152) (xy 132.725886 -67.978974) (xy 132.725414 -67.951604) (xy 132.725859 -67.92435)
			(xy 132.733616 -67.870398) (xy 132.748973 -67.818098) (xy 132.771616 -67.768516) (xy 132.801086 -67.722662)
			(xy 132.836782 -67.681469) (xy 132.877977 -67.645775) (xy 132.923832 -67.616308) (xy 132.973415 -67.593666)
			(xy 133.025715 -67.578312) (xy 133.079668 -67.570558) (xy 133.106922 -67.570096) (xy 133.133236 -67.57055)
			(xy 133.185365 -67.577788) (xy 133.236008 -67.59211) (xy 133.284207 -67.613245) (xy 133.32905 -67.640793)
			(xy 133.36969 -67.674234) (xy 133.387846 -67.693286) (xy 133.39535 -67.700708) (xy 133.414643 -67.709221)
			(xy 133.425184 -67.709796) (xy 133.49986 -67.709796) (xy 133.510409 -67.70926) (xy 133.529704 -67.70073)
			(xy 133.537198 -67.693286) (xy 133.555359 -67.674236) (xy 133.595988 -67.640779) (xy 133.640827 -67.613219)
			(xy 133.689027 -67.59208) (xy 133.739673 -67.577762) (xy 133.791806 -67.570535) (xy 133.818122 -67.570096)
			(xy 133.845493 -67.57055) (xy 133.899672 -67.578371) (xy 133.952175 -67.593863) (xy 134.001922 -67.616707)
			(xy 134.047889 -67.646434) (xy 134.06882 -67.664076) (xy 134.069074 -67.66433) (xy 134.076161 -67.669915)
			(xy 134.093078 -67.676162) (xy 134.102094 -67.676522) (xy 134.16915 -67.676522) (xy 134.178164 -67.676136)
			(xy 134.195081 -67.669908) (xy 134.20217 -67.66433) (xy 134.20217 -67.664076) (xy 134.202424 -67.664076)
			(xy 134.223371 -67.646455) (xy 134.26934 -67.616742) (xy 134.319084 -67.593902) (xy 134.371581 -67.578407)
			(xy 134.425754 -67.570573) (xy 134.453122 -67.570096) (xy 134.480374 -67.570557) (xy 134.534323 -67.578317)
			(xy 134.586618 -67.593675) (xy 134.636196 -67.616319) (xy 134.682046 -67.645788) (xy 134.723236 -67.681482)
			(xy 134.758928 -67.722675) (xy 134.788393 -67.768527) (xy 134.811034 -67.818106) (xy 134.826389 -67.870403)
			(xy 134.834145 -67.924352) (xy 134.83463 -67.951604) (xy 134.834183 -67.978975) (xy 134.826363 -68.033156)
			(xy 134.810871 -68.08566) (xy 134.788024 -68.135406) (xy 134.758294 -68.181372) (xy 134.74065 -68.202302)
			(xy 134.740396 -68.202556) (xy 134.734821 -68.209651) (xy 134.728568 -68.226561) (xy 134.728204 -68.235576)
			(xy 134.728204 -68.302632) (xy 134.728545 -68.311651) (xy 134.734804 -68.328567) (xy 134.740396 -68.335652)
			(xy 134.74065 -68.335652) (xy 134.74065 -68.335906) (xy 134.758298 -68.356831) (xy 134.78801 -68.402805)
			(xy 134.810845 -68.452554) (xy 134.826334 -68.505057) (xy 134.834158 -68.559234) (xy 134.83463 -68.586604)
			(xy 134.834126 -68.613854) (xy 134.82637 -68.6678) (xy 134.811015 -68.720093) (xy 134.794375 -68.75653)
			(xy 138.270488 -68.75653) (xy 138.270975 -68.729161) (xy 138.278788 -68.674982) (xy 138.294272 -68.62248)
			(xy 138.317109 -68.572733) (xy 138.346829 -68.526765) (xy 138.364468 -68.505832) (xy 138.364722 -68.505578)
			(xy 138.370326 -68.498504) (xy 138.376562 -68.481577) (xy 138.376914 -68.472558) (xy 138.376914 -68.405502)
			(xy 138.376553 -68.396486) (xy 138.370308 -68.379569) (xy 138.364722 -68.372482) (xy 138.364468 -68.372482)
			(xy 138.364468 -68.372228) (xy 138.346824 -68.3513) (xy 138.317114 -68.305326) (xy 138.294279 -68.255577)
			(xy 138.278789 -68.203076) (xy 138.270962 -68.148899) (xy 138.270488 -68.12153) (xy 138.270983 -68.094278)
			(xy 138.278736 -68.040328) (xy 138.294088 -67.988031) (xy 138.316727 -67.938452) (xy 138.346191 -67.892599)
			(xy 138.381882 -67.851406) (xy 138.423071 -67.815712) (xy 138.468922 -67.786243) (xy 138.5185 -67.7636)
			(xy 138.570795 -67.748243) (xy 138.624744 -67.740486) (xy 138.651996 -67.740022) (xy 138.679366 -67.740485)
			(xy 138.733546 -67.748303) (xy 138.786049 -67.763792) (xy 138.835796 -67.786635) (xy 138.881763 -67.81636)
			(xy 138.902694 -67.834002) (xy 138.902948 -67.834256) (xy 138.91004 -67.839834) (xy 138.926953 -67.846084)
			(xy 138.935968 -67.846448) (xy 139.003024 -67.846448) (xy 139.012043 -67.846114) (xy 139.028961 -67.839852)
			(xy 139.036044 -67.834256) (xy 139.036044 -67.834002) (xy 139.036298 -67.834002) (xy 139.05722 -67.816351)
			(xy 139.103196 -67.786641) (xy 139.152946 -67.763807) (xy 139.205449 -67.748319) (xy 139.259626 -67.740494)
			(xy 139.286996 -67.740022) (xy 139.31331 -67.740485) (xy 139.365439 -67.74772) (xy 139.416082 -67.762039)
			(xy 139.464281 -67.783173) (xy 139.509125 -67.81072) (xy 139.549764 -67.84416) (xy 139.56792 -67.863212)
			(xy 139.575431 -67.870626) (xy 139.594719 -67.879143) (xy 139.605258 -67.879722) (xy 139.679934 -67.879722)
			(xy 139.69048 -67.879164) (xy 139.709776 -67.870649) (xy 139.717272 -67.863212) (xy 139.735451 -67.844179)
			(xy 139.776075 -67.81072) (xy 139.82091 -67.783157) (xy 139.869107 -67.762015) (xy 139.91975 -67.747693)
			(xy 139.971881 -67.740463) (xy 139.998196 -67.740022) (xy 140.02545 -67.740459) (xy 140.079404 -67.748216)
			(xy 140.131704 -67.763573) (xy 140.181286 -67.786218) (xy 140.22714 -67.815688) (xy 140.268334 -67.851385)
			(xy 140.304028 -67.89258) (xy 140.333495 -67.938437) (xy 140.356136 -67.988021) (xy 140.371489 -68.040322)
			(xy 140.379243 -68.094276) (xy 140.379704 -68.12153) (xy 140.379255 -68.148901) (xy 140.371433 -68.203081)
			(xy 140.35594 -68.255584) (xy 140.333094 -68.30533) (xy 140.303367 -68.351297) (xy 140.285724 -68.372228)
			(xy 140.28547 -68.372482) (xy 140.279881 -68.379567) (xy 140.273637 -68.396485) (xy 140.273278 -68.405502)
			(xy 140.273278 -68.472558) (xy 140.27366 -68.481572) (xy 140.279891 -68.498489) (xy 140.28547 -68.505578)
			(xy 140.285724 -68.505578) (xy 140.285724 -68.505832) (xy 140.303348 -68.526776) (xy 140.333062 -68.572746)
			(xy 140.3559 -68.62249) (xy 140.371395 -68.674988) (xy 140.379227 -68.729162) (xy 140.379704 -68.75653)
			(xy 140.37925 -68.783782) (xy 140.371489 -68.837731) (xy 140.35613 -68.890027) (xy 140.333485 -68.939604)
			(xy 140.304016 -68.985455) (xy 140.268321 -69.026645) (xy 140.227128 -69.062336) (xy 140.181275 -69.091802)
			(xy 140.131695 -69.114442) (xy 140.079398 -69.129797) (xy 140.025448 -69.137553) (xy 139.998196 -69.138038)
			(xy 139.971881 -69.137593) (xy 139.919751 -69.130356) (xy 139.869107 -69.116034) (xy 139.820907 -69.094898)
			(xy 139.776065 -69.067347) (xy 139.735427 -69.033902) (xy 139.717272 -69.014848) (xy 139.709756 -69.007439)
			(xy 139.690472 -68.998917) (xy 139.679934 -68.998338) (xy 139.605258 -68.998338) (xy 139.594709 -68.998874)
			(xy 139.575413 -69.007403) (xy 139.56792 -69.014848) (xy 139.549757 -69.033896) (xy 139.509128 -69.067352)
			(xy 139.464289 -69.094911) (xy 139.41609 -69.11605) (xy 139.365444 -69.13037) (xy 139.313312 -69.137597)
			(xy 139.286996 -69.138038) (xy 139.259625 -69.137589) (xy 139.205445 -69.12977) (xy 139.152941 -69.114277)
			(xy 139.103194 -69.091431) (xy 139.057229 -69.061702) (xy 139.036298 -69.044058) (xy 139.036044 -69.043804)
			(xy 139.028949 -69.03823) (xy 139.012039 -69.031976) (xy 139.003024 -69.031612) (xy 138.935968 -69.031612)
			(xy 138.926949 -69.031951) (xy 138.910032 -69.038211) (xy 138.902948 -69.043804) (xy 138.902948 -69.044058)
			(xy 138.902694 -69.044058) (xy 138.88177 -69.061707) (xy 138.835795 -69.091419) (xy 138.786046 -69.114253)
			(xy 138.733543 -69.129742) (xy 138.679366 -69.137566) (xy 138.651996 -69.138038) (xy 138.624746 -69.137526)
			(xy 138.570801 -69.12977) (xy 138.518508 -69.114416) (xy 138.468933 -69.091776) (xy 138.423084 -69.062312)
			(xy 138.381895 -69.026624) (xy 138.346203 -68.985437) (xy 138.316736 -68.93959) (xy 138.294093 -68.890016)
			(xy 138.278736 -68.837725) (xy 138.270976 -68.78378) (xy 138.270488 -68.75653) (xy 134.794375 -68.75653)
			(xy 134.788375 -68.769669) (xy 134.75891 -68.815518) (xy 134.723221 -68.856708) (xy 134.682033 -68.8924)
			(xy 134.636185 -68.921866) (xy 134.58661 -68.944509) (xy 134.534318 -68.959866) (xy 134.480372 -68.967625)
			(xy 134.453122 -68.968112) (xy 134.425752 -68.96763) (xy 134.371574 -68.959816) (xy 134.319071 -68.94433)
			(xy 134.269324 -68.921492) (xy 134.223356 -68.891771) (xy 134.202424 -68.874132) (xy 134.20217 -68.873878)
			(xy 134.195069 -68.868312) (xy 134.178163 -68.862054) (xy 134.16915 -68.861686) (xy 134.102094 -68.861686)
			(xy 134.093077 -68.862043) (xy 134.07616 -68.868291) (xy 134.069074 -68.873878) (xy 134.069074 -68.874132)
			(xy 134.06882 -68.874132) (xy 134.047895 -68.89178) (xy 134.00192 -68.92149) (xy 133.952171 -68.944323)
			(xy 133.899668 -68.959812) (xy 133.845492 -68.967639) (xy 133.818122 -68.968112) (xy 133.791809 -68.967626)
			(xy 133.739681 -68.960394) (xy 133.689039 -68.946079) (xy 133.64084 -68.92495) (xy 133.595996 -68.897407)
			(xy 133.555355 -68.863972) (xy 133.537198 -68.844922) (xy 133.529676 -68.837521) (xy 133.510396 -68.828995)
			(xy 133.49986 -68.828412) (xy 133.425184 -68.828412) (xy 133.414631 -68.828915) (xy 133.395336 -68.837468)
			(xy 133.387846 -68.844922) (xy 133.369714 -68.864001) (xy 133.329079 -68.897455) (xy 133.284233 -68.925011)
			(xy 133.236028 -68.946145) (xy 133.185377 -68.960457) (xy 133.133239 -68.967676) (xy 133.106922 -68.968112)
			(xy 133.07967 -68.967624) (xy 133.02572 -68.95987) (xy 132.973423 -68.944517) (xy 132.923843 -68.921878)
			(xy 132.87799 -68.892412) (xy 132.836797 -68.856721) (xy 132.801103 -68.815531) (xy 132.771635 -68.76968)
			(xy 132.748992 -68.720102) (xy 132.733635 -68.667805) (xy 132.725878 -68.613856) (xy 132.725414 -68.586604)
			(xy 130.352772 -68.586604) (xy 130.347212 -69.027802) (xy 130.34391 -69.30263) (xy 130.325651 -71.555864)
			(xy 135.294622 -71.555864) (xy 135.298693 -71.500242) (xy 135.310819 -71.445805) (xy 135.330742 -71.393714)
			(xy 135.358038 -71.345079) (xy 135.392124 -71.300936) (xy 135.432273 -71.262227) (xy 135.477631 -71.229776)
			(xy 135.527231 -71.204275) (xy 135.580015 -71.186268) (xy 135.634858 -71.176138) (xy 135.690592 -71.174101)
			(xy 135.746029 -71.180201) (xy 135.799986 -71.194307) (xy 135.851315 -71.216119) (xy 135.898921 -71.245173)
			(xy 135.941789 -71.280848) (xy 135.979006 -71.322385) (xy 136.009779 -71.368898) (xy 136.033451 -71.419395)
			(xy 136.049519 -71.472802) (xy 136.057639 -71.527978) (xy 136.058148 -71.555864) (xy 136.057639 -71.58375)
			(xy 136.0518 -71.623428) (xy 136.803636 -71.623428) (xy 136.807707 -71.567806) (xy 136.819833 -71.513369)
			(xy 136.839756 -71.461278) (xy 136.867052 -71.412643) (xy 136.901138 -71.3685) (xy 136.941287 -71.329791)
			(xy 136.986645 -71.29734) (xy 137.036245 -71.271839) (xy 137.089029 -71.253832) (xy 137.143872 -71.243702)
			(xy 137.199606 -71.241665) (xy 137.255043 -71.247765) (xy 137.309 -71.261871) (xy 137.360329 -71.283683)
			(xy 137.407935 -71.312737) (xy 137.450803 -71.348412) (xy 137.48802 -71.389949) (xy 137.518793 -71.436462)
			(xy 137.542465 -71.486959) (xy 137.558533 -71.540366) (xy 137.566653 -71.595542) (xy 137.567162 -71.623428)
			(xy 137.566653 -71.651314) (xy 137.558533 -71.70649) (xy 137.542465 -71.759897) (xy 137.518793 -71.810394)
			(xy 137.48802 -71.856907) (xy 137.450803 -71.898444) (xy 137.407935 -71.934119) (xy 137.360329 -71.963173)
			(xy 137.309 -71.984985) (xy 137.255043 -71.999091) (xy 137.199606 -72.005191) (xy 137.143872 -72.003154)
			(xy 137.089029 -71.993024) (xy 137.036245 -71.975017) (xy 136.986645 -71.949516) (xy 136.941287 -71.917065)
			(xy 136.901138 -71.878356) (xy 136.867052 -71.834213) (xy 136.839756 -71.785578) (xy 136.819833 -71.733487)
			(xy 136.807707 -71.67905) (xy 136.803636 -71.623428) (xy 136.0518 -71.623428) (xy 136.049519 -71.638926)
			(xy 136.033451 -71.692333) (xy 136.009779 -71.74283) (xy 135.979006 -71.789343) (xy 135.941789 -71.83088)
			(xy 135.898921 -71.866555) (xy 135.851315 -71.895609) (xy 135.799986 -71.917421) (xy 135.746029 -71.931527)
			(xy 135.690592 -71.937627) (xy 135.634858 -71.93559) (xy 135.580015 -71.92546) (xy 135.527231 -71.907453)
			(xy 135.477631 -71.881952) (xy 135.432273 -71.849501) (xy 135.392124 -71.810792) (xy 135.358038 -71.766649)
			(xy 135.330742 -71.718014) (xy 135.310819 -71.665923) (xy 135.298693 -71.611486) (xy 135.294622 -71.555864)
			(xy 130.325651 -71.555864) (xy 130.288792 -76.104242) (xy 130.26775 -78.707234) (xy 150.214582 -78.707234)
			(xy 150.218653 -78.651612) (xy 150.230779 -78.597175) (xy 150.250702 -78.545084) (xy 150.277998 -78.496449)
			(xy 150.312084 -78.452306) (xy 150.352233 -78.413597) (xy 150.397591 -78.381146) (xy 150.447191 -78.355645)
			(xy 150.499975 -78.337638) (xy 150.554818 -78.327508) (xy 150.610552 -78.325471) (xy 150.665989 -78.331571)
			(xy 150.719946 -78.345677) (xy 150.771275 -78.367489) (xy 150.818881 -78.396543) (xy 150.861749 -78.432218)
			(xy 150.898966 -78.473755) (xy 150.929739 -78.520268) (xy 150.953411 -78.570765) (xy 150.969479 -78.624172)
			(xy 150.977599 -78.679348) (xy 150.978108 -78.707234) (xy 150.977599 -78.73512) (xy 150.969479 -78.790296)
			(xy 150.953411 -78.843703) (xy 150.929739 -78.8942) (xy 150.898966 -78.940713) (xy 150.861749 -78.98225)
			(xy 150.818881 -79.017925) (xy 150.771275 -79.046979) (xy 150.719946 -79.068791) (xy 150.665989 -79.082897)
			(xy 150.610552 -79.088997) (xy 150.554818 -79.08696) (xy 150.499975 -79.07683) (xy 150.447191 -79.058823)
			(xy 150.397591 -79.033322) (xy 150.352233 -79.000871) (xy 150.312084 -78.962162) (xy 150.277998 -78.918019)
			(xy 150.250702 -78.869384) (xy 150.230779 -78.817293) (xy 150.218653 -78.762856) (xy 150.214582 -78.707234)
			(xy 130.26775 -78.707234) (xy 130.262122 -79.403448) (xy 130.262423 -79.413014) (xy 130.269196 -79.430901)
			(xy 130.27533 -79.438246) (xy 130.276092 -79.439008) (xy 130.28295 -79.446374) (xy 130.283204 -79.446374)
			(xy 130.292602 -79.456788) (xy 130.302254 -79.461106) (xy 130.309112 -79.462884) (xy 130.320525 -79.464824)
			(xy 130.343003 -79.459383) (xy 130.352292 -79.45247) (xy 130.360928 -79.444596) (xy 130.361182 -79.444342)
			(xy 130.367278 -79.438754) (xy 130.374898 -79.425546) (xy 130.376676 -79.416656) (xy 130.382174 -79.390939)
			(xy 130.399295 -79.341217) (xy 130.423081 -79.294315) (xy 130.453081 -79.251123) (xy 130.488726 -79.212459)
			(xy 130.529342 -79.179054) (xy 130.574159 -79.151542) (xy 130.622329 -79.130443) (xy 130.672939 -79.116157)
			(xy 130.725032 -79.108955) (xy 130.751326 -79.108554) (xy 130.778577 -79.109042) (xy 130.832524 -79.116801)
			(xy 130.884818 -79.132158) (xy 130.934394 -79.1548) (xy 130.980244 -79.184266) (xy 131.021434 -79.219957)
			(xy 131.057126 -79.261146) (xy 131.086594 -79.306995) (xy 131.109238 -79.356571) (xy 131.124597 -79.408864)
			(xy 131.132358 -79.462811) (xy 131.132834 -79.490062) (xy 131.132332 -79.517798) (xy 131.124292 -79.572686)
			(xy 131.10839 -79.625831) (xy 131.084961 -79.676114) (xy 131.054499 -79.722475) (xy 131.017645 -79.763937)
			(xy 130.975178 -79.799626) (xy 130.92799 -79.828792) (xy 130.893105 -79.843884) (xy 131.606034 -79.843884)
			(xy 131.610105 -79.788262) (xy 131.622231 -79.733825) (xy 131.642154 -79.681734) (xy 131.66945 -79.633099)
			(xy 131.703536 -79.588956) (xy 131.743685 -79.550247) (xy 131.789043 -79.517796) (xy 131.838643 -79.492295)
			(xy 131.891427 -79.474288) (xy 131.94627 -79.464158) (xy 132.002004 -79.462121) (xy 132.057441 -79.468221)
			(xy 132.111398 -79.482327) (xy 132.162727 -79.504139) (xy 132.210333 -79.533193) (xy 132.253201 -79.568868)
			(xy 132.290418 -79.610405) (xy 132.321191 -79.656918) (xy 132.344863 -79.707415) (xy 132.360931 -79.760822)
			(xy 132.369051 -79.815998) (xy 132.36956 -79.843884) (xy 132.369051 -79.87177) (xy 132.360931 -79.926946)
			(xy 132.344863 -79.980353) (xy 132.321191 -80.03085) (xy 132.290418 -80.077363) (xy 132.253201 -80.1189)
			(xy 132.210333 -80.154575) (xy 132.162727 -80.183629) (xy 132.111398 -80.205441) (xy 132.057441 -80.219547)
			(xy 132.002004 -80.225647) (xy 131.94627 -80.22361) (xy 131.891427 -80.21348) (xy 131.838643 -80.195473)
			(xy 131.789043 -80.169972) (xy 131.743685 -80.137521) (xy 131.703536 -80.098812) (xy 131.66945 -80.054669)
			(xy 131.642154 -80.006034) (xy 131.622231 -79.953943) (xy 131.610105 -79.899506) (xy 131.606034 -79.843884)
			(xy 130.893105 -79.843884) (xy 130.877077 -79.850818) (xy 130.823512 -79.865241) (xy 130.79603 -79.86903)
			(xy 130.781552 -79.870554) (xy 130.751326 -79.871824) (xy 130.750818 -79.871824) (xy 130.725109 -79.871404)
			(xy 130.674157 -79.864499) (xy 130.624595 -79.850812) (xy 130.577321 -79.83059) (xy 130.533192 -79.804201)
			(xy 130.51282 -79.788512) (xy 130.51028 -79.78648) (xy 130.500598 -79.780327) (xy 130.477982 -79.776618)
			(xy 130.466846 -79.779368) (xy 130.408934 -79.796132) (xy 130.408426 -79.796132) (xy 130.385312 -79.803244)
			(xy 130.381111 -79.804839) (xy 130.37332 -79.809317) (xy 130.369818 -79.812134) (xy 130.368294 -79.813404)
			(xy 130.36423 -79.824834) (xy 130.36169 -79.8322) (xy 130.36169 -79.832454) (xy 130.357141 -79.845346)
			(xy 130.346463 -79.870516) (xy 130.340354 -79.882746) (xy 130.326472 -79.908807) (xy 130.292029 -79.956765)
			(xy 130.271774 -79.97825) (xy 130.26898 -79.981044) (xy 130.264017 -79.987448) (xy 130.257938 -80.002456)
			(xy 130.257042 -80.010508) (xy 130.230372 -83.318858) (xy 130.217926 -84.852256) (xy 130.217926 -84.852764)
			(xy 130.218434 -84.859368) (xy 130.231388 -84.950046) (xy 130.265932 -85.191092) (xy 130.266186 -85.193124)
			(xy 130.266694 -85.195156) (xy 130.341908 -85.443314) (xy 146.479004 -85.443314) (xy 146.483075 -85.387692)
			(xy 146.495201 -85.333255) (xy 146.515124 -85.281164) (xy 146.54242 -85.232529) (xy 146.576506 -85.188386)
			(xy 146.616655 -85.149677) (xy 146.662013 -85.117226) (xy 146.711613 -85.091725) (xy 146.764397 -85.073718)
			(xy 146.81924 -85.063588) (xy 146.874974 -85.061551) (xy 146.930411 -85.067651) (xy 146.984368 -85.081757)
			(xy 147.035697 -85.103569) (xy 147.083303 -85.132623) (xy 147.126171 -85.168298) (xy 147.163388 -85.209835)
			(xy 147.194161 -85.256348) (xy 147.217833 -85.306845) (xy 147.233901 -85.360252) (xy 147.242021 -85.415428)
			(xy 147.242039 -85.41639) (xy 148.126448 -85.41639) (xy 148.130519 -85.360768) (xy 148.142645 -85.306331)
			(xy 148.162568 -85.25424) (xy 148.189864 -85.205605) (xy 148.22395 -85.161462) (xy 148.264099 -85.122753)
			(xy 148.309457 -85.090302) (xy 148.359057 -85.064801) (xy 148.411841 -85.046794) (xy 148.466684 -85.036664)
			(xy 148.522418 -85.034627) (xy 148.577855 -85.040727) (xy 148.631812 -85.054833) (xy 148.683141 -85.076645)
			(xy 148.730747 -85.105699) (xy 148.773615 -85.141374) (xy 148.810832 -85.182911) (xy 148.841605 -85.229424)
			(xy 148.865277 -85.279921) (xy 148.881345 -85.333328) (xy 148.889465 -85.388504) (xy 148.889974 -85.41639)
			(xy 148.889465 -85.444276) (xy 148.881345 -85.499452) (xy 148.865277 -85.552859) (xy 148.841605 -85.603356)
			(xy 148.810832 -85.649869) (xy 148.773615 -85.691406) (xy 148.730747 -85.727081) (xy 148.683141 -85.756135)
			(xy 148.631812 -85.777947) (xy 148.577855 -85.792053) (xy 148.522418 -85.798153) (xy 148.466684 -85.796116)
			(xy 148.411841 -85.785986) (xy 148.359057 -85.767979) (xy 148.309457 -85.742478) (xy 148.264099 -85.710027)
			(xy 148.22395 -85.671318) (xy 148.189864 -85.627175) (xy 148.162568 -85.57854) (xy 148.142645 -85.526449)
			(xy 148.130519 -85.472012) (xy 148.126448 -85.41639) (xy 147.242039 -85.41639) (xy 147.24253 -85.443314)
			(xy 147.242021 -85.4712) (xy 147.233901 -85.526376) (xy 147.217833 -85.579783) (xy 147.194161 -85.63028)
			(xy 147.163388 -85.676793) (xy 147.126171 -85.71833) (xy 147.083303 -85.754005) (xy 147.035697 -85.783059)
			(xy 146.984368 -85.804871) (xy 146.930411 -85.818977) (xy 146.874974 -85.825077) (xy 146.81924 -85.82304)
			(xy 146.764397 -85.81291) (xy 146.711613 -85.794903) (xy 146.662013 -85.769402) (xy 146.616655 -85.736951)
			(xy 146.576506 -85.698242) (xy 146.54242 -85.654099) (xy 146.515124 -85.605464) (xy 146.495201 -85.553373)
			(xy 146.483075 -85.498936) (xy 146.479004 -85.443314) (xy 130.341908 -85.443314) (xy 131.060324 -87.813642)
			(xy 139.708126 -87.813642) (xy 139.712197 -87.75802) (xy 139.724323 -87.703583) (xy 139.744246 -87.651492)
			(xy 139.771542 -87.602857) (xy 139.805628 -87.558714) (xy 139.845777 -87.520005) (xy 139.891135 -87.487554)
			(xy 139.940735 -87.462053) (xy 139.993519 -87.444046) (xy 140.048362 -87.433916) (xy 140.104096 -87.431879)
			(xy 140.159533 -87.437979) (xy 140.21349 -87.452085) (xy 140.264819 -87.473897) (xy 140.312425 -87.502951)
			(xy 140.355293 -87.538626) (xy 140.39251 -87.580163) (xy 140.423283 -87.626676) (xy 140.446955 -87.677173)
			(xy 140.463023 -87.73058) (xy 140.471143 -87.785756) (xy 140.471652 -87.813642) (xy 140.471143 -87.841528)
			(xy 140.463023 -87.896704) (xy 140.446955 -87.950111) (xy 140.423283 -88.000608) (xy 140.39251 -88.047121)
			(xy 140.355293 -88.088658) (xy 140.312425 -88.124333) (xy 140.264819 -88.153387) (xy 140.21349 -88.175199)
			(xy 140.159533 -88.189305) (xy 140.104096 -88.195405) (xy 140.048362 -88.193368) (xy 139.993519 -88.183238)
			(xy 139.940735 -88.165231) (xy 139.891135 -88.13973) (xy 139.845777 -88.107279) (xy 139.805628 -88.06857)
			(xy 139.771542 -88.024427) (xy 139.744246 -87.975792) (xy 139.724323 -87.923701) (xy 139.712197 -87.869264)
			(xy 139.708126 -87.813642) (xy 131.060324 -87.813642) (xy 131.316989 -88.660478) (xy 134.653526 -88.660478)
			(xy 134.657597 -88.604856) (xy 134.669723 -88.550419) (xy 134.689646 -88.498328) (xy 134.716942 -88.449693)
			(xy 134.751028 -88.40555) (xy 134.791177 -88.366841) (xy 134.836535 -88.33439) (xy 134.886135 -88.308889)
			(xy 134.938919 -88.290882) (xy 134.993762 -88.280752) (xy 135.049496 -88.278715) (xy 135.104933 -88.284815)
			(xy 135.15889 -88.298921) (xy 135.210219 -88.320733) (xy 135.257825 -88.349787) (xy 135.300693 -88.385462)
			(xy 135.33791 -88.426999) (xy 135.368683 -88.473512) (xy 135.392355 -88.524009) (xy 135.408423 -88.577416)
			(xy 135.416543 -88.632592) (xy 135.417052 -88.660478) (xy 135.416543 -88.688364) (xy 135.408423 -88.74354)
			(xy 135.392355 -88.796947) (xy 135.368683 -88.847444) (xy 135.33791 -88.893957) (xy 135.300693 -88.935494)
			(xy 135.275281 -88.956642) (xy 139.708126 -88.956642) (xy 139.712197 -88.90102) (xy 139.724323 -88.846583)
			(xy 139.744246 -88.794492) (xy 139.771542 -88.745857) (xy 139.805628 -88.701714) (xy 139.845777 -88.663005)
			(xy 139.891135 -88.630554) (xy 139.940735 -88.605053) (xy 139.993519 -88.587046) (xy 140.048362 -88.576916)
			(xy 140.104096 -88.574879) (xy 140.159533 -88.580979) (xy 140.21349 -88.595085) (xy 140.264819 -88.616897)
			(xy 140.312425 -88.645951) (xy 140.355293 -88.681626) (xy 140.39251 -88.723163) (xy 140.423283 -88.769676)
			(xy 140.446955 -88.820173) (xy 140.463023 -88.87358) (xy 140.471143 -88.928756) (xy 140.471652 -88.956642)
			(xy 140.471143 -88.984528) (xy 140.463023 -89.039704) (xy 140.446955 -89.093111) (xy 140.423283 -89.143608)
			(xy 140.39251 -89.190121) (xy 140.355293 -89.231658) (xy 140.312425 -89.267333) (xy 140.264819 -89.296387)
			(xy 140.21349 -89.318199) (xy 140.159533 -89.332305) (xy 140.104096 -89.338405) (xy 140.048362 -89.336368)
			(xy 139.993519 -89.326238) (xy 139.940735 -89.308231) (xy 139.891135 -89.28273) (xy 139.845777 -89.250279)
			(xy 139.805628 -89.21157) (xy 139.771542 -89.167427) (xy 139.744246 -89.118792) (xy 139.724323 -89.066701)
			(xy 139.712197 -89.012264) (xy 139.708126 -88.956642) (xy 135.275281 -88.956642) (xy 135.257825 -88.971169)
			(xy 135.210219 -89.000223) (xy 135.15889 -89.022035) (xy 135.104933 -89.036141) (xy 135.049496 -89.042241)
			(xy 134.993762 -89.040204) (xy 134.938919 -89.030074) (xy 134.886135 -89.012067) (xy 134.836535 -88.986566)
			(xy 134.791177 -88.954115) (xy 134.751028 -88.915406) (xy 134.716942 -88.871263) (xy 134.689646 -88.822628)
			(xy 134.669723 -88.770537) (xy 134.657597 -88.7161) (xy 134.653526 -88.660478) (xy 131.316989 -88.660478)
			(xy 131.489742 -89.230454) (xy 133.320534 -89.230454) (xy 133.324605 -89.174832) (xy 133.336731 -89.120395)
			(xy 133.356654 -89.068304) (xy 133.38395 -89.019669) (xy 133.418036 -88.975526) (xy 133.458185 -88.936817)
			(xy 133.503543 -88.904366) (xy 133.553143 -88.878865) (xy 133.605927 -88.860858) (xy 133.66077 -88.850728)
			(xy 133.716504 -88.848691) (xy 133.771941 -88.854791) (xy 133.825898 -88.868897) (xy 133.877227 -88.890709)
			(xy 133.924833 -88.919763) (xy 133.967701 -88.955438) (xy 134.004918 -88.996975) (xy 134.035691 -89.043488)
			(xy 134.059363 -89.093985) (xy 134.075431 -89.147392) (xy 134.083551 -89.202568) (xy 134.08406 -89.230454)
			(xy 134.083551 -89.25834) (xy 134.075431 -89.313516) (xy 134.059363 -89.366923) (xy 134.035691 -89.41742)
			(xy 134.004918 -89.463933) (xy 133.967701 -89.50547) (xy 133.924833 -89.541145) (xy 133.877227 -89.570199)
			(xy 133.825898 -89.592011) (xy 133.771941 -89.606117) (xy 133.716504 -89.612217) (xy 133.66077 -89.61018)
			(xy 133.605927 -89.60005) (xy 133.553143 -89.582043) (xy 133.503543 -89.556542) (xy 133.458185 -89.524091)
			(xy 133.418036 -89.485382) (xy 133.38395 -89.441239) (xy 133.356654 -89.392604) (xy 133.336731 -89.340513)
			(xy 133.324605 -89.286076) (xy 133.320534 -89.230454) (xy 131.489742 -89.230454) (xy 131.718462 -89.985088)
			(xy 134.64743 -89.985088) (xy 134.651501 -89.929466) (xy 134.663627 -89.875029) (xy 134.68355 -89.822938)
			(xy 134.710846 -89.774303) (xy 134.744932 -89.73016) (xy 134.785081 -89.691451) (xy 134.830439 -89.659)
			(xy 134.880039 -89.633499) (xy 134.932823 -89.615492) (xy 134.987666 -89.605362) (xy 135.0434 -89.603325)
			(xy 135.098837 -89.609425) (xy 135.152794 -89.623531) (xy 135.204123 -89.645343) (xy 135.251729 -89.674397)
			(xy 135.294597 -89.710072) (xy 135.331814 -89.751609) (xy 135.362587 -89.798122) (xy 135.386259 -89.848619)
			(xy 135.402327 -89.902026) (xy 135.410447 -89.957202) (xy 135.410956 -89.985088) (xy 135.410447 -90.012974)
			(xy 135.402327 -90.06815) (xy 135.392852 -90.099642) (xy 139.708126 -90.099642) (xy 139.712197 -90.04402)
			(xy 139.724323 -89.989583) (xy 139.744246 -89.937492) (xy 139.771542 -89.888857) (xy 139.805628 -89.844714)
			(xy 139.845777 -89.806005) (xy 139.891135 -89.773554) (xy 139.940735 -89.748053) (xy 139.993519 -89.730046)
			(xy 140.048362 -89.719916) (xy 140.104096 -89.717879) (xy 140.159533 -89.723979) (xy 140.21349 -89.738085)
			(xy 140.264819 -89.759897) (xy 140.312425 -89.788951) (xy 140.355293 -89.824626) (xy 140.39251 -89.866163)
			(xy 140.423283 -89.912676) (xy 140.446955 -89.963173) (xy 140.463023 -90.01658) (xy 140.471143 -90.071756)
			(xy 140.471652 -90.099642) (xy 140.471143 -90.127528) (xy 140.463023 -90.182704) (xy 140.446955 -90.236111)
			(xy 140.423283 -90.286608) (xy 140.39251 -90.333121) (xy 140.355293 -90.374658) (xy 140.312425 -90.410333)
			(xy 140.264819 -90.439387) (xy 140.21349 -90.461199) (xy 140.159533 -90.475305) (xy 140.104096 -90.481405)
			(xy 140.048362 -90.479368) (xy 139.993519 -90.469238) (xy 139.940735 -90.451231) (xy 139.891135 -90.42573)
			(xy 139.845777 -90.393279) (xy 139.805628 -90.35457) (xy 139.771542 -90.310427) (xy 139.744246 -90.261792)
			(xy 139.724323 -90.209701) (xy 139.712197 -90.155264) (xy 139.708126 -90.099642) (xy 135.392852 -90.099642)
			(xy 135.386259 -90.121557) (xy 135.362587 -90.172054) (xy 135.331814 -90.218567) (xy 135.294597 -90.260104)
			(xy 135.251729 -90.295779) (xy 135.204123 -90.324833) (xy 135.152794 -90.346645) (xy 135.098837 -90.360751)
			(xy 135.0434 -90.366851) (xy 134.987666 -90.364814) (xy 134.932823 -90.354684) (xy 134.880039 -90.336677)
			(xy 134.830439 -90.311176) (xy 134.785081 -90.278725) (xy 134.744932 -90.240016) (xy 134.710846 -90.195873)
			(xy 134.68355 -90.147238) (xy 134.663627 -90.095147) (xy 134.651501 -90.04071) (xy 134.64743 -89.985088)
			(xy 131.718462 -89.985088) (xy 132.125324 -91.327478) (xy 134.913368 -91.327478) (xy 134.917439 -91.271856)
			(xy 134.929565 -91.217419) (xy 134.949488 -91.165328) (xy 134.976784 -91.116693) (xy 135.01087 -91.07255)
			(xy 135.051019 -91.033841) (xy 135.096377 -91.00139) (xy 135.145977 -90.975889) (xy 135.198761 -90.957882)
			(xy 135.253604 -90.947752) (xy 135.309338 -90.945715) (xy 135.364775 -90.951815) (xy 135.418732 -90.965921)
			(xy 135.470061 -90.987733) (xy 135.517667 -91.016787) (xy 135.560535 -91.052462) (xy 135.597752 -91.093999)
			(xy 135.628525 -91.140512) (xy 135.652197 -91.191009) (xy 135.667731 -91.242642) (xy 139.708126 -91.242642)
			(xy 139.712197 -91.18702) (xy 139.724323 -91.132583) (xy 139.744246 -91.080492) (xy 139.771542 -91.031857)
			(xy 139.805628 -90.987714) (xy 139.845777 -90.949005) (xy 139.891135 -90.916554) (xy 139.940735 -90.891053)
			(xy 139.993519 -90.873046) (xy 140.048362 -90.862916) (xy 140.104096 -90.860879) (xy 140.159533 -90.866979)
			(xy 140.21349 -90.881085) (xy 140.264819 -90.902897) (xy 140.312425 -90.931951) (xy 140.355293 -90.967626)
			(xy 140.39251 -91.009163) (xy 140.423283 -91.055676) (xy 140.446955 -91.106173) (xy 140.463023 -91.15958)
			(xy 140.471143 -91.214756) (xy 140.471652 -91.242642) (xy 140.471143 -91.270528) (xy 140.463023 -91.325704)
			(xy 140.446955 -91.379111) (xy 140.423283 -91.429608) (xy 140.39251 -91.476121) (xy 140.355293 -91.517658)
			(xy 140.312425 -91.553333) (xy 140.264819 -91.582387) (xy 140.21349 -91.604199) (xy 140.159533 -91.618305)
			(xy 140.104096 -91.624405) (xy 140.048362 -91.622368) (xy 139.993519 -91.612238) (xy 139.940735 -91.594231)
			(xy 139.891135 -91.56873) (xy 139.845777 -91.536279) (xy 139.805628 -91.49757) (xy 139.771542 -91.453427)
			(xy 139.744246 -91.404792) (xy 139.724323 -91.352701) (xy 139.712197 -91.298264) (xy 139.708126 -91.242642)
			(xy 135.667731 -91.242642) (xy 135.668265 -91.244416) (xy 135.676385 -91.299592) (xy 135.676894 -91.327478)
			(xy 135.676385 -91.355364) (xy 135.668265 -91.41054) (xy 135.652197 -91.463947) (xy 135.628525 -91.514444)
			(xy 135.597752 -91.560957) (xy 135.560535 -91.602494) (xy 135.517667 -91.638169) (xy 135.470061 -91.667223)
			(xy 135.418732 -91.689035) (xy 135.364775 -91.703141) (xy 135.309338 -91.709241) (xy 135.253604 -91.707204)
			(xy 135.198761 -91.697074) (xy 135.145977 -91.679067) (xy 135.096377 -91.653566) (xy 135.051019 -91.621115)
			(xy 135.01087 -91.582406) (xy 134.976784 -91.538263) (xy 134.949488 -91.489628) (xy 134.929565 -91.437537)
			(xy 134.917439 -91.3831) (xy 134.913368 -91.327478) (xy 132.125324 -91.327478) (xy 132.524795 -92.645484)
			(xy 135.053576 -92.645484) (xy 135.057647 -92.589862) (xy 135.069773 -92.535425) (xy 135.089696 -92.483334)
			(xy 135.116992 -92.434699) (xy 135.151078 -92.390556) (xy 135.191227 -92.351847) (xy 135.236585 -92.319396)
			(xy 135.286185 -92.293895) (xy 135.338969 -92.275888) (xy 135.393812 -92.265758) (xy 135.449546 -92.263721)
			(xy 135.504983 -92.269821) (xy 135.55894 -92.283927) (xy 135.610269 -92.305739) (xy 135.657875 -92.334793)
			(xy 135.700743 -92.370468) (xy 135.714339 -92.385642) (xy 139.708126 -92.385642) (xy 139.712197 -92.33002)
			(xy 139.724323 -92.275583) (xy 139.744246 -92.223492) (xy 139.771542 -92.174857) (xy 139.805628 -92.130714)
			(xy 139.845777 -92.092005) (xy 139.891135 -92.059554) (xy 139.940735 -92.034053) (xy 139.993519 -92.016046)
			(xy 140.048362 -92.005916) (xy 140.104096 -92.003879) (xy 140.159533 -92.009979) (xy 140.21349 -92.024085)
			(xy 140.264819 -92.045897) (xy 140.312425 -92.074951) (xy 140.355293 -92.110626) (xy 140.39251 -92.152163)
			(xy 140.423283 -92.198676) (xy 140.446955 -92.249173) (xy 140.463023 -92.30258) (xy 140.471143 -92.357756)
			(xy 140.471652 -92.385642) (xy 140.471143 -92.413528) (xy 140.463023 -92.468704) (xy 140.446955 -92.522111)
			(xy 140.423283 -92.572608) (xy 140.39251 -92.619121) (xy 140.355293 -92.660658) (xy 140.312425 -92.696333)
			(xy 140.264819 -92.725387) (xy 140.21349 -92.747199) (xy 140.159533 -92.761305) (xy 140.104096 -92.767405)
			(xy 140.048362 -92.765368) (xy 139.993519 -92.755238) (xy 139.940735 -92.737231) (xy 139.891135 -92.71173)
			(xy 139.845777 -92.679279) (xy 139.805628 -92.64057) (xy 139.771542 -92.596427) (xy 139.744246 -92.547792)
			(xy 139.724323 -92.495701) (xy 139.712197 -92.441264) (xy 139.708126 -92.385642) (xy 135.714339 -92.385642)
			(xy 135.73796 -92.412005) (xy 135.768733 -92.458518) (xy 135.792405 -92.509015) (xy 135.808473 -92.562422)
			(xy 135.816593 -92.617598) (xy 135.817102 -92.645484) (xy 135.816593 -92.67337) (xy 135.808473 -92.728546)
			(xy 135.792405 -92.781953) (xy 135.768733 -92.83245) (xy 135.73796 -92.878963) (xy 135.700743 -92.9205)
			(xy 135.657875 -92.956175) (xy 135.610269 -92.985229) (xy 135.55894 -93.007041) (xy 135.504983 -93.021147)
			(xy 135.449546 -93.027247) (xy 135.393812 -93.02521) (xy 135.338969 -93.01508) (xy 135.286185 -92.997073)
			(xy 135.236585 -92.971572) (xy 135.191227 -92.939121) (xy 135.151078 -92.900412) (xy 135.116992 -92.856269)
			(xy 135.089696 -92.807634) (xy 135.069773 -92.755543) (xy 135.057647 -92.701106) (xy 135.053576 -92.645484)
			(xy 132.524795 -92.645484) (xy 132.864911 -93.767656) (xy 133.93623 -93.767656) (xy 133.940301 -93.712034)
			(xy 133.952427 -93.657597) (xy 133.97235 -93.605506) (xy 133.999646 -93.556871) (xy 134.033732 -93.512728)
			(xy 134.073881 -93.474019) (xy 134.119239 -93.441568) (xy 134.168839 -93.416067) (xy 134.221623 -93.39806)
			(xy 134.276466 -93.38793) (xy 134.3322 -93.385893) (xy 134.387637 -93.391993) (xy 134.441594 -93.406099)
			(xy 134.492923 -93.427911) (xy 134.540529 -93.456965) (xy 134.583397 -93.49264) (xy 134.615655 -93.528642)
			(xy 139.708126 -93.528642) (xy 139.712197 -93.47302) (xy 139.724323 -93.418583) (xy 139.744246 -93.366492)
			(xy 139.771542 -93.317857) (xy 139.805628 -93.273714) (xy 139.845777 -93.235005) (xy 139.891135 -93.202554)
			(xy 139.940735 -93.177053) (xy 139.993519 -93.159046) (xy 140.048362 -93.148916) (xy 140.104096 -93.146879)
			(xy 140.159533 -93.152979) (xy 140.21349 -93.167085) (xy 140.264819 -93.188897) (xy 140.312425 -93.217951)
			(xy 140.355293 -93.253626) (xy 140.39251 -93.295163) (xy 140.423283 -93.341676) (xy 140.446955 -93.392173)
			(xy 140.463023 -93.44558) (xy 140.471143 -93.500756) (xy 140.471652 -93.528642) (xy 140.471143 -93.556528)
			(xy 140.463023 -93.611704) (xy 140.446955 -93.665111) (xy 140.423283 -93.715608) (xy 140.39251 -93.762121)
			(xy 140.355293 -93.803658) (xy 140.312425 -93.839333) (xy 140.264819 -93.868387) (xy 140.21349 -93.890199)
			(xy 140.159533 -93.904305) (xy 140.104096 -93.910405) (xy 140.048362 -93.908368) (xy 139.993519 -93.898238)
			(xy 139.940735 -93.880231) (xy 139.891135 -93.85473) (xy 139.845777 -93.822279) (xy 139.805628 -93.78357)
			(xy 139.771542 -93.739427) (xy 139.744246 -93.690792) (xy 139.724323 -93.638701) (xy 139.712197 -93.584264)
			(xy 139.708126 -93.528642) (xy 134.615655 -93.528642) (xy 134.620614 -93.534177) (xy 134.651387 -93.58069)
			(xy 134.675059 -93.631187) (xy 134.691127 -93.684594) (xy 134.699247 -93.73977) (xy 134.699756 -93.767656)
			(xy 134.699247 -93.795542) (xy 134.691127 -93.850718) (xy 134.675059 -93.904125) (xy 134.651387 -93.954622)
			(xy 134.620614 -94.001135) (xy 134.583397 -94.042672) (xy 134.540529 -94.078347) (xy 134.492923 -94.107401)
			(xy 134.441594 -94.129213) (xy 134.387637 -94.143319) (xy 134.3322 -94.149419) (xy 134.276466 -94.147382)
			(xy 134.221623 -94.137252) (xy 134.168839 -94.119245) (xy 134.119239 -94.093744) (xy 134.073881 -94.061293)
			(xy 134.033732 -94.022584) (xy 133.999646 -93.978441) (xy 133.97235 -93.929806) (xy 133.952427 -93.877715)
			(xy 133.940301 -93.823278) (xy 133.93623 -93.767656) (xy 132.864911 -93.767656) (xy 133.072152 -94.451424)
			(xy 135.029192 -94.451424) (xy 135.033263 -94.395802) (xy 135.045389 -94.341365) (xy 135.065312 -94.289274)
			(xy 135.092608 -94.240639) (xy 135.126694 -94.196496) (xy 135.166843 -94.157787) (xy 135.212201 -94.125336)
			(xy 135.261801 -94.099835) (xy 135.314585 -94.081828) (xy 135.369428 -94.071698) (xy 135.425162 -94.069661)
			(xy 135.480599 -94.075761) (xy 135.534556 -94.089867) (xy 135.585885 -94.111679) (xy 135.633491 -94.140733)
			(xy 135.676359 -94.176408) (xy 135.713576 -94.217945) (xy 135.744349 -94.264458) (xy 135.768021 -94.314955)
			(xy 135.784089 -94.368362) (xy 135.792209 -94.423538) (xy 135.792718 -94.451424) (xy 135.792209 -94.47931)
			(xy 135.784089 -94.534486) (xy 135.768021 -94.587893) (xy 135.744349 -94.63839) (xy 135.722349 -94.671642)
			(xy 139.708126 -94.671642) (xy 139.712197 -94.61602) (xy 139.724323 -94.561583) (xy 139.744246 -94.509492)
			(xy 139.771542 -94.460857) (xy 139.805628 -94.416714) (xy 139.845777 -94.378005) (xy 139.891135 -94.345554)
			(xy 139.940735 -94.320053) (xy 139.993519 -94.302046) (xy 140.048362 -94.291916) (xy 140.104096 -94.289879)
			(xy 140.159533 -94.295979) (xy 140.21349 -94.310085) (xy 140.264819 -94.331897) (xy 140.312425 -94.360951)
			(xy 140.355293 -94.396626) (xy 140.39251 -94.438163) (xy 140.423283 -94.484676) (xy 140.446955 -94.535173)
			(xy 140.463023 -94.58858) (xy 140.471143 -94.643756) (xy 140.471652 -94.671642) (xy 140.471143 -94.699528)
			(xy 140.463023 -94.754704) (xy 140.446955 -94.808111) (xy 140.423283 -94.858608) (xy 140.39251 -94.905121)
			(xy 140.355293 -94.946658) (xy 140.312425 -94.982333) (xy 140.264819 -95.011387) (xy 140.21349 -95.033199)
			(xy 140.159533 -95.047305) (xy 140.104096 -95.053405) (xy 140.048362 -95.051368) (xy 139.993519 -95.041238)
			(xy 139.940735 -95.023231) (xy 139.891135 -94.99773) (xy 139.845777 -94.965279) (xy 139.805628 -94.92657)
			(xy 139.771542 -94.882427) (xy 139.744246 -94.833792) (xy 139.724323 -94.781701) (xy 139.712197 -94.727264)
			(xy 139.708126 -94.671642) (xy 135.722349 -94.671642) (xy 135.713576 -94.684903) (xy 135.676359 -94.72644)
			(xy 135.633491 -94.762115) (xy 135.585885 -94.791169) (xy 135.534556 -94.812981) (xy 135.480599 -94.827087)
			(xy 135.425162 -94.833187) (xy 135.369428 -94.83115) (xy 135.314585 -94.82102) (xy 135.261801 -94.803013)
			(xy 135.212201 -94.777512) (xy 135.166843 -94.745061) (xy 135.126694 -94.706352) (xy 135.092608 -94.662209)
			(xy 135.065312 -94.613574) (xy 135.045389 -94.561483) (xy 135.033263 -94.507046) (xy 135.029192 -94.451424)
			(xy 133.072152 -94.451424) (xy 133.395948 -95.519748) (xy 134.274558 -95.519748) (xy 134.278629 -95.464126)
			(xy 134.290755 -95.409689) (xy 134.310678 -95.357598) (xy 134.337974 -95.308963) (xy 134.37206 -95.26482)
			(xy 134.412209 -95.226111) (xy 134.457567 -95.19366) (xy 134.507167 -95.168159) (xy 134.559951 -95.150152)
			(xy 134.614794 -95.140022) (xy 134.670528 -95.137985) (xy 134.725965 -95.144085) (xy 134.779922 -95.158191)
			(xy 134.819642 -95.17507) (xy 145.281648 -95.17507) (xy 145.285719 -95.119448) (xy 145.297845 -95.065011)
			(xy 145.317768 -95.01292) (xy 145.345064 -94.964285) (xy 145.37915 -94.920142) (xy 145.419299 -94.881433)
			(xy 145.464657 -94.848982) (xy 145.514257 -94.823481) (xy 145.567041 -94.805474) (xy 145.621884 -94.795344)
			(xy 145.677618 -94.793307) (xy 145.733055 -94.799407) (xy 145.787012 -94.813513) (xy 145.838341 -94.835325)
			(xy 145.885947 -94.864379) (xy 145.928815 -94.900054) (xy 145.966032 -94.941591) (xy 145.996805 -94.988104)
			(xy 146.020477 -95.038601) (xy 146.036545 -95.092008) (xy 146.044665 -95.147184) (xy 146.045174 -95.17507)
			(xy 146.044665 -95.202956) (xy 146.036545 -95.258132) (xy 146.020477 -95.311539) (xy 145.996805 -95.362036)
			(xy 145.966032 -95.408549) (xy 145.928815 -95.450086) (xy 145.885947 -95.485761) (xy 145.838341 -95.514815)
			(xy 145.787012 -95.536627) (xy 145.733055 -95.550733) (xy 145.677618 -95.556833) (xy 145.621884 -95.554796)
			(xy 145.567041 -95.544666) (xy 145.514257 -95.526659) (xy 145.464657 -95.501158) (xy 145.419299 -95.468707)
			(xy 145.37915 -95.429998) (xy 145.345064 -95.385855) (xy 145.317768 -95.33722) (xy 145.297845 -95.285129)
			(xy 145.285719 -95.230692) (xy 145.281648 -95.17507) (xy 134.819642 -95.17507) (xy 134.831251 -95.180003)
			(xy 134.878857 -95.209057) (xy 134.921725 -95.244732) (xy 134.958942 -95.286269) (xy 134.989715 -95.332782)
			(xy 135.013387 -95.383279) (xy 135.029455 -95.436686) (xy 135.037575 -95.491862) (xy 135.038084 -95.519748)
			(xy 135.037575 -95.547634) (xy 135.029455 -95.60281) (xy 135.013387 -95.656217) (xy 134.989715 -95.706714)
			(xy 134.958942 -95.753227) (xy 134.921725 -95.794764) (xy 134.897839 -95.814642) (xy 139.708126 -95.814642)
			(xy 139.712197 -95.75902) (xy 139.724323 -95.704583) (xy 139.744246 -95.652492) (xy 139.771542 -95.603857)
			(xy 139.805628 -95.559714) (xy 139.845777 -95.521005) (xy 139.891135 -95.488554) (xy 139.940735 -95.463053)
			(xy 139.993519 -95.445046) (xy 140.048362 -95.434916) (xy 140.104096 -95.432879) (xy 140.159533 -95.438979)
			(xy 140.21349 -95.453085) (xy 140.264819 -95.474897) (xy 140.312425 -95.503951) (xy 140.355293 -95.539626)
			(xy 140.39251 -95.581163) (xy 140.423283 -95.627676) (xy 140.446955 -95.678173) (xy 140.463023 -95.73158)
			(xy 140.471143 -95.786756) (xy 140.471652 -95.814642) (xy 140.471143 -95.842528) (xy 140.463023 -95.897704)
			(xy 140.446955 -95.951111) (xy 140.423283 -96.001608) (xy 140.39251 -96.048121) (xy 140.355293 -96.089658)
			(xy 140.351856 -96.092518) (xy 144.382234 -96.092518) (xy 144.386305 -96.036896) (xy 144.398431 -95.982459)
			(xy 144.418354 -95.930368) (xy 144.44565 -95.881733) (xy 144.479736 -95.83759) (xy 144.519885 -95.798881)
			(xy 144.565243 -95.76643) (xy 144.614843 -95.740929) (xy 144.667627 -95.722922) (xy 144.72247 -95.712792)
			(xy 144.778204 -95.710755) (xy 144.833641 -95.716855) (xy 144.887598 -95.730961) (xy 144.938927 -95.752773)
			(xy 144.986533 -95.781827) (xy 145.029401 -95.817502) (xy 145.066618 -95.859039) (xy 145.097391 -95.905552)
			(xy 145.121063 -95.956049) (xy 145.137131 -96.009456) (xy 145.145251 -96.064632) (xy 145.14576 -96.092518)
			(xy 145.145251 -96.120404) (xy 145.137131 -96.17558) (xy 145.121063 -96.228987) (xy 145.097391 -96.279484)
			(xy 145.066618 -96.325997) (xy 145.029401 -96.367534) (xy 144.986533 -96.403209) (xy 144.938927 -96.432263)
			(xy 144.887598 -96.454075) (xy 144.833641 -96.468181) (xy 144.778204 -96.474281) (xy 144.72247 -96.472244)
			(xy 144.667627 -96.462114) (xy 144.614843 -96.444107) (xy 144.565243 -96.418606) (xy 144.519885 -96.386155)
			(xy 144.479736 -96.347446) (xy 144.44565 -96.303303) (xy 144.418354 -96.254668) (xy 144.398431 -96.202577)
			(xy 144.386305 -96.14814) (xy 144.382234 -96.092518) (xy 140.351856 -96.092518) (xy 140.312425 -96.125333)
			(xy 140.264819 -96.154387) (xy 140.21349 -96.176199) (xy 140.159533 -96.190305) (xy 140.104096 -96.196405)
			(xy 140.048362 -96.194368) (xy 139.993519 -96.184238) (xy 139.940735 -96.166231) (xy 139.891135 -96.14073)
			(xy 139.845777 -96.108279) (xy 139.805628 -96.06957) (xy 139.771542 -96.025427) (xy 139.744246 -95.976792)
			(xy 139.724323 -95.924701) (xy 139.712197 -95.870264) (xy 139.708126 -95.814642) (xy 134.897839 -95.814642)
			(xy 134.878857 -95.830439) (xy 134.831251 -95.859493) (xy 134.779922 -95.881305) (xy 134.725965 -95.895411)
			(xy 134.670528 -95.901511) (xy 134.614794 -95.899474) (xy 134.559951 -95.889344) (xy 134.507167 -95.871337)
			(xy 134.457567 -95.845836) (xy 134.412209 -95.813385) (xy 134.37206 -95.774676) (xy 134.337974 -95.730533)
			(xy 134.310678 -95.681898) (xy 134.290755 -95.629807) (xy 134.278629 -95.57537) (xy 134.274558 -95.519748)
			(xy 133.395948 -95.519748) (xy 133.756773 -96.710246) (xy 134.734044 -96.710246) (xy 134.738115 -96.654624)
			(xy 134.750241 -96.600187) (xy 134.770164 -96.548096) (xy 134.79746 -96.499461) (xy 134.831546 -96.455318)
			(xy 134.871695 -96.416609) (xy 134.917053 -96.384158) (xy 134.966653 -96.358657) (xy 135.019437 -96.34065)
			(xy 135.07428 -96.33052) (xy 135.130014 -96.328483) (xy 135.185451 -96.334583) (xy 135.239408 -96.348689)
			(xy 135.290737 -96.370501) (xy 135.338343 -96.399555) (xy 135.381211 -96.43523) (xy 135.418428 -96.476767)
			(xy 135.449201 -96.52328) (xy 135.472873 -96.573777) (xy 135.488941 -96.627184) (xy 135.497061 -96.68236)
			(xy 135.49757 -96.710246) (xy 135.497061 -96.738132) (xy 135.488941 -96.793308) (xy 135.472873 -96.846715)
			(xy 135.449201 -96.897212) (xy 135.418428 -96.943725) (xy 135.405958 -96.957642) (xy 139.708126 -96.957642)
			(xy 139.712197 -96.90202) (xy 139.724323 -96.847583) (xy 139.744246 -96.795492) (xy 139.771542 -96.746857)
			(xy 139.805628 -96.702714) (xy 139.845777 -96.664005) (xy 139.891135 -96.631554) (xy 139.940735 -96.606053)
			(xy 139.993519 -96.588046) (xy 140.048362 -96.577916) (xy 140.104096 -96.575879) (xy 140.159533 -96.581979)
			(xy 140.21349 -96.596085) (xy 140.264819 -96.617897) (xy 140.312425 -96.646951) (xy 140.355293 -96.682626)
			(xy 140.39251 -96.724163) (xy 140.423283 -96.770676) (xy 140.446955 -96.821173) (xy 140.463023 -96.87458)
			(xy 140.471143 -96.929756) (xy 140.471652 -96.957642) (xy 140.471143 -96.985528) (xy 140.463023 -97.040704)
			(xy 140.446955 -97.094111) (xy 140.423283 -97.144608) (xy 140.39251 -97.191121) (xy 140.355293 -97.232658)
			(xy 140.312425 -97.268333) (xy 140.264819 -97.297387) (xy 140.21349 -97.319199) (xy 140.159533 -97.333305)
			(xy 140.104096 -97.339405) (xy 140.048362 -97.337368) (xy 139.993519 -97.327238) (xy 139.940735 -97.309231)
			(xy 139.891135 -97.28373) (xy 139.845777 -97.251279) (xy 139.805628 -97.21257) (xy 139.771542 -97.168427)
			(xy 139.744246 -97.119792) (xy 139.724323 -97.067701) (xy 139.712197 -97.013264) (xy 139.708126 -96.957642)
			(xy 135.405958 -96.957642) (xy 135.381211 -96.985262) (xy 135.338343 -97.020937) (xy 135.290737 -97.049991)
			(xy 135.239408 -97.071803) (xy 135.185451 -97.085909) (xy 135.130014 -97.092009) (xy 135.07428 -97.089972)
			(xy 135.019437 -97.079842) (xy 134.966653 -97.061835) (xy 134.917053 -97.036334) (xy 134.871695 -97.003883)
			(xy 134.831546 -96.965174) (xy 134.79746 -96.921031) (xy 134.770164 -96.872396) (xy 134.750241 -96.820305)
			(xy 134.738115 -96.765868) (xy 134.734044 -96.710246) (xy 133.756773 -96.710246) (xy 134.141694 -97.980246)
			(xy 134.734044 -97.980246) (xy 134.738115 -97.924624) (xy 134.750241 -97.870187) (xy 134.770164 -97.818096)
			(xy 134.79746 -97.769461) (xy 134.831546 -97.725318) (xy 134.871695 -97.686609) (xy 134.917053 -97.654158)
			(xy 134.966653 -97.628657) (xy 135.019437 -97.61065) (xy 135.07428 -97.60052) (xy 135.130014 -97.598483)
			(xy 135.185451 -97.604583) (xy 135.239408 -97.618689) (xy 135.290737 -97.640501) (xy 135.338343 -97.669555)
			(xy 135.381211 -97.70523) (xy 135.418428 -97.746767) (xy 135.449201 -97.79328) (xy 135.472873 -97.843777)
			(xy 135.488941 -97.897184) (xy 135.497061 -97.95236) (xy 135.49757 -97.980246) (xy 135.497061 -98.008132)
			(xy 135.488941 -98.063308) (xy 135.477709 -98.100642) (xy 137.211306 -98.100642) (xy 137.215377 -98.04502)
			(xy 137.227503 -97.990583) (xy 137.247426 -97.938492) (xy 137.274722 -97.889857) (xy 137.308808 -97.845714)
			(xy 137.348957 -97.807005) (xy 137.394315 -97.774554) (xy 137.443915 -97.749053) (xy 137.496699 -97.731046)
			(xy 137.551542 -97.720916) (xy 137.607276 -97.718879) (xy 137.662713 -97.724979) (xy 137.71667 -97.739085)
			(xy 137.767999 -97.760897) (xy 137.810275 -97.786698) (xy 140.222984 -97.786698) (xy 140.227055 -97.731076)
			(xy 140.239181 -97.676639) (xy 140.259104 -97.624548) (xy 140.2864 -97.575913) (xy 140.320486 -97.53177)
			(xy 140.360635 -97.493061) (xy 140.405993 -97.46061) (xy 140.455593 -97.435109) (xy 140.508377 -97.417102)
			(xy 140.56322 -97.406972) (xy 140.618954 -97.404935) (xy 140.674391 -97.411035) (xy 140.728348 -97.425141)
			(xy 140.779677 -97.446953) (xy 140.827283 -97.476007) (xy 140.870151 -97.511682) (xy 140.907368 -97.553219)
			(xy 140.938141 -97.599732) (xy 140.961813 -97.650229) (xy 140.977881 -97.703636) (xy 140.986001 -97.758812)
			(xy 140.98651 -97.786698) (xy 140.986001 -97.814584) (xy 140.977881 -97.86976) (xy 140.961813 -97.923167)
			(xy 140.938141 -97.973664) (xy 140.907368 -98.020177) (xy 140.870151 -98.061714) (xy 140.827283 -98.097389)
			(xy 140.779677 -98.126443) (xy 140.728348 -98.148255) (xy 140.674391 -98.162361) (xy 140.618954 -98.168461)
			(xy 140.56322 -98.166424) (xy 140.508377 -98.156294) (xy 140.455593 -98.138287) (xy 140.405993 -98.112786)
			(xy 140.360635 -98.080335) (xy 140.320486 -98.041626) (xy 140.2864 -97.997483) (xy 140.259104 -97.948848)
			(xy 140.239181 -97.896757) (xy 140.227055 -97.84232) (xy 140.222984 -97.786698) (xy 137.810275 -97.786698)
			(xy 137.815605 -97.789951) (xy 137.858473 -97.825626) (xy 137.89569 -97.867163) (xy 137.926463 -97.913676)
			(xy 137.950135 -97.964173) (xy 137.966203 -98.01758) (xy 137.974323 -98.072756) (xy 137.974832 -98.100642)
			(xy 137.974323 -98.128528) (xy 137.966203 -98.183704) (xy 137.950135 -98.237111) (xy 137.926463 -98.287608)
			(xy 137.89569 -98.334121) (xy 137.858473 -98.375658) (xy 137.815605 -98.411333) (xy 137.767999 -98.440387)
			(xy 137.71667 -98.462199) (xy 137.662713 -98.476305) (xy 137.607276 -98.482405) (xy 137.551542 -98.480368)
			(xy 137.496699 -98.470238) (xy 137.443915 -98.452231) (xy 137.394315 -98.42673) (xy 137.348957 -98.394279)
			(xy 137.308808 -98.35557) (xy 137.274722 -98.311427) (xy 137.247426 -98.262792) (xy 137.227503 -98.210701)
			(xy 137.215377 -98.156264) (xy 137.211306 -98.100642) (xy 135.477709 -98.100642) (xy 135.472873 -98.116715)
			(xy 135.449201 -98.167212) (xy 135.418428 -98.213725) (xy 135.381211 -98.255262) (xy 135.338343 -98.290937)
			(xy 135.290737 -98.319991) (xy 135.239408 -98.341803) (xy 135.185451 -98.355909) (xy 135.130014 -98.362009)
			(xy 135.07428 -98.359972) (xy 135.019437 -98.349842) (xy 134.966653 -98.331835) (xy 134.917053 -98.306334)
			(xy 134.871695 -98.273883) (xy 134.831546 -98.235174) (xy 134.79746 -98.191031) (xy 134.770164 -98.142396)
			(xy 134.750241 -98.090305) (xy 134.738115 -98.035868) (xy 134.734044 -97.980246) (xy 134.141694 -97.980246)
			(xy 134.524613 -99.243642) (xy 135.047988 -99.243642) (xy 135.052059 -99.18802) (xy 135.064185 -99.133583)
			(xy 135.084108 -99.081492) (xy 135.111404 -99.032857) (xy 135.14549 -98.988714) (xy 135.185639 -98.950005)
			(xy 135.230997 -98.917554) (xy 135.280597 -98.892053) (xy 135.333381 -98.874046) (xy 135.388224 -98.863916)
			(xy 135.443958 -98.861879) (xy 135.499395 -98.867979) (xy 135.553352 -98.882085) (xy 135.604681 -98.903897)
			(xy 135.652287 -98.932951) (xy 135.695155 -98.968626) (xy 135.732372 -99.010163) (xy 135.763145 -99.056676)
			(xy 135.786817 -99.107173) (xy 135.802885 -99.16058) (xy 135.811005 -99.215756) (xy 135.811514 -99.243642)
			(xy 135.811005 -99.271528) (xy 135.802885 -99.326704) (xy 135.786817 -99.380111) (xy 135.763145 -99.430608)
			(xy 135.732372 -99.477121) (xy 135.695155 -99.518658) (xy 135.652287 -99.554333) (xy 135.604681 -99.583387)
			(xy 135.553352 -99.605199) (xy 135.499395 -99.619305) (xy 135.483209 -99.621086) (xy 137.294618 -99.621086)
			(xy 137.298689 -99.565464) (xy 137.310815 -99.511027) (xy 137.330738 -99.458936) (xy 137.358034 -99.410301)
			(xy 137.39212 -99.366158) (xy 137.432269 -99.327449) (xy 137.477627 -99.294998) (xy 137.527227 -99.269497)
			(xy 137.580011 -99.25149) (xy 137.634854 -99.24136) (xy 137.690588 -99.239323) (xy 137.729839 -99.243642)
			(xy 139.729462 -99.243642) (xy 139.733533 -99.18802) (xy 139.745659 -99.133583) (xy 139.765582 -99.081492)
			(xy 139.792878 -99.032857) (xy 139.826964 -98.988714) (xy 139.867113 -98.950005) (xy 139.912471 -98.917554)
			(xy 139.962071 -98.892053) (xy 140.014855 -98.874046) (xy 140.069698 -98.863916) (xy 140.125432 -98.861879)
			(xy 140.180869 -98.867979) (xy 140.234826 -98.882085) (xy 140.286155 -98.903897) (xy 140.333761 -98.932951)
			(xy 140.376629 -98.968626) (xy 140.413846 -99.010163) (xy 140.444619 -99.056676) (xy 140.468291 -99.107173)
			(xy 140.484359 -99.16058) (xy 140.492479 -99.215756) (xy 140.492988 -99.243642) (xy 140.492479 -99.271528)
			(xy 140.484359 -99.326704) (xy 140.468291 -99.380111) (xy 140.444619 -99.430608) (xy 140.413846 -99.477121)
			(xy 140.376629 -99.518658) (xy 140.333761 -99.554333) (xy 140.286155 -99.583387) (xy 140.234826 -99.605199)
			(xy 140.180869 -99.619305) (xy 140.125432 -99.625405) (xy 140.069698 -99.623368) (xy 140.014855 -99.613238)
			(xy 139.962071 -99.595231) (xy 139.912471 -99.56973) (xy 139.867113 -99.537279) (xy 139.826964 -99.49857)
			(xy 139.792878 -99.454427) (xy 139.765582 -99.405792) (xy 139.745659 -99.353701) (xy 139.733533 -99.299264)
			(xy 139.729462 -99.243642) (xy 137.729839 -99.243642) (xy 137.746025 -99.245423) (xy 137.799982 -99.259529)
			(xy 137.851311 -99.281341) (xy 137.898917 -99.310395) (xy 137.941785 -99.34607) (xy 137.979002 -99.387607)
			(xy 138.009775 -99.43412) (xy 138.033447 -99.484617) (xy 138.049515 -99.538024) (xy 138.057635 -99.5932)
			(xy 138.058144 -99.621086) (xy 138.057635 -99.648972) (xy 138.049515 -99.704148) (xy 138.033447 -99.757555)
			(xy 138.009775 -99.808052) (xy 137.979002 -99.854565) (xy 137.941785 -99.896102) (xy 137.898917 -99.931777)
			(xy 137.851311 -99.960831) (xy 137.799982 -99.982643) (xy 137.746025 -99.996749) (xy 137.690588 -100.002849)
			(xy 137.634854 -100.000812) (xy 137.580011 -99.990682) (xy 137.527227 -99.972675) (xy 137.477627 -99.947174)
			(xy 137.432269 -99.914723) (xy 137.39212 -99.876014) (xy 137.358034 -99.831871) (xy 137.330738 -99.783236)
			(xy 137.310815 -99.731145) (xy 137.298689 -99.676708) (xy 137.294618 -99.621086) (xy 135.483209 -99.621086)
			(xy 135.443958 -99.625405) (xy 135.388224 -99.623368) (xy 135.333381 -99.613238) (xy 135.280597 -99.595231)
			(xy 135.230997 -99.56973) (xy 135.185639 -99.537279) (xy 135.14549 -99.49857) (xy 135.111404 -99.454427)
			(xy 135.084108 -99.405792) (xy 135.064185 -99.353701) (xy 135.052059 -99.299264) (xy 135.047988 -99.243642)
			(xy 134.524613 -99.243642) (xy 134.922006 -100.55479) (xy 134.925482 -100.563887) (xy 134.938019 -100.578769)
			(xy 134.94639 -100.583746) (xy 134.986776 -100.60559) (xy 134.993888 -100.6094) (xy 135.009128 -100.612448)
			(xy 135.02259 -100.610924) (xy 135.027162 -100.609654) (xy 135.049676 -100.603977) (xy 135.095651 -100.597488)
			(xy 135.118856 -100.5967) (xy 135.125968 -100.5967) (xy 135.153706 -100.597202) (xy 135.208596 -100.605243)
			(xy 135.261743 -100.621145) (xy 135.312029 -100.644573) (xy 135.358394 -100.675033) (xy 135.399861 -100.711885)
			(xy 135.435556 -100.754351) (xy 135.464728 -100.801538) (xy 135.486762 -100.85245) (xy 135.501194 -100.906016)
			(xy 135.504936 -100.933504) (xy 135.50646 -100.94722) (xy 135.508237 -100.97487) (xy 135.504744 -101.030165)
			(xy 135.493288 -101.084374) (xy 135.47411 -101.136354) (xy 135.447613 -101.185013) (xy 135.414355 -101.229326)
			(xy 135.375036 -101.268362) (xy 135.330483 -101.301299) (xy 135.281633 -101.327443) (xy 135.255762 -101.337364)
			(xy 135.246872 -101.340666) (xy 135.217662 -101.365812) (xy 135.21309 -101.374956) (xy 135.203692 -101.393498)
			(xy 135.195056 -101.410516) (xy 135.19171 -101.418663) (xy 135.190163 -101.436194) (xy 135.192008 -101.444806)
			(xy 135.192516 -101.446584) (xy 135.355502 -101.984302) (xy 151.377396 -101.984302) (xy 151.377396 -101.120702)
			(xy 151.377886 -101.090718) (xy 151.385714 -101.031262) (xy 151.401235 -100.973337) (xy 151.424184 -100.917933)
			(xy 151.454168 -100.865999) (xy 151.490674 -100.818423) (xy 151.533079 -100.776018) (xy 151.580655 -100.739512)
			(xy 151.632589 -100.709528) (xy 151.687993 -100.686579) (xy 151.745918 -100.671058) (xy 151.805374 -100.66323)
			(xy 151.865342 -100.66323) (xy 151.924798 -100.671058) (xy 151.982723 -100.686579) (xy 152.038127 -100.709528)
			(xy 152.090061 -100.739512) (xy 152.137637 -100.776018) (xy 152.180042 -100.818423) (xy 152.216548 -100.865999)
			(xy 152.246532 -100.917933) (xy 152.269481 -100.973337) (xy 152.285002 -101.031262) (xy 152.29283 -101.090718)
			(xy 152.29332 -101.120702) (xy 152.29332 -101.984302) (xy 152.29283 -102.014286) (xy 152.285002 -102.073742)
			(xy 152.269481 -102.131667) (xy 152.246532 -102.187071) (xy 152.216548 -102.239005) (xy 152.180042 -102.286581)
			(xy 152.137637 -102.328986) (xy 152.090061 -102.365492) (xy 152.038127 -102.395476) (xy 151.982723 -102.418425)
			(xy 151.924798 -102.433946) (xy 151.865342 -102.441774) (xy 151.805374 -102.441774) (xy 151.745918 -102.433946)
			(xy 151.687993 -102.418425) (xy 151.632589 -102.395476) (xy 151.580655 -102.365492) (xy 151.533079 -102.328986)
			(xy 151.490674 -102.286581) (xy 151.454168 -102.239005) (xy 151.424184 -102.187071) (xy 151.401235 -102.131667)
			(xy 151.385714 -102.073742) (xy 151.377886 -102.014286) (xy 151.377396 -101.984302) (xy 135.355502 -101.984302)
			(xy 136.446749 -105.584498) (xy 150.767796 -105.584498) (xy 150.767796 -104.720898) (xy 150.768286 -104.690914)
			(xy 150.776114 -104.631458) (xy 150.791635 -104.573533) (xy 150.814584 -104.518129) (xy 150.844568 -104.466195)
			(xy 150.881074 -104.418619) (xy 150.923479 -104.376214) (xy 150.971055 -104.339708) (xy 151.022989 -104.309724)
			(xy 151.078393 -104.286775) (xy 151.136318 -104.271254) (xy 151.195774 -104.263426) (xy 151.255742 -104.263426)
			(xy 151.315198 -104.271254) (xy 151.373123 -104.286775) (xy 151.428527 -104.309724) (xy 151.480461 -104.339708)
			(xy 151.528037 -104.376214) (xy 151.570442 -104.418619) (xy 151.606948 -104.466195) (xy 151.636932 -104.518129)
			(xy 151.659881 -104.573533) (xy 151.675402 -104.631458) (xy 151.68323 -104.690914) (xy 151.68372 -104.720898)
			(xy 151.68372 -105.584498) (xy 151.68323 -105.614482) (xy 151.675402 -105.673938) (xy 151.659881 -105.731863)
			(xy 151.636932 -105.787267) (xy 151.606948 -105.839201) (xy 151.570442 -105.886777) (xy 151.528037 -105.929182)
			(xy 151.480461 -105.965688) (xy 151.428527 -105.995672) (xy 151.373123 -106.018621) (xy 151.315198 -106.034142)
			(xy 151.255742 -106.04197) (xy 151.195774 -106.04197) (xy 151.136318 -106.034142) (xy 151.078393 -106.018621)
			(xy 151.022989 -105.995672) (xy 150.971055 -105.965688) (xy 150.923479 -105.929182) (xy 150.881074 -105.886777)
			(xy 150.844568 -105.839201) (xy 150.814584 -105.787267) (xy 150.791635 -105.731863) (xy 150.776114 -105.673938)
			(xy 150.768286 -105.614482) (xy 150.767796 -105.584498) (xy 136.446749 -105.584498) (xy 136.990293 -107.377738)
			(xy 153.409904 -107.377738) (xy 153.409904 -106.514138) (xy 153.410394 -106.484154) (xy 153.418222 -106.424698)
			(xy 153.433743 -106.366773) (xy 153.456692 -106.311369) (xy 153.486676 -106.259435) (xy 153.523182 -106.211859)
			(xy 153.565587 -106.169454) (xy 153.613163 -106.132948) (xy 153.665097 -106.102964) (xy 153.720501 -106.080015)
			(xy 153.778426 -106.064494) (xy 153.837882 -106.056666) (xy 153.89785 -106.056666) (xy 153.957306 -106.064494)
			(xy 154.015231 -106.080015) (xy 154.070635 -106.102964) (xy 154.122569 -106.132948) (xy 154.170145 -106.169454)
			(xy 154.21255 -106.211859) (xy 154.249056 -106.259435) (xy 154.27904 -106.311369) (xy 154.301989 -106.366773)
			(xy 154.31751 -106.424698) (xy 154.325338 -106.484154) (xy 154.325828 -106.514138) (xy 154.325828 -107.377738)
			(xy 154.325338 -107.407722) (xy 154.31751 -107.467178) (xy 154.301989 -107.525103) (xy 154.27904 -107.580507)
			(xy 154.249056 -107.632441) (xy 154.21255 -107.680017) (xy 154.170145 -107.722422) (xy 154.122569 -107.758928)
			(xy 154.070635 -107.788912) (xy 154.015231 -107.811861) (xy 153.957306 -107.827382) (xy 153.89785 -107.83521)
			(xy 153.837882 -107.83521) (xy 153.778426 -107.827382) (xy 153.720501 -107.811861) (xy 153.665097 -107.788912)
			(xy 153.613163 -107.758928) (xy 153.565587 -107.722422) (xy 153.523182 -107.680017) (xy 153.486676 -107.632441)
			(xy 153.456692 -107.580507) (xy 153.433743 -107.525103) (xy 153.418222 -107.467178) (xy 153.410394 -107.407722)
			(xy 153.409904 -107.377738) (xy 136.990293 -107.377738) (xy 137.308336 -108.427012) (xy 137.539588 -109.18444)
			(xy 150.767796 -109.18444) (xy 150.767796 -108.32084) (xy 150.768286 -108.290856) (xy 150.776114 -108.2314)
			(xy 150.791635 -108.173475) (xy 150.814584 -108.118071) (xy 150.844568 -108.066137) (xy 150.881074 -108.018561)
			(xy 150.923479 -107.976156) (xy 150.971055 -107.93965) (xy 151.022989 -107.909666) (xy 151.078393 -107.886717)
			(xy 151.136318 -107.871196) (xy 151.195774 -107.863368) (xy 151.255742 -107.863368) (xy 151.315198 -107.871196)
			(xy 151.373123 -107.886717) (xy 151.428527 -107.909666) (xy 151.480461 -107.93965) (xy 151.528037 -107.976156)
			(xy 151.570442 -108.018561) (xy 151.606948 -108.066137) (xy 151.636932 -108.118071) (xy 151.659881 -108.173475)
			(xy 151.675402 -108.2314) (xy 151.68323 -108.290856) (xy 151.68372 -108.32084) (xy 151.68372 -109.18444)
			(xy 151.68323 -109.214424) (xy 151.675402 -109.27388) (xy 151.659881 -109.331805) (xy 151.636932 -109.387209)
			(xy 151.606948 -109.439143) (xy 151.570442 -109.486719) (xy 151.528037 -109.529124) (xy 151.480461 -109.56563)
			(xy 151.428527 -109.595614) (xy 151.373123 -109.618563) (xy 151.315198 -109.634084) (xy 151.255742 -109.641912)
			(xy 151.195774 -109.641912) (xy 151.136318 -109.634084) (xy 151.078393 -109.618563) (xy 151.022989 -109.595614)
			(xy 150.971055 -109.56563) (xy 150.923479 -109.529124) (xy 150.881074 -109.486719) (xy 150.844568 -109.439143)
			(xy 150.814584 -109.387209) (xy 150.791635 -109.331805) (xy 150.776114 -109.27388) (xy 150.768286 -109.214424)
			(xy 150.767796 -109.18444) (xy 137.539588 -109.18444) (xy 138.087163 -110.977934) (xy 153.409904 -110.977934)
			(xy 153.409904 -110.114334) (xy 153.410394 -110.08435) (xy 153.418222 -110.024894) (xy 153.433743 -109.966969)
			(xy 153.456692 -109.911565) (xy 153.486676 -109.859631) (xy 153.523182 -109.812055) (xy 153.565587 -109.76965)
			(xy 153.613163 -109.733144) (xy 153.665097 -109.70316) (xy 153.720501 -109.680211) (xy 153.778426 -109.66469)
			(xy 153.837882 -109.656862) (xy 153.89785 -109.656862) (xy 153.957306 -109.66469) (xy 154.015231 -109.680211)
			(xy 154.070635 -109.70316) (xy 154.122569 -109.733144) (xy 154.170145 -109.76965) (xy 154.21255 -109.812055)
			(xy 154.249056 -109.859631) (xy 154.27904 -109.911565) (xy 154.301989 -109.966969) (xy 154.31751 -110.024894)
			(xy 154.325338 -110.08435) (xy 154.325828 -110.114334) (xy 154.325828 -110.977934) (xy 154.325338 -111.007918)
			(xy 154.31751 -111.067374) (xy 154.301989 -111.125299) (xy 154.27904 -111.180703) (xy 154.249056 -111.232637)
			(xy 154.21255 -111.280213) (xy 154.170145 -111.322618) (xy 154.122569 -111.359124) (xy 154.070635 -111.389108)
			(xy 154.015231 -111.412057) (xy 153.957306 -111.427578) (xy 153.89785 -111.435406) (xy 153.837882 -111.435406)
			(xy 153.778426 -111.427578) (xy 153.720501 -111.412057) (xy 153.665097 -111.389108) (xy 153.613163 -111.359124)
			(xy 153.565587 -111.322618) (xy 153.523182 -111.280213) (xy 153.486676 -111.232637) (xy 153.456692 -111.180703)
			(xy 153.433743 -111.125299) (xy 153.418222 -111.067374) (xy 153.410394 -111.007918) (xy 153.409904 -110.977934)
			(xy 138.087163 -110.977934) (xy 138.638693 -112.784382) (xy 150.767796 -112.784382) (xy 150.767796 -111.920782)
			(xy 150.768286 -111.890798) (xy 150.776114 -111.831342) (xy 150.791635 -111.773417) (xy 150.814584 -111.718013)
			(xy 150.844568 -111.666079) (xy 150.881074 -111.618503) (xy 150.923479 -111.576098) (xy 150.971055 -111.539592)
			(xy 151.022989 -111.509608) (xy 151.078393 -111.486659) (xy 151.136318 -111.471138) (xy 151.195774 -111.46331)
			(xy 151.255742 -111.46331) (xy 151.315198 -111.471138) (xy 151.373123 -111.486659) (xy 151.428527 -111.509608)
			(xy 151.480461 -111.539592) (xy 151.528037 -111.576098) (xy 151.570442 -111.618503) (xy 151.606948 -111.666079)
			(xy 151.636932 -111.718013) (xy 151.659881 -111.773417) (xy 151.675402 -111.831342) (xy 151.68323 -111.890798)
			(xy 151.68372 -111.920782) (xy 151.68372 -112.784382) (xy 151.68323 -112.814366) (xy 151.675402 -112.873822)
			(xy 151.659881 -112.931747) (xy 151.636932 -112.987151) (xy 151.606948 -113.039085) (xy 151.570442 -113.086661)
			(xy 151.528037 -113.129066) (xy 151.480461 -113.165572) (xy 151.428527 -113.195556) (xy 151.373123 -113.218505)
			(xy 151.315198 -113.234026) (xy 151.255742 -113.241854) (xy 151.195774 -113.241854) (xy 151.136318 -113.234026)
			(xy 151.078393 -113.218505) (xy 151.022989 -113.195556) (xy 150.971055 -113.165572) (xy 150.923479 -113.129066)
			(xy 150.881074 -113.086661) (xy 150.844568 -113.039085) (xy 150.814584 -112.987151) (xy 150.791635 -112.931747)
			(xy 150.776114 -112.873822) (xy 150.768286 -112.814366) (xy 150.767796 -112.784382) (xy 138.638693 -112.784382)
			(xy 139.785283 -116.539855) (xy 152.64425 -116.539855) (xy 152.64425 -116.485345) (xy 152.652008 -116.431389)
			(xy 152.667367 -116.379086) (xy 152.690013 -116.329502) (xy 152.719486 -116.283646) (xy 152.755185 -116.242451)
			(xy 152.796384 -116.206757) (xy 152.842244 -116.17729) (xy 152.891831 -116.15465) (xy 152.944136 -116.139298)
			(xy 152.998092 -116.131546) (xy 153.025348 -116.131086) (xy 153.051663 -116.131526) (xy 153.103792 -116.138767)
			(xy 153.154435 -116.153092) (xy 153.202634 -116.174229) (xy 153.247477 -116.20178) (xy 153.288116 -116.235223)
			(xy 153.306272 -116.254276) (xy 153.313805 -116.261664) (xy 153.333076 -116.270197) (xy 153.34361 -116.270786)
			(xy 153.418286 -116.270786) (xy 153.428837 -116.270267) (xy 153.448132 -116.261725) (xy 153.455624 -116.254276)
			(xy 153.472631 -116.236404) (xy 153.510464 -116.204739) (xy 153.552068 -116.178223) (xy 153.574242 -116.167408)
			(xy 153.584402 -116.162582) (xy 153.598626 -116.145818) (xy 153.625042 -116.049044) (xy 153.621486 -116.027708)
			(xy 153.615136 -116.018564) (xy 153.615136 -116.01831) (xy 153.599564 -115.994468) (xy 153.57491 -115.943136)
			(xy 153.558147 -115.888714) (xy 153.549646 -115.832406) (xy 153.549096 -115.803934) (xy 153.54963 -115.775041)
			(xy 153.558312 -115.717911) (xy 153.575514 -115.662745) (xy 153.600841 -115.610805) (xy 153.633714 -115.56328)
			(xy 153.67338 -115.521259) (xy 153.718932 -115.485702) (xy 153.769326 -115.457425) (xy 153.82341 -115.437073)
			(xy 153.879944 -115.425113) (xy 153.90876 -115.422934) (xy 153.919682 -115.422426) (xy 153.938986 -115.412266)
			(xy 153.999692 -115.335304) (xy 154.005026 -115.314222) (xy 154.002994 -115.303554) (xy 154.000151 -115.286807)
			(xy 153.997096 -115.252975) (xy 153.996898 -115.23599) (xy 153.996898 -115.235228) (xy 153.997384 -115.207977)
			(xy 154.00514 -115.154029) (xy 154.020495 -115.101734) (xy 154.043137 -115.052157) (xy 154.072603 -115.006307)
			(xy 154.108294 -114.965116) (xy 154.149485 -114.929425) (xy 154.195335 -114.899959) (xy 154.244912 -114.877317)
			(xy 154.297207 -114.861962) (xy 154.351155 -114.854206) (xy 154.405657 -114.854206) (xy 154.459605 -114.861962)
			(xy 154.5119 -114.877317) (xy 154.561477 -114.899959) (xy 154.607327 -114.929425) (xy 154.648518 -114.965116)
			(xy 154.684209 -115.006307) (xy 154.713675 -115.052157) (xy 154.736317 -115.101734) (xy 154.751672 -115.154029)
			(xy 154.759428 -115.207977) (xy 154.759914 -115.235228) (xy 154.759429 -115.264123) (xy 154.750738 -115.321254)
			(xy 154.733528 -115.37642) (xy 154.708194 -115.42836) (xy 154.675315 -115.475884) (xy 154.635644 -115.517904)
			(xy 154.590088 -115.55346) (xy 154.539691 -115.581737) (xy 154.485604 -115.602088) (xy 154.429067 -115.614049)
			(xy 154.40025 -115.616228) (xy 154.389328 -115.616736) (xy 154.370024 -115.626896) (xy 154.309318 -115.703858)
			(xy 154.303984 -115.72494) (xy 154.306016 -115.735608) (xy 154.308867 -115.752353) (xy 154.311917 -115.786187)
			(xy 154.312112 -115.803172) (xy 154.312112 -115.803934) (xy 154.31163 -115.830916) (xy 154.304008 -115.884341)
			(xy 154.288936 -115.936158) (xy 154.266714 -115.985336) (xy 154.237786 -116.030892) (xy 154.202728 -116.071918)
			(xy 154.162239 -116.107596) (xy 154.117128 -116.137214) (xy 154.09291 -116.14912) (xy 154.08275 -116.153946)
			(xy 154.068526 -116.17071) (xy 154.04211 -116.267484) (xy 154.045666 -116.28882) (xy 154.052016 -116.297964)
			(xy 154.052016 -116.298218) (xy 154.067595 -116.322057) (xy 154.092249 -116.373389) (xy 154.10901 -116.427813)
			(xy 154.117508 -116.484121) (xy 154.118056 -116.512594) (xy 154.117517 -116.539843) (xy 154.109762 -116.593786)
			(xy 154.09441 -116.646077) (xy 154.071773 -116.695651) (xy 154.042312 -116.741499) (xy 154.006626 -116.782688)
			(xy 153.965442 -116.81838) (xy 153.919599 -116.847848) (xy 153.870028 -116.870492) (xy 153.817739 -116.885851)
			(xy 153.763797 -116.893613) (xy 153.736548 -116.894102) (xy 153.710233 -116.893669) (xy 153.658103 -116.886427)
			(xy 153.60746 -116.872101) (xy 153.559261 -116.850962) (xy 153.514418 -116.82341) (xy 153.47378 -116.789966)
			(xy 153.455624 -116.770912) (xy 153.448094 -116.763521) (xy 153.42882 -116.75499) (xy 153.418286 -116.754402)
			(xy 153.34361 -116.754402) (xy 153.333059 -116.754923) (xy 153.313764 -116.763464) (xy 153.306272 -116.770912)
			(xy 153.288125 -116.789976) (xy 153.247493 -116.823432) (xy 153.202651 -116.85099) (xy 153.154449 -116.872127)
			(xy 153.1038 -116.886442) (xy 153.051665 -116.893665) (xy 153.025348 -116.894102) (xy 152.998092 -116.893654)
			(xy 152.944136 -116.885902) (xy 152.891831 -116.87055) (xy 152.842244 -116.84791) (xy 152.796384 -116.818443)
			(xy 152.755185 -116.782749) (xy 152.719486 -116.741554) (xy 152.690013 -116.695698) (xy 152.667367 -116.646114)
			(xy 152.652008 -116.593811) (xy 152.64425 -116.539855) (xy 139.785283 -116.539855) (xy 140.156098 -117.7544)
			(xy 153.187906 -117.7544) (xy 153.191977 -117.698778) (xy 153.204103 -117.644341) (xy 153.224026 -117.59225)
			(xy 153.251322 -117.543615) (xy 153.285408 -117.499472) (xy 153.325557 -117.460763) (xy 153.370915 -117.428312)
			(xy 153.420515 -117.402811) (xy 153.473299 -117.384804) (xy 153.528142 -117.374674) (xy 153.583876 -117.372637)
			(xy 153.639313 -117.378737) (xy 153.69327 -117.392843) (xy 153.744599 -117.414655) (xy 153.792205 -117.443709)
			(xy 153.835073 -117.479384) (xy 153.87229 -117.520921) (xy 153.903063 -117.567434) (xy 153.926735 -117.617931)
			(xy 153.942803 -117.671338) (xy 153.950923 -117.726514) (xy 153.951432 -117.7544) (xy 153.950923 -117.782286)
			(xy 153.942803 -117.837462) (xy 153.926735 -117.890869) (xy 153.903063 -117.941366) (xy 153.87229 -117.987879)
			(xy 153.835073 -118.029416) (xy 153.792205 -118.065091) (xy 153.744599 -118.094145) (xy 153.69327 -118.115957)
			(xy 153.639313 -118.130063) (xy 153.583876 -118.136163) (xy 153.528142 -118.134126) (xy 153.473299 -118.123996)
			(xy 153.420515 -118.105989) (xy 153.370915 -118.080488) (xy 153.325557 -118.048037) (xy 153.285408 -118.009328)
			(xy 153.251322 -117.965185) (xy 153.224026 -117.91655) (xy 153.204103 -117.864459) (xy 153.191977 -117.810022)
			(xy 153.187906 -117.7544) (xy 140.156098 -117.7544) (xy 140.410692 -118.588282) (xy 140.422363 -118.6281)
			(xy 140.439783 -118.709235) (xy 140.44549 -118.750334) (xy 140.451078 -118.79326) (xy 140.452856 -118.801388)
			(xy 140.531342 -119.060214) (xy 140.542762 -119.099363) (xy 140.559931 -119.179092) (xy 140.565632 -119.219472)
			(xy 140.679868 -120.087898) (xy 150.767796 -120.087898) (xy 150.767796 -119.224298) (xy 150.768286 -119.194314)
			(xy 150.776114 -119.134858) (xy 150.791635 -119.076933) (xy 150.814584 -119.021529) (xy 150.844568 -118.969595)
			(xy 150.881074 -118.922019) (xy 150.923479 -118.879614) (xy 150.971055 -118.843108) (xy 151.022989 -118.813124)
			(xy 151.078393 -118.790175) (xy 151.136318 -118.774654) (xy 151.195774 -118.766826) (xy 151.255742 -118.766826)
			(xy 151.315198 -118.774654) (xy 151.373123 -118.790175) (xy 151.428527 -118.813124) (xy 151.480461 -118.843108)
			(xy 151.528037 -118.879614) (xy 151.570442 -118.922019) (xy 151.606948 -118.969595) (xy 151.636932 -119.021529)
			(xy 151.659881 -119.076933) (xy 151.675402 -119.134858) (xy 151.68323 -119.194314) (xy 151.68372 -119.224298)
			(xy 151.68372 -120.087898) (xy 151.68323 -120.117882) (xy 151.675402 -120.177338) (xy 151.659881 -120.235263)
			(xy 151.636932 -120.290667) (xy 151.606948 -120.342601) (xy 151.570442 -120.390177) (xy 151.528037 -120.432582)
			(xy 151.480461 -120.469088) (xy 151.428527 -120.499072) (xy 151.373123 -120.522021) (xy 151.315198 -120.537542)
			(xy 151.255742 -120.54537) (xy 151.195774 -120.54537) (xy 151.136318 -120.537542) (xy 151.078393 -120.522021)
			(xy 151.022989 -120.499072) (xy 150.971055 -120.469088) (xy 150.923479 -120.432582) (xy 150.881074 -120.390177)
			(xy 150.844568 -120.342601) (xy 150.814584 -120.290667) (xy 150.791635 -120.235263) (xy 150.776114 -120.177338)
			(xy 150.768286 -120.117882) (xy 150.767796 -120.087898) (xy 140.679868 -120.087898) (xy 140.917496 -121.894346)
			(xy 153.409904 -121.894346) (xy 153.409904 -121.030746) (xy 153.410394 -121.000762) (xy 153.418222 -120.941306)
			(xy 153.433743 -120.883381) (xy 153.456692 -120.827977) (xy 153.486676 -120.776043) (xy 153.523182 -120.728467)
			(xy 153.565587 -120.686062) (xy 153.613163 -120.649556) (xy 153.665097 -120.619572) (xy 153.720501 -120.596623)
			(xy 153.778426 -120.581102) (xy 153.837882 -120.573274) (xy 153.89785 -120.573274) (xy 153.957306 -120.581102)
			(xy 154.015231 -120.596623) (xy 154.070635 -120.619572) (xy 154.122569 -120.649556) (xy 154.170145 -120.686062)
			(xy 154.21255 -120.728467) (xy 154.249056 -120.776043) (xy 154.27904 -120.827977) (xy 154.301989 -120.883381)
			(xy 154.31751 -120.941306) (xy 154.325338 -121.000762) (xy 154.325828 -121.030746) (xy 154.325828 -121.894346)
			(xy 154.325338 -121.92433) (xy 154.31751 -121.983786) (xy 154.301989 -122.041711) (xy 154.27904 -122.097115)
			(xy 154.249056 -122.149049) (xy 154.21255 -122.196625) (xy 154.170145 -122.23903) (xy 154.122569 -122.275536)
			(xy 154.070635 -122.30552) (xy 154.015231 -122.328469) (xy 153.957306 -122.34399) (xy 153.89785 -122.351818)
			(xy 153.837882 -122.351818) (xy 153.778426 -122.34399) (xy 153.720501 -122.328469) (xy 153.665097 -122.30552)
			(xy 153.613163 -122.275536) (xy 153.565587 -122.23903) (xy 153.523182 -122.196625) (xy 153.486676 -122.149049)
			(xy 153.456692 -122.097115) (xy 153.433743 -122.041711) (xy 153.418222 -121.983786) (xy 153.410394 -121.92433)
			(xy 153.409904 -121.894346) (xy 140.917496 -121.894346) (xy 141.15342 -123.68784) (xy 150.767796 -123.68784)
			(xy 150.767796 -122.82424) (xy 150.768286 -122.794256) (xy 150.776114 -122.7348) (xy 150.791635 -122.676875)
			(xy 150.814584 -122.621471) (xy 150.844568 -122.569537) (xy 150.881074 -122.521961) (xy 150.923479 -122.479556)
			(xy 150.971055 -122.44305) (xy 151.022989 -122.413066) (xy 151.078393 -122.390117) (xy 151.136318 -122.374596)
			(xy 151.195774 -122.366768) (xy 151.255742 -122.366768) (xy 151.315198 -122.374596) (xy 151.373123 -122.390117)
			(xy 151.428527 -122.413066) (xy 151.480461 -122.44305) (xy 151.528037 -122.479556) (xy 151.570442 -122.521961)
			(xy 151.606948 -122.569537) (xy 151.636932 -122.621471) (xy 151.659881 -122.676875) (xy 151.675402 -122.7348)
			(xy 151.68323 -122.794256) (xy 151.68372 -122.82424) (xy 151.68372 -123.68784) (xy 151.68323 -123.717824)
			(xy 151.675402 -123.77728) (xy 151.659881 -123.835205) (xy 151.636932 -123.890609) (xy 151.606948 -123.942543)
			(xy 151.570442 -123.990119) (xy 151.528037 -124.032524) (xy 151.480461 -124.06903) (xy 151.428527 -124.099014)
			(xy 151.373123 -124.121963) (xy 151.315198 -124.137484) (xy 151.255742 -124.145312) (xy 151.195774 -124.145312)
			(xy 151.136318 -124.137484) (xy 151.078393 -124.121963) (xy 151.022989 -124.099014) (xy 150.971055 -124.06903)
			(xy 150.923479 -124.032524) (xy 150.881074 -123.990119) (xy 150.844568 -123.942543) (xy 150.814584 -123.890609)
			(xy 150.791635 -123.835205) (xy 150.776114 -123.77728) (xy 150.768286 -123.717824) (xy 150.767796 -123.68784)
			(xy 141.15342 -123.68784) (xy 141.391081 -125.494542) (xy 153.409904 -125.494542) (xy 153.409904 -124.630942)
			(xy 153.410394 -124.600958) (xy 153.418222 -124.541502) (xy 153.433743 -124.483577) (xy 153.456692 -124.428173)
			(xy 153.486676 -124.376239) (xy 153.523182 -124.328663) (xy 153.565587 -124.286258) (xy 153.613163 -124.249752)
			(xy 153.665097 -124.219768) (xy 153.720501 -124.196819) (xy 153.778426 -124.181298) (xy 153.837882 -124.17347)
			(xy 153.89785 -124.17347) (xy 153.957306 -124.181298) (xy 154.015231 -124.196819) (xy 154.070635 -124.219768)
			(xy 154.122569 -124.249752) (xy 154.170145 -124.286258) (xy 154.21255 -124.328663) (xy 154.249056 -124.376239)
			(xy 154.27904 -124.428173) (xy 154.301989 -124.483577) (xy 154.31751 -124.541502) (xy 154.325338 -124.600958)
			(xy 154.325828 -124.630942) (xy 154.325828 -125.494542) (xy 154.325338 -125.524526) (xy 154.31751 -125.583982)
			(xy 154.301989 -125.641907) (xy 154.27904 -125.697311) (xy 154.249056 -125.749245) (xy 154.21255 -125.796821)
			(xy 154.170145 -125.839226) (xy 154.122569 -125.875732) (xy 154.070635 -125.905716) (xy 154.015231 -125.928665)
			(xy 153.957306 -125.944186) (xy 153.89785 -125.952014) (xy 153.837882 -125.952014) (xy 153.778426 -125.944186)
			(xy 153.720501 -125.928665) (xy 153.665097 -125.905716) (xy 153.613163 -125.875732) (xy 153.565587 -125.839226)
			(xy 153.523182 -125.796821) (xy 153.486676 -125.749245) (xy 153.456692 -125.697311) (xy 153.433743 -125.641907)
			(xy 153.418222 -125.583982) (xy 153.410394 -125.524526) (xy 153.409904 -125.494542) (xy 141.391081 -125.494542)
			(xy 141.745618 -128.189736) (xy 151.62733 -128.189736) (xy 151.631401 -128.134114) (xy 151.643527 -128.079677)
			(xy 151.66345 -128.027586) (xy 151.690746 -127.978951) (xy 151.724832 -127.934808) (xy 151.764981 -127.896099)
			(xy 151.810339 -127.863648) (xy 151.859939 -127.838147) (xy 151.912723 -127.82014) (xy 151.967566 -127.81001)
			(xy 152.0233 -127.807973) (xy 152.078737 -127.814073) (xy 152.132694 -127.828179) (xy 152.184023 -127.849991)
			(xy 152.231629 -127.879045) (xy 152.274497 -127.91472) (xy 152.311714 -127.956257) (xy 152.342487 -128.00277)
			(xy 152.366159 -128.053267) (xy 152.382227 -128.106674) (xy 152.390347 -128.16185) (xy 152.390856 -128.189736)
			(xy 152.390347 -128.217622) (xy 152.382227 -128.272798) (xy 152.366159 -128.326205) (xy 152.342487 -128.376702)
			(xy 152.311714 -128.423215) (xy 152.274497 -128.464752) (xy 152.231629 -128.500427) (xy 152.184023 -128.529481)
			(xy 152.132694 -128.551293) (xy 152.078737 -128.565399) (xy 152.0233 -128.571499) (xy 151.967566 -128.569462)
			(xy 151.912723 -128.559332) (xy 151.859939 -128.541325) (xy 151.810339 -128.515824) (xy 151.764981 -128.483373)
			(xy 151.724832 -128.444664) (xy 151.690746 -128.400521) (xy 151.66345 -128.351886) (xy 151.643527 -128.299795)
			(xy 151.631401 -128.245358) (xy 151.62733 -128.189736) (xy 141.745618 -128.189736) (xy 142.154483 -131.297934)
			(xy 150.767796 -131.297934) (xy 150.767796 -130.434334) (xy 150.768286 -130.40435) (xy 150.776114 -130.344894)
			(xy 150.791635 -130.286969) (xy 150.814584 -130.231565) (xy 150.844568 -130.179631) (xy 150.881074 -130.132055)
			(xy 150.923479 -130.08965) (xy 150.971055 -130.053144) (xy 151.022989 -130.02316) (xy 151.078393 -130.000211)
			(xy 151.136318 -129.98469) (xy 151.195774 -129.976862) (xy 151.255742 -129.976862) (xy 151.315198 -129.98469)
			(xy 151.373123 -130.000211) (xy 151.428527 -130.02316) (xy 151.480461 -130.053144) (xy 151.528037 -130.08965)
			(xy 151.570442 -130.132055) (xy 151.606948 -130.179631) (xy 151.636932 -130.231565) (xy 151.659881 -130.286969)
			(xy 151.675402 -130.344894) (xy 151.68323 -130.40435) (xy 151.68372 -130.434334) (xy 151.68372 -131.297934)
			(xy 151.68323 -131.327918) (xy 151.675402 -131.387374) (xy 151.659881 -131.445299) (xy 151.636932 -131.500703)
			(xy 151.606948 -131.552637) (xy 151.570442 -131.600213) (xy 151.528037 -131.642618) (xy 151.480461 -131.679124)
			(xy 151.428527 -131.709108) (xy 151.373123 -131.732057) (xy 151.315198 -131.747578) (xy 151.255742 -131.755406)
			(xy 151.195774 -131.755406) (xy 151.136318 -131.747578) (xy 151.078393 -131.732057) (xy 151.022989 -131.709108)
			(xy 150.971055 -131.679124) (xy 150.923479 -131.642618) (xy 150.881074 -131.600213) (xy 150.844568 -131.552637)
			(xy 150.814584 -131.500703) (xy 150.791635 -131.445299) (xy 150.776114 -131.387374) (xy 150.768286 -131.327918)
			(xy 150.767796 -131.297934) (xy 142.154483 -131.297934) (xy 142.392111 -133.104382) (xy 153.409904 -133.104382)
			(xy 153.409904 -132.240782) (xy 153.410394 -132.210798) (xy 153.418222 -132.151342) (xy 153.433743 -132.093417)
			(xy 153.456692 -132.038013) (xy 153.486676 -131.986079) (xy 153.523182 -131.938503) (xy 153.565587 -131.896098)
			(xy 153.613163 -131.859592) (xy 153.665097 -131.829608) (xy 153.720501 -131.806659) (xy 153.778426 -131.791138)
			(xy 153.837882 -131.78331) (xy 153.89785 -131.78331) (xy 153.957306 -131.791138) (xy 154.015231 -131.806659)
			(xy 154.070635 -131.829608) (xy 154.122569 -131.859592) (xy 154.170145 -131.896098) (xy 154.21255 -131.938503)
			(xy 154.249056 -131.986079) (xy 154.27904 -132.038013) (xy 154.301989 -132.093417) (xy 154.31751 -132.151342)
			(xy 154.325338 -132.210798) (xy 154.325828 -132.240782) (xy 154.325828 -133.104382) (xy 154.325338 -133.134366)
			(xy 154.31751 -133.193822) (xy 154.301989 -133.251747) (xy 154.27904 -133.307151) (xy 154.249056 -133.359085)
			(xy 154.21255 -133.406661) (xy 154.170145 -133.449066) (xy 154.122569 -133.485572) (xy 154.070635 -133.515556)
			(xy 154.015231 -133.538505) (xy 153.957306 -133.554026) (xy 153.89785 -133.561854) (xy 153.837882 -133.561854)
			(xy 153.778426 -133.554026) (xy 153.720501 -133.538505) (xy 153.665097 -133.515556) (xy 153.613163 -133.485572)
			(xy 153.565587 -133.449066) (xy 153.523182 -133.406661) (xy 153.486676 -133.359085) (xy 153.456692 -133.307151)
			(xy 153.433743 -133.251747) (xy 153.418222 -133.193822) (xy 153.410394 -133.134366) (xy 153.409904 -133.104382)
			(xy 142.392111 -133.104382) (xy 142.628034 -134.897876) (xy 150.767796 -134.897876) (xy 150.767796 -134.034276)
			(xy 150.768286 -134.004292) (xy 150.776114 -133.944836) (xy 150.791635 -133.886911) (xy 150.814584 -133.831507)
			(xy 150.844568 -133.779573) (xy 150.881074 -133.731997) (xy 150.923479 -133.689592) (xy 150.971055 -133.653086)
			(xy 151.022989 -133.623102) (xy 151.078393 -133.600153) (xy 151.136318 -133.584632) (xy 151.195774 -133.576804)
			(xy 151.255742 -133.576804) (xy 151.315198 -133.584632) (xy 151.373123 -133.600153) (xy 151.428527 -133.623102)
			(xy 151.480461 -133.653086) (xy 151.528037 -133.689592) (xy 151.570442 -133.731997) (xy 151.606948 -133.779573)
			(xy 151.636932 -133.831507) (xy 151.659881 -133.886911) (xy 151.675402 -133.944836) (xy 151.68323 -134.004292)
			(xy 151.68372 -134.034276) (xy 151.68372 -134.897876) (xy 151.68323 -134.92786) (xy 151.675402 -134.987316)
			(xy 151.659881 -135.045241) (xy 151.636932 -135.100645) (xy 151.606948 -135.152579) (xy 151.570442 -135.200155)
			(xy 151.528037 -135.24256) (xy 151.480461 -135.279066) (xy 151.428527 -135.30905) (xy 151.373123 -135.331999)
			(xy 151.315198 -135.34752) (xy 151.255742 -135.355348) (xy 151.195774 -135.355348) (xy 151.136318 -135.34752)
			(xy 151.078393 -135.331999) (xy 151.022989 -135.30905) (xy 150.971055 -135.279066) (xy 150.923479 -135.24256)
			(xy 150.881074 -135.200155) (xy 150.844568 -135.152579) (xy 150.814584 -135.100645) (xy 150.791635 -135.045241)
			(xy 150.776114 -134.987316) (xy 150.768286 -134.92786) (xy 150.767796 -134.897876) (xy 142.628034 -134.897876)
			(xy 143.34212 -140.326364) (xy 151.791922 -140.326364) (xy 151.795993 -140.270742) (xy 151.808119 -140.216305)
			(xy 151.828042 -140.164214) (xy 151.855338 -140.115579) (xy 151.889424 -140.071436) (xy 151.929573 -140.032727)
			(xy 151.974931 -140.000276) (xy 152.024531 -139.974775) (xy 152.077315 -139.956768) (xy 152.132158 -139.946638)
			(xy 152.187892 -139.944601) (xy 152.243329 -139.950701) (xy 152.297286 -139.964807) (xy 152.348615 -139.986619)
			(xy 152.396221 -140.015673) (xy 152.439089 -140.051348) (xy 152.476306 -140.092885) (xy 152.507079 -140.139398)
			(xy 152.530751 -140.189895) (xy 152.546819 -140.243302) (xy 152.554939 -140.298478) (xy 152.555448 -140.326364)
			(xy 152.554939 -140.35425) (xy 152.546819 -140.409426) (xy 152.530751 -140.462833) (xy 152.507079 -140.51333)
			(xy 152.476306 -140.559843) (xy 152.439089 -140.60138) (xy 152.396221 -140.637055) (xy 152.348615 -140.666109)
			(xy 152.297286 -140.687921) (xy 152.243329 -140.702027) (xy 152.187892 -140.708127) (xy 152.132158 -140.70609)
			(xy 152.077315 -140.69596) (xy 152.024531 -140.677953) (xy 151.974931 -140.652452) (xy 151.929573 -140.620001)
			(xy 151.889424 -140.581292) (xy 151.855338 -140.537149) (xy 151.828042 -140.488514) (xy 151.808119 -140.436423)
			(xy 151.795993 -140.381986) (xy 151.791922 -140.326364) (xy 143.34212 -140.326364) (xy 143.851122 -144.1958)
			(xy 143.851376 -144.197324) (xy 145.575405 -153.3144) (xy 153.290776 -153.3144) (xy 153.294847 -153.258778)
			(xy 153.306973 -153.204341) (xy 153.326896 -153.15225) (xy 153.354192 -153.103615) (xy 153.388278 -153.059472)
			(xy 153.428427 -153.020763) (xy 153.473785 -152.988312) (xy 153.523385 -152.962811) (xy 153.576169 -152.944804)
			(xy 153.631012 -152.934674) (xy 153.686746 -152.932637) (xy 153.742183 -152.938737) (xy 153.79614 -152.952843)
			(xy 153.847469 -152.974655) (xy 153.895075 -153.003709) (xy 153.937943 -153.039384) (xy 153.97516 -153.080921)
			(xy 154.005933 -153.127434) (xy 154.029605 -153.177931) (xy 154.045673 -153.231338) (xy 154.053793 -153.286514)
			(xy 154.054302 -153.3144) (xy 154.053793 -153.342286) (xy 154.045673 -153.397462) (xy 154.029605 -153.450869)
			(xy 154.005933 -153.501366) (xy 153.97516 -153.547879) (xy 153.937943 -153.589416) (xy 153.895075 -153.625091)
			(xy 153.847469 -153.654145) (xy 153.79614 -153.675957) (xy 153.742183 -153.690063) (xy 153.686746 -153.696163)
			(xy 153.631012 -153.694126) (xy 153.576169 -153.683996) (xy 153.523385 -153.665989) (xy 153.473785 -153.640488)
			(xy 153.428427 -153.608037) (xy 153.388278 -153.569328) (xy 153.354192 -153.525185) (xy 153.326896 -153.47655)
			(xy 153.306973 -153.424459) (xy 153.294847 -153.370022) (xy 153.290776 -153.3144) (xy 145.575405 -153.3144)
			(xy 146.343903 -157.3784) (xy 153.290776 -157.3784) (xy 153.294847 -157.322778) (xy 153.306973 -157.268341)
			(xy 153.326896 -157.21625) (xy 153.354192 -157.167615) (xy 153.388278 -157.123472) (xy 153.428427 -157.084763)
			(xy 153.473785 -157.052312) (xy 153.523385 -157.026811) (xy 153.576169 -157.008804) (xy 153.631012 -156.998674)
			(xy 153.686746 -156.996637) (xy 153.742183 -157.002737) (xy 153.79614 -157.016843) (xy 153.847469 -157.038655)
			(xy 153.895075 -157.067709) (xy 153.937943 -157.103384) (xy 153.97516 -157.144921) (xy 154.005933 -157.191434)
			(xy 154.029605 -157.241931) (xy 154.045673 -157.295338) (xy 154.053793 -157.350514) (xy 154.054302 -157.3784)
			(xy 154.053793 -157.406286) (xy 154.045673 -157.461462) (xy 154.029605 -157.514869) (xy 154.005933 -157.565366)
			(xy 153.97516 -157.611879) (xy 153.937943 -157.653416) (xy 153.895075 -157.689091) (xy 153.847469 -157.718145)
			(xy 153.79614 -157.739957) (xy 153.742183 -157.754063) (xy 153.686746 -157.760163) (xy 153.631012 -157.758126)
			(xy 153.576169 -157.747996) (xy 153.523385 -157.729989) (xy 153.473785 -157.704488) (xy 153.428427 -157.672037)
			(xy 153.388278 -157.633328) (xy 153.354192 -157.589185) (xy 153.326896 -157.54055) (xy 153.306973 -157.488459)
			(xy 153.294847 -157.434022) (xy 153.290776 -157.3784) (xy 146.343903 -157.3784) (xy 146.536028 -158.3944)
			(xy 153.290776 -158.3944) (xy 153.294847 -158.338778) (xy 153.306973 -158.284341) (xy 153.326896 -158.23225)
			(xy 153.354192 -158.183615) (xy 153.388278 -158.139472) (xy 153.428427 -158.100763) (xy 153.473785 -158.068312)
			(xy 153.523385 -158.042811) (xy 153.576169 -158.024804) (xy 153.631012 -158.014674) (xy 153.686746 -158.012637)
			(xy 153.742183 -158.018737) (xy 153.79614 -158.032843) (xy 153.847469 -158.054655) (xy 153.895075 -158.083709)
			(xy 153.937943 -158.119384) (xy 153.97516 -158.160921) (xy 154.005933 -158.207434) (xy 154.029605 -158.257931)
			(xy 154.045673 -158.311338) (xy 154.053793 -158.366514) (xy 154.054302 -158.3944) (xy 154.053793 -158.422286)
			(xy 154.045673 -158.477462) (xy 154.029605 -158.530869) (xy 154.005933 -158.581366) (xy 153.97516 -158.627879)
			(xy 153.937943 -158.669416) (xy 153.895075 -158.705091) (xy 153.847469 -158.734145) (xy 153.79614 -158.755957)
			(xy 153.742183 -158.770063) (xy 153.686746 -158.776163) (xy 153.631012 -158.774126) (xy 153.576169 -158.763996)
			(xy 153.523385 -158.745989) (xy 153.473785 -158.720488) (xy 153.428427 -158.688037) (xy 153.388278 -158.649328)
			(xy 153.354192 -158.605185) (xy 153.326896 -158.55655) (xy 153.306973 -158.504459) (xy 153.294847 -158.450022)
			(xy 153.290776 -158.3944) (xy 146.536028 -158.3944) (xy 153.991564 -197.821042) (xy 153.995586 -197.830011)
			(xy 154.009114 -197.844246) (xy 154.026987 -197.852383) (xy 154.036776 -197.8533) (xy 158.367984 -197.8533)
			(xy 158.381969 -197.852823) (xy 158.408873 -197.845165) (xy 158.432694 -197.830501) (xy 158.451649 -197.809929)
			(xy 158.464317 -197.784989) (xy 158.46975 -197.757549) (xy 158.469076 -197.743572) (xy 158.395416 -196.831712)
			(xy 158.341822 -196.167502) (xy 158.169356 -194.031616) (xy 157.986222 -191.765428) (xy 156.59735 -174.570136)
			(xy 156.59735 -174.568866) (xy 156.596842 -174.564802) (xy 156.596588 -174.562516) (xy 156.596334 -174.559468)
			(xy 156.596334 -174.558706) (xy 156.59608 -174.55642) (xy 156.595572 -174.55007) (xy 156.53004 -173.739302)
			(xy 156.361892 -171.656502) (xy 156.220414 -169.905426) (xy 156.16936 -169.272204) (xy 155.94584 -166.503604)
			(xy 155.720034 -163.70554) (xy 155.718764 -163.686744) (xy 155.35148 -157.708854) (xy 155.128722 -154.084528)
			(xy 155.128722 -154.083766) (xy 155.042616 -152.989534) (xy 154.330908 -143.941546) (xy 154.330908 -143.940022)
			(xy 154.042872 -141.203426) (xy 154.042618 -141.201902) (xy 154.039075 -141.17161) (xy 154.035261 -141.110734)
			(xy 154.034998 -141.080236) (xy 154.029156 -138.52398) (xy 154.028902 -138.521694) (xy 154.029215 -138.488826)
			(xy 154.033664 -138.423239) (xy 154.037792 -138.39063) (xy 154.038046 -138.38936) (xy 154.158696 -137.503662)
			(xy 154.196288 -137.228834) (xy 154.197077 -137.220221) (xy 154.193504 -137.203311) (xy 154.18451 -137.188551)
			(xy 154.178 -137.18286) (xy 154.155902 -137.165842) (xy 154.155394 -137.165842) (xy 154.111198 -137.132568)
			(xy 154.104458 -137.127896) (xy 154.088912 -137.122708) (xy 154.080718 -137.122408) (xy 154.065732 -137.122408)
			(xy 154.046936 -137.126218) (xy 154.042618 -137.127996) (xy 154.010849 -137.140319) (xy 153.944662 -137.156513)
			(xy 153.910792 -137.160254) (xy 153.871422 -137.162032) (xy 153.867866 -137.162032) (xy 153.857198 -137.162286)
			(xy 153.82768 -137.161141) (xy 153.76929 -137.15219) (xy 153.712536 -137.135805) (xy 153.658359 -137.112257)
			(xy 153.607662 -137.081937) (xy 153.561284 -137.04535) (xy 153.519996 -137.003102) (xy 153.484484 -136.955895)
			(xy 153.455338 -136.904514) (xy 153.433041 -136.849811) (xy 153.417964 -136.792695) (xy 153.410357 -136.734114)
			(xy 153.409904 -136.704578) (xy 153.409904 -135.840724) (xy 153.410393 -135.810751) (xy 153.418214 -135.751318)
			(xy 153.433725 -135.693414) (xy 153.456662 -135.638031) (xy 153.486632 -135.586114) (xy 153.523121 -135.538554)
			(xy 153.565506 -135.496163) (xy 153.613061 -135.459667) (xy 153.638758 -135.44423) (xy 153.650188 -135.43788)
			(xy 153.674064 -135.425942) (xy 153.688071 -135.419506) (xy 153.716798 -135.408321) (xy 153.731468 -135.40359)
			(xy 153.744744 -135.399569) (xy 153.771687 -135.392962) (xy 153.785316 -135.390382) (xy 153.805524 -135.386943)
			(xy 153.846353 -135.383254) (xy 153.86685 -135.383016) (xy 153.867612 -135.383016) (xy 153.86812 -135.383016)
			(xy 153.893266 -135.383524) (xy 153.909014 -135.38454) (xy 153.910792 -135.384794) (xy 153.911554 -135.384794)
			(xy 153.91638 -135.385302) (xy 153.918666 -135.385556) (xy 153.924508 -135.386318) (xy 153.925778 -135.386572)
			(xy 153.928318 -135.386826) (xy 153.933906 -135.387588) (xy 153.940002 -135.38835) (xy 153.948892 -135.389874)
			(xy 153.952702 -135.390382) (xy 153.952956 -135.390382) (xy 153.954226 -135.390636) (xy 153.95448 -135.390636)
			(xy 153.959814 -135.391652) (xy 153.97734 -135.39597) (xy 154.006451 -135.403628) (xy 154.062513 -135.425545)
			(xy 154.0891 -135.439658) (xy 154.094688 -135.442706) (xy 154.109928 -135.44677) (xy 154.110182 -135.44677)
			(xy 154.121612 -135.450072) (xy 154.13863 -135.446262) (xy 154.138884 -135.446262) (xy 154.16149 -135.44169)
			(xy 154.17419 -135.43661) (xy 154.179778 -135.432546) (xy 154.18562 -135.428228) (xy 154.1907 -135.421624)
			(xy 154.191208 -135.420862) (xy 154.199957 -135.408927) (xy 154.219027 -135.386294) (xy 154.229308 -135.37565)
			(xy 154.23007 -135.374888) (xy 154.230324 -135.37438) (xy 154.232356 -135.372602) (xy 154.232864 -135.372094)
			(xy 154.233372 -135.37184) (xy 154.235658 -135.369554) (xy 154.236166 -135.369046) (xy 154.23642 -135.368792)
			(xy 154.238706 -135.366506) (xy 154.239214 -135.365998) (xy 154.239976 -135.365236) (xy 154.243278 -135.362188)
			(xy 154.249628 -135.356346) (xy 154.251152 -135.353806) (xy 154.268424 -135.340852) (xy 154.269694 -135.339836)
			(xy 154.288998 -135.32612) (xy 154.298767 -135.319671) (xy 154.318973 -135.307849) (xy 154.329384 -135.302498)
			(xy 154.334718 -135.299958) (xy 154.335226 -135.299704) (xy 154.357568 -135.289266) (xy 154.404324 -135.273591)
			(xy 154.428444 -135.268462) (xy 154.428698 -135.268462) (xy 154.430984 -135.267954) (xy 154.439904 -135.265361)
			(xy 154.455184 -135.254825) (xy 154.465695 -135.239528) (xy 154.468322 -135.230616) (xy 154.469338 -135.225536)
			(xy 154.799792 -132.800344) (xy 154.799792 -132.79882) (xy 154.867864 -132.169916) (xy 154.895804 -131.911344)
			(xy 154.896058 -131.90728) (xy 154.9908 -123.120658) (xy 155.028646 -119.60606) (xy 155.028646 -119.604028)
			(xy 154.973782 -117.788944) (xy 154.64282 -106.861102) (xy 154.619198 -106.144568) (xy 154.606752 -105.76433)
			(xy 154.585162 -105.114344) (xy 154.585162 -105.111804) (xy 154.528266 -104.403144) (xy 154.527153 -104.394056)
			(xy 154.519343 -104.377513) (xy 154.513026 -104.370886) (xy 154.506168 -104.364028) (xy 154.489658 -104.356916)
			(xy 154.480514 -104.356408) (xy 154.457392 -104.354787) (xy 154.411761 -104.34664) (xy 154.367452 -104.333028)
			(xy 154.346148 -104.323896) (xy 154.323196 -104.313223) (xy 154.280089 -104.28669) (xy 154.240876 -104.254683)
			(xy 154.206247 -104.217764) (xy 154.191208 -104.197404) (xy 154.189176 -104.194356) (xy 154.183497 -104.188156)
			(xy 154.169114 -104.17947) (xy 154.160982 -104.177338) (xy 154.130756 -104.17048) (xy 154.119326 -104.16921)
			(xy 154.094688 -104.175814) (xy 154.0891 -104.178862) (xy 154.063637 -104.192407) (xy 154.010033 -104.213697)
			(xy 153.954178 -104.228081) (xy 153.896959 -104.235332) (xy 153.86812 -104.235758) (xy 153.867866 -104.235758)
			(xy 153.837883 -104.235266) (xy 153.778431 -104.227435) (xy 153.72051 -104.211911) (xy 153.66511 -104.18896)
			(xy 153.61318 -104.158974) (xy 153.565608 -104.122467) (xy 153.523208 -104.080063) (xy 153.486705 -104.032488)
			(xy 153.456723 -103.980556) (xy 153.433777 -103.925154) (xy 153.418258 -103.867231) (xy 153.410432 -103.807779)
			(xy 153.409904 -103.777796) (xy 153.409904 -102.914196) (xy 153.410394 -102.884211) (xy 153.418222 -102.824754)
			(xy 153.433743 -102.766828) (xy 153.456692 -102.711423) (xy 153.486676 -102.659487) (xy 153.523182 -102.611908)
			(xy 153.565586 -102.569502) (xy 153.613162 -102.532993) (xy 153.665096 -102.503005) (xy 153.720499 -102.480053)
			(xy 153.778425 -102.464528) (xy 153.837881 -102.456696) (xy 153.867866 -102.456234) (xy 153.86812 -102.456234)
			(xy 153.896486 -102.456678) (xy 153.952781 -102.463715) (xy 154.007777 -102.477644) (xy 154.060635 -102.49825)
			(xy 154.085798 -102.511352) (xy 154.088592 -102.512876) (xy 154.101038 -102.517702) (xy 154.110944 -102.520242)
			(xy 154.136344 -102.520242) (xy 154.147774 -102.517702) (xy 154.161236 -102.5144) (xy 154.165548 -102.513253)
			(xy 154.173724 -102.509678) (xy 154.177492 -102.507288) (xy 154.18562 -102.501954) (xy 154.191208 -102.494334)
			(xy 154.191462 -102.49408) (xy 154.203383 -102.477892) (xy 154.23011 -102.447859) (xy 154.244802 -102.434136)
			(xy 154.263118 -102.417979) (xy 154.303117 -102.389952) (xy 154.324558 -102.378256) (xy 154.333194 -102.37343)
			(xy 154.361388 -102.328472) (xy 154.361134 -102.326694) (xy 154.258264 -101.041962) (xy 154.22753 -100.656644)
			(xy 154.227082 -100.652376) (xy 154.224912 -100.644074) (xy 154.223212 -100.640134) (xy 154.220418 -100.63353)
			(xy 154.21483 -100.62718) (xy 154.212544 -100.62464) (xy 154.211528 -100.623116) (xy 154.210258 -100.621846)
			(xy 154.209242 -100.620576) (xy 154.191208 -100.597462) (xy 154.185366 -100.589588) (xy 154.178254 -100.584762)
			(xy 154.174871 -100.582634) (xy 154.167601 -100.579315) (xy 154.163776 -100.578158) (xy 154.128216 -100.57003)
			(xy 154.116024 -100.570284) (xy 154.109928 -100.571808) (xy 154.094688 -100.575872) (xy 154.0891 -100.57892)
			(xy 154.063637 -100.592466) (xy 154.010033 -100.613758) (xy 153.954179 -100.628143) (xy 153.896959 -100.635395)
			(xy 153.86812 -100.635816) (xy 153.867866 -100.635816) (xy 153.837883 -100.635345) (xy 153.77843 -100.627513)
			(xy 153.720508 -100.611988) (xy 153.665109 -100.589035) (xy 153.613179 -100.559048) (xy 153.565607 -100.522539)
			(xy 153.523208 -100.480132) (xy 153.486708 -100.432555) (xy 153.456729 -100.38062) (xy 153.433786 -100.325216)
			(xy 153.418271 -100.267291) (xy 153.41045 -100.207837) (xy 153.409904 -100.177854) (xy 153.409904 -99.314254)
			(xy 153.410397 -99.284271) (xy 153.418229 -99.224818) (xy 153.433754 -99.166896) (xy 153.456705 -99.111496)
			(xy 153.48669 -99.059565) (xy 153.523197 -99.011991) (xy 153.5656 -98.969589) (xy 153.613175 -98.933084)
			(xy 153.665107 -98.9031) (xy 153.720508 -98.88015) (xy 153.77843 -98.864627) (xy 153.837883 -98.856796)
			(xy 153.867866 -98.856292) (xy 153.881489 -98.856407) (xy 153.908685 -98.85806) (xy 153.922222 -98.859594)
			(xy 153.940256 -98.862134) (xy 153.953802 -98.864415) (xy 153.980617 -98.870387) (xy 153.99385 -98.874072)
			(xy 153.997406 -98.875088) (xy 154.00401 -98.876104) (xy 154.011713 -98.876883) (xy 154.026971 -98.874306)
			(xy 154.033982 -98.871024) (xy 154.037792 -98.868738) (xy 154.042364 -98.864928) (xy 154.050238 -98.859594)
			(xy 154.074622 -98.839782) (xy 154.080972 -98.834448) (xy 153.99385 -97.74682) (xy 153.979372 -97.566734)
			(xy 153.977314 -97.555401) (xy 153.964629 -97.536202) (xy 153.954988 -97.529904) (xy 153.953464 -97.529142)
			(xy 153.940002 -97.521776) (xy 153.931874 -97.519744) (xy 153.920952 -97.518474) (xy 153.896822 -97.518474)
			(xy 153.892879 -97.518566) (xy 153.885097 -97.519849) (xy 153.881328 -97.521014) (xy 153.88082 -97.521014)
			(xy 153.878026 -97.52203) (xy 153.874724 -97.523554) (xy 153.872946 -97.524316) (xy 153.87193 -97.524824)
			(xy 153.846175 -97.536524) (xy 153.792075 -97.553042) (xy 153.736129 -97.561388) (xy 153.707846 -97.561908)
			(xy 153.707338 -97.561908) (xy 153.680083 -97.561447) (xy 153.626128 -97.553695) (xy 153.573826 -97.538342)
			(xy 153.524241 -97.515702) (xy 153.478383 -97.486235) (xy 153.437186 -97.450541) (xy 153.401488 -97.409347)
			(xy 153.372017 -97.363492) (xy 153.349371 -97.31391) (xy 153.334013 -97.261609) (xy 153.326255 -97.207655)
			(xy 153.326255 -97.153145) (xy 153.334013 -97.099191) (xy 153.349371 -97.04689) (xy 153.372017 -96.997308)
			(xy 153.401488 -96.951453) (xy 153.437186 -96.910259) (xy 153.478383 -96.874565) (xy 153.524241 -96.845098)
			(xy 153.573826 -96.822458) (xy 153.626128 -96.807105) (xy 153.680083 -96.799353) (xy 153.707338 -96.798892)
			(xy 153.707592 -96.798892) (xy 153.737895 -96.799478) (xy 153.797742 -96.809052) (xy 153.826718 -96.817942)
			(xy 153.830274 -96.819212) (xy 153.836878 -96.820482) (xy 153.847077 -96.822073) (xy 153.867263 -96.817863)
			(xy 153.875994 -96.812354) (xy 153.897584 -96.795082) (xy 153.905323 -96.787323) (xy 153.913885 -96.767176)
			(xy 153.914094 -96.75622) (xy 153.89987 -96.576642) (xy 153.897948 -96.565757) (xy 153.886224 -96.547047)
			(xy 153.877264 -96.540574) (xy 153.869136 -96.53524) (xy 153.868882 -96.534986) (xy 153.843301 -96.545656)
			(xy 153.789952 -96.560686) (xy 153.735051 -96.568288) (xy 153.707338 -96.568768) (xy 153.67845 -96.56828)
			(xy 153.621263 -96.560063) (xy 153.565826 -96.54379) (xy 153.513271 -96.519793) (xy 153.464665 -96.48856)
			(xy 153.421 -96.450727) (xy 153.383163 -96.407065) (xy 153.351926 -96.358463) (xy 153.327924 -96.305909)
			(xy 153.311646 -96.250475) (xy 153.303423 -96.193288) (xy 153.303423 -96.135512) (xy 153.311646 -96.078325)
			(xy 153.327924 -96.022891) (xy 153.351926 -95.970337) (xy 153.383163 -95.921735) (xy 153.421 -95.878073)
			(xy 153.464665 -95.84024) (xy 153.513271 -95.809007) (xy 153.565826 -95.78501) (xy 153.621263 -95.768737)
			(xy 153.67845 -95.76052) (xy 153.707338 -95.760032) (xy 153.707592 -95.760032) (xy 153.733212 -95.760442)
			(xy 153.78404 -95.766935) (xy 153.808938 -95.772986) (xy 153.809446 -95.772478) (xy 153.809954 -95.77197)
			(xy 153.822654 -95.760286) (xy 153.824178 -95.758762) (xy 153.828242 -95.748348) (xy 153.83021 -95.742922)
			(xy 153.831882 -95.731504) (xy 153.831544 -95.725742) (xy 153.518108 -91.82227) (xy 151.392636 -65.347088)
			(xy 151.392128 -65.34023) (xy 151.39035 -65.30721) (xy 151.219408 -61.041534) (xy 151.218135 -61.032565)
			(xy 151.210185 -61.016299) (xy 151.197099 -61.003789) (xy 151.188928 -60.999878) (xy 151.183594 -60.998354)
			(xy 151.157893 -60.989992) (xy 151.108966 -60.967036) (xy 151.063765 -60.937409) (xy 151.023193 -60.901705)
			(xy 150.988062 -60.860635) (xy 150.959075 -60.815021) (xy 150.936809 -60.765776) (xy 150.92171 -60.713883)
			(xy 150.914081 -60.660379) (xy 150.913592 -60.633356) (xy 150.914124 -60.604861) (xy 150.922606 -60.548505)
			(xy 150.939375 -60.494038) (xy 150.964058 -60.44267) (xy 150.996105 -60.395544) (xy 151.034805 -60.353708)
			(xy 151.079296 -60.318093) (xy 151.128589 -60.28949) (xy 151.154892 -60.278518) (xy 151.1554 -60.278264)
			(xy 151.162568 -60.27514) (xy 151.174719 -60.265314) (xy 151.179276 -60.25896) (xy 151.183086 -60.252864)
			(xy 151.187404 -60.237878) (xy 151.144224 -59.159648) (xy 151.130762 -58.824876) (xy 151.130356 -58.818521)
			(xy 151.126745 -58.806312) (xy 151.12365 -58.800746) (xy 151.120602 -58.795666) (xy 151.11095 -58.786522)
			(xy 151.104854 -58.78322) (xy 151.079825 -58.768619) (xy 151.034094 -58.733038) (xy 150.994264 -58.690955)
			(xy 150.961249 -58.643337) (xy 150.935809 -58.591277) (xy 150.918527 -58.535972) (xy 150.909799 -58.47869)
			(xy 150.909274 -58.449718) (xy 150.909515 -58.430988) (xy 150.913203 -58.393709) (xy 150.91664 -58.375296)
			(xy 150.921639 -58.351892) (xy 150.93671 -58.306469) (xy 150.957353 -58.263292) (xy 150.96998 -58.242962)
			(xy 150.970234 -58.242708) (xy 150.974044 -58.236612) (xy 150.977092 -58.226706) (xy 150.978108 -58.22061)
			(xy 150.978616 -58.204354) (xy 150.977854 -58.194194) (xy 150.977562 -58.188214) (xy 150.979478 -58.176399)
			(xy 150.981664 -58.170826) (xy 150.983188 -58.167524) (xy 150.984966 -58.164222) (xy 150.988776 -58.159142)
			(xy 150.993461 -58.153359) (xy 151.005462 -58.144568) (xy 151.012398 -58.14187) (xy 151.068278 -58.122566)
			(xy 151.076868 -58.118894) (xy 151.090718 -58.106376) (xy 151.095202 -58.098182) (xy 151.095964 -58.096658)
			(xy 151.098308 -58.091115) (xy 151.100627 -58.079307) (xy 151.100536 -58.07329) (xy 151.09952 -58.04916)
			(xy 151.038814 -56.528716) (xy 150.998682 -55.52313) (xy 150.99792 -55.483252) (xy 150.99792 -55.467758)
			(xy 150.99792 -55.466742) (xy 151.003254 -55.125112) (xy 151.040846 -52.728622) (xy 151.040846 -52.726082)
			(xy 150.942548 -49.908714) (xy 150.941114 -49.898999) (xy 150.931948 -49.881651) (xy 150.916931 -49.869024)
			(xy 150.90775 -49.865534) (xy 150.85568 -49.844706) (xy 150.855172 -49.844706) (xy 150.833074 -49.835816)
			(xy 150.828502 -49.8348) (xy 150.821136 -49.83353) (xy 150.80988 -49.833002) (xy 150.788669 -49.840526)
			(xy 150.780242 -49.848008) (xy 150.778464 -49.849786) (xy 150.759981 -49.867979) (xy 150.719056 -49.899833)
			(xy 150.674288 -49.926013) (xy 150.626458 -49.946062) (xy 150.576402 -49.959628) (xy 150.524995 -49.966475)
			(xy 150.499064 -49.96688) (xy 150.471556 -49.966421) (xy 150.417079 -49.958743) (xy 150.364209 -49.943529)
			(xy 150.313984 -49.921076) (xy 150.267388 -49.891827) (xy 150.24608 -49.874424) (xy 150.245826 -49.87417)
			(xy 150.243032 -49.871884) (xy 150.236403 -49.867474) (xy 150.221269 -49.862552) (xy 150.213314 -49.862232)
			(xy 150.208234 -49.862232) (xy 150.202796 -49.862085) (xy 150.192168 -49.859768) (xy 150.187152 -49.85766)
			(xy 150.17369 -49.851564) (xy 150.165029 -49.847948) (xy 150.146312 -49.846723) (xy 150.128421 -49.852354)
			(xy 150.120858 -49.857914) (xy 150.113746 -49.863502) (xy 150.109174 -49.867058) (xy 150.108412 -49.867566)
			(xy 150.087771 -49.884207) (xy 150.042758 -49.912224) (xy 149.994299 -49.933738) (xy 149.943328 -49.948336)
			(xy 149.890827 -49.955735) (xy 149.864318 -49.956212) (xy 149.854412 -49.956212) (xy 149.825691 -49.954972)
			(xy 149.76909 -49.944918) (xy 149.714644 -49.926472) (xy 149.663588 -49.900052) (xy 149.640036 -49.883568)
			(xy 149.6314 -49.877472) (xy 149.62632 -49.873154) (xy 149.618954 -49.868582) (xy 149.616922 -49.867566)
			(xy 149.611596 -49.865107) (xy 149.60018 -49.862418) (xy 149.594316 -49.862232) (xy 149.573234 -49.862232)
			(xy 149.567796 -49.862085) (xy 149.557168 -49.859768) (xy 149.552152 -49.85766) (xy 149.53869 -49.851564)
			(xy 149.530029 -49.847948) (xy 149.511312 -49.846723) (xy 149.493421 -49.852354) (xy 149.485858 -49.857914)
			(xy 149.478746 -49.863502) (xy 149.474174 -49.867058) (xy 149.473412 -49.867566) (xy 149.452771 -49.884207)
			(xy 149.407758 -49.912224) (xy 149.359299 -49.933738) (xy 149.308328 -49.948336) (xy 149.255827 -49.955735)
			(xy 149.229318 -49.956212) (xy 149.219412 -49.956212) (xy 149.190691 -49.954972) (xy 149.13409 -49.944918)
			(xy 149.079644 -49.926472) (xy 149.028588 -49.900052) (xy 149.005036 -49.883568) (xy 148.9964 -49.877472)
			(xy 148.99132 -49.873154) (xy 148.983954 -49.868582) (xy 148.981922 -49.867566) (xy 148.976596 -49.865107)
			(xy 148.96518 -49.862418) (xy 148.959316 -49.862232) (xy 148.938234 -49.862232) (xy 148.932796 -49.862085)
			(xy 148.922168 -49.859768) (xy 148.917152 -49.85766) (xy 148.90369 -49.851564) (xy 148.895029 -49.847948)
			(xy 148.876312 -49.846723) (xy 148.858421 -49.852354) (xy 148.850858 -49.857914) (xy 148.843746 -49.863502)
			(xy 148.839174 -49.867058) (xy 148.838412 -49.867566) (xy 148.817771 -49.884207) (xy 148.772758 -49.912224)
			(xy 148.724299 -49.933738) (xy 148.673328 -49.948336) (xy 148.620827 -49.955735) (xy 148.594318 -49.956212)
			(xy 148.594064 -49.956212) (xy 148.566814 -49.955724) (xy 148.51287 -49.947963) (xy 148.460579 -49.932605)
			(xy 148.411006 -49.909961) (xy 148.365159 -49.880494) (xy 148.323973 -49.844802) (xy 148.288285 -49.803612)
			(xy 148.258822 -49.757763) (xy 148.236183 -49.708187) (xy 148.220829 -49.655895) (xy 148.213074 -49.60195)
			(xy 148.213074 -49.54745) (xy 148.220829 -49.493505) (xy 148.236183 -49.441213) (xy 148.258822 -49.391637)
			(xy 148.288285 -49.345788) (xy 148.323973 -49.304598) (xy 148.365159 -49.268906) (xy 148.411006 -49.239439)
			(xy 148.460579 -49.216795) (xy 148.51287 -49.201437) (xy 148.566814 -49.193676) (xy 148.594064 -49.193196)
			(xy 148.594318 -49.193196) (xy 148.619935 -49.193607) (xy 148.670708 -49.200462) (xy 148.720105 -49.214059)
			(xy 148.767234 -49.234153) (xy 148.811245 -49.260382) (xy 148.831554 -49.276) (xy 148.83638 -49.27981)
			(xy 148.843746 -49.283112) (xy 148.848486 -49.284977) (xy 148.858466 -49.287014) (xy 148.863558 -49.287176)
			(xy 148.884894 -49.287176) (xy 148.890335 -49.287315) (xy 148.90097 -49.289614) (xy 148.905976 -49.291748)
			(xy 148.919438 -49.297844) (xy 148.928099 -49.301455) (xy 148.94681 -49.30267) (xy 148.964694 -49.297033)
			(xy 148.97227 -49.291494) (xy 148.979382 -49.285906) (xy 148.983954 -49.28235) (xy 148.984716 -49.281842)
			(xy 149.005358 -49.265203) (xy 149.050371 -49.237188) (xy 149.09883 -49.215677) (xy 149.149801 -49.201083)
			(xy 149.202301 -49.193688) (xy 149.22881 -49.193196) (xy 149.238716 -49.193196) (xy 149.269503 -49.194568)
			(xy 149.330055 -49.206009) (xy 149.387983 -49.227025) (xy 149.441785 -49.257071) (xy 149.4663 -49.275746)
			(xy 149.47138 -49.27981) (xy 149.479254 -49.283366) (xy 149.483881 -49.285144) (xy 149.493603 -49.287072)
			(xy 149.498558 -49.287176) (xy 149.519894 -49.287176) (xy 149.525335 -49.287315) (xy 149.53597 -49.289614)
			(xy 149.540976 -49.291748) (xy 149.554438 -49.297844) (xy 149.563099 -49.301455) (xy 149.58181 -49.30267)
			(xy 149.599694 -49.297033) (xy 149.60727 -49.291494) (xy 149.614382 -49.285906) (xy 149.618954 -49.28235)
			(xy 149.619716 -49.281842) (xy 149.640358 -49.265203) (xy 149.685371 -49.237188) (xy 149.73383 -49.215677)
			(xy 149.784801 -49.201083) (xy 149.837301 -49.193688) (xy 149.86381 -49.193196) (xy 149.873716 -49.193196)
			(xy 149.904503 -49.194568) (xy 149.965055 -49.206009) (xy 150.022983 -49.227025) (xy 150.076785 -49.257071)
			(xy 150.1013 -49.275746) (xy 150.10638 -49.27981) (xy 150.114254 -49.283366) (xy 150.118881 -49.285144)
			(xy 150.128603 -49.287072) (xy 150.133558 -49.287176) (xy 150.230078 -49.287176) (xy 150.237887 -49.286853)
			(xy 150.252757 -49.28207) (xy 150.259288 -49.277778) (xy 150.26259 -49.275238) (xy 150.265638 -49.272952)
			(xy 150.270464 -49.268126) (xy 150.278592 -49.257204) (xy 150.28418 -49.246536) (xy 150.308257 -49.231402)
			(xy 150.35985 -49.207481) (xy 150.414354 -49.191253) (xy 150.47063 -49.183058) (xy 150.499064 -49.182528)
			(xy 150.499572 -49.182528) (xy 150.527309 -49.183044) (xy 150.582218 -49.190944) (xy 150.635461 -49.206518)
			(xy 150.685972 -49.229454) (xy 150.732738 -49.259294) (xy 150.75408 -49.277016) (xy 150.759668 -49.281588)
			(xy 150.77567 -49.288954) (xy 150.78631 -49.293103) (xy 150.809114 -49.292692) (xy 150.819612 -49.288192)
			(xy 150.826216 -49.28489) (xy 150.826724 -49.28489) (xy 150.895558 -49.25187) (xy 150.903297 -49.247189)
			(xy 150.915126 -49.233522) (xy 150.918672 -49.2252) (xy 150.917402 -49.186084) (xy 150.917148 -49.182782)
			(xy 150.91664 -49.178718) (xy 150.913338 -49.163732) (xy 150.912068 -49.15535) (xy 150.912068 -49.034954)
			(xy 150.912068 -49.032922) (xy 150.874984 -47.977806) (xy 150.87473 -47.973996) (xy 149.786594 -39.919656)
			(xy 149.782832 -39.890264) (xy 149.778384 -39.83117) (xy 149.777704 -39.801546) (xy 149.767036 -39.111936)
			(xy 149.764496 -39.101014) (xy 149.761956 -39.095934) (xy 149.761702 -39.09568) (xy 149.761702 -39.095426)
			(xy 149.746459 -39.063949) (xy 149.719893 -38.999246) (xy 149.708616 -38.96614) (xy 149.693351 -38.917886)
			(xy 149.67149 -38.819063) (xy 149.659736 -38.718535) (xy 149.658324 -38.667944) (xy 149.650704 -38.17366)
			(xy 149.650704 -38.157404) (xy 149.650899 -38.126783) (xy 149.654587 -38.065653) (xy 149.65807 -38.03523)
			(xy 149.658324 -38.03396) (xy 149.658578 -38.029388) (xy 149.658324 -38.015418) (xy 149.658324 -38.013132)
			(xy 149.658578 -37.992812) (xy 149.664928 -37.682424) (xy 149.663658 -37.676328) (xy 149.653178 -37.62648)
			(xy 149.641219 -37.525316) (xy 149.639782 -37.474398) (xy 149.632162 -36.978082) (xy 149.629368 -36.9697)
			(xy 149.625304 -36.958778) (xy 149.622764 -36.95192) (xy 149.61997 -36.944554) (xy 149.61997 -36.944046)
			(xy 149.616668 -36.935664) (xy 149.612858 -36.92525) (xy 149.610318 -36.919408) (xy 149.606781 -36.913014)
			(xy 149.596714 -36.902433) (xy 149.590506 -36.89858) (xy 149.567438 -36.903892) (xy 149.520448 -36.909617)
			(xy 149.49678 -36.91001) (xy 149.496272 -36.91001) (xy 149.468093 -36.909506) (xy 149.41231 -36.901482)
			(xy 149.358236 -36.885601) (xy 149.306973 -36.862186) (xy 149.259564 -36.831715) (xy 149.216973 -36.794807)
			(xy 149.180068 -36.752214) (xy 149.1496 -36.704802) (xy 149.12619 -36.653537) (xy 149.110312 -36.599463)
			(xy 149.102292 -36.543679) (xy 149.102292 -36.487321) (xy 149.110312 -36.431537) (xy 149.12619 -36.377463)
			(xy 149.1496 -36.326198) (xy 149.180068 -36.278786) (xy 149.216973 -36.236193) (xy 149.259564 -36.199285)
			(xy 149.306973 -36.168814) (xy 149.358236 -36.145399) (xy 149.41231 -36.129518) (xy 149.468093 -36.121494)
			(xy 149.496272 -36.121086) (xy 149.532086 -36.122864) (xy 149.53488 -36.120578) (xy 149.549612 -36.107878)
			(xy 149.557232 -36.101274) (xy 149.5679 -36.080192) (xy 149.569932 -36.076128) (xy 149.575266 -36.058856)
			(xy 149.575774 -36.05403) (xy 149.581441 -36.008192) (xy 149.600233 -35.917757) (xy 149.627382 -35.82947)
			(xy 149.662652 -35.744102) (xy 149.683724 -35.703002) (xy 149.68601 -35.698684) (xy 149.691344 -35.682174)
			(xy 149.691598 -35.66795) (xy 149.68982 -35.661092) (xy 149.688296 -35.654742) (xy 149.685756 -35.644836)
			(xy 149.678136 -35.61715) (xy 149.678136 -35.616642) (xy 149.660102 -35.551364) (xy 149.657291 -35.544491)
			(xy 149.648391 -35.532613) (xy 149.642576 -35.527996) (xy 149.592538 -35.498024) (xy 149.59203 -35.498024)
			(xy 149.580346 -35.491166) (xy 149.572726 -35.487356) (xy 149.572218 -35.487356) (xy 149.568916 -35.486086)
			(xy 149.550882 -35.490404) (xy 149.544786 -35.491928) (xy 149.523804 -35.496853) (xy 149.481498 -35.50511)
			(xy 149.460204 -35.508438) (xy 149.459696 -35.508438) (xy 149.42566 -35.513264) (xy 149.425152 -35.513264)
			(xy 149.397942 -35.51623) (xy 149.343301 -35.519534) (xy 149.315932 -35.519868) (xy 149.303232 -35.519868)
			(xy 149.256836 -35.518989) (xy 149.164502 -35.50967) (xy 149.073435 -35.491808) (xy 148.984422 -35.465558)
			(xy 148.898235 -35.431148) (xy 148.81562 -35.388874) (xy 148.776182 -35.36442) (xy 148.77415 -35.364928)
			(xy 148.770086 -35.36569) (xy 148.753088 -35.368566) (xy 148.718745 -35.371622) (xy 148.701506 -35.371786)
			(xy 148.700998 -35.371786) (xy 148.673746 -35.371323) (xy 148.619796 -35.363565) (xy 148.5675 -35.348209)
			(xy 148.517921 -35.325566) (xy 148.47207 -35.296097) (xy 148.43088 -35.260403) (xy 148.395188 -35.219211)
			(xy 148.365723 -35.173357) (xy 148.343083 -35.123778) (xy 148.32773 -35.07148) (xy 148.319976 -35.01753)
			(xy 148.31949 -34.990278) (xy 148.31949 -34.987484) (xy 148.320059 -34.963282) (xy 148.326575 -34.91531)
			(xy 148.339118 -34.868551) (xy 148.347938 -34.846006) (xy 148.348446 -34.844482) (xy 148.350224 -34.840164)
			(xy 148.356828 -34.824162) (xy 148.358098 -34.818574) (xy 148.353526 -34.802826) (xy 148.341029 -34.758474)
			(xy 148.323319 -34.668039) (xy 148.314036 -34.576355) (xy 148.31314 -34.530284) (xy 148.31314 -34.519108)
			(xy 148.313716 -34.477574) (xy 148.320917 -34.394817) (xy 148.334971 -34.312943) (xy 148.355781 -34.232522)
			(xy 148.383203 -34.154107) (xy 148.399754 -34.11601) (xy 148.402802 -34.106358) (xy 148.406358 -34.091118)
			(xy 148.406358 -34.090102) (xy 148.402802 -34.074862) (xy 148.399754 -34.06521) (xy 148.383073 -34.026807)
			(xy 148.355462 -33.947757) (xy 148.334581 -33.866669) (xy 148.320578 -33.784115) (xy 148.313551 -33.700677)
			(xy 148.31314 -33.65881) (xy 148.31314 -33.658302) (xy 148.313411 -33.626014) (xy 148.317608 -33.561575)
			(xy 148.321522 -33.529524) (xy 148.325022 -33.504119) (xy 148.334297 -33.453675) (xy 148.340064 -33.428686)
			(xy 148.344082 -33.412172) (xy 148.353102 -33.379399) (xy 148.358098 -33.363154) (xy 148.35632 -33.35528)
			(xy 148.354034 -33.349692) (xy 148.344519 -33.328077) (xy 148.330297 -33.28304) (xy 148.321743 -33.236593)
			(xy 148.319998 -33.21304) (xy 148.319998 -33.208722) (xy 148.31949 -33.19018) (xy 148.31949 -33.18256)
			(xy 148.320484 -33.155663) (xy 148.329101 -33.102534) (xy 148.345101 -33.051143) (xy 148.368164 -33.002512)
			(xy 148.397835 -32.957605) (xy 148.433523 -32.917315) (xy 148.47452 -32.882441) (xy 148.520012 -32.853675)
			(xy 148.569095 -32.83159) (xy 148.620795 -32.816622) (xy 148.674086 -32.809071) (xy 148.700998 -32.808672)
			(xy 148.701252 -32.808672) (xy 148.715723 -32.808784) (xy 148.744584 -32.810943) (xy 148.75891 -32.81299)
			(xy 148.76773 -32.813988) (xy 148.785144 -32.810619) (xy 148.792946 -32.806386) (xy 148.831987 -32.783274)
			(xy 148.913491 -32.743406) (xy 148.998278 -32.711102) (xy 149.085647 -32.686628) (xy 149.174878 -32.670186)
			(xy 149.265232 -32.661913) (xy 149.310598 -32.661352) (xy 149.310852 -32.661352) (xy 149.356191 -32.66188)
			(xy 149.446494 -32.670137) (xy 149.535675 -32.686551) (xy 149.622999 -32.710987) (xy 149.707748 -32.743243)
			(xy 149.789221 -32.783053) (xy 149.82825 -32.806132) (xy 149.835976 -32.810391) (xy 149.853254 -32.813888)
			(xy 149.862032 -32.81299) (xy 149.876738 -32.810912) (xy 149.906362 -32.808752) (xy 149.921214 -32.808672)
			(xy 149.921976 -32.808672) (xy 149.951694 -32.809364) (xy 150.01038 -32.818808) (xy 150.038816 -32.827468)
			(xy 150.052532 -32.83204) (xy 150.063962 -32.831024) (xy 150.071846 -32.830018) (xy 150.086469 -32.823811)
			(xy 150.092664 -32.818832) (xy 150.112222 -32.804608) (xy 150.154894 -32.773366) (xy 150.157938 -32.770885)
			(xy 150.163292 -32.76514) (xy 150.165562 -32.761936) (xy 150.16607 -32.761428) (xy 150.168102 -32.75838)
			(xy 150.167594 -32.737552) (xy 150.167594 -32.737044) (xy 150.16734 -32.722566) (xy 150.16734 -32.720788)
			(xy 150.167594 -32.696912) (xy 150.169438 -32.647678) (xy 150.181642 -32.549908) (xy 150.203439 -32.453821)
			(xy 150.234616 -32.360355) (xy 150.254208 -32.31515) (xy 150.255986 -32.311086) (xy 150.260558 -32.29102)
			(xy 150.260558 -32.290004) (xy 150.257002 -32.274764) (xy 150.253954 -32.265112) (xy 150.237273 -32.226709)
			(xy 150.209662 -32.147659) (xy 150.18878 -32.066571) (xy 150.174777 -31.984017) (xy 150.16775 -31.900579)
			(xy 150.16734 -31.858712) (xy 150.16734 -31.858204) (xy 150.167422 -31.840472) (xy 150.168692 -31.80503)
			(xy 150.16988 -31.787338) (xy 150.170134 -31.78556) (xy 150.170134 -31.785052) (xy 150.171404 -31.76651)
			(xy 150.167086 -31.76016) (xy 150.16226 -31.753556) (xy 150.15464 -31.744412) (xy 150.146931 -31.736386)
			(xy 150.126645 -31.727299) (xy 150.115524 -31.726886) (xy 150.10511 -31.728156) (xy 150.098506 -31.72968)
			(xy 150.092918 -31.73095) (xy 150.090632 -31.73222) (xy 150.087838 -31.73349) (xy 150.061738 -31.745568)
			(xy 150.00682 -31.762633) (xy 149.949968 -31.771294) (xy 149.921214 -31.771844) (xy 149.911308 -31.771844)
			(xy 149.894818 -31.771373) (xy 149.862006 -31.767939) (xy 149.845776 -31.764986) (xy 149.845522 -31.764986)
			(xy 149.84476 -31.764732) (xy 149.804791 -31.789429) (xy 149.721052 -31.832049) (xy 149.633673 -31.8666)
			(xy 149.543431 -31.892775) (xy 149.451127 -31.910343) (xy 149.357579 -31.919147) (xy 149.310598 -31.919672)
			(xy 149.263589 -31.919147) (xy 149.169985 -31.910329) (xy 149.077627 -31.892735) (xy 148.987337 -31.86652)
			(xy 148.899918 -31.831918) (xy 148.816146 -31.789237) (xy 148.776182 -31.764478) (xy 148.775166 -31.764732)
			(xy 148.768308 -31.766002) (xy 148.753943 -31.768426) (xy 148.724956 -31.771352) (xy 148.710396 -31.771844)
			(xy 148.699474 -31.771844) (xy 148.672339 -31.771258) (xy 148.618644 -31.763352) (xy 148.566611 -31.747917)
			(xy 148.51729 -31.725264) (xy 148.471678 -31.695851) (xy 148.430693 -31.660271) (xy 148.395164 -31.619243)
			(xy 148.365808 -31.573593) (xy 148.343216 -31.524245) (xy 148.327846 -31.472193) (xy 148.320007 -31.418488)
			(xy 148.31949 -31.391352) (xy 148.31949 -31.390844) (xy 148.31949 -31.390336) (xy 148.31949 -31.387542)
			(xy 148.320055 -31.363339) (xy 148.326564 -31.315365) (xy 148.339101 -31.268603) (xy 148.347938 -31.246064)
			(xy 148.348446 -31.24454) (xy 148.350224 -31.240222) (xy 148.356828 -31.22422) (xy 148.358098 -31.218632)
			(xy 148.353526 -31.202884) (xy 148.340797 -31.157586) (xy 148.322912 -31.065204) (xy 148.313802 -30.971547)
			(xy 148.31314 -30.9245) (xy 148.31314 -30.91561) (xy 148.31374 -30.878397) (xy 148.319799 -30.804211)
			(xy 148.331376 -30.730684) (xy 148.339556 -30.694376) (xy 148.350922 -30.648428) (xy 148.381201 -30.558742)
			(xy 148.400008 -30.515306) (xy 148.401786 -30.511242) (xy 148.406358 -30.491176) (xy 148.406358 -30.49016)
			(xy 148.401786 -30.470094) (xy 148.400008 -30.46603) (xy 148.38328 -30.42756) (xy 148.355591 -30.348366)
			(xy 148.334654 -30.267126) (xy 148.320617 -30.184414) (xy 148.313579 -30.100815) (xy 148.31314 -30.058868)
			(xy 148.313596 -30.015527) (xy 148.321102 -29.929172) (xy 148.328126 -29.886402) (xy 148.332284 -29.863598)
			(xy 148.342447 -29.818368) (xy 148.348446 -29.795978) (xy 148.358352 -29.76245) (xy 148.356574 -29.755084)
			(xy 148.34487 -29.729286) (xy 148.328352 -29.6751) (xy 148.320013 -29.61907) (xy 148.31949 -29.590746)
			(xy 148.31949 -29.590238) (xy 148.319951 -29.562983) (xy 148.327703 -29.509028) (xy 148.343056 -29.456726)
			(xy 148.365696 -29.407141) (xy 148.395163 -29.361283) (xy 148.430857 -29.320085) (xy 148.472051 -29.284387)
			(xy 148.517905 -29.254916) (xy 148.567488 -29.23227) (xy 148.619789 -29.216912) (xy 148.673743 -29.209154)
			(xy 148.700998 -29.20873) (xy 148.70176 -29.20873) (xy 148.719456 -29.208941) (xy 148.754693 -29.212246)
			(xy 148.772118 -29.215334) (xy 148.776182 -29.216096) (xy 148.776944 -29.21635) (xy 148.816886 -29.191703)
			(xy 148.900559 -29.14917) (xy 148.987858 -29.114685) (xy 149.07801 -29.088553) (xy 149.170218 -29.071006)
			(xy 149.263666 -29.062198) (xy 149.310598 -29.061664) (xy 149.357502 -29.062191) (xy 149.450899 -29.070977)
			(xy 149.543058 -29.088489) (xy 149.633167 -29.114574) (xy 149.720431 -29.149001) (xy 149.804077 -29.191466)
			(xy 149.843998 -29.216096) (xy 149.845014 -29.215842) (xy 149.84857 -29.215334) (xy 149.866248 -29.21222)
			(xy 149.901994 -29.20891) (xy 149.919944 -29.20873) (xy 149.92096 -29.20873) (xy 149.946353 -29.209145)
			(xy 149.996687 -29.215895) (xy 150.02129 -29.222192) (xy 150.023068 -29.2227) (xy 150.024338 -29.222954)
			(xy 150.028148 -29.22397) (xy 150.042118 -29.228542) (xy 150.042626 -29.228542) (xy 150.04796 -29.230574)
			(xy 150.06066 -29.231844) (xy 150.066502 -29.231082) (xy 150.07717 -29.228288) (xy 150.089362 -29.221684)
			(xy 150.152354 -29.17571) (xy 150.153116 -29.175202) (xy 150.157942 -29.171646) (xy 150.164546 -29.165296)
			(xy 150.168102 -29.16047) (xy 150.167594 -29.137864) (xy 150.167594 -29.13761) (xy 150.16734 -29.122624)
			(xy 150.16734 -29.120846) (xy 150.167594 -29.09697) (xy 150.16944 -29.047737) (xy 150.181648 -28.949968)
			(xy 150.203448 -28.853882) (xy 150.234629 -28.760418) (xy 150.254208 -28.715208) (xy 150.255986 -28.711144)
			(xy 150.260558 -28.691078) (xy 150.260558 -28.690062) (xy 150.255986 -28.669996) (xy 150.254208 -28.665932)
			(xy 150.23748 -28.627462) (xy 150.209791 -28.548268) (xy 150.188854 -28.467028) (xy 150.174816 -28.384316)
			(xy 150.167778 -28.300717) (xy 150.16734 -28.25877) (xy 150.167796 -28.215429) (xy 150.175302 -28.129074)
			(xy 150.182326 -28.086304) (xy 150.18649 -28.063565) (xy 150.196654 -28.018461) (xy 150.202646 -27.996134)
			(xy 150.202646 -27.995626) (xy 150.209758 -27.972004) (xy 150.209758 -27.971496) (xy 150.212552 -27.962352)
			(xy 150.210774 -27.954986) (xy 150.208488 -27.95016) (xy 150.198904 -27.928472) (xy 150.184568 -27.883273)
			(xy 150.175938 -27.836647) (xy 150.174198 -27.813) (xy 150.174198 -27.808682) (xy 150.17369 -27.79014)
			(xy 150.17369 -27.78252) (xy 150.174687 -27.755625) (xy 150.183308 -27.7025) (xy 150.199311 -27.651114)
			(xy 150.222377 -27.602488) (xy 150.252049 -27.557586) (xy 150.287737 -27.5173) (xy 150.328733 -27.48243)
			(xy 150.374222 -27.453669) (xy 150.423303 -27.431586) (xy 150.475 -27.416621) (xy 150.528288 -27.40907)
			(xy 150.555198 -27.408632) (xy 150.572819 -27.40874) (xy 150.607927 -27.411789) (xy 150.625302 -27.414728)
			(xy 150.627334 -27.415236) (xy 150.631652 -27.415998) (xy 150.674578 -27.39009) (xy 150.675594 -27.389582)
			(xy 150.678896 -27.387804) (xy 150.696422 -27.377898) (xy 150.697692 -27.375104) (xy 150.6982 -27.37358)
			(xy 150.698708 -27.372564) (xy 150.71979 -27.295348) (xy 150.719536 -27.281632) (xy 150.717758 -27.275028)
			(xy 150.71344 -27.259534) (xy 150.710392 -27.2542) (xy 150.698696 -27.232664) (xy 150.680277 -27.18725)
			(xy 150.667817 -27.139853) (xy 150.661519 -27.091251) (xy 150.661116 -27.066748) (xy 150.661116 -27.057604)
			(xy 150.66137 -27.05354) (xy 150.66137 -27.052778) (xy 150.663656 -27.022552) (xy 150.66676 -26.998918)
			(xy 150.678108 -26.95262) (xy 150.695153 -26.908104) (xy 150.706074 -26.886916) (xy 150.718903 -26.863799)
			(xy 150.749973 -26.821021) (xy 150.786652 -26.782945) (xy 150.807166 -26.766266) (xy 150.809198 -26.764742)
			(xy 150.81631 -26.757884) (xy 150.829264 -26.742136) (xy 150.831804 -26.736802) (xy 150.834344 -26.725118)
			(xy 150.83028 -26.647394) (xy 150.829772 -26.634948) (xy 150.814786 -26.609294) (xy 150.806912 -26.59888)
			(xy 150.799546 -26.591514) (xy 150.791418 -26.584656) (xy 150.789132 -26.583132) (xy 150.767235 -26.567858)
			(xy 150.727529 -26.532168) (xy 150.693181 -26.491295) (xy 150.664864 -26.446036) (xy 150.643128 -26.397272)
			(xy 150.628398 -26.345956) (xy 150.62096 -26.293088) (xy 150.620476 -26.266394) (xy 150.620962 -26.239125)
			(xy 150.628724 -26.185141) (xy 150.644089 -26.132811) (xy 150.666746 -26.083201) (xy 150.696232 -26.03732)
			(xy 150.731947 -25.996103) (xy 150.773164 -25.960388) (xy 150.819045 -25.930902) (xy 150.868655 -25.908245)
			(xy 150.920985 -25.89288) (xy 150.974969 -25.885118) (xy 151.029507 -25.885118) (xy 151.083491 -25.89288)
			(xy 151.135821 -25.908245) (xy 151.185431 -25.930902) (xy 151.231312 -25.960388) (xy 151.272529 -25.996103)
			(xy 151.308244 -26.03732) (xy 151.33773 -26.083201) (xy 151.360387 -26.132811) (xy 151.375752 -26.185141)
			(xy 151.383514 -26.239125) (xy 151.384 -26.266394) (xy 151.383462 -26.295751) (xy 151.374475 -26.353772)
			(xy 151.356711 -26.409734) (xy 151.330589 -26.462316) (xy 151.296725 -26.51028) (xy 151.255918 -26.552494)
			(xy 151.23287 -26.570686) (xy 151.229568 -26.573226) (xy 151.225758 -26.577036) (xy 151.219662 -26.58491)
			(xy 151.215936 -26.591022) (xy 151.211696 -26.604687) (xy 151.21128 -26.611834) (xy 151.21509 -26.69667)
			(xy 151.219916 -26.706068) (xy 151.220932 -26.708354) (xy 151.233632 -26.72969) (xy 151.23795 -26.734008)
			(xy 151.249126 -26.745438) (xy 151.255476 -26.749756) (xy 151.277336 -26.764968) (xy 151.316987 -26.800521)
			(xy 151.351303 -26.841247) (xy 151.379615 -26.886354) (xy 151.401373 -26.934963) (xy 151.416152 -26.986127)
			(xy 151.423666 -27.038851) (xy 151.424132 -27.065478) (xy 151.424132 -27.07005) (xy 151.423288 -27.100326)
			(xy 151.413205 -27.160046) (xy 151.404066 -27.188922) (xy 151.403304 -27.191208) (xy 151.400764 -27.199336)
			(xy 151.40178 -27.210512) (xy 151.404066 -27.221688) (xy 151.404828 -27.223466) (xy 151.419814 -27.254454)
			(xy 151.420322 -27.254962) (xy 151.428196 -27.27071) (xy 151.442674 -27.298904) (xy 151.444452 -27.30119)
			(xy 151.457406 -27.305254) (xy 151.46401 -27.307286) (xy 151.487876 -27.314951) (xy 151.534888 -27.332358)
			(xy 151.55799 -27.342084) (xy 151.559726 -27.342846) (xy 158.623508 -27.342846) (xy 158.623508 -26.479246)
			(xy 158.623998 -26.449262) (xy 158.631826 -26.389806) (xy 158.647347 -26.331881) (xy 158.670296 -26.276477)
			(xy 158.70028 -26.224543) (xy 158.736786 -26.176967) (xy 158.779191 -26.134562) (xy 158.826767 -26.098056)
			(xy 158.878701 -26.068072) (xy 158.934105 -26.045123) (xy 158.99203 -26.029602) (xy 159.051486 -26.021774)
			(xy 159.111454 -26.021774) (xy 159.17091 -26.029602) (xy 159.228835 -26.045123) (xy 159.284239 -26.068072)
			(xy 159.336173 -26.098056) (xy 159.383749 -26.134562) (xy 159.426154 -26.176967) (xy 159.46266 -26.224543)
			(xy 159.492644 -26.276477) (xy 159.515593 -26.331881) (xy 159.523364 -26.360882) (xy 161.189668 -26.360882)
			(xy 161.193739 -26.30526) (xy 161.205865 -26.250823) (xy 161.225788 -26.198732) (xy 161.253084 -26.150097)
			(xy 161.28717 -26.105954) (xy 161.327319 -26.067245) (xy 161.372677 -26.034794) (xy 161.422277 -26.009293)
			(xy 161.475061 -25.991286) (xy 161.529904 -25.981156) (xy 161.585638 -25.979119) (xy 161.641075 -25.985219)
			(xy 161.695032 -25.999325) (xy 161.746361 -26.021137) (xy 161.793967 -26.050191) (xy 161.836835 -26.085866)
			(xy 161.874052 -26.127403) (xy 161.904825 -26.173916) (xy 161.928497 -26.224413) (xy 161.944565 -26.27782)
			(xy 161.950733 -26.319734) (xy 166.942006 -26.319734) (xy 166.946077 -26.264112) (xy 166.958203 -26.209675)
			(xy 166.978126 -26.157584) (xy 167.005422 -26.108949) (xy 167.039508 -26.064806) (xy 167.079657 -26.026097)
			(xy 167.125015 -25.993646) (xy 167.174615 -25.968145) (xy 167.227399 -25.950138) (xy 167.282242 -25.940008)
			(xy 167.337976 -25.937971) (xy 167.393413 -25.944071) (xy 167.44737 -25.958177) (xy 167.498699 -25.979989)
			(xy 167.546305 -26.009043) (xy 167.57597 -26.03373) (xy 173.367952 -26.03373) (xy 173.372023 -25.978108)
			(xy 173.384149 -25.923671) (xy 173.404072 -25.87158) (xy 173.431368 -25.822945) (xy 173.465454 -25.778802)
			(xy 173.505603 -25.740093) (xy 173.550961 -25.707642) (xy 173.600561 -25.682141) (xy 173.653345 -25.664134)
			(xy 173.708188 -25.654004) (xy 173.763922 -25.651967) (xy 173.819359 -25.658067) (xy 173.873316 -25.672173)
			(xy 173.924645 -25.693985) (xy 173.972251 -25.723039) (xy 174.015119 -25.758714) (xy 174.052336 -25.800251)
			(xy 174.083109 -25.846764) (xy 174.106781 -25.897261) (xy 174.122849 -25.950668) (xy 174.130969 -26.005844)
			(xy 174.131478 -26.03373) (xy 174.130969 -26.061616) (xy 174.122849 -26.116792) (xy 174.106781 -26.170199)
			(xy 174.083109 -26.220696) (xy 174.052336 -26.267209) (xy 174.015119 -26.308746) (xy 173.972251 -26.344421)
			(xy 173.924645 -26.373475) (xy 173.873316 -26.395287) (xy 173.819359 -26.409393) (xy 173.763922 -26.415493)
			(xy 173.708188 -26.413456) (xy 173.653345 -26.403326) (xy 173.600561 -26.385319) (xy 173.550961 -26.359818)
			(xy 173.505603 -26.327367) (xy 173.465454 -26.288658) (xy 173.431368 -26.244515) (xy 173.404072 -26.19588)
			(xy 173.384149 -26.143789) (xy 173.372023 -26.089352) (xy 173.367952 -26.03373) (xy 167.57597 -26.03373)
			(xy 167.589173 -26.044718) (xy 167.62639 -26.086255) (xy 167.657163 -26.132768) (xy 167.680835 -26.183265)
			(xy 167.696903 -26.236672) (xy 167.705023 -26.291848) (xy 167.705532 -26.319734) (xy 167.705023 -26.34762)
			(xy 167.696903 -26.402796) (xy 167.680835 -26.456203) (xy 167.657163 -26.5067) (xy 167.62639 -26.553213)
			(xy 167.589173 -26.59475) (xy 167.546305 -26.630425) (xy 167.498699 -26.659479) (xy 167.44737 -26.681291)
			(xy 167.393413 -26.695397) (xy 167.337976 -26.701497) (xy 167.282242 -26.69946) (xy 167.227399 -26.68933)
			(xy 167.174615 -26.671323) (xy 167.125015 -26.645822) (xy 167.079657 -26.613371) (xy 167.039508 -26.574662)
			(xy 167.005422 -26.530519) (xy 166.978126 -26.481884) (xy 166.958203 -26.429793) (xy 166.946077 -26.375356)
			(xy 166.942006 -26.319734) (xy 161.950733 -26.319734) (xy 161.952685 -26.332996) (xy 161.953194 -26.360882)
			(xy 161.952685 -26.388768) (xy 161.944565 -26.443944) (xy 161.928497 -26.497351) (xy 161.904825 -26.547848)
			(xy 161.874052 -26.594361) (xy 161.836835 -26.635898) (xy 161.793967 -26.671573) (xy 161.746361 -26.700627)
			(xy 161.695032 -26.722439) (xy 161.641075 -26.736545) (xy 161.585638 -26.742645) (xy 161.529904 -26.740608)
			(xy 161.475061 -26.730478) (xy 161.422277 -26.712471) (xy 161.372677 -26.68697) (xy 161.327319 -26.654519)
			(xy 161.28717 -26.61581) (xy 161.253084 -26.571667) (xy 161.225788 -26.523032) (xy 161.205865 -26.470941)
			(xy 161.193739 -26.416504) (xy 161.189668 -26.360882) (xy 159.523364 -26.360882) (xy 159.531114 -26.389806)
			(xy 159.538942 -26.449262) (xy 159.539432 -26.479246) (xy 159.539432 -26.971244) (xy 162.951158 -26.971244)
			(xy 162.955229 -26.915622) (xy 162.967355 -26.861185) (xy 162.987278 -26.809094) (xy 163.014574 -26.760459)
			(xy 163.04866 -26.716316) (xy 163.088809 -26.677607) (xy 163.134167 -26.645156) (xy 163.183767 -26.619655)
			(xy 163.236551 -26.601648) (xy 163.291394 -26.591518) (xy 163.347128 -26.589481) (xy 163.402565 -26.595581)
			(xy 163.456522 -26.609687) (xy 163.507851 -26.631499) (xy 163.555457 -26.660553) (xy 163.598325 -26.696228)
			(xy 163.635542 -26.737765) (xy 163.666315 -26.784278) (xy 163.689987 -26.834775) (xy 163.706055 -26.888182)
			(xy 163.714175 -26.943358) (xy 163.714684 -26.971244) (xy 163.714175 -26.99913) (xy 163.706055 -27.054306)
			(xy 163.689987 -27.107713) (xy 163.666315 -27.15821) (xy 163.635542 -27.204723) (xy 163.598325 -27.24626)
			(xy 163.555457 -27.281935) (xy 163.507851 -27.310989) (xy 163.456522 -27.332801) (xy 163.402565 -27.346907)
			(xy 163.347128 -27.353007) (xy 163.291394 -27.35097) (xy 163.236551 -27.34084) (xy 163.183767 -27.322833)
			(xy 163.134167 -27.297332) (xy 163.088809 -27.264881) (xy 163.04866 -27.226172) (xy 163.014574 -27.182029)
			(xy 162.987278 -27.133394) (xy 162.967355 -27.081303) (xy 162.955229 -27.026866) (xy 162.951158 -26.971244)
			(xy 159.539432 -26.971244) (xy 159.539432 -27.342846) (xy 159.538942 -27.37283) (xy 159.531114 -27.432286)
			(xy 159.515593 -27.490211) (xy 159.492644 -27.545615) (xy 159.46266 -27.597549) (xy 159.426154 -27.645125)
			(xy 159.383749 -27.68753) (xy 159.336173 -27.724036) (xy 159.284239 -27.75402) (xy 159.228835 -27.776969)
			(xy 159.17091 -27.79249) (xy 159.111454 -27.800318) (xy 159.051486 -27.800318) (xy 158.99203 -27.79249)
			(xy 158.934105 -27.776969) (xy 158.878701 -27.75402) (xy 158.826767 -27.724036) (xy 158.779191 -27.68753)
			(xy 158.736786 -27.645125) (xy 158.70028 -27.597549) (xy 158.670296 -27.545615) (xy 158.647347 -27.490211)
			(xy 158.631826 -27.432286) (xy 158.623998 -27.37283) (xy 158.623508 -27.342846) (xy 151.559726 -27.342846)
			(xy 151.588912 -27.355655) (xy 151.649032 -27.386419) (xy 151.678132 -27.403552) (xy 151.685179 -27.407426)
			(xy 151.700835 -27.411057) (xy 151.708866 -27.410664) (xy 151.712676 -27.410156) (xy 151.7142 -27.410156)
			(xy 151.717248 -27.409648) (xy 151.718264 -27.409648) (xy 151.719026 -27.409394) (xy 151.728932 -27.408886)
			(xy 151.730456 -27.408886) (xy 151.738838 -27.408378) (xy 151.744934 -27.408378) (xy 151.748998 -27.408378)
			(xy 151.768302 -27.408886) (xy 151.777954 -27.409648) (xy 151.804962 -27.412181) (xy 151.857924 -27.423913)
			(xy 151.90869 -27.443026) (xy 151.956239 -27.469135) (xy 151.999612 -27.501714) (xy 152.037934 -27.540105)
			(xy 152.05456 -27.56154) (xy 152.056592 -27.56408) (xy 152.100988 -27.571474) (xy 152.188329 -27.593234)
			(xy 152.273354 -27.622774) (xy 152.355372 -27.659853) (xy 152.433716 -27.704171) (xy 152.507749 -27.755366)
			(xy 152.576869 -27.813022) (xy 152.609042 -27.844496) (xy 153.879018 -29.114242) (xy 160.947608 -29.114242)
			(xy 160.947608 -28.250642) (xy 160.948098 -28.220674) (xy 160.955921 -28.161252) (xy 160.971434 -28.103359)
			(xy 160.99437 -28.047986) (xy 161.024337 -27.99608) (xy 161.060824 -27.94853) (xy 161.103204 -27.90615)
			(xy 161.150754 -27.869663) (xy 161.20266 -27.839696) (xy 161.258033 -27.81676) (xy 161.315926 -27.801247)
			(xy 161.375348 -27.793424) (xy 161.435284 -27.793424) (xy 161.494706 -27.801247) (xy 161.552599 -27.81676)
			(xy 161.607972 -27.839696) (xy 161.659878 -27.869663) (xy 161.707428 -27.90615) (xy 161.749808 -27.94853)
			(xy 161.786295 -27.99608) (xy 161.816262 -28.047986) (xy 161.839198 -28.103359) (xy 161.854711 -28.161252)
			(xy 161.862534 -28.220674) (xy 161.863024 -28.250642) (xy 161.863024 -28.469082) (xy 165.8526 -28.469082)
			(xy 165.856671 -28.41346) (xy 165.868797 -28.359023) (xy 165.88872 -28.306932) (xy 165.916016 -28.258297)
			(xy 165.950102 -28.214154) (xy 165.990251 -28.175445) (xy 166.035609 -28.142994) (xy 166.085209 -28.117493)
			(xy 166.137993 -28.099486) (xy 166.192836 -28.089356) (xy 166.24857 -28.087319) (xy 166.304007 -28.093419)
			(xy 166.357964 -28.107525) (xy 166.409293 -28.129337) (xy 166.425349 -28.139136) (xy 170.498006 -28.139136)
			(xy 170.502077 -28.083514) (xy 170.514203 -28.029077) (xy 170.534126 -27.976986) (xy 170.561422 -27.928351)
			(xy 170.595508 -27.884208) (xy 170.635657 -27.845499) (xy 170.681015 -27.813048) (xy 170.730615 -27.787547)
			(xy 170.783399 -27.76954) (xy 170.838242 -27.75941) (xy 170.893976 -27.757373) (xy 170.949413 -27.763473)
			(xy 171.00337 -27.777579) (xy 171.054699 -27.799391) (xy 171.102305 -27.828445) (xy 171.145173 -27.86412)
			(xy 171.18239 -27.905657) (xy 171.213163 -27.95217) (xy 171.236835 -28.002667) (xy 171.252903 -28.056074)
			(xy 171.261023 -28.11125) (xy 171.261532 -28.139136) (xy 171.768006 -28.139136) (xy 171.772077 -28.083514)
			(xy 171.784203 -28.029077) (xy 171.804126 -27.976986) (xy 171.831422 -27.928351) (xy 171.865508 -27.884208)
			(xy 171.905657 -27.845499) (xy 171.951015 -27.813048) (xy 172.000615 -27.787547) (xy 172.053399 -27.76954)
			(xy 172.108242 -27.75941) (xy 172.163976 -27.757373) (xy 172.219413 -27.763473) (xy 172.27337 -27.777579)
			(xy 172.324699 -27.799391) (xy 172.372305 -27.828445) (xy 172.415173 -27.86412) (xy 172.45239 -27.905657)
			(xy 172.483163 -27.95217) (xy 172.506835 -28.002667) (xy 172.522903 -28.056074) (xy 172.531023 -28.11125)
			(xy 172.531532 -28.139136) (xy 172.531023 -28.167022) (xy 172.522903 -28.222198) (xy 172.506835 -28.275605)
			(xy 172.483163 -28.326102) (xy 172.45239 -28.372615) (xy 172.415173 -28.414152) (xy 172.372305 -28.449827)
			(xy 172.324699 -28.478881) (xy 172.27337 -28.500693) (xy 172.219413 -28.514799) (xy 172.163976 -28.520899)
			(xy 172.108242 -28.518862) (xy 172.053399 -28.508732) (xy 172.000615 -28.490725) (xy 171.951015 -28.465224)
			(xy 171.905657 -28.432773) (xy 171.865508 -28.394064) (xy 171.831422 -28.349921) (xy 171.804126 -28.301286)
			(xy 171.784203 -28.249195) (xy 171.772077 -28.194758) (xy 171.768006 -28.139136) (xy 171.261532 -28.139136)
			(xy 171.261023 -28.167022) (xy 171.252903 -28.222198) (xy 171.236835 -28.275605) (xy 171.213163 -28.326102)
			(xy 171.18239 -28.372615) (xy 171.145173 -28.414152) (xy 171.102305 -28.449827) (xy 171.054699 -28.478881)
			(xy 171.00337 -28.500693) (xy 170.949413 -28.514799) (xy 170.893976 -28.520899) (xy 170.838242 -28.518862)
			(xy 170.783399 -28.508732) (xy 170.730615 -28.490725) (xy 170.681015 -28.465224) (xy 170.635657 -28.432773)
			(xy 170.595508 -28.394064) (xy 170.561422 -28.349921) (xy 170.534126 -28.301286) (xy 170.514203 -28.249195)
			(xy 170.502077 -28.194758) (xy 170.498006 -28.139136) (xy 166.425349 -28.139136) (xy 166.456899 -28.158391)
			(xy 166.499767 -28.194066) (xy 166.536984 -28.235603) (xy 166.567757 -28.282116) (xy 166.591429 -28.332613)
			(xy 166.607497 -28.38602) (xy 166.615617 -28.441196) (xy 166.616126 -28.469082) (xy 166.615617 -28.496968)
			(xy 166.607497 -28.552144) (xy 166.591429 -28.605551) (xy 166.567757 -28.656048) (xy 166.536984 -28.702561)
			(xy 166.499767 -28.744098) (xy 166.456899 -28.779773) (xy 166.409293 -28.808827) (xy 166.357964 -28.830639)
			(xy 166.304007 -28.844745) (xy 166.24857 -28.850845) (xy 166.192836 -28.848808) (xy 166.137993 -28.838678)
			(xy 166.085209 -28.820671) (xy 166.035609 -28.79517) (xy 165.990251 -28.762719) (xy 165.950102 -28.72401)
			(xy 165.916016 -28.679867) (xy 165.88872 -28.631232) (xy 165.868797 -28.579141) (xy 165.856671 -28.524704)
			(xy 165.8526 -28.469082) (xy 161.863024 -28.469082) (xy 161.863024 -29.114242) (xy 161.862534 -29.14421)
			(xy 161.854711 -29.203632) (xy 161.839198 -29.261525) (xy 161.816262 -29.316898) (xy 161.786295 -29.368804)
			(xy 161.749808 -29.416354) (xy 161.707428 -29.458734) (xy 161.659878 -29.495221) (xy 161.607972 -29.525188)
			(xy 161.552599 -29.548124) (xy 161.494706 -29.563637) (xy 161.435284 -29.57146) (xy 161.375348 -29.57146)
			(xy 161.315926 -29.563637) (xy 161.258033 -29.548124) (xy 161.20266 -29.525188) (xy 161.150754 -29.495221)
			(xy 161.103204 -29.458734) (xy 161.060824 -29.416354) (xy 161.024337 -29.368804) (xy 160.99437 -29.316898)
			(xy 160.971434 -29.261525) (xy 160.955921 -29.203632) (xy 160.948098 -29.14421) (xy 160.947608 -29.114242)
			(xy 153.879018 -29.114242) (xy 154.011122 -29.246322) (xy 154.01417 -29.247846) (xy 154.017218 -29.24937)
			(xy 154.018234 -29.249878) (xy 154.044721 -29.263996) (xy 154.093281 -29.29927) (xy 154.135721 -29.341709)
			(xy 154.170997 -29.390267) (xy 154.185112 -29.416756) (xy 154.18562 -29.417772) (xy 154.187144 -29.42082)
			(xy 154.188668 -29.423868) (xy 154.308048 -29.543248) (xy 155.507944 -30.743398) (xy 155.532604 -30.768433)
			(xy 155.578748 -30.821441) (xy 155.600146 -30.849316) (xy 155.615296 -30.869693) (xy 155.643759 -30.91175)
			(xy 155.649247 -30.92069) (xy 163.589716 -30.92069) (xy 163.589716 -30.05709) (xy 163.590206 -30.027122)
			(xy 163.598029 -29.9677) (xy 163.613542 -29.909807) (xy 163.636478 -29.854434) (xy 163.666445 -29.802528)
			(xy 163.702932 -29.754978) (xy 163.745312 -29.712598) (xy 163.792862 -29.676111) (xy 163.844768 -29.646144)
			(xy 163.900141 -29.623208) (xy 163.958034 -29.607695) (xy 164.017456 -29.599872) (xy 164.077392 -29.599872)
			(xy 164.136814 -29.607695) (xy 164.194707 -29.623208) (xy 164.25008 -29.646144) (xy 164.301986 -29.676111)
			(xy 164.349536 -29.712598) (xy 164.391916 -29.754978) (xy 164.428403 -29.802528) (xy 164.45837 -29.854434)
			(xy 164.481306 -29.909807) (xy 164.496819 -29.9677) (xy 164.504642 -30.027122) (xy 164.505132 -30.05709)
			(xy 164.505132 -30.376876) (xy 168.988994 -30.376876) (xy 168.989531 -30.347959) (xy 168.998251 -30.290787)
			(xy 169.015503 -30.235587) (xy 169.040891 -30.183625) (xy 169.073833 -30.136091) (xy 169.113574 -30.094075)
			(xy 169.13606 -30.075886) (xy 169.144874 -30.068286) (xy 169.155051 -30.047379) (xy 169.155618 -30.035754)
			(xy 169.155618 -29.955998) (xy 169.155059 -29.944369) (xy 169.144884 -29.923459) (xy 169.13606 -29.915866)
			(xy 169.113552 -29.897704) (xy 169.07382 -29.855677) (xy 169.040885 -29.808136) (xy 169.015501 -29.756169)
			(xy 168.99825 -29.700967) (xy 168.989526 -29.643794) (xy 168.988994 -29.614876) (xy 168.98948 -29.587625)
			(xy 168.997236 -29.533677) (xy 169.012591 -29.481382) (xy 169.035233 -29.431805) (xy 169.064699 -29.385955)
			(xy 169.10039 -29.344764) (xy 169.141581 -29.309073) (xy 169.187431 -29.279607) (xy 169.237008 -29.256965)
			(xy 169.289303 -29.24161) (xy 169.343251 -29.233854) (xy 169.397753 -29.233854) (xy 169.451701 -29.24161)
			(xy 169.503996 -29.256965) (xy 169.553573 -29.279607) (xy 169.599423 -29.309073) (xy 169.640614 -29.344764)
			(xy 169.676305 -29.385955) (xy 169.705771 -29.431805) (xy 169.728413 -29.481382) (xy 169.743768 -29.533677)
			(xy 169.751524 -29.587625) (xy 169.75201 -29.614876) (xy 169.751509 -29.643794) (xy 169.742781 -29.700968)
			(xy 169.725522 -29.756168) (xy 169.700127 -29.808131) (xy 169.667179 -29.855664) (xy 169.627432 -29.897678)
			(xy 169.604944 -29.915866) (xy 169.596153 -29.923488) (xy 169.585963 -29.944378) (xy 169.585386 -29.955998)
			(xy 169.585386 -30.035754) (xy 169.585913 -30.047387) (xy 169.596111 -30.068296) (xy 169.604944 -30.075886)
			(xy 169.62743 -30.094074) (xy 169.667163 -30.136096) (xy 169.7001 -30.183632) (xy 169.725488 -30.235593)
			(xy 169.742744 -30.290791) (xy 169.751474 -30.34796) (xy 169.75201 -30.376876) (xy 172.02912 -30.376876)
			(xy 172.029685 -30.347961) (xy 172.038403 -30.290791) (xy 172.055651 -30.235593) (xy 172.081034 -30.183631)
			(xy 172.11397 -30.136096) (xy 172.153704 -30.094077) (xy 172.176186 -30.075886) (xy 172.185004 -30.06829)
			(xy 172.195178 -30.04738) (xy 172.195744 -30.035754) (xy 172.195744 -29.955998) (xy 172.195211 -29.944365)
			(xy 172.18502 -29.923454) (xy 172.176186 -29.915866) (xy 172.153683 -29.897698) (xy 172.11395 -29.855673)
			(xy 172.081014 -29.808133) (xy 172.055629 -29.756167) (xy 172.038377 -29.700966) (xy 172.029652 -29.643793)
			(xy 172.02912 -29.614876) (xy 172.029606 -29.587625) (xy 172.037362 -29.533677) (xy 172.052717 -29.481382)
			(xy 172.075359 -29.431805) (xy 172.104825 -29.385955) (xy 172.140516 -29.344764) (xy 172.181707 -29.309073)
			(xy 172.227557 -29.279607) (xy 172.277134 -29.256965) (xy 172.329429 -29.24161) (xy 172.383377 -29.233854)
			(xy 172.437879 -29.233854) (xy 172.491827 -29.24161) (xy 172.544122 -29.256965) (xy 172.593699 -29.279607)
			(xy 172.639549 -29.309073) (xy 172.68074 -29.344764) (xy 172.716431 -29.385955) (xy 172.745897 -29.431805)
			(xy 172.768539 -29.481382) (xy 172.783894 -29.533677) (xy 172.79165 -29.587625) (xy 172.792136 -29.614876)
			(xy 172.791625 -29.643793) (xy 172.782898 -29.700966) (xy 172.76564 -29.756166) (xy 172.740247 -29.808128)
			(xy 172.707301 -29.855662) (xy 172.667557 -29.897677) (xy 172.64507 -29.915866) (xy 172.636283 -29.923493)
			(xy 172.62609 -29.944379) (xy 172.625512 -29.955998) (xy 172.625512 -30.035754) (xy 172.62603 -30.047389)
			(xy 172.636233 -30.068298) (xy 172.64507 -30.075886) (xy 172.667541 -30.094093) (xy 172.707278 -30.136108)
			(xy 172.740219 -30.18364) (xy 172.76561 -30.235598) (xy 172.782869 -30.290793) (xy 172.7916 -30.347961)
			(xy 172.792136 -30.376876) (xy 172.79165 -30.404127) (xy 172.783894 -30.458075) (xy 172.768539 -30.51037)
			(xy 172.745897 -30.559947) (xy 172.716431 -30.605797) (xy 172.68074 -30.646988) (xy 172.639549 -30.682679)
			(xy 172.593699 -30.712145) (xy 172.544122 -30.734787) (xy 172.491827 -30.750142) (xy 172.437879 -30.757898)
			(xy 172.383377 -30.757898) (xy 172.329429 -30.750142) (xy 172.277134 -30.734787) (xy 172.227557 -30.712145)
			(xy 172.181707 -30.682679) (xy 172.140516 -30.646988) (xy 172.104825 -30.605797) (xy 172.075359 -30.559947)
			(xy 172.052717 -30.51037) (xy 172.037362 -30.458075) (xy 172.029606 -30.404127) (xy 172.02912 -30.376876)
			(xy 169.75201 -30.376876) (xy 169.751524 -30.404127) (xy 169.743768 -30.458075) (xy 169.728413 -30.51037)
			(xy 169.705771 -30.559947) (xy 169.676305 -30.605797) (xy 169.640614 -30.646988) (xy 169.599423 -30.682679)
			(xy 169.553573 -30.712145) (xy 169.503996 -30.734787) (xy 169.451701 -30.750142) (xy 169.397753 -30.757898)
			(xy 169.343251 -30.757898) (xy 169.289303 -30.750142) (xy 169.237008 -30.734787) (xy 169.187431 -30.712145)
			(xy 169.141581 -30.682679) (xy 169.10039 -30.646988) (xy 169.064699 -30.605797) (xy 169.035233 -30.559947)
			(xy 169.012591 -30.51037) (xy 168.997236 -30.458075) (xy 168.98948 -30.404127) (xy 168.988994 -30.376876)
			(xy 164.505132 -30.376876) (xy 164.505132 -30.92069) (xy 164.504642 -30.950658) (xy 164.496819 -31.01008)
			(xy 164.481306 -31.067973) (xy 164.45837 -31.123346) (xy 164.428403 -31.175252) (xy 164.391916 -31.222802)
			(xy 164.349536 -31.265182) (xy 164.301986 -31.301669) (xy 164.25008 -31.331636) (xy 164.194707 -31.354572)
			(xy 164.136814 -31.370085) (xy 164.077392 -31.377908) (xy 164.017456 -31.377908) (xy 163.958034 -31.370085)
			(xy 163.900141 -31.354572) (xy 163.844768 -31.331636) (xy 163.792862 -31.301669) (xy 163.745312 -31.265182)
			(xy 163.702932 -31.222802) (xy 163.666445 -31.175252) (xy 163.636478 -31.123346) (xy 163.613542 -31.067973)
			(xy 163.598029 -31.01008) (xy 163.590206 -30.950658) (xy 163.589716 -30.92069) (xy 155.649247 -30.92069)
			(xy 155.657042 -30.93339) (xy 155.658058 -30.935168) (xy 155.664154 -30.94355) (xy 155.677991 -30.958748)
			(xy 155.704542 -30.990127) (xy 155.71724 -31.006288) (xy 155.730343 -31.023208) (xy 155.755243 -31.058019)
			(xy 155.767024 -31.075884) (xy 155.783534 -31.1023) (xy 155.78455 -31.104332) (xy 155.786074 -31.106618)
			(xy 155.79217 -31.116778) (xy 155.800298 -31.130748) (xy 155.800298 -31.131002) (xy 155.806394 -31.142178)
			(xy 155.80741 -31.14421) (xy 155.819366 -31.166691) (xy 155.841219 -31.212689) (xy 155.851098 -31.236158)
			(xy 156.441394 -32.660844) (xy 156.463534 -32.714184) (xy 160.947608 -32.714184) (xy 160.947608 -31.850584)
			(xy 160.948098 -31.820616) (xy 160.955921 -31.761194) (xy 160.971434 -31.703301) (xy 160.99437 -31.647928)
			(xy 161.024337 -31.596022) (xy 161.060824 -31.548472) (xy 161.103204 -31.506092) (xy 161.150754 -31.469605)
			(xy 161.20266 -31.439638) (xy 161.258033 -31.416702) (xy 161.315926 -31.401189) (xy 161.375348 -31.393366)
			(xy 161.435284 -31.393366) (xy 161.494706 -31.401189) (xy 161.552599 -31.416702) (xy 161.607972 -31.439638)
			(xy 161.659878 -31.469605) (xy 161.707428 -31.506092) (xy 161.749808 -31.548472) (xy 161.764702 -31.567882)
			(xy 169.09872 -31.567882) (xy 169.102791 -31.51226) (xy 169.114917 -31.457823) (xy 169.13484 -31.405732)
			(xy 169.162136 -31.357097) (xy 169.196222 -31.312954) (xy 169.236371 -31.274245) (xy 169.281729 -31.241794)
			(xy 169.331329 -31.216293) (xy 169.384113 -31.198286) (xy 169.438956 -31.188156) (xy 169.49469 -31.186119)
			(xy 169.550127 -31.192219) (xy 169.604084 -31.206325) (xy 169.655413 -31.228137) (xy 169.703019 -31.257191)
			(xy 169.745887 -31.292866) (xy 169.783104 -31.334403) (xy 169.813877 -31.380916) (xy 169.837549 -31.431413)
			(xy 169.853617 -31.48482) (xy 169.861737 -31.539996) (xy 169.862246 -31.567882) (xy 169.861737 -31.595768)
			(xy 169.853617 -31.650944) (xy 169.837549 -31.704351) (xy 169.830557 -31.719266) (xy 170.385484 -31.719266)
			(xy 170.389555 -31.663644) (xy 170.401681 -31.609207) (xy 170.421604 -31.557116) (xy 170.4489 -31.508481)
			(xy 170.482986 -31.464338) (xy 170.523135 -31.425629) (xy 170.568493 -31.393178) (xy 170.618093 -31.367677)
			(xy 170.670877 -31.34967) (xy 170.72572 -31.33954) (xy 170.781454 -31.337503) (xy 170.836891 -31.343603)
			(xy 170.890848 -31.357709) (xy 170.942177 -31.379521) (xy 170.989783 -31.408575) (xy 171.032651 -31.44425)
			(xy 171.069868 -31.485787) (xy 171.100641 -31.5323) (xy 171.124313 -31.582797) (xy 171.140381 -31.636204)
			(xy 171.144531 -31.664402) (xy 171.661072 -31.664402) (xy 171.665143 -31.60878) (xy 171.677269 -31.554343)
			(xy 171.697192 -31.502252) (xy 171.724488 -31.453617) (xy 171.758574 -31.409474) (xy 171.798723 -31.370765)
			(xy 171.844081 -31.338314) (xy 171.893681 -31.312813) (xy 171.946465 -31.294806) (xy 172.001308 -31.284676)
			(xy 172.057042 -31.282639) (xy 172.112479 -31.288739) (xy 172.166436 -31.302845) (xy 172.217765 -31.324657)
			(xy 172.265371 -31.353711) (xy 172.308239 -31.389386) (xy 172.345456 -31.430923) (xy 172.376229 -31.477436)
			(xy 172.399901 -31.527933) (xy 172.415969 -31.58134) (xy 172.424089 -31.636516) (xy 172.424598 -31.664402)
			(xy 172.424089 -31.692288) (xy 172.415969 -31.747464) (xy 172.407029 -31.777178) (xy 172.926246 -31.777178)
			(xy 172.930317 -31.721556) (xy 172.942443 -31.667119) (xy 172.962366 -31.615028) (xy 172.989662 -31.566393)
			(xy 173.023748 -31.52225) (xy 173.063897 -31.483541) (xy 173.109255 -31.45109) (xy 173.158855 -31.425589)
			(xy 173.211639 -31.407582) (xy 173.266482 -31.397452) (xy 173.322216 -31.395415) (xy 173.377653 -31.401515)
			(xy 173.43161 -31.415621) (xy 173.482939 -31.437433) (xy 173.530545 -31.466487) (xy 173.573413 -31.502162)
			(xy 173.61063 -31.543699) (xy 173.641403 -31.590212) (xy 173.665075 -31.640709) (xy 173.681143 -31.694116)
			(xy 173.689263 -31.749292) (xy 173.689772 -31.777178) (xy 173.689263 -31.805064) (xy 173.681143 -31.86024)
			(xy 173.665075 -31.913647) (xy 173.641403 -31.964144) (xy 173.61063 -32.010657) (xy 173.573413 -32.052194)
			(xy 173.530545 -32.087869) (xy 173.482939 -32.116923) (xy 173.43161 -32.138735) (xy 173.377653 -32.152841)
			(xy 173.322216 -32.158941) (xy 173.266482 -32.156904) (xy 173.211639 -32.146774) (xy 173.158855 -32.128767)
			(xy 173.109255 -32.103266) (xy 173.063897 -32.070815) (xy 173.023748 -32.032106) (xy 172.989662 -31.987963)
			(xy 172.962366 -31.939328) (xy 172.942443 -31.887237) (xy 172.930317 -31.8328) (xy 172.926246 -31.777178)
			(xy 172.407029 -31.777178) (xy 172.399901 -31.800871) (xy 172.376229 -31.851368) (xy 172.345456 -31.897881)
			(xy 172.308239 -31.939418) (xy 172.265371 -31.975093) (xy 172.217765 -32.004147) (xy 172.166436 -32.025959)
			(xy 172.112479 -32.040065) (xy 172.057042 -32.046165) (xy 172.001308 -32.044128) (xy 171.946465 -32.033998)
			(xy 171.893681 -32.015991) (xy 171.844081 -31.99049) (xy 171.798723 -31.958039) (xy 171.758574 -31.91933)
			(xy 171.724488 -31.875187) (xy 171.697192 -31.826552) (xy 171.677269 -31.774461) (xy 171.665143 -31.720024)
			(xy 171.661072 -31.664402) (xy 171.144531 -31.664402) (xy 171.148501 -31.69138) (xy 171.14901 -31.719266)
			(xy 171.148501 -31.747152) (xy 171.140381 -31.802328) (xy 171.124313 -31.855735) (xy 171.100641 -31.906232)
			(xy 171.069868 -31.952745) (xy 171.032651 -31.994282) (xy 170.989783 -32.029957) (xy 170.942177 -32.059011)
			(xy 170.890848 -32.080823) (xy 170.836891 -32.094929) (xy 170.781454 -32.101029) (xy 170.72572 -32.098992)
			(xy 170.670877 -32.088862) (xy 170.618093 -32.070855) (xy 170.568493 -32.045354) (xy 170.523135 -32.012903)
			(xy 170.482986 -31.974194) (xy 170.4489 -31.930051) (xy 170.421604 -31.881416) (xy 170.401681 -31.829325)
			(xy 170.389555 -31.774888) (xy 170.385484 -31.719266) (xy 169.830557 -31.719266) (xy 169.813877 -31.754848)
			(xy 169.783104 -31.801361) (xy 169.745887 -31.842898) (xy 169.703019 -31.878573) (xy 169.655413 -31.907627)
			(xy 169.604084 -31.929439) (xy 169.550127 -31.943545) (xy 169.49469 -31.949645) (xy 169.438956 -31.947608)
			(xy 169.384113 -31.937478) (xy 169.331329 -31.919471) (xy 169.281729 -31.89397) (xy 169.236371 -31.861519)
			(xy 169.196222 -31.82281) (xy 169.162136 -31.778667) (xy 169.13484 -31.730032) (xy 169.114917 -31.677941)
			(xy 169.102791 -31.623504) (xy 169.09872 -31.567882) (xy 161.764702 -31.567882) (xy 161.786295 -31.596022)
			(xy 161.816262 -31.647928) (xy 161.839198 -31.703301) (xy 161.854711 -31.761194) (xy 161.862534 -31.820616)
			(xy 161.863024 -31.850584) (xy 161.863024 -32.714184) (xy 161.862534 -32.744152) (xy 161.854711 -32.803574)
			(xy 161.839198 -32.861467) (xy 161.816262 -32.91684) (xy 161.786295 -32.968746) (xy 161.749808 -33.016296)
			(xy 161.707428 -33.058676) (xy 161.659878 -33.095163) (xy 161.607972 -33.12513) (xy 161.552599 -33.148066)
			(xy 161.494706 -33.163579) (xy 161.435284 -33.171402) (xy 161.375348 -33.171402) (xy 161.315926 -33.163579)
			(xy 161.258033 -33.148066) (xy 161.20266 -33.12513) (xy 161.150754 -33.095163) (xy 161.103204 -33.058676)
			(xy 161.060824 -33.016296) (xy 161.024337 -32.968746) (xy 160.99437 -32.91684) (xy 160.971434 -32.861467)
			(xy 160.955921 -32.803574) (xy 160.948098 -32.744152) (xy 160.947608 -32.714184) (xy 156.463534 -32.714184)
			(xy 156.512768 -32.832802) (xy 156.514396 -32.836437) (xy 156.51861 -32.843196) (xy 156.52115 -32.846264)
			(xy 156.525976 -32.852106) (xy 156.529786 -32.854138) (xy 156.530548 -32.854646) (xy 156.534612 -32.856932)
			(xy 156.559424 -32.871354) (xy 156.604803 -32.906484) (xy 156.644411 -32.948012) (xy 156.677355 -32.995003)
			(xy 156.702892 -33.046396) (xy 156.720446 -33.101033) (xy 156.729622 -33.157683) (xy 156.730446 -33.18637)
			(xy 156.730446 -33.190688) (xy 156.730083 -33.215746) (xy 156.723583 -33.265439) (xy 156.717492 -33.289748)
			(xy 156.716984 -33.292034) (xy 156.713682 -33.302702) (xy 156.714698 -33.318704) (xy 156.718 -33.32734)
			(xy 157.212077 -34.520886) (xy 163.589716 -34.520886) (xy 163.589716 -33.657286) (xy 163.590206 -33.627318)
			(xy 163.598029 -33.567896) (xy 163.613542 -33.510003) (xy 163.636478 -33.45463) (xy 163.666445 -33.402724)
			(xy 163.702932 -33.355174) (xy 163.745312 -33.312794) (xy 163.792862 -33.276307) (xy 163.844768 -33.24634)
			(xy 163.900141 -33.223404) (xy 163.958034 -33.207891) (xy 164.017456 -33.200068) (xy 164.077392 -33.200068)
			(xy 164.136814 -33.207891) (xy 164.194707 -33.223404) (xy 164.25008 -33.24634) (xy 164.301986 -33.276307)
			(xy 164.349536 -33.312794) (xy 164.391916 -33.355174) (xy 164.428403 -33.402724) (xy 164.45837 -33.45463)
			(xy 164.481306 -33.510003) (xy 164.496819 -33.567896) (xy 164.504642 -33.627318) (xy 164.505132 -33.657286)
			(xy 164.505132 -34.520886) (xy 164.504642 -34.550854) (xy 164.496819 -34.610276) (xy 164.481306 -34.668169)
			(xy 164.45837 -34.723542) (xy 164.428403 -34.775448) (xy 164.391916 -34.822998) (xy 164.349536 -34.865378)
			(xy 164.301986 -34.901865) (xy 164.25008 -34.931832) (xy 164.194707 -34.954768) (xy 164.136814 -34.970281)
			(xy 164.077392 -34.978104) (xy 164.017456 -34.978104) (xy 163.958034 -34.970281) (xy 163.900141 -34.954768)
			(xy 163.844768 -34.931832) (xy 163.792862 -34.901865) (xy 163.745312 -34.865378) (xy 163.702932 -34.822998)
			(xy 163.666445 -34.775448) (xy 163.636478 -34.723542) (xy 163.613542 -34.668169) (xy 163.598029 -34.610276)
			(xy 163.590206 -34.550854) (xy 163.589716 -34.520886) (xy 157.212077 -34.520886) (xy 157.468316 -35.139884)
			(xy 157.503368 -35.224466) (xy 157.520095 -35.264852) (xy 172.002448 -35.264852) (xy 172.006519 -35.20923)
			(xy 172.018645 -35.154793) (xy 172.038568 -35.102702) (xy 172.065864 -35.054067) (xy 172.09995 -35.009924)
			(xy 172.140099 -34.971215) (xy 172.185457 -34.938764) (xy 172.235057 -34.913263) (xy 172.287841 -34.895256)
			(xy 172.342684 -34.885126) (xy 172.398418 -34.883089) (xy 172.453855 -34.889189) (xy 172.507812 -34.903295)
			(xy 172.559141 -34.925107) (xy 172.606747 -34.954161) (xy 172.649615 -34.989836) (xy 172.686832 -35.031373)
			(xy 172.717605 -35.077886) (xy 172.741277 -35.128383) (xy 172.757345 -35.18179) (xy 172.765465 -35.236966)
			(xy 172.765974 -35.264852) (xy 172.765465 -35.292738) (xy 172.757345 -35.347914) (xy 172.741277 -35.401321)
			(xy 172.717605 -35.451818) (xy 172.686832 -35.498331) (xy 172.649615 -35.539868) (xy 172.606747 -35.575543)
			(xy 172.559141 -35.604597) (xy 172.507812 -35.626409) (xy 172.453855 -35.640515) (xy 172.398418 -35.646615)
			(xy 172.342684 -35.644578) (xy 172.287841 -35.634448) (xy 172.235057 -35.616441) (xy 172.185457 -35.59094)
			(xy 172.140099 -35.558489) (xy 172.09995 -35.51978) (xy 172.065864 -35.475637) (xy 172.038568 -35.427002)
			(xy 172.018645 -35.374911) (xy 172.006519 -35.320474) (xy 172.002448 -35.264852) (xy 157.520095 -35.264852)
			(xy 157.773528 -35.876738) (xy 160.817304 -35.876738) (xy 160.821375 -35.821116) (xy 160.833501 -35.766679)
			(xy 160.853424 -35.714588) (xy 160.88072 -35.665953) (xy 160.914806 -35.62181) (xy 160.954955 -35.583101)
			(xy 161.000313 -35.55065) (xy 161.049913 -35.525149) (xy 161.102697 -35.507142) (xy 161.15754 -35.497012)
			(xy 161.213274 -35.494975) (xy 161.268711 -35.501075) (xy 161.322668 -35.515181) (xy 161.373997 -35.536993)
			(xy 161.421603 -35.566047) (xy 161.464471 -35.601722) (xy 161.501688 -35.643259) (xy 161.532461 -35.689772)
			(xy 161.556133 -35.740269) (xy 161.572201 -35.793676) (xy 161.580321 -35.848852) (xy 161.58083 -35.876738)
			(xy 164.888924 -35.876738) (xy 164.892995 -35.821116) (xy 164.905121 -35.766679) (xy 164.925044 -35.714588)
			(xy 164.95234 -35.665953) (xy 164.986426 -35.62181) (xy 165.026575 -35.583101) (xy 165.071933 -35.55065)
			(xy 165.121533 -35.525149) (xy 165.174317 -35.507142) (xy 165.22916 -35.497012) (xy 165.284894 -35.494975)
			(xy 165.340331 -35.501075) (xy 165.394288 -35.515181) (xy 165.445617 -35.536993) (xy 165.493223 -35.566047)
			(xy 165.536091 -35.601722) (xy 165.573308 -35.643259) (xy 165.604081 -35.689772) (xy 165.627753 -35.740269)
			(xy 165.643821 -35.793676) (xy 165.651941 -35.848852) (xy 165.65245 -35.876738) (xy 165.651941 -35.904624)
			(xy 165.643821 -35.9598) (xy 165.627753 -36.013207) (xy 165.604081 -36.063704) (xy 165.573308 -36.110217)
			(xy 165.536091 -36.151754) (xy 165.493223 -36.187429) (xy 165.445617 -36.216483) (xy 165.394288 -36.238295)
			(xy 165.340331 -36.252401) (xy 165.284894 -36.258501) (xy 165.22916 -36.256464) (xy 165.174317 -36.246334)
			(xy 165.121533 -36.228327) (xy 165.071933 -36.202826) (xy 165.026575 -36.170375) (xy 164.986426 -36.131666)
			(xy 164.95234 -36.087523) (xy 164.925044 -36.038888) (xy 164.905121 -35.986797) (xy 164.892995 -35.93236)
			(xy 164.888924 -35.876738) (xy 161.58083 -35.876738) (xy 161.580321 -35.904624) (xy 161.572201 -35.9598)
			(xy 161.556133 -36.013207) (xy 161.532461 -36.063704) (xy 161.501688 -36.110217) (xy 161.464471 -36.151754)
			(xy 161.421603 -36.187429) (xy 161.373997 -36.216483) (xy 161.322668 -36.238295) (xy 161.268711 -36.252401)
			(xy 161.213274 -36.258501) (xy 161.15754 -36.256464) (xy 161.102697 -36.246334) (xy 161.049913 -36.228327)
			(xy 161.000313 -36.202826) (xy 160.954955 -36.170375) (xy 160.914806 -36.131666) (xy 160.88072 -36.087523)
			(xy 160.853424 -36.038888) (xy 160.833501 -35.986797) (xy 160.821375 -35.93236) (xy 160.817304 -35.876738)
			(xy 157.773528 -35.876738) (xy 158.035797 -36.50996) (xy 162.713922 -36.50996) (xy 162.717993 -36.454338)
			(xy 162.730119 -36.399901) (xy 162.750042 -36.34781) (xy 162.777338 -36.299175) (xy 162.811424 -36.255032)
			(xy 162.851573 -36.216323) (xy 162.896931 -36.183872) (xy 162.946531 -36.158371) (xy 162.999315 -36.140364)
			(xy 163.054158 -36.130234) (xy 163.109892 -36.128197) (xy 163.165329 -36.134297) (xy 163.219286 -36.148403)
			(xy 163.270615 -36.170215) (xy 163.318221 -36.199269) (xy 163.361089 -36.234944) (xy 163.398306 -36.276481)
			(xy 163.429079 -36.322994) (xy 163.452751 -36.373491) (xy 163.468819 -36.426898) (xy 163.472744 -36.453572)
			(xy 166.028622 -36.453572) (xy 166.032693 -36.39795) (xy 166.044819 -36.343513) (xy 166.064742 -36.291422)
			(xy 166.092038 -36.242787) (xy 166.126124 -36.198644) (xy 166.166273 -36.159935) (xy 166.211631 -36.127484)
			(xy 166.261231 -36.101983) (xy 166.314015 -36.083976) (xy 166.368858 -36.073846) (xy 166.424592 -36.071809)
			(xy 166.480029 -36.077909) (xy 166.533986 -36.092015) (xy 166.585315 -36.113827) (xy 166.632921 -36.142881)
			(xy 166.675789 -36.178556) (xy 166.713006 -36.220093) (xy 166.743779 -36.266606) (xy 166.753315 -36.286948)
			(xy 173.300388 -36.286948) (xy 173.304459 -36.231326) (xy 173.316585 -36.176889) (xy 173.336508 -36.124798)
			(xy 173.363804 -36.076163) (xy 173.39789 -36.03202) (xy 173.438039 -35.993311) (xy 173.483397 -35.96086)
			(xy 173.532997 -35.935359) (xy 173.585781 -35.917352) (xy 173.640624 -35.907222) (xy 173.696358 -35.905185)
			(xy 173.751795 -35.911285) (xy 173.805752 -35.925391) (xy 173.857081 -35.947203) (xy 173.904687 -35.976257)
			(xy 173.947555 -36.011932) (xy 173.984772 -36.053469) (xy 174.015545 -36.099982) (xy 174.039217 -36.150479)
			(xy 174.055285 -36.203886) (xy 174.063405 -36.259062) (xy 174.063914 -36.286948) (xy 174.063405 -36.314834)
			(xy 174.055285 -36.37001) (xy 174.039217 -36.423417) (xy 174.015545 -36.473914) (xy 173.984772 -36.520427)
			(xy 173.947555 -36.561964) (xy 173.904687 -36.597639) (xy 173.857081 -36.626693) (xy 173.805752 -36.648505)
			(xy 173.751795 -36.662611) (xy 173.696358 -36.668711) (xy 173.640624 -36.666674) (xy 173.585781 -36.656544)
			(xy 173.532997 -36.638537) (xy 173.483397 -36.613036) (xy 173.438039 -36.580585) (xy 173.39789 -36.541876)
			(xy 173.363804 -36.497733) (xy 173.336508 -36.449098) (xy 173.316585 -36.397007) (xy 173.304459 -36.34257)
			(xy 173.300388 -36.286948) (xy 166.753315 -36.286948) (xy 166.767451 -36.317103) (xy 166.783519 -36.37051)
			(xy 166.791639 -36.425686) (xy 166.792148 -36.453572) (xy 166.791639 -36.481458) (xy 166.783519 -36.536634)
			(xy 166.767451 -36.590041) (xy 166.743779 -36.640538) (xy 166.713006 -36.687051) (xy 166.675789 -36.728588)
			(xy 166.632921 -36.764263) (xy 166.585315 -36.793317) (xy 166.533986 -36.815129) (xy 166.480029 -36.829235)
			(xy 166.424592 -36.835335) (xy 166.368858 -36.833298) (xy 166.314015 -36.823168) (xy 166.261231 -36.805161)
			(xy 166.211631 -36.77966) (xy 166.166273 -36.747209) (xy 166.126124 -36.7085) (xy 166.092038 -36.664357)
			(xy 166.064742 -36.615722) (xy 166.044819 -36.563631) (xy 166.032693 -36.509194) (xy 166.028622 -36.453572)
			(xy 163.472744 -36.453572) (xy 163.476939 -36.482074) (xy 163.477448 -36.50996) (xy 163.476939 -36.537846)
			(xy 163.468819 -36.593022) (xy 163.452751 -36.646429) (xy 163.429079 -36.696926) (xy 163.398306 -36.743439)
			(xy 163.361089 -36.784976) (xy 163.318221 -36.820651) (xy 163.270615 -36.849705) (xy 163.219286 -36.871517)
			(xy 163.165329 -36.885623) (xy 163.109892 -36.891723) (xy 163.054158 -36.889686) (xy 162.999315 -36.879556)
			(xy 162.946531 -36.861549) (xy 162.896931 -36.836048) (xy 162.851573 -36.803597) (xy 162.811424 -36.764888)
			(xy 162.777338 -36.720745) (xy 162.750042 -36.67211) (xy 162.730119 -36.620019) (xy 162.717993 -36.565582)
			(xy 162.713922 -36.50996) (xy 158.035797 -36.50996) (xy 158.27629 -37.090604) (xy 158.290606 -37.125953)
			(xy 158.314382 -37.198424) (xy 158.323788 -37.235384) (xy 158.324296 -37.237924) (xy 158.32455 -37.23894)
			(xy 158.350458 -37.300916) (xy 158.371226 -37.351975) (xy 158.402665 -37.45763) (xy 158.406077 -37.47516)
			(xy 159.859216 -37.47516) (xy 159.863287 -37.419538) (xy 159.875413 -37.365101) (xy 159.895336 -37.31301)
			(xy 159.922632 -37.264375) (xy 159.956718 -37.220232) (xy 159.996867 -37.181523) (xy 160.042225 -37.149072)
			(xy 160.091825 -37.123571) (xy 160.144609 -37.105564) (xy 160.199452 -37.095434) (xy 160.255186 -37.093397)
			(xy 160.310623 -37.099497) (xy 160.36458 -37.113603) (xy 160.415909 -37.135415) (xy 160.463515 -37.164469)
			(xy 160.506383 -37.200144) (xy 160.5436 -37.241681) (xy 160.574373 -37.288194) (xy 160.598045 -37.338691)
			(xy 160.614113 -37.392098) (xy 160.622233 -37.447274) (xy 160.622742 -37.47516) (xy 160.622233 -37.503046)
			(xy 160.614113 -37.558222) (xy 160.598045 -37.611629) (xy 160.574373 -37.662126) (xy 160.57422 -37.662358)
			(xy 162.048442 -37.662358) (xy 162.052513 -37.606736) (xy 162.064639 -37.552299) (xy 162.084562 -37.500208)
			(xy 162.111858 -37.451573) (xy 162.145944 -37.40743) (xy 162.186093 -37.368721) (xy 162.231451 -37.33627)
			(xy 162.281051 -37.310769) (xy 162.333835 -37.292762) (xy 162.388678 -37.282632) (xy 162.444412 -37.280595)
			(xy 162.499849 -37.286695) (xy 162.553806 -37.300801) (xy 162.605135 -37.322613) (xy 162.652741 -37.351667)
			(xy 162.695609 -37.387342) (xy 162.732826 -37.428879) (xy 162.763599 -37.475392) (xy 162.787271 -37.525889)
			(xy 162.803339 -37.579296) (xy 162.811459 -37.634472) (xy 162.811968 -37.662358) (xy 162.811459 -37.690244)
			(xy 162.803339 -37.74542) (xy 162.794705 -37.774118) (xy 173.564802 -37.774118) (xy 173.568873 -37.718496)
			(xy 173.580999 -37.664059) (xy 173.600922 -37.611968) (xy 173.628218 -37.563333) (xy 173.662304 -37.51919)
			(xy 173.702453 -37.480481) (xy 173.747811 -37.44803) (xy 173.797411 -37.422529) (xy 173.850195 -37.404522)
			(xy 173.905038 -37.394392) (xy 173.960772 -37.392355) (xy 174.016209 -37.398455) (xy 174.070166 -37.412561)
			(xy 174.121495 -37.434373) (xy 174.169101 -37.463427) (xy 174.211969 -37.499102) (xy 174.249186 -37.540639)
			(xy 174.279959 -37.587152) (xy 174.303631 -37.637649) (xy 174.319699 -37.691056) (xy 174.327819 -37.746232)
			(xy 174.328328 -37.774118) (xy 174.327819 -37.802004) (xy 174.319699 -37.85718) (xy 174.303631 -37.910587)
			(xy 174.279959 -37.961084) (xy 174.249186 -38.007597) (xy 174.211969 -38.049134) (xy 174.169101 -38.084809)
			(xy 174.121495 -38.113863) (xy 174.070166 -38.135675) (xy 174.016209 -38.149781) (xy 173.960772 -38.155881)
			(xy 173.905038 -38.153844) (xy 173.850195 -38.143714) (xy 173.797411 -38.125707) (xy 173.747811 -38.100206)
			(xy 173.702453 -38.067755) (xy 173.662304 -38.029046) (xy 173.628218 -37.984903) (xy 173.600922 -37.936268)
			(xy 173.580999 -37.884177) (xy 173.568873 -37.82974) (xy 173.564802 -37.774118) (xy 162.794705 -37.774118)
			(xy 162.787271 -37.798827) (xy 162.763599 -37.849324) (xy 162.732826 -37.895837) (xy 162.695609 -37.937374)
			(xy 162.652741 -37.973049) (xy 162.605135 -38.002103) (xy 162.553806 -38.023915) (xy 162.499849 -38.038021)
			(xy 162.444412 -38.044121) (xy 162.388678 -38.042084) (xy 162.333835 -38.031954) (xy 162.281051 -38.013947)
			(xy 162.231451 -37.988446) (xy 162.186093 -37.955995) (xy 162.145944 -37.917286) (xy 162.111858 -37.873143)
			(xy 162.084562 -37.824508) (xy 162.064639 -37.772417) (xy 162.052513 -37.71798) (xy 162.048442 -37.662358)
			(xy 160.57422 -37.662358) (xy 160.5436 -37.708639) (xy 160.506383 -37.750176) (xy 160.463515 -37.785851)
			(xy 160.415909 -37.814905) (xy 160.36458 -37.836717) (xy 160.310623 -37.850823) (xy 160.255186 -37.856923)
			(xy 160.199452 -37.854886) (xy 160.144609 -37.844756) (xy 160.091825 -37.826749) (xy 160.042225 -37.801248)
			(xy 159.996867 -37.768797) (xy 159.956718 -37.730088) (xy 159.922632 -37.685945) (xy 159.895336 -37.63731)
			(xy 159.875413 -37.585219) (xy 159.863287 -37.530782) (xy 159.859216 -37.47516) (xy 158.406077 -37.47516)
			(xy 158.413196 -37.511736) (xy 158.420556 -37.555369) (xy 158.428441 -37.643511) (xy 158.428944 -37.687758)
			(xy 158.428944 -37.688266) (xy 158.42869 -37.704268) (xy 158.42869 -37.704522) (xy 158.426658 -37.830506)
			(xy 158.418784 -38.304978) (xy 158.413958 -38.593268) (xy 158.412602 -38.640617) (xy 158.402584 -38.729952)
			(xy 165.800997 -38.729952) (xy 165.800997 -38.675448) (xy 165.808755 -38.6215) (xy 165.824111 -38.569205)
			(xy 165.846754 -38.519627) (xy 165.876222 -38.473777) (xy 165.911916 -38.432588) (xy 165.953109 -38.396898)
			(xy 165.998962 -38.367435) (xy 166.048542 -38.344797) (xy 166.100839 -38.329446) (xy 166.154788 -38.321695)
			(xy 166.18204 -38.321234) (xy 166.210343 -38.321755) (xy 166.266331 -38.330099) (xy 166.32047 -38.346628)
			(xy 166.371571 -38.370978) (xy 166.418512 -38.402614) (xy 166.46026 -38.440841) (xy 166.495899 -38.48482)
			(xy 166.510716 -38.50894) (xy 166.518326 -38.520966) (xy 166.538943 -38.540567) (xy 166.564172 -38.55371)
			(xy 166.59205 -38.55937) (xy 166.620407 -38.557108) (xy 166.647036 -38.547099) (xy 166.669862 -38.530123)
			(xy 166.678864 -38.5191) (xy 166.697076 -38.496245) (xy 166.739234 -38.45578) (xy 166.787064 -38.42221)
			(xy 166.839451 -38.396319) (xy 166.895171 -38.378712) (xy 166.952922 -38.3698) (xy 166.98214 -38.36924)
			(xy 167.009393 -38.369633) (xy 167.063343 -38.377395) (xy 167.11564 -38.392755) (xy 167.165218 -38.415402)
			(xy 167.211069 -38.444873) (xy 167.25226 -38.480569) (xy 167.287951 -38.521763) (xy 167.317418 -38.567617)
			(xy 167.340059 -38.617198) (xy 167.355414 -38.669496) (xy 167.36317 -38.723447) (xy 167.36317 -38.777953)
			(xy 167.355414 -38.831904) (xy 167.340059 -38.884202) (xy 167.317418 -38.933783) (xy 167.287951 -38.979637)
			(xy 167.25226 -39.020831) (xy 167.211069 -39.056527) (xy 167.165218 -39.085998) (xy 167.11564 -39.108645)
			(xy 167.063343 -39.124005) (xy 167.009393 -39.131767) (xy 166.98214 -39.132256) (xy 166.953836 -39.131756)
			(xy 166.897847 -39.123408) (xy 166.843707 -39.106877) (xy 166.792606 -39.082523) (xy 166.745666 -39.050884)
			(xy 166.703918 -39.012653) (xy 166.668281 -38.968671) (xy 166.653464 -38.94455) (xy 166.64588 -38.932507)
			(xy 166.625257 -38.912906) (xy 166.600023 -38.899765) (xy 166.57214 -38.894107) (xy 166.543779 -38.896373)
			(xy 166.517147 -38.906385) (xy 166.494319 -38.923365) (xy 166.485316 -38.93439) (xy 166.467113 -38.957252)
			(xy 166.424954 -38.997717) (xy 166.377122 -39.031287) (xy 166.324733 -39.057176) (xy 166.269012 -39.074781)
			(xy 166.211258 -39.083691) (xy 166.18204 -39.08425) (xy 166.154788 -39.083705) (xy 166.100839 -39.075954)
			(xy 166.048542 -39.060603) (xy 165.998962 -39.037965) (xy 165.953109 -39.008502) (xy 165.911916 -38.972812)
			(xy 165.876222 -38.931623) (xy 165.846754 -38.885773) (xy 165.824111 -38.836195) (xy 165.808755 -38.7839)
			(xy 165.800997 -38.729952) (xy 158.402584 -38.729952) (xy 158.402045 -38.734756) (xy 158.392876 -38.781228)
			(xy 158.143606 -39.97198) (xy 167.995852 -39.97198) (xy 167.999923 -39.916358) (xy 168.012049 -39.861921)
			(xy 168.031972 -39.80983) (xy 168.059268 -39.761195) (xy 168.093354 -39.717052) (xy 168.133503 -39.678343)
			(xy 168.178861 -39.645892) (xy 168.228461 -39.620391) (xy 168.281245 -39.602384) (xy 168.336088 -39.592254)
			(xy 168.391822 -39.590217) (xy 168.447259 -39.596317) (xy 168.501216 -39.610423) (xy 168.552545 -39.632235)
			(xy 168.600151 -39.661289) (xy 168.643019 -39.696964) (xy 168.680236 -39.738501) (xy 168.711009 -39.785014)
			(xy 168.734681 -39.835511) (xy 168.750749 -39.888918) (xy 168.758869 -39.944094) (xy 168.759378 -39.97198)
			(xy 168.758869 -39.999866) (xy 168.750749 -40.055042) (xy 168.734681 -40.108449) (xy 168.711009 -40.158946)
			(xy 168.680236 -40.205459) (xy 168.643019 -40.246996) (xy 168.600151 -40.282671) (xy 168.552545 -40.311725)
			(xy 168.501216 -40.333537) (xy 168.447259 -40.347643) (xy 168.391822 -40.353743) (xy 168.336088 -40.351706)
			(xy 168.281245 -40.341576) (xy 168.228461 -40.323569) (xy 168.178861 -40.298068) (xy 168.133503 -40.265617)
			(xy 168.093354 -40.226908) (xy 168.059268 -40.182765) (xy 168.031972 -40.13413) (xy 168.012049 -40.082039)
			(xy 167.999923 -40.027602) (xy 167.995852 -39.97198) (xy 158.143606 -39.97198) (xy 157.945328 -40.919146)
			(xy 157.944684 -40.925246) (xy 157.94597 -40.937442) (xy 157.947868 -40.943276) (xy 157.949434 -40.947393)
			(xy 157.953775 -40.955058) (xy 157.956504 -40.958516) (xy 157.959806 -40.96258) (xy 157.968442 -40.969438)
			(xy 157.973522 -40.971724) (xy 157.978744 -40.974071) (xy 157.989897 -40.976644) (xy 157.99562 -40.976804)
			(xy 158.030418 -40.976804) (xy 158.03626 -40.97655) (xy 158.054894 -40.956911) (xy 158.096634 -40.922433)
			(xy 158.142722 -40.894029) (xy 158.19228 -40.872239) (xy 158.244367 -40.857477) (xy 158.297989 -40.850025)
			(xy 158.352127 -40.850025) (xy 158.405749 -40.857477) (xy 158.457836 -40.872239) (xy 158.507394 -40.894029)
			(xy 158.553482 -40.922433) (xy 158.595222 -40.956911) (xy 158.613856 -40.97655) (xy 158.619698 -40.976804)
			(xy 158.690818 -40.976804) (xy 158.69666 -40.97655) (xy 158.715297 -40.956915) (xy 158.757039 -40.922443)
			(xy 158.803128 -40.894043) (xy 158.852685 -40.872255) (xy 158.90477 -40.857493) (xy 158.95839 -40.850038)
			(xy 158.985458 -40.84955) (xy 159.013459 -40.850023) (xy 159.068891 -40.857988) (xy 159.122625 -40.87376)
			(xy 159.173568 -40.89702) (xy 159.220681 -40.927293) (xy 159.263006 -40.963964) (xy 159.299681 -41.006285)
			(xy 159.32996 -41.053395) (xy 159.353225 -41.104335) (xy 159.369004 -41.158068) (xy 159.376974 -41.213499)
			(xy 159.376974 -41.269501) (xy 159.369004 -41.324932) (xy 159.353225 -41.378665) (xy 159.32996 -41.429605)
			(xy 159.299681 -41.476715) (xy 159.263006 -41.519036) (xy 159.220681 -41.555707) (xy 159.173568 -41.58598)
			(xy 159.122625 -41.60924) (xy 159.068891 -41.625012) (xy 159.013459 -41.632977) (xy 158.985458 -41.633394)
			(xy 158.958387 -41.632941) (xy 158.90476 -41.625494) (xy 158.85267 -41.610735) (xy 158.803107 -41.588943)
			(xy 158.757017 -41.560534) (xy 158.715278 -41.52605) (xy 158.69666 -41.506394) (xy 158.690818 -41.50614)
			(xy 158.619698 -41.50614) (xy 158.613856 -41.506394) (xy 158.595222 -41.526033) (xy 158.553482 -41.560511)
			(xy 158.507394 -41.588915) (xy 158.457836 -41.610705) (xy 158.405749 -41.625467) (xy 158.352127 -41.632919)
			(xy 158.297989 -41.632919) (xy 158.244367 -41.625467) (xy 158.19228 -41.610705) (xy 158.142722 -41.588915)
			(xy 158.096634 -41.560511) (xy 158.054894 -41.526033) (xy 158.03626 -41.506394) (xy 158.030418 -41.50614)
			(xy 157.96006 -41.50614) (xy 157.955306 -41.506234) (xy 157.945967 -41.508018) (xy 157.941518 -41.509696)
			(xy 157.932882 -41.512998) (xy 157.925516 -41.519856) (xy 157.922468 -41.52265) (xy 157.915864 -41.528492)
			(xy 157.91434 -41.529762) (xy 157.909768 -41.534334) (xy 157.889414 -41.550734) (xy 157.845063 -41.578398)
			(xy 157.821376 -41.589452) (xy 157.82036 -41.58996) (xy 157.815026 -41.5925) (xy 157.807914 -41.60139)
			(xy 157.804286 -41.606136) (xy 157.799149 -41.616917) (xy 157.797754 -41.622726) (xy 157.445584 -43.305222)
			(xy 160.40735 -43.305222) (xy 160.407817 -43.277852) (xy 160.415633 -43.223672) (xy 160.431121 -43.171169)
			(xy 160.453963 -43.121422) (xy 160.483688 -43.075455) (xy 160.50133 -43.054524) (xy 160.501584 -43.05427)
			(xy 160.507146 -43.047166) (xy 160.513408 -43.030263) (xy 160.513776 -43.02125) (xy 160.513776 -42.954194)
			(xy 160.513427 -42.945176) (xy 160.507175 -42.928259) (xy 160.501584 -42.921174) (xy 160.50133 -42.921174)
			(xy 160.50133 -42.92092) (xy 160.483691 -42.899987) (xy 160.453979 -42.854015) (xy 160.431142 -42.804268)
			(xy 160.415651 -42.751767) (xy 160.407823 -42.697591) (xy 160.40735 -42.670222) (xy 160.4079 -42.641484)
			(xy 160.416519 -42.584659) (xy 160.433563 -42.529769) (xy 160.458648 -42.478057) (xy 160.491207 -42.430692)
			(xy 160.510474 -42.409364) (xy 160.517078 -42.402506) (xy 160.52419 -42.384472) (xy 160.52419 -42.295572)
			(xy 160.517078 -42.277538) (xy 160.510474 -42.27068) (xy 160.491227 -42.249333) (xy 160.458665 -42.201973)
			(xy 160.433576 -42.150264) (xy 160.416527 -42.095377) (xy 160.407903 -42.038553) (xy 160.407901 -41.981079)
			(xy 160.41652 -41.924255) (xy 160.433564 -41.869366) (xy 160.458649 -41.817655) (xy 160.491207 -41.770292)
			(xy 160.510474 -41.748964) (xy 160.517078 -41.742106) (xy 160.52419 -41.724072) (xy 160.52419 -41.635172)
			(xy 160.517078 -41.617138) (xy 160.510474 -41.61028) (xy 160.49122 -41.588939) (xy 160.45865 -41.541581)
			(xy 160.433554 -41.489873) (xy 160.416499 -41.434985) (xy 160.407873 -41.37816) (xy 160.40735 -41.349422)
			(xy 160.407836 -41.322171) (xy 160.415592 -41.268223) (xy 160.430947 -41.215928) (xy 160.453589 -41.166351)
			(xy 160.483055 -41.120501) (xy 160.518746 -41.07931) (xy 160.559937 -41.043619) (xy 160.605787 -41.014153)
			(xy 160.655364 -40.991511) (xy 160.707659 -40.976156) (xy 160.761607 -40.9684) (xy 160.816109 -40.9684)
			(xy 160.83923 -40.971724) (xy 168.694098 -40.971724) (xy 168.698169 -40.916102) (xy 168.710295 -40.861665)
			(xy 168.730218 -40.809574) (xy 168.757514 -40.760939) (xy 168.7916 -40.716796) (xy 168.831749 -40.678087)
			(xy 168.877107 -40.645636) (xy 168.926707 -40.620135) (xy 168.979491 -40.602128) (xy 169.034334 -40.591998)
			(xy 169.090068 -40.589961) (xy 169.145505 -40.596061) (xy 169.199462 -40.610167) (xy 169.250791 -40.631979)
			(xy 169.298397 -40.661033) (xy 169.341265 -40.696708) (xy 169.378482 -40.738245) (xy 169.409255 -40.784758)
			(xy 169.432927 -40.835255) (xy 169.448995 -40.888662) (xy 169.457115 -40.943838) (xy 169.457624 -40.971724)
			(xy 169.457115 -40.99961) (xy 169.448995 -41.054786) (xy 169.432927 -41.108193) (xy 169.409255 -41.15869)
			(xy 169.378482 -41.205203) (xy 169.341265 -41.24674) (xy 169.298397 -41.282415) (xy 169.250791 -41.311469)
			(xy 169.199462 -41.333281) (xy 169.145505 -41.347387) (xy 169.090068 -41.353487) (xy 169.034334 -41.35145)
			(xy 168.979491 -41.34132) (xy 168.926707 -41.323313) (xy 168.877107 -41.297812) (xy 168.831749 -41.265361)
			(xy 168.7916 -41.226652) (xy 168.757514 -41.182509) (xy 168.730218 -41.133874) (xy 168.710295 -41.081783)
			(xy 168.698169 -41.027346) (xy 168.694098 -40.971724) (xy 160.83923 -40.971724) (xy 160.870057 -40.976156)
			(xy 160.922352 -40.991511) (xy 160.971929 -41.014153) (xy 161.017779 -41.043619) (xy 161.05897 -41.07931)
			(xy 161.094661 -41.120501) (xy 161.124127 -41.166351) (xy 161.146769 -41.215928) (xy 161.162124 -41.268223)
			(xy 161.16988 -41.322171) (xy 161.170366 -41.349422) (xy 161.169838 -41.378161) (xy 161.161214 -41.434987)
			(xy 161.144164 -41.489877) (xy 161.119074 -41.541589) (xy 161.086511 -41.588952) (xy 161.067242 -41.61028)
			(xy 161.060638 -41.617138) (xy 161.053526 -41.635172) (xy 161.053526 -41.724072) (xy 161.060638 -41.742106)
			(xy 161.067242 -41.748964) (xy 161.086536 -41.770271) (xy 161.119103 -41.817636) (xy 161.144196 -41.869351)
			(xy 161.161246 -41.924245) (xy 161.169868 -41.981076) (xy 161.169865 -42.038557) (xy 161.161239 -42.095387)
			(xy 161.144184 -42.150279) (xy 161.119087 -42.201992) (xy 161.086516 -42.249354) (xy 161.067242 -42.27068)
			(xy 161.060638 -42.277538) (xy 161.053526 -42.295572) (xy 161.053526 -42.384472) (xy 161.060638 -42.402506)
			(xy 161.067242 -42.409364) (xy 161.08652 -42.430685) (xy 161.119086 -42.478048) (xy 161.144177 -42.529761)
			(xy 161.161226 -42.584654) (xy 161.169847 -42.641483) (xy 161.170366 -42.670222) (xy 161.169921 -42.697593)
			(xy 161.162099 -42.751773) (xy 161.146606 -42.804277) (xy 161.126049 -42.849038) (xy 162.992052 -42.849038)
			(xy 162.996123 -42.793416) (xy 163.008249 -42.738979) (xy 163.028172 -42.686888) (xy 163.055468 -42.638253)
			(xy 163.089554 -42.59411) (xy 163.129703 -42.555401) (xy 163.175061 -42.52295) (xy 163.224661 -42.497449)
			(xy 163.277445 -42.479442) (xy 163.332288 -42.469312) (xy 163.388022 -42.467275) (xy 163.443459 -42.473375)
			(xy 163.497416 -42.487481) (xy 163.548745 -42.509293) (xy 163.596351 -42.538347) (xy 163.639219 -42.574022)
			(xy 163.676436 -42.615559) (xy 163.707209 -42.662072) (xy 163.730881 -42.712569) (xy 163.746949 -42.765976)
			(xy 163.755069 -42.821152) (xy 163.75543 -42.84091) (xy 169.033188 -42.84091) (xy 169.037259 -42.785288)
			(xy 169.049385 -42.730851) (xy 169.069308 -42.67876) (xy 169.096604 -42.630125) (xy 169.13069 -42.585982)
			(xy 169.170839 -42.547273) (xy 169.216197 -42.514822) (xy 169.265797 -42.489321) (xy 169.318581 -42.471314)
			(xy 169.373424 -42.461184) (xy 169.429158 -42.459147) (xy 169.484595 -42.465247) (xy 169.538552 -42.479353)
			(xy 169.589881 -42.501165) (xy 169.637487 -42.530219) (xy 169.680355 -42.565894) (xy 169.717572 -42.607431)
			(xy 169.748345 -42.653944) (xy 169.772017 -42.704441) (xy 169.788085 -42.757848) (xy 169.796205 -42.813024)
			(xy 169.796714 -42.84091) (xy 169.796205 -42.868796) (xy 169.788085 -42.923972) (xy 169.772017 -42.977379)
			(xy 169.748345 -43.027876) (xy 169.717572 -43.074389) (xy 169.680355 -43.115926) (xy 169.637487 -43.151601)
			(xy 169.589881 -43.180655) (xy 169.538552 -43.202467) (xy 169.484595 -43.216573) (xy 169.429158 -43.222673)
			(xy 169.373424 -43.220636) (xy 169.318581 -43.210506) (xy 169.265797 -43.192499) (xy 169.216197 -43.166998)
			(xy 169.170839 -43.134547) (xy 169.13069 -43.095838) (xy 169.096604 -43.051695) (xy 169.069308 -43.00306)
			(xy 169.049385 -42.950969) (xy 169.037259 -42.896532) (xy 169.033188 -42.84091) (xy 163.75543 -42.84091)
			(xy 163.755578 -42.849038) (xy 163.755069 -42.876924) (xy 163.746949 -42.9321) (xy 163.730881 -42.985507)
			(xy 163.707209 -43.036004) (xy 163.676436 -43.082517) (xy 163.639219 -43.124054) (xy 163.596351 -43.159729)
			(xy 163.548745 -43.188783) (xy 163.497416 -43.210595) (xy 163.443459 -43.224701) (xy 163.388022 -43.230801)
			(xy 163.332288 -43.228764) (xy 163.277445 -43.218634) (xy 163.224661 -43.200627) (xy 163.175061 -43.175126)
			(xy 163.129703 -43.142675) (xy 163.089554 -43.103966) (xy 163.055468 -43.059823) (xy 163.028172 -43.011188)
			(xy 163.008249 -42.959097) (xy 162.996123 -42.90466) (xy 162.992052 -42.849038) (xy 161.126049 -42.849038)
			(xy 161.123759 -42.854024) (xy 161.09403 -42.899989) (xy 161.076386 -42.92092) (xy 161.076132 -42.921174)
			(xy 161.070542 -42.928258) (xy 161.064299 -42.945177) (xy 161.06394 -42.954194) (xy 161.06394 -43.02125)
			(xy 161.064312 -43.030266) (xy 161.070548 -43.047183) (xy 161.076132 -43.05427) (xy 161.076386 -43.05427)
			(xy 161.076386 -43.054524) (xy 161.094001 -43.075476) (xy 161.123717 -43.121443) (xy 161.146558 -43.171185)
			(xy 161.162054 -43.223682) (xy 161.169889 -43.277854) (xy 161.170366 -43.305222) (xy 161.16988 -43.332473)
			(xy 161.162124 -43.386421) (xy 161.146769 -43.438716) (xy 161.124127 -43.488293) (xy 161.094661 -43.534143)
			(xy 161.05897 -43.575334) (xy 161.017779 -43.611025) (xy 160.971929 -43.640491) (xy 160.922352 -43.663133)
			(xy 160.870057 -43.678488) (xy 160.816109 -43.686244) (xy 160.761607 -43.686244) (xy 160.707659 -43.678488)
			(xy 160.655364 -43.663133) (xy 160.605787 -43.640491) (xy 160.559937 -43.611025) (xy 160.518746 -43.575334)
			(xy 160.483055 -43.534143) (xy 160.453589 -43.488293) (xy 160.430947 -43.438716) (xy 160.415592 -43.386421)
			(xy 160.407836 -43.332473) (xy 160.40735 -43.305222) (xy 157.445584 -43.305222) (xy 157.355361 -43.73626)
			(xy 162.31311 -43.73626) (xy 162.317181 -43.680638) (xy 162.329307 -43.626201) (xy 162.34923 -43.57411)
			(xy 162.376526 -43.525475) (xy 162.410612 -43.481332) (xy 162.450761 -43.442623) (xy 162.496119 -43.410172)
			(xy 162.545719 -43.384671) (xy 162.598503 -43.366664) (xy 162.653346 -43.356534) (xy 162.70908 -43.354497)
			(xy 162.764517 -43.360597) (xy 162.818474 -43.374703) (xy 162.869803 -43.396515) (xy 162.917409 -43.425569)
			(xy 162.960277 -43.461244) (xy 162.997494 -43.502781) (xy 163.028267 -43.549294) (xy 163.051939 -43.599791)
			(xy 163.068007 -43.653198) (xy 163.076127 -43.708374) (xy 163.076636 -43.73626) (xy 163.076127 -43.764146)
			(xy 163.068007 -43.819322) (xy 163.056698 -43.85691) (xy 166.819832 -43.85691) (xy 166.823903 -43.801288)
			(xy 166.836029 -43.746851) (xy 166.855952 -43.69476) (xy 166.883248 -43.646125) (xy 166.917334 -43.601982)
			(xy 166.957483 -43.563273) (xy 167.002841 -43.530822) (xy 167.052441 -43.505321) (xy 167.105225 -43.487314)
			(xy 167.160068 -43.477184) (xy 167.215802 -43.475147) (xy 167.271239 -43.481247) (xy 167.325196 -43.495353)
			(xy 167.376525 -43.517165) (xy 167.424131 -43.546219) (xy 167.466999 -43.581894) (xy 167.504216 -43.623431)
			(xy 167.534989 -43.669944) (xy 167.558661 -43.720441) (xy 167.574729 -43.773848) (xy 167.582849 -43.829024)
			(xy 167.583358 -43.85691) (xy 167.582849 -43.884796) (xy 167.574729 -43.939972) (xy 167.558661 -43.993379)
			(xy 167.534989 -44.043876) (xy 167.504216 -44.090389) (xy 167.466999 -44.131926) (xy 167.424131 -44.167601)
			(xy 167.376525 -44.196655) (xy 167.325196 -44.218467) (xy 167.271239 -44.232573) (xy 167.215802 -44.238673)
			(xy 167.160068 -44.236636) (xy 167.105225 -44.226506) (xy 167.052441 -44.208499) (xy 167.002841 -44.182998)
			(xy 166.957483 -44.150547) (xy 166.917334 -44.111838) (xy 166.883248 -44.067695) (xy 166.855952 -44.01906)
			(xy 166.836029 -43.966969) (xy 166.823903 -43.912532) (xy 166.819832 -43.85691) (xy 163.056698 -43.85691)
			(xy 163.051939 -43.872729) (xy 163.028267 -43.923226) (xy 162.997494 -43.969739) (xy 162.960277 -44.011276)
			(xy 162.917409 -44.046951) (xy 162.869803 -44.076005) (xy 162.818474 -44.097817) (xy 162.764517 -44.111923)
			(xy 162.70908 -44.118023) (xy 162.653346 -44.115986) (xy 162.598503 -44.105856) (xy 162.545719 -44.087849)
			(xy 162.496119 -44.062348) (xy 162.450761 -44.029897) (xy 162.410612 -43.991188) (xy 162.376526 -43.947045)
			(xy 162.34923 -43.89841) (xy 162.329307 -43.846319) (xy 162.317181 -43.791882) (xy 162.31311 -43.73626)
			(xy 157.355361 -43.73626) (xy 157.278324 -44.104306) (xy 157.278324 -44.105322) (xy 157.087524 -45.114464)
			(xy 162.165536 -45.114464) (xy 162.169607 -45.058842) (xy 162.181733 -45.004405) (xy 162.201656 -44.952314)
			(xy 162.228952 -44.903679) (xy 162.263038 -44.859536) (xy 162.303187 -44.820827) (xy 162.348545 -44.788376)
			(xy 162.398145 -44.762875) (xy 162.450929 -44.744868) (xy 162.505772 -44.734738) (xy 162.561506 -44.732701)
			(xy 162.616943 -44.738801) (xy 162.6709 -44.752907) (xy 162.722229 -44.774719) (xy 162.769835 -44.803773)
			(xy 162.812703 -44.839448) (xy 162.842685 -44.87291) (xy 169.033188 -44.87291) (xy 169.037259 -44.817288)
			(xy 169.049385 -44.762851) (xy 169.069308 -44.71076) (xy 169.096604 -44.662125) (xy 169.13069 -44.617982)
			(xy 169.170839 -44.579273) (xy 169.216197 -44.546822) (xy 169.265797 -44.521321) (xy 169.318581 -44.503314)
			(xy 169.373424 -44.493184) (xy 169.429158 -44.491147) (xy 169.484595 -44.497247) (xy 169.538552 -44.511353)
			(xy 169.589881 -44.533165) (xy 169.637487 -44.562219) (xy 169.680355 -44.597894) (xy 169.717572 -44.639431)
			(xy 169.748345 -44.685944) (xy 169.772017 -44.736441) (xy 169.788085 -44.789848) (xy 169.796205 -44.845024)
			(xy 169.796714 -44.87291) (xy 169.796205 -44.900796) (xy 169.788085 -44.955972) (xy 169.772017 -45.009379)
			(xy 169.748345 -45.059876) (xy 169.717572 -45.106389) (xy 169.680355 -45.147926) (xy 169.637487 -45.183601)
			(xy 169.589881 -45.212655) (xy 169.538552 -45.234467) (xy 169.484595 -45.248573) (xy 169.429158 -45.254673)
			(xy 169.373424 -45.252636) (xy 169.318581 -45.242506) (xy 169.265797 -45.224499) (xy 169.216197 -45.198998)
			(xy 169.170839 -45.166547) (xy 169.13069 -45.127838) (xy 169.096604 -45.083695) (xy 169.069308 -45.03506)
			(xy 169.049385 -44.982969) (xy 169.037259 -44.928532) (xy 169.033188 -44.87291) (xy 162.842685 -44.87291)
			(xy 162.84992 -44.880985) (xy 162.880693 -44.927498) (xy 162.904365 -44.977995) (xy 162.920433 -45.031402)
			(xy 162.928553 -45.086578) (xy 162.929062 -45.114464) (xy 162.928553 -45.14235) (xy 162.920433 -45.197526)
			(xy 162.904365 -45.250933) (xy 162.880693 -45.30143) (xy 162.84992 -45.347943) (xy 162.844278 -45.35424)
			(xy 166.80383 -45.35424) (xy 166.807901 -45.298618) (xy 166.820027 -45.244181) (xy 166.83995 -45.19209)
			(xy 166.867246 -45.143455) (xy 166.901332 -45.099312) (xy 166.941481 -45.060603) (xy 166.986839 -45.028152)
			(xy 167.036439 -45.002651) (xy 167.089223 -44.984644) (xy 167.144066 -44.974514) (xy 167.1998 -44.972477)
			(xy 167.255237 -44.978577) (xy 167.309194 -44.992683) (xy 167.360523 -45.014495) (xy 167.408129 -45.043549)
			(xy 167.450997 -45.079224) (xy 167.488214 -45.120761) (xy 167.518987 -45.167274) (xy 167.542659 -45.217771)
			(xy 167.558727 -45.271178) (xy 167.566847 -45.326354) (xy 167.567356 -45.35424) (xy 167.566847 -45.382126)
			(xy 167.558727 -45.437302) (xy 167.542659 -45.490709) (xy 167.518987 -45.541206) (xy 167.488214 -45.587719)
			(xy 167.450997 -45.629256) (xy 167.408129 -45.664931) (xy 167.360523 -45.693985) (xy 167.309194 -45.715797)
			(xy 167.255237 -45.729903) (xy 167.1998 -45.736003) (xy 167.144066 -45.733966) (xy 167.089223 -45.723836)
			(xy 167.036439 -45.705829) (xy 166.986839 -45.680328) (xy 166.941481 -45.647877) (xy 166.901332 -45.609168)
			(xy 166.867246 -45.565025) (xy 166.83995 -45.51639) (xy 166.820027 -45.464299) (xy 166.807901 -45.409862)
			(xy 166.80383 -45.35424) (xy 162.844278 -45.35424) (xy 162.812703 -45.38948) (xy 162.769835 -45.425155)
			(xy 162.722229 -45.454209) (xy 162.6709 -45.476021) (xy 162.616943 -45.490127) (xy 162.561506 -45.496227)
			(xy 162.505772 -45.49419) (xy 162.450929 -45.48406) (xy 162.398145 -45.466053) (xy 162.348545 -45.440552)
			(xy 162.303187 -45.408101) (xy 162.263038 -45.369392) (xy 162.228952 -45.325249) (xy 162.201656 -45.276614)
			(xy 162.181733 -45.224523) (xy 162.169607 -45.170086) (xy 162.165536 -45.114464) (xy 157.087524 -45.114464)
			(xy 156.904552 -46.082204) (xy 160.152588 -46.082204) (xy 160.153081 -46.054953) (xy 160.160837 -46.001006)
			(xy 160.176192 -45.948711) (xy 160.198832 -45.899134) (xy 160.228298 -45.853284) (xy 160.263988 -45.812094)
			(xy 160.305178 -45.776402) (xy 160.351027 -45.746936) (xy 160.400604 -45.724295) (xy 160.452898 -45.708939)
			(xy 160.506845 -45.701182) (xy 160.534096 -45.700696) (xy 160.560998 -45.701161) (xy 160.614268 -45.708733)
			(xy 160.665947 -45.723711) (xy 160.715008 -45.745801) (xy 160.760481 -45.774563) (xy 160.801462 -45.809427)
			(xy 160.83714 -45.849702) (xy 160.852358 -45.871892) (xy 160.85947 -45.882814) (xy 160.88233 -45.894752)
			(xy 160.994598 -45.89272) (xy 161.01695 -45.879766) (xy 161.023808 -45.86859) (xy 161.038738 -45.844994)
			(xy 161.074415 -45.802042) (xy 161.115972 -45.764749) (xy 161.162521 -45.733911) (xy 161.213067 -45.710187)
			(xy 161.266531 -45.694083) (xy 161.321772 -45.685943) (xy 161.34969 -45.685456) (xy 161.376683 -45.685923)
			(xy 161.430131 -45.693527) (xy 161.481974 -45.708586) (xy 161.531179 -45.730799) (xy 161.576763 -45.759722)
			(xy 161.597594 -45.776896) (xy 161.605722 -45.784008) (xy 161.626296 -45.790104) (xy 161.71164 -45.779182)
			(xy 161.72218 -45.777388) (xy 161.740465 -45.766348) (xy 161.746946 -45.757846) (xy 161.762277 -45.736599)
			(xy 161.797868 -45.698146) (xy 161.838389 -45.664929) (xy 161.883076 -45.637572) (xy 161.931087 -45.616592)
			(xy 161.98152 -45.602382) (xy 162.033422 -45.595211) (xy 162.05962 -45.594778) (xy 162.086869 -45.595294)
			(xy 162.140813 -45.603052) (xy 162.193103 -45.618408) (xy 162.242676 -45.64105) (xy 162.288522 -45.670516)
			(xy 162.329708 -45.706206) (xy 162.365396 -45.747394) (xy 162.39486 -45.793242) (xy 162.417499 -45.842816)
			(xy 162.432852 -45.895107) (xy 162.440608 -45.949051) (xy 162.440608 -46.003549) (xy 162.432852 -46.057493)
			(xy 162.417499 -46.109784) (xy 162.39486 -46.159358) (xy 162.365396 -46.205206) (xy 162.329708 -46.246394)
			(xy 162.288522 -46.282084) (xy 162.242676 -46.31155) (xy 162.193103 -46.334192) (xy 162.140813 -46.349548)
			(xy 162.086869 -46.357306) (xy 162.05962 -46.357794) (xy 162.032628 -46.357309) (xy 161.979181 -46.349707)
			(xy 161.927338 -46.334652) (xy 161.878133 -46.312444) (xy 161.832548 -46.283525) (xy 161.811716 -46.266354)
			(xy 161.803588 -46.259242) (xy 161.783014 -46.253146) (xy 161.69767 -46.264068) (xy 161.687124 -46.265835)
			(xy 161.668843 -46.276896) (xy 161.662364 -46.285404) (xy 161.644753 -46.309706) (xy 161.603156 -46.352964)
			(xy 161.57956 -46.37151) (xy 161.571686 -46.377352) (xy 161.561272 -46.394878) (xy 161.548064 -46.485302)
			(xy 161.55289 -46.504606) (xy 161.558732 -46.51248) (xy 161.558732 -46.512734) (xy 161.57623 -46.537482)
			(xy 161.604035 -46.591333) (xy 161.622973 -46.648904) (xy 161.630176 -46.693836) (xy 166.7764 -46.693836)
			(xy 166.776886 -46.666585) (xy 166.784642 -46.612637) (xy 166.799997 -46.560342) (xy 166.822639 -46.510765)
			(xy 166.852105 -46.464915) (xy 166.887796 -46.423724) (xy 166.928987 -46.388033) (xy 166.974837 -46.358567)
			(xy 167.024414 -46.335925) (xy 167.076709 -46.32057) (xy 167.130657 -46.312814) (xy 167.185159 -46.312814)
			(xy 167.239107 -46.32057) (xy 167.291402 -46.335925) (xy 167.340979 -46.358567) (xy 167.386829 -46.388033)
			(xy 167.42802 -46.423724) (xy 167.463711 -46.464915) (xy 167.493177 -46.510765) (xy 167.515819 -46.560342)
			(xy 167.531174 -46.612637) (xy 167.53893 -46.666585) (xy 167.539416 -46.693836) (xy 167.538941 -46.720263)
			(xy 167.531632 -46.772611) (xy 167.517159 -46.823446) (xy 167.4958 -46.871793) (xy 167.482266 -46.894496)
			(xy 167.482012 -46.89475) (xy 167.476675 -46.904768) (xy 167.474419 -46.927318) (xy 167.477694 -46.938184)
			(xy 167.503856 -47.01286) (xy 167.508238 -47.023376) (xy 167.524328 -47.039464) (xy 167.534844 -47.043848)
			(xy 167.535098 -47.043848) (xy 167.559618 -47.052888) (xy 167.606069 -47.076837) (xy 167.648819 -47.106898)
			(xy 167.68707 -47.14251) (xy 167.720104 -47.183006) (xy 167.747306 -47.22763) (xy 167.768167 -47.275548)
			(xy 167.782296 -47.325863) (xy 167.789429 -47.377635) (xy 167.78986 -47.403766) (xy 167.789374 -47.431017)
			(xy 167.787851 -47.441612) (xy 169.06189 -47.441612) (xy 169.065961 -47.38599) (xy 169.078087 -47.331553)
			(xy 169.09801 -47.279462) (xy 169.125306 -47.230827) (xy 169.159392 -47.186684) (xy 169.199541 -47.147975)
			(xy 169.244899 -47.115524) (xy 169.294499 -47.090023) (xy 169.347283 -47.072016) (xy 169.402126 -47.061886)
			(xy 169.45786 -47.059849) (xy 169.513297 -47.065949) (xy 169.567254 -47.080055) (xy 169.618583 -47.101867)
			(xy 169.666189 -47.130921) (xy 169.709057 -47.166596) (xy 169.746274 -47.208133) (xy 169.777047 -47.254646)
			(xy 169.800719 -47.305143) (xy 169.816787 -47.35855) (xy 169.824907 -47.413726) (xy 169.825416 -47.441612)
			(xy 169.824907 -47.469498) (xy 169.816787 -47.524674) (xy 169.800719 -47.578081) (xy 169.777047 -47.628578)
			(xy 169.746274 -47.675091) (xy 169.709057 -47.716628) (xy 169.666189 -47.752303) (xy 169.618583 -47.781357)
			(xy 169.567254 -47.803169) (xy 169.513297 -47.817275) (xy 169.45786 -47.823375) (xy 169.402126 -47.821338)
			(xy 169.347283 -47.811208) (xy 169.294499 -47.793201) (xy 169.244899 -47.7677) (xy 169.199541 -47.735249)
			(xy 169.159392 -47.69654) (xy 169.125306 -47.652397) (xy 169.09801 -47.603762) (xy 169.078087 -47.551671)
			(xy 169.065961 -47.497234) (xy 169.06189 -47.441612) (xy 167.787851 -47.441612) (xy 167.781618 -47.484965)
			(xy 167.766263 -47.53726) (xy 167.743621 -47.586837) (xy 167.714155 -47.632687) (xy 167.678464 -47.673878)
			(xy 167.637273 -47.709569) (xy 167.591423 -47.739035) (xy 167.541846 -47.761677) (xy 167.489551 -47.777032)
			(xy 167.435603 -47.784788) (xy 167.381101 -47.784788) (xy 167.327153 -47.777032) (xy 167.274858 -47.761677)
			(xy 167.225281 -47.739035) (xy 167.179431 -47.709569) (xy 167.13824 -47.673878) (xy 167.102549 -47.632687)
			(xy 167.073083 -47.586837) (xy 167.050441 -47.53726) (xy 167.035086 -47.484965) (xy 167.02733 -47.431017)
			(xy 167.026844 -47.403766) (xy 167.027312 -47.377338) (xy 167.034622 -47.32499) (xy 167.049096 -47.274155)
			(xy 167.070458 -47.225809) (xy 167.083994 -47.203106) (xy 167.084248 -47.202852) (xy 167.089583 -47.192834)
			(xy 167.091842 -47.170284) (xy 167.088566 -47.159418) (xy 167.062404 -47.084742) (xy 167.058039 -47.074217)
			(xy 167.041938 -47.058132) (xy 167.031416 -47.053754) (xy 167.031162 -47.053754) (xy 167.006656 -47.044678)
			(xy 166.960203 -47.020737) (xy 166.917451 -46.990682) (xy 166.879199 -46.955076) (xy 166.846162 -46.914584)
			(xy 166.818958 -46.869963) (xy 166.798096 -46.822048) (xy 166.783965 -46.771736) (xy 166.776831 -46.719966)
			(xy 166.7764 -46.693836) (xy 161.630176 -46.693836) (xy 161.632566 -46.708745) (xy 161.633154 -46.739048)
			(xy 161.632667 -46.766298) (xy 161.624905 -46.820244) (xy 161.609546 -46.872536) (xy 161.586903 -46.92211)
			(xy 161.557436 -46.967958) (xy 161.521745 -47.009146) (xy 161.480556 -47.044837) (xy 161.434708 -47.074304)
			(xy 161.385134 -47.096947) (xy 161.332842 -47.112306) (xy 161.278896 -47.120067) (xy 161.251646 -47.120556)
			(xy 161.225612 -47.120132) (xy 161.174028 -47.113038) (xy 161.123886 -47.099003) (xy 161.076116 -47.078287)
			(xy 161.031602 -47.051274) (xy 161.011108 -47.035212) (xy 161.003355 -47.029463) (xy 160.984941 -47.023727)
			(xy 160.975294 -47.024036) (xy 160.895538 -47.030386) (xy 160.877758 -47.039022) (xy 160.871408 -47.046388)
			(xy 160.853246 -47.066052) (xy 160.812334 -47.100573) (xy 160.767001 -47.129039) (xy 160.718136 -47.150894)
			(xy 160.666697 -47.165707) (xy 160.613693 -47.173189) (xy 160.586928 -47.173642) (xy 160.559679 -47.173096)
			(xy 160.505735 -47.165344) (xy 160.453444 -47.149994) (xy 160.403869 -47.127359) (xy 160.35802 -47.097899)
			(xy 160.31683 -47.062213) (xy 160.281139 -47.02103) (xy 160.251671 -46.975185) (xy 160.229028 -46.925614)
			(xy 160.213669 -46.873325) (xy 160.205909 -46.819383) (xy 160.20542 -46.792134) (xy 160.205939 -46.76336)
			(xy 160.214591 -46.706465) (xy 160.231688 -46.651514) (xy 160.256843 -46.599754) (xy 160.289485 -46.552359)
			(xy 160.308798 -46.531022) (xy 160.316164 -46.523148) (xy 160.323276 -46.503336) (xy 160.31591 -46.40707)
			(xy 160.306004 -46.388274) (xy 160.297622 -46.38167) (xy 160.275438 -46.363445) (xy 160.236228 -46.32151)
			(xy 160.203742 -46.274174) (xy 160.178713 -46.222506) (xy 160.161707 -46.167672) (xy 160.153106 -46.110909)
			(xy 160.152588 -46.082204) (xy 156.904552 -46.082204) (xy 156.68244 -47.256954) (xy 156.48396 -48.30699)
			(xy 166.65397 -48.30699) (xy 166.658041 -48.251368) (xy 166.670167 -48.196931) (xy 166.69009 -48.14484)
			(xy 166.717386 -48.096205) (xy 166.751472 -48.052062) (xy 166.791621 -48.013353) (xy 166.836979 -47.980902)
			(xy 166.886579 -47.955401) (xy 166.939363 -47.937394) (xy 166.994206 -47.927264) (xy 167.04994 -47.925227)
			(xy 167.105377 -47.931327) (xy 167.159334 -47.945433) (xy 167.210663 -47.967245) (xy 167.258269 -47.996299)
			(xy 167.301137 -48.031974) (xy 167.338354 -48.073511) (xy 167.369127 -48.120024) (xy 167.392799 -48.170521)
			(xy 167.408867 -48.223928) (xy 167.416987 -48.279104) (xy 167.417496 -48.30699) (xy 167.416987 -48.334876)
			(xy 167.408867 -48.390052) (xy 167.392799 -48.443459) (xy 167.369127 -48.493956) (xy 167.338354 -48.540469)
			(xy 167.301137 -48.582006) (xy 167.258269 -48.617681) (xy 167.210663 -48.646735) (xy 167.159334 -48.668547)
			(xy 167.105377 -48.682653) (xy 167.04994 -48.688753) (xy 166.994206 -48.686716) (xy 166.939363 -48.676586)
			(xy 166.886579 -48.658579) (xy 166.836979 -48.633078) (xy 166.791621 -48.600627) (xy 166.751472 -48.561918)
			(xy 166.717386 -48.517775) (xy 166.69009 -48.46914) (xy 166.670167 -48.417049) (xy 166.658041 -48.362612)
			(xy 166.65397 -48.30699) (xy 156.48396 -48.30699) (xy 156.399651 -48.753014) (xy 163.268404 -48.753014)
			(xy 163.272475 -48.697392) (xy 163.284601 -48.642955) (xy 163.304524 -48.590864) (xy 163.33182 -48.542229)
			(xy 163.365906 -48.498086) (xy 163.406055 -48.459377) (xy 163.451413 -48.426926) (xy 163.501013 -48.401425)
			(xy 163.553797 -48.383418) (xy 163.60864 -48.373288) (xy 163.664374 -48.371251) (xy 163.719811 -48.377351)
			(xy 163.773768 -48.391457) (xy 163.825097 -48.413269) (xy 163.872703 -48.442323) (xy 163.915571 -48.477998)
			(xy 163.952788 -48.519535) (xy 163.983561 -48.566048) (xy 164.007233 -48.616545) (xy 164.023301 -48.669952)
			(xy 164.031421 -48.725128) (xy 164.03193 -48.753014) (xy 164.031421 -48.7809) (xy 164.023301 -48.836076)
			(xy 164.007233 -48.889483) (xy 164.005837 -48.89246) (xy 165.31412 -48.89246) (xy 165.318191 -48.836838)
			(xy 165.330317 -48.782401) (xy 165.35024 -48.73031) (xy 165.377536 -48.681675) (xy 165.411622 -48.637532)
			(xy 165.451771 -48.598823) (xy 165.497129 -48.566372) (xy 165.546729 -48.540871) (xy 165.599513 -48.522864)
			(xy 165.654356 -48.512734) (xy 165.71009 -48.510697) (xy 165.765527 -48.516797) (xy 165.819484 -48.530903)
			(xy 165.870813 -48.552715) (xy 165.918419 -48.581769) (xy 165.961287 -48.617444) (xy 165.998504 -48.658981)
			(xy 166.029277 -48.705494) (xy 166.052949 -48.755991) (xy 166.069017 -48.809398) (xy 166.077137 -48.864574)
			(xy 166.077646 -48.89246) (xy 166.077137 -48.920346) (xy 166.074699 -48.93691) (xy 169.033188 -48.93691)
			(xy 169.037259 -48.881288) (xy 169.049385 -48.826851) (xy 169.069308 -48.77476) (xy 169.096604 -48.726125)
			(xy 169.13069 -48.681982) (xy 169.170839 -48.643273) (xy 169.216197 -48.610822) (xy 169.265797 -48.585321)
			(xy 169.318581 -48.567314) (xy 169.373424 -48.557184) (xy 169.429158 -48.555147) (xy 169.484595 -48.561247)
			(xy 169.538552 -48.575353) (xy 169.589881 -48.597165) (xy 169.637487 -48.626219) (xy 169.680355 -48.661894)
			(xy 169.717572 -48.703431) (xy 169.748345 -48.749944) (xy 169.772017 -48.800441) (xy 169.788085 -48.853848)
			(xy 169.796205 -48.909024) (xy 169.796714 -48.93691) (xy 169.796205 -48.964796) (xy 169.788085 -49.019972)
			(xy 169.772017 -49.073379) (xy 169.748345 -49.123876) (xy 169.717572 -49.170389) (xy 169.680355 -49.211926)
			(xy 169.637487 -49.247601) (xy 169.589881 -49.276655) (xy 169.538552 -49.298467) (xy 169.484595 -49.312573)
			(xy 169.429158 -49.318673) (xy 169.373424 -49.316636) (xy 169.318581 -49.306506) (xy 169.265797 -49.288499)
			(xy 169.216197 -49.262998) (xy 169.170839 -49.230547) (xy 169.13069 -49.191838) (xy 169.096604 -49.147695)
			(xy 169.069308 -49.09906) (xy 169.049385 -49.046969) (xy 169.037259 -48.992532) (xy 169.033188 -48.93691)
			(xy 166.074699 -48.93691) (xy 166.069017 -48.975522) (xy 166.052949 -49.028929) (xy 166.029277 -49.079426)
			(xy 165.998504 -49.125939) (xy 165.961287 -49.167476) (xy 165.918419 -49.203151) (xy 165.870813 -49.232205)
			(xy 165.819484 -49.254017) (xy 165.765527 -49.268123) (xy 165.71009 -49.274223) (xy 165.654356 -49.272186)
			(xy 165.599513 -49.262056) (xy 165.546729 -49.244049) (xy 165.497129 -49.218548) (xy 165.451771 -49.186097)
			(xy 165.411622 -49.147388) (xy 165.377536 -49.103245) (xy 165.35024 -49.05461) (xy 165.330317 -49.002519)
			(xy 165.318191 -48.948082) (xy 165.31412 -48.89246) (xy 164.005837 -48.89246) (xy 163.983561 -48.93998)
			(xy 163.952788 -48.986493) (xy 163.915571 -49.02803) (xy 163.872703 -49.063705) (xy 163.825097 -49.092759)
			(xy 163.773768 -49.114571) (xy 163.719811 -49.128677) (xy 163.664374 -49.134777) (xy 163.60864 -49.13274)
			(xy 163.553797 -49.12261) (xy 163.501013 -49.104603) (xy 163.451413 -49.079102) (xy 163.406055 -49.046651)
			(xy 163.365906 -49.007942) (xy 163.33182 -48.963799) (xy 163.304524 -48.915164) (xy 163.284601 -48.863073)
			(xy 163.272475 -48.808636) (xy 163.268404 -48.753014) (xy 156.399651 -48.753014) (xy 156.323792 -49.154334)
			(xy 156.257498 -49.505108) (xy 156.256736 -49.513744) (xy 156.249889 -49.95291) (xy 169.033188 -49.95291)
			(xy 169.037259 -49.897288) (xy 169.049385 -49.842851) (xy 169.069308 -49.79076) (xy 169.096604 -49.742125)
			(xy 169.13069 -49.697982) (xy 169.170839 -49.659273) (xy 169.216197 -49.626822) (xy 169.265797 -49.601321)
			(xy 169.318581 -49.583314) (xy 169.373424 -49.573184) (xy 169.429158 -49.571147) (xy 169.484595 -49.577247)
			(xy 169.538552 -49.591353) (xy 169.589881 -49.613165) (xy 169.637487 -49.642219) (xy 169.680355 -49.677894)
			(xy 169.717572 -49.719431) (xy 169.748345 -49.765944) (xy 169.772017 -49.816441) (xy 169.788085 -49.869848)
			(xy 169.796205 -49.925024) (xy 169.796714 -49.95291) (xy 169.796205 -49.980796) (xy 169.788085 -50.035972)
			(xy 169.772017 -50.089379) (xy 169.748345 -50.139876) (xy 169.717572 -50.186389) (xy 169.680355 -50.227926)
			(xy 169.637487 -50.263601) (xy 169.589881 -50.292655) (xy 169.538552 -50.314467) (xy 169.484595 -50.328573)
			(xy 169.429158 -50.334673) (xy 169.373424 -50.332636) (xy 169.318581 -50.322506) (xy 169.265797 -50.304499)
			(xy 169.216197 -50.278998) (xy 169.170839 -50.246547) (xy 169.13069 -50.207838) (xy 169.096604 -50.163695)
			(xy 169.069308 -50.11506) (xy 169.049385 -50.062969) (xy 169.037259 -50.008532) (xy 169.033188 -49.95291)
			(xy 156.249889 -49.95291) (xy 156.233262 -51.019456) (xy 166.84955 -51.019456) (xy 166.853621 -50.963834)
			(xy 166.865747 -50.909397) (xy 166.88567 -50.857306) (xy 166.912966 -50.808671) (xy 166.947052 -50.764528)
			(xy 166.987201 -50.725819) (xy 167.032559 -50.693368) (xy 167.082159 -50.667867) (xy 167.134943 -50.64986)
			(xy 167.189786 -50.63973) (xy 167.24552 -50.637693) (xy 167.300957 -50.643793) (xy 167.354914 -50.657899)
			(xy 167.406243 -50.679711) (xy 167.453849 -50.708765) (xy 167.496717 -50.74444) (xy 167.533934 -50.785977)
			(xy 167.564707 -50.83249) (xy 167.588379 -50.882987) (xy 167.604447 -50.936394) (xy 167.612567 -50.99157)
			(xy 167.613076 -51.019456) (xy 167.612567 -51.047342) (xy 167.604447 -51.102518) (xy 167.588379 -51.155925)
			(xy 167.564707 -51.206422) (xy 167.539851 -51.243992) (xy 175.233076 -51.243992) (xy 175.233519 -51.216621)
			(xy 175.241339 -51.16244) (xy 175.256833 -51.109936) (xy 175.27968 -51.060189) (xy 175.309411 -51.014224)
			(xy 175.327056 -50.993294) (xy 175.32731 -50.99304) (xy 175.332887 -50.985947) (xy 175.339139 -50.969035)
			(xy 175.339502 -50.96002) (xy 175.339502 -50.892964) (xy 175.339162 -50.883945) (xy 175.332902 -50.867029)
			(xy 175.32731 -50.859944) (xy 175.327056 -50.859944) (xy 175.327056 -50.85969) (xy 175.309392 -50.838778)
			(xy 175.279685 -50.792799) (xy 175.256854 -50.743047) (xy 175.241369 -50.690542) (xy 175.233547 -50.636362)
			(xy 175.233076 -50.608992) (xy 175.23357 -50.581741) (xy 175.241327 -50.527795) (xy 175.256683 -50.475501)
			(xy 175.279324 -50.425925) (xy 175.308789 -50.380075) (xy 175.34448 -50.338886) (xy 175.385669 -50.303194)
			(xy 175.431518 -50.273728) (xy 175.481094 -50.251086) (xy 175.533387 -50.235729) (xy 175.587333 -50.227971)
			(xy 175.614584 -50.227484) (xy 175.643502 -50.227982) (xy 175.700676 -50.236711) (xy 175.755876 -50.25397)
			(xy 175.807839 -50.279366) (xy 175.855372 -50.312315) (xy 175.897386 -50.352061) (xy 175.915574 -50.37455)
			(xy 175.923194 -50.383344) (xy 175.944085 -50.393533) (xy 175.955706 -50.394108) (xy 176.035462 -50.394108)
			(xy 176.047096 -50.393587) (xy 176.068005 -50.383385) (xy 176.075594 -50.37455) (xy 176.093776 -50.352059)
			(xy 176.135799 -50.312327) (xy 176.183336 -50.27939) (xy 176.235299 -50.254003) (xy 176.290498 -50.236748)
			(xy 176.347668 -50.228019) (xy 176.376584 -50.227484) (xy 176.403836 -50.22797) (xy 176.457786 -50.235725)
			(xy 176.510083 -50.251078) (xy 176.559662 -50.273718) (xy 176.605515 -50.303184) (xy 176.646708 -50.338875)
			(xy 176.682402 -50.380066) (xy 176.71187 -50.425917) (xy 176.734513 -50.475495) (xy 176.74987 -50.527791)
			(xy 176.757628 -50.58174) (xy 176.758092 -50.608992) (xy 176.757622 -50.635306) (xy 176.750388 -50.687434)
			(xy 176.736069 -50.738077) (xy 176.714938 -50.786276) (xy 176.687392 -50.83112) (xy 176.653953 -50.871759)
			(xy 176.634902 -50.889916) (xy 176.627492 -50.89743) (xy 176.618972 -50.916716) (xy 176.618392 -50.927254)
			(xy 176.618392 -51.00193) (xy 176.618948 -51.012476) (xy 176.627465 -51.031772) (xy 176.634902 -51.039268)
			(xy 176.653984 -51.057397) (xy 176.687439 -51.098033) (xy 176.714994 -51.142878) (xy 176.736128 -51.191084)
			(xy 176.750439 -51.241736) (xy 176.757657 -51.293874) (xy 176.758092 -51.320192) (xy 176.757637 -51.347445)
			(xy 176.749881 -51.401397) (xy 176.734525 -51.453696) (xy 176.711882 -51.503278) (xy 176.682414 -51.549132)
			(xy 176.646719 -51.590325) (xy 176.605525 -51.626018) (xy 176.559671 -51.655486) (xy 176.510089 -51.678128)
			(xy 176.45779 -51.693483) (xy 176.403837 -51.701238) (xy 176.376584 -51.7017) (xy 176.348918 -51.7012)
			(xy 176.294169 -51.693199) (xy 176.241147 -51.67738) (xy 176.190963 -51.654075) (xy 176.144667 -51.623772)
			(xy 176.103229 -51.587105) (xy 176.067517 -51.544842) (xy 176.05248 -51.521614) (xy 176.045862 -51.511922)
			(xy 176.025987 -51.499487) (xy 176.01438 -51.497738) (xy 175.93437 -51.489864) (xy 175.922731 -51.489217)
			(xy 175.900893 -51.497307) (xy 175.89246 -51.505358) (xy 175.892206 -51.505612) (xy 175.874107 -51.524175)
			(xy 175.833779 -51.556755) (xy 175.789408 -51.58357) (xy 175.741813 -51.604126) (xy 175.691872 -51.618043)
			(xy 175.640506 -51.625065) (xy 175.614584 -51.6255) (xy 175.587332 -51.625037) (xy 175.533383 -51.617278)
			(xy 175.481087 -51.601921) (xy 175.43151 -51.579277) (xy 175.385659 -51.549808) (xy 175.344469 -51.514114)
			(xy 175.308777 -51.472922) (xy 175.279311 -51.427069) (xy 175.256671 -51.37749) (xy 175.241317 -51.325193)
			(xy 175.233561 -51.271244) (xy 175.233076 -51.243992) (xy 167.539851 -51.243992) (xy 167.533934 -51.252935)
			(xy 167.496717 -51.294472) (xy 167.453849 -51.330147) (xy 167.406243 -51.359201) (xy 167.354914 -51.381013)
			(xy 167.300957 -51.395119) (xy 167.24552 -51.401219) (xy 167.189786 -51.399182) (xy 167.134943 -51.389052)
			(xy 167.082159 -51.371045) (xy 167.032559 -51.345544) (xy 166.987201 -51.313093) (xy 166.947052 -51.274384)
			(xy 166.912966 -51.230241) (xy 166.88567 -51.181606) (xy 166.865747 -51.129515) (xy 166.853621 -51.075078)
			(xy 166.84955 -51.019456) (xy 156.233262 -51.019456) (xy 156.217422 -52.035456) (xy 169.041316 -52.035456)
			(xy 169.045387 -51.979834) (xy 169.057513 -51.925397) (xy 169.077436 -51.873306) (xy 169.104732 -51.824671)
			(xy 169.138818 -51.780528) (xy 169.178967 -51.741819) (xy 169.224325 -51.709368) (xy 169.273925 -51.683867)
			(xy 169.326709 -51.66586) (xy 169.381552 -51.65573) (xy 169.437286 -51.653693) (xy 169.492723 -51.659793)
			(xy 169.54668 -51.673899) (xy 169.598009 -51.695711) (xy 169.645615 -51.724765) (xy 169.688483 -51.76044)
			(xy 169.7257 -51.801977) (xy 169.756473 -51.84849) (xy 169.780145 -51.898987) (xy 169.796213 -51.952394)
			(xy 169.804333 -52.00757) (xy 169.804842 -52.035456) (xy 169.804333 -52.063342) (xy 169.796213 -52.118518)
			(xy 169.780145 -52.171925) (xy 169.756473 -52.222422) (xy 169.7257 -52.268935) (xy 169.688483 -52.310472)
			(xy 169.645615 -52.346147) (xy 169.598009 -52.375201) (xy 169.54668 -52.397013) (xy 169.492723 -52.411119)
			(xy 169.437286 -52.417219) (xy 169.381552 -52.415182) (xy 169.326709 -52.405052) (xy 169.273925 -52.387045)
			(xy 169.224325 -52.361544) (xy 169.178967 -52.329093) (xy 169.138818 -52.290384) (xy 169.104732 -52.246241)
			(xy 169.077436 -52.197606) (xy 169.057513 -52.145515) (xy 169.045387 -52.091078) (xy 169.041316 -52.035456)
			(xy 156.217422 -52.035456) (xy 156.210508 -52.47894) (xy 156.210553 -52.484922) (xy 156.213121 -52.496604)
			(xy 156.215588 -52.502054) (xy 156.218128 -52.507388) (xy 156.225748 -52.516532) (xy 156.230828 -52.520342)
			(xy 156.252176 -52.536919) (xy 156.290436 -52.575095) (xy 156.322935 -52.618281) (xy 156.349025 -52.665615)
			(xy 156.368186 -52.716153) (xy 156.380035 -52.768887) (xy 156.384336 -52.822764) (xy 156.381003 -52.876709)
			(xy 156.370103 -52.929647) (xy 156.351853 -52.980521) (xy 156.326617 -53.028316) (xy 156.311092 -53.05044)
			(xy 156.304742 -53.059076) (xy 156.300932 -53.063902) (xy 156.295598 -53.072538) (xy 156.29509 -53.073554)
			(xy 156.292631 -53.07888) (xy 156.289941 -53.090296) (xy 156.289756 -53.09616) (xy 156.289756 -53.117242)
			(xy 156.289611 -53.122681) (xy 156.2873 -53.133311) (xy 156.285184 -53.138324) (xy 156.279088 -53.151786)
			(xy 156.275466 -53.160448) (xy 156.274232 -53.179169) (xy 156.27986 -53.197066) (xy 156.285438 -53.204618)
			(xy 156.291026 -53.21173) (xy 156.294582 -53.216302) (xy 156.29509 -53.217064) (xy 156.295598 -53.217572)
			(xy 156.29636 -53.218588) (xy 156.312549 -53.238851) (xy 156.339876 -53.282933) (xy 156.360973 -53.330313)
			(xy 156.375451 -53.380116) (xy 156.383042 -53.431422) (xy 156.383736 -53.457348) (xy 156.383736 -53.460396)
			(xy 156.3834 -53.48578) (xy 156.376834 -53.536119) (xy 156.363657 -53.585144) (xy 156.354272 -53.608732)
			(xy 156.354272 -53.608986) (xy 156.353002 -53.611526) (xy 156.344355 -53.630985) (xy 156.32335 -53.668028)
			(xy 156.311092 -53.68544) (xy 156.304996 -53.693822) (xy 156.300424 -53.699664) (xy 156.296106 -53.706522)
			(xy 156.29509 -53.708554) (xy 156.292631 -53.71388) (xy 156.289941 -53.725296) (xy 156.289756 -53.73116)
			(xy 156.289756 -53.752242) (xy 156.289611 -53.757681) (xy 156.2873 -53.768311) (xy 156.285184 -53.773324)
			(xy 156.279088 -53.786786) (xy 156.275466 -53.795448) (xy 156.274232 -53.814169) (xy 156.27986 -53.832066)
			(xy 156.285438 -53.839618) (xy 156.291026 -53.84673) (xy 156.294582 -53.851302) (xy 156.29509 -53.852064)
			(xy 156.295598 -53.852572) (xy 156.29636 -53.853588) (xy 156.312549 -53.873851) (xy 156.339876 -53.917933)
			(xy 156.360973 -53.965313) (xy 156.375451 -54.015116) (xy 156.383042 -54.066422) (xy 156.383736 -54.092348)
			(xy 156.383736 -54.095396) (xy 156.3834 -54.12078) (xy 156.376834 -54.171119) (xy 156.363657 -54.220144)
			(xy 156.354272 -54.243732) (xy 156.354272 -54.243986) (xy 156.353002 -54.246526) (xy 156.344355 -54.265985)
			(xy 156.32335 -54.303028) (xy 156.311092 -54.32044) (xy 156.304996 -54.328822) (xy 156.300424 -54.334664)
			(xy 156.296106 -54.341522) (xy 156.29509 -54.343554) (xy 156.292631 -54.34888) (xy 156.289941 -54.360296)
			(xy 156.289756 -54.36616) (xy 156.289756 -54.387242) (xy 156.289611 -54.392681) (xy 156.2873 -54.403311)
			(xy 156.285184 -54.408324) (xy 156.279088 -54.421786) (xy 156.275466 -54.430448) (xy 156.274232 -54.449169)
			(xy 156.27986 -54.467066) (xy 156.285438 -54.474618) (xy 156.291026 -54.48173) (xy 156.29636 -54.488334)
			(xy 156.296614 -54.488588) (xy 156.30295 -54.496374) (xy 156.314894 -54.512512) (xy 156.32049 -54.520846)
			(xy 156.336787 -54.546459) (xy 156.361926 -54.601714) (xy 156.370528 -54.630828) (xy 156.370528 -54.631336)
			(xy 156.372814 -54.64048) (xy 156.376613 -54.656708) (xy 156.381699 -54.689648) (xy 156.382974 -54.706266)
			(xy 156.383736 -54.72684) (xy 156.383736 -54.73065) (xy 156.383736 -54.732174) (xy 156.383736 -54.74716)
			(xy 156.382107 -54.774144) (xy 156.378945 -54.791102) (xy 158.276544 -54.791102) (xy 158.277001 -54.763731)
			(xy 158.284819 -54.709551) (xy 158.30031 -54.657048) (xy 158.323154 -54.607301) (xy 158.352881 -54.561335)
			(xy 158.370524 -54.540404) (xy 158.370778 -54.54015) (xy 158.376359 -54.53306) (xy 158.382607 -54.516146)
			(xy 158.38297 -54.50713) (xy 158.38297 -54.440074) (xy 158.382632 -54.431055) (xy 158.376372 -54.414138)
			(xy 158.370778 -54.407054) (xy 158.370524 -54.407054) (xy 158.370524 -54.4068) (xy 158.352885 -54.385866)
			(xy 158.323161 -54.339898) (xy 158.300315 -54.290152) (xy 158.284819 -54.23765) (xy 158.27699 -54.183472)
			(xy 158.27699 -54.128731) (xy 158.284819 -54.074553) (xy 158.300314 -54.022051) (xy 158.323159 -53.972305)
			(xy 158.352884 -53.926337) (xy 158.370524 -53.905404) (xy 158.370778 -53.90515) (xy 158.376359 -53.89806)
			(xy 158.382607 -53.881146) (xy 158.38297 -53.87213) (xy 158.38297 -53.805074) (xy 158.382632 -53.796055)
			(xy 158.376372 -53.779138) (xy 158.370778 -53.772054) (xy 158.370524 -53.772054) (xy 158.370524 -53.7718)
			(xy 158.352885 -53.750866) (xy 158.323161 -53.704898) (xy 158.300315 -53.655152) (xy 158.284819 -53.60265)
			(xy 158.27699 -53.548472) (xy 158.27699 -53.493731) (xy 158.284819 -53.439553) (xy 158.300314 -53.387051)
			(xy 158.323159 -53.337305) (xy 158.352884 -53.291337) (xy 158.370524 -53.270404) (xy 158.370778 -53.27015)
			(xy 158.376359 -53.26306) (xy 158.382607 -53.246146) (xy 158.38297 -53.23713) (xy 158.38297 -53.170074)
			(xy 158.382632 -53.161055) (xy 158.376372 -53.144138) (xy 158.370778 -53.137054) (xy 158.370524 -53.137054)
			(xy 158.370524 -53.1368) (xy 158.352875 -53.115876) (xy 158.323164 -53.069901) (xy 158.30033 -53.020152)
			(xy 158.284841 -52.967649) (xy 158.277016 -52.913472) (xy 158.276544 -52.886102) (xy 158.27703 -52.858851)
			(xy 158.284786 -52.804903) (xy 158.300141 -52.752608) (xy 158.322783 -52.703031) (xy 158.352249 -52.657181)
			(xy 158.38794 -52.61599) (xy 158.429131 -52.580299) (xy 158.474981 -52.550833) (xy 158.524558 -52.528191)
			(xy 158.576853 -52.512836) (xy 158.630801 -52.50508) (xy 158.685303 -52.50508) (xy 158.739251 -52.512836)
			(xy 158.791546 -52.528191) (xy 158.830655 -52.546052) (xy 163.779673 -52.546052) (xy 163.779673 -52.491548)
			(xy 163.78743 -52.437599) (xy 163.802786 -52.385303) (xy 163.825428 -52.335725) (xy 163.854895 -52.289873)
			(xy 163.890588 -52.248682) (xy 163.93178 -52.21299) (xy 163.977632 -52.183524) (xy 164.02721 -52.160883)
			(xy 164.079507 -52.145528) (xy 164.133456 -52.137773) (xy 164.160708 -52.13731) (xy 164.188079 -52.137769)
			(xy 164.242258 -52.145588) (xy 164.294761 -52.161079) (xy 164.344508 -52.183922) (xy 164.390475 -52.213648)
			(xy 164.411406 -52.23129) (xy 164.41166 -52.231544) (xy 164.41875 -52.237125) (xy 164.435664 -52.243374)
			(xy 164.44468 -52.243736) (xy 164.511736 -52.243736) (xy 164.520754 -52.243388) (xy 164.53767 -52.237134)
			(xy 164.544756 -52.231544) (xy 164.544756 -52.23129) (xy 164.54501 -52.23129) (xy 164.565943 -52.213649)
			(xy 164.611911 -52.183925) (xy 164.661657 -52.161079) (xy 164.714159 -52.145583) (xy 164.768337 -52.137754)
			(xy 164.823079 -52.137754) (xy 164.877257 -52.145583) (xy 164.929759 -52.161079) (xy 164.979505 -52.183925)
			(xy 165.025473 -52.213649) (xy 165.046406 -52.23129) (xy 165.04666 -52.231544) (xy 165.05375 -52.237125)
			(xy 165.070664 -52.243374) (xy 165.07968 -52.243736) (xy 165.146736 -52.243736) (xy 165.155754 -52.243388)
			(xy 165.17267 -52.237134) (xy 165.179756 -52.231544) (xy 165.179756 -52.23129) (xy 165.18001 -52.23129)
			(xy 165.200926 -52.213631) (xy 165.246904 -52.183923) (xy 165.296655 -52.161091) (xy 165.349159 -52.145604)
			(xy 165.403338 -52.137781) (xy 165.430708 -52.13731) (xy 165.45796 -52.13776) (xy 165.51191 -52.145518)
			(xy 165.564206 -52.160875) (xy 165.613784 -52.183517) (xy 165.659636 -52.212985) (xy 165.700827 -52.248678)
			(xy 165.73652 -52.28987) (xy 165.765986 -52.335723) (xy 165.788628 -52.385302) (xy 165.803984 -52.437598)
			(xy 165.81174 -52.491548) (xy 165.81174 -52.546052) (xy 165.805796 -52.587398) (xy 166.855392 -52.587398)
			(xy 166.859463 -52.531776) (xy 166.871589 -52.477339) (xy 166.891512 -52.425248) (xy 166.918808 -52.376613)
			(xy 166.952894 -52.33247) (xy 166.993043 -52.293761) (xy 167.038401 -52.26131) (xy 167.088001 -52.235809)
			(xy 167.140785 -52.217802) (xy 167.195628 -52.207672) (xy 167.251362 -52.205635) (xy 167.306799 -52.211735)
			(xy 167.360756 -52.225841) (xy 167.412085 -52.247653) (xy 167.459691 -52.276707) (xy 167.502559 -52.312382)
			(xy 167.539776 -52.353919) (xy 167.570549 -52.400432) (xy 167.594221 -52.450929) (xy 167.610289 -52.504336)
			(xy 167.617885 -52.555952) (xy 174.683879 -52.555952) (xy 174.683879 -52.501448) (xy 174.691637 -52.447498)
			(xy 174.706993 -52.395201) (xy 174.729636 -52.345622) (xy 174.759105 -52.29977) (xy 174.794799 -52.25858)
			(xy 174.835993 -52.222888) (xy 174.881847 -52.193423) (xy 174.931427 -52.170783) (xy 174.983725 -52.155431)
			(xy 175.037676 -52.147677) (xy 175.064928 -52.147216) (xy 175.092299 -52.147662) (xy 175.146479 -52.155484)
			(xy 175.198983 -52.170978) (xy 175.248729 -52.193824) (xy 175.294695 -52.223553) (xy 175.315626 -52.241196)
			(xy 175.31588 -52.24145) (xy 175.322964 -52.24704) (xy 175.339883 -52.253284) (xy 175.3489 -52.253642)
			(xy 175.415956 -52.253642) (xy 175.424972 -52.253277) (xy 175.44189 -52.247036) (xy 175.448976 -52.24145)
			(xy 175.448976 -52.241196) (xy 175.44923 -52.241196) (xy 175.470177 -52.223576) (xy 175.516146 -52.193861)
			(xy 175.56589 -52.171022) (xy 175.618387 -52.155526) (xy 175.67256 -52.147693) (xy 175.699928 -52.147216)
			(xy 175.72718 -52.147656) (xy 175.781128 -52.155416) (xy 175.833422 -52.170775) (xy 175.882999 -52.193419)
			(xy 175.928849 -52.222888) (xy 175.970038 -52.258581) (xy 176.005729 -52.299773) (xy 176.035195 -52.345625)
			(xy 176.057835 -52.395204) (xy 176.07319 -52.4475) (xy 176.080946 -52.501448) (xy 176.080946 -52.555952)
			(xy 176.07319 -52.6099) (xy 176.057835 -52.662196) (xy 176.035195 -52.711775) (xy 176.005729 -52.757627)
			(xy 175.970038 -52.798819) (xy 175.928849 -52.834512) (xy 175.882999 -52.863981) (xy 175.833422 -52.886625)
			(xy 175.781128 -52.901984) (xy 175.72718 -52.909744) (xy 175.699928 -52.910232) (xy 175.672558 -52.909766)
			(xy 175.618378 -52.901951) (xy 175.565874 -52.886463) (xy 175.516127 -52.86362) (xy 175.470161 -52.833894)
			(xy 175.44923 -52.816252) (xy 175.448976 -52.815998) (xy 175.441901 -52.810395) (xy 175.424975 -52.804158)
			(xy 175.415956 -52.803806) (xy 175.3489 -52.803806) (xy 175.339883 -52.804162) (xy 175.322966 -52.81041)
			(xy 175.31588 -52.815998) (xy 175.31588 -52.816252) (xy 175.315626 -52.816252) (xy 175.294689 -52.833885)
			(xy 175.248718 -52.863599) (xy 175.198972 -52.886437) (xy 175.146472 -52.90193) (xy 175.092297 -52.909758)
			(xy 175.064928 -52.910232) (xy 175.037676 -52.909723) (xy 174.983725 -52.901969) (xy 174.931427 -52.886617)
			(xy 174.881847 -52.863977) (xy 174.835993 -52.834512) (xy 174.794799 -52.79882) (xy 174.759105 -52.75763)
			(xy 174.729636 -52.711778) (xy 174.706993 -52.662199) (xy 174.691637 -52.609902) (xy 174.683879 -52.555952)
			(xy 167.617885 -52.555952) (xy 167.618409 -52.559512) (xy 167.618918 -52.587398) (xy 167.618409 -52.615284)
			(xy 167.610289 -52.67046) (xy 167.594221 -52.723867) (xy 167.570549 -52.774364) (xy 167.539776 -52.820877)
			(xy 167.502559 -52.862414) (xy 167.459691 -52.898089) (xy 167.412085 -52.927143) (xy 167.360756 -52.948955)
			(xy 167.306799 -52.963061) (xy 167.251362 -52.969161) (xy 167.195628 -52.967124) (xy 167.140785 -52.956994)
			(xy 167.088001 -52.938987) (xy 167.038401 -52.913486) (xy 166.993043 -52.881035) (xy 166.952894 -52.842326)
			(xy 166.918808 -52.798183) (xy 166.891512 -52.749548) (xy 166.871589 -52.697457) (xy 166.859463 -52.64302)
			(xy 166.855392 -52.587398) (xy 165.805796 -52.587398) (xy 165.803984 -52.600002) (xy 165.788628 -52.652298)
			(xy 165.765986 -52.701877) (xy 165.73652 -52.74773) (xy 165.700827 -52.788922) (xy 165.659636 -52.824615)
			(xy 165.613784 -52.854083) (xy 165.564206 -52.876725) (xy 165.51191 -52.892082) (xy 165.45796 -52.89984)
			(xy 165.430708 -52.900326) (xy 165.403337 -52.899873) (xy 165.349157 -52.892055) (xy 165.296653 -52.876564)
			(xy 165.246906 -52.853719) (xy 165.20094 -52.82399) (xy 165.18001 -52.806346) (xy 165.179756 -52.806092)
			(xy 165.172658 -52.800522) (xy 165.15575 -52.794266) (xy 165.146736 -52.7939) (xy 165.07968 -52.7939)
			(xy 165.070662 -52.794248) (xy 165.053745 -52.800502) (xy 165.04666 -52.806092) (xy 165.046406 -52.806346)
			(xy 165.025473 -52.823987) (xy 164.979505 -52.853711) (xy 164.929759 -52.876557) (xy 164.877257 -52.892053)
			(xy 164.823079 -52.899882) (xy 164.768337 -52.899882) (xy 164.714159 -52.892053) (xy 164.661657 -52.876557)
			(xy 164.611911 -52.853711) (xy 164.565943 -52.823987) (xy 164.54501 -52.806346) (xy 164.544756 -52.806092)
			(xy 164.537658 -52.800522) (xy 164.52075 -52.794266) (xy 164.511736 -52.7939) (xy 164.44468 -52.7939)
			(xy 164.435662 -52.794248) (xy 164.418745 -52.800502) (xy 164.41166 -52.806092) (xy 164.41166 -52.806346)
			(xy 164.411406 -52.806346) (xy 164.390476 -52.823987) (xy 164.344503 -52.853701) (xy 164.294755 -52.876537)
			(xy 164.242254 -52.892027) (xy 164.188077 -52.899854) (xy 164.160708 -52.900326) (xy 164.133456 -52.899827)
			(xy 164.079507 -52.892072) (xy 164.02721 -52.876717) (xy 163.977632 -52.854076) (xy 163.93178 -52.82461)
			(xy 163.890588 -52.788918) (xy 163.854895 -52.747727) (xy 163.825428 -52.701875) (xy 163.802786 -52.652297)
			(xy 163.78743 -52.600001) (xy 163.779673 -52.546052) (xy 158.830655 -52.546052) (xy 158.841123 -52.550833)
			(xy 158.886973 -52.580299) (xy 158.928164 -52.61599) (xy 158.963855 -52.657181) (xy 158.993321 -52.703031)
			(xy 159.015963 -52.752608) (xy 159.031318 -52.804903) (xy 159.039074 -52.858851) (xy 159.03956 -52.886102)
			(xy 159.039105 -52.913473) (xy 159.031286 -52.967653) (xy 159.015795 -53.020156) (xy 158.99295 -53.069903)
			(xy 158.963223 -53.115869) (xy 158.94558 -53.1368) (xy 158.945326 -53.137054) (xy 158.939744 -53.144143)
			(xy 158.933496 -53.161058) (xy 158.933134 -53.170074) (xy 158.933134 -53.23713) (xy 158.933469 -53.246149)
			(xy 158.939731 -53.263066) (xy 158.945326 -53.27015) (xy 158.94558 -53.27015) (xy 158.94558 -53.270404)
			(xy 158.963222 -53.291335) (xy 158.992947 -53.337304) (xy 159.015791 -53.38705) (xy 159.031287 -53.439552)
			(xy 159.039115 -53.493731) (xy 159.039115 -53.548472) (xy 159.031287 -53.602651) (xy 159.01579 -53.655153)
			(xy 158.992945 -53.704899) (xy 158.963221 -53.750867) (xy 158.94665 -53.77053) (xy 159.310832 -53.77053)
			(xy 159.31136 -53.741613) (xy 159.320085 -53.684442) (xy 159.33734 -53.629243) (xy 159.36273 -53.577281)
			(xy 159.395673 -53.529747) (xy 159.435413 -53.48773) (xy 159.457898 -53.46954) (xy 159.466677 -53.461905)
			(xy 159.476876 -53.441026) (xy 159.477456 -53.429408) (xy 159.477456 -53.349652) (xy 159.476946 -53.338016)
			(xy 159.466738 -53.317106) (xy 159.457898 -53.30952) (xy 159.435424 -53.291318) (xy 159.395688 -53.249301)
			(xy 159.362748 -53.201768) (xy 159.337358 -53.149809) (xy 159.3201 -53.094613) (xy 159.311368 -53.037445)
			(xy 159.310832 -53.00853) (xy 159.311283 -52.981276) (xy 159.319037 -52.927323) (xy 159.334392 -52.875022)
			(xy 159.357033 -52.825439) (xy 159.386502 -52.779584) (xy 159.422197 -52.73839) (xy 159.463392 -52.702696)
			(xy 159.509248 -52.673229) (xy 159.558831 -52.650588) (xy 159.611132 -52.635235) (xy 159.665086 -52.627483)
			(xy 159.69234 -52.627022) (xy 159.718655 -52.627456) (xy 159.770785 -52.634696) (xy 159.821429 -52.649022)
			(xy 159.869628 -52.67016) (xy 159.914471 -52.697713) (xy 159.955109 -52.731158) (xy 159.973264 -52.750212)
			(xy 159.980795 -52.757602) (xy 160.000068 -52.766133) (xy 160.010602 -52.766722) (xy 160.085278 -52.766722)
			(xy 160.095827 -52.766188) (xy 160.115122 -52.757655) (xy 160.122616 -52.750212) (xy 160.140773 -52.731158)
			(xy 160.181402 -52.6977) (xy 160.226242 -52.670141) (xy 160.274443 -52.649002) (xy 160.32509 -52.634685)
			(xy 160.377224 -52.62746) (xy 160.40354 -52.627022) (xy 160.430794 -52.627441) (xy 160.484745 -52.635203)
			(xy 160.537043 -52.650565) (xy 160.586622 -52.673213) (xy 160.632474 -52.702686) (xy 160.673665 -52.738385)
			(xy 160.709356 -52.779582) (xy 160.73882 -52.825439) (xy 160.761459 -52.875023) (xy 160.776811 -52.927323)
			(xy 160.784564 -52.981276) (xy 160.785048 -53.00853) (xy 160.784583 -53.036197) (xy 160.782352 -53.051456)
			(xy 169.041316 -53.051456) (xy 169.045387 -52.995834) (xy 169.057513 -52.941397) (xy 169.077436 -52.889306)
			(xy 169.104732 -52.840671) (xy 169.138818 -52.796528) (xy 169.178967 -52.757819) (xy 169.224325 -52.725368)
			(xy 169.273925 -52.699867) (xy 169.326709 -52.68186) (xy 169.381552 -52.67173) (xy 169.437286 -52.669693)
			(xy 169.492723 -52.675793) (xy 169.54668 -52.689899) (xy 169.598009 -52.711711) (xy 169.645615 -52.740765)
			(xy 169.688483 -52.77644) (xy 169.7257 -52.817977) (xy 169.756473 -52.86449) (xy 169.780145 -52.914987)
			(xy 169.796213 -52.968394) (xy 169.804333 -53.02357) (xy 169.804842 -53.051456) (xy 169.804333 -53.079342)
			(xy 169.796213 -53.134518) (xy 169.780145 -53.187925) (xy 169.756473 -53.238422) (xy 169.7257 -53.284935)
			(xy 169.688483 -53.326472) (xy 169.645615 -53.362147) (xy 169.598009 -53.391201) (xy 169.54668 -53.413013)
			(xy 169.492723 -53.427119) (xy 169.437286 -53.433219) (xy 169.381552 -53.431182) (xy 169.326709 -53.421052)
			(xy 169.273925 -53.403045) (xy 169.224325 -53.377544) (xy 169.178967 -53.345093) (xy 169.138818 -53.306384)
			(xy 169.104732 -53.262241) (xy 169.077436 -53.213606) (xy 169.057513 -53.161515) (xy 169.045387 -53.107078)
			(xy 169.041316 -53.051456) (xy 160.782352 -53.051456) (xy 160.776578 -53.090949) (xy 160.760755 -53.143973)
			(xy 160.737445 -53.194158) (xy 160.707136 -53.240453) (xy 160.670462 -53.28189) (xy 160.628193 -53.317599)
			(xy 160.604962 -53.332634) (xy 160.595274 -53.339257) (xy 160.582835 -53.359128) (xy 160.581086 -53.370734)
			(xy 160.573212 -53.450744) (xy 160.572572 -53.462382) (xy 160.580659 -53.484219) (xy 160.588706 -53.492654)
			(xy 160.58896 -53.492908) (xy 160.60752 -53.51101) (xy 160.640102 -53.551337) (xy 160.666919 -53.595706)
			(xy 160.687475 -53.643301) (xy 160.701393 -53.693242) (xy 160.708414 -53.744608) (xy 160.708848 -53.77053)
			(xy 160.70835 -53.79778) (xy 160.700591 -53.851725) (xy 160.685234 -53.904017) (xy 160.662592 -53.953592)
			(xy 160.633126 -53.99944) (xy 160.597436 -54.040629) (xy 160.556248 -54.07632) (xy 160.510401 -54.105787)
			(xy 160.460827 -54.12843) (xy 160.408535 -54.143789) (xy 160.35459 -54.15155) (xy 160.32734 -54.152038)
			(xy 160.29997 -54.151564) (xy 160.245791 -54.14375) (xy 160.193287 -54.128264) (xy 160.14354 -54.105424)
			(xy 160.097573 -54.075699) (xy 160.076642 -54.058058) (xy 160.076388 -54.057804) (xy 160.069309 -54.052207)
			(xy 160.052386 -54.045966) (xy 160.043368 -54.045612) (xy 159.976312 -54.045612) (xy 159.967295 -54.045972)
			(xy 159.950378 -54.052217) (xy 159.943292 -54.057804) (xy 159.943292 -54.058058) (xy 159.943038 -54.058058)
			(xy 159.922097 -54.075686) (xy 159.876127 -54.105401) (xy 159.826382 -54.12824) (xy 159.773883 -54.143733)
			(xy 159.719709 -54.151563) (xy 159.69234 -54.152038) (xy 159.665089 -54.151508) (xy 159.611143 -54.143757)
			(xy 159.558848 -54.128407) (xy 159.50927 -54.105772) (xy 159.463418 -54.076311) (xy 159.422226 -54.040624)
			(xy 159.386531 -53.999438) (xy 159.357062 -53.953592) (xy 159.334417 -53.904018) (xy 159.319058 -53.851726)
			(xy 159.311297 -53.79778) (xy 159.310832 -53.77053) (xy 158.94665 -53.77053) (xy 158.94558 -53.7718)
			(xy 158.945326 -53.772054) (xy 158.939744 -53.779143) (xy 158.933496 -53.796058) (xy 158.933134 -53.805074)
			(xy 158.933134 -53.87213) (xy 158.933469 -53.881149) (xy 158.939731 -53.898066) (xy 158.945326 -53.90515)
			(xy 158.94558 -53.90515) (xy 158.94558 -53.905404) (xy 158.963222 -53.926335) (xy 158.992947 -53.972304)
			(xy 159.015791 -54.02205) (xy 159.031287 -54.074552) (xy 159.039115 -54.128731) (xy 159.039115 -54.183472)
			(xy 159.031287 -54.237651) (xy 159.01579 -54.290153) (xy 159.001998 -54.320186) (xy 161.230564 -54.320186)
			(xy 161.231006 -54.292815) (xy 161.238827 -54.238634) (xy 161.254321 -54.18613) (xy 161.277169 -54.136383)
			(xy 161.3069 -54.090418) (xy 161.324544 -54.069488) (xy 161.324798 -54.069234) (xy 161.330376 -54.062142)
			(xy 161.336628 -54.045229) (xy 161.33699 -54.036214) (xy 161.33699 -53.969158) (xy 161.336607 -53.960144)
			(xy 161.330378 -53.943226) (xy 161.324798 -53.936138) (xy 161.324544 -53.936138) (xy 161.324544 -53.935884)
			(xy 161.306938 -53.914925) (xy 161.277219 -53.868961) (xy 161.254376 -53.81922) (xy 161.238878 -53.766725)
			(xy 161.231042 -53.712553) (xy 161.230564 -53.685186) (xy 161.23105 -53.657935) (xy 161.238806 -53.603987)
			(xy 161.254161 -53.551692) (xy 161.276803 -53.502115) (xy 161.306269 -53.456265) (xy 161.34196 -53.415074)
			(xy 161.383151 -53.379383) (xy 161.429001 -53.349917) (xy 161.478578 -53.327275) (xy 161.530873 -53.31192)
			(xy 161.584821 -53.304164) (xy 161.639323 -53.304164) (xy 161.693271 -53.31192) (xy 161.745566 -53.327275)
			(xy 161.795143 -53.349917) (xy 161.840993 -53.379383) (xy 161.882184 -53.415074) (xy 161.917875 -53.456265)
			(xy 161.943766 -53.496552) (xy 174.233564 -53.496552) (xy 174.233564 -53.442048) (xy 174.24132 -53.3881)
			(xy 174.256675 -53.335804) (xy 174.279316 -53.286226) (xy 174.308782 -53.240375) (xy 174.344474 -53.199183)
			(xy 174.385664 -53.163491) (xy 174.431514 -53.134023) (xy 174.481091 -53.11138) (xy 174.533386 -53.096023)
			(xy 174.587334 -53.088265) (xy 174.614586 -53.087778) (xy 174.641957 -53.088233) (xy 174.696137 -53.096051)
			(xy 174.748641 -53.111541) (xy 174.798388 -53.134386) (xy 174.844353 -53.164114) (xy 174.865284 -53.181758)
			(xy 174.865538 -53.182012) (xy 174.872637 -53.18758) (xy 174.889544 -53.193838) (xy 174.898558 -53.194204)
			(xy 174.965614 -53.194204) (xy 174.974631 -53.193853) (xy 174.991548 -53.187601) (xy 174.998634 -53.182012)
			(xy 174.998634 -53.181758) (xy 174.998888 -53.181758) (xy 175.019808 -53.164104) (xy 175.065785 -53.134396)
			(xy 175.115535 -53.111563) (xy 175.168039 -53.096075) (xy 175.222216 -53.08825) (xy 175.249586 -53.087778)
			(xy 175.276839 -53.088268) (xy 175.330789 -53.096023) (xy 175.383087 -53.111378) (xy 175.432667 -53.134019)
			(xy 175.47852 -53.163485) (xy 175.519713 -53.199177) (xy 175.555407 -53.240369) (xy 175.584875 -53.286221)
			(xy 175.607517 -53.3358) (xy 175.622874 -53.388097) (xy 175.630631 -53.442048) (xy 175.630631 -53.496552)
			(xy 175.622874 -53.550503) (xy 175.607517 -53.6028) (xy 175.584875 -53.652379) (xy 175.555407 -53.698231)
			(xy 175.519713 -53.739423) (xy 175.47852 -53.775115) (xy 175.432667 -53.804581) (xy 175.383087 -53.827222)
			(xy 175.330789 -53.842577) (xy 175.276839 -53.850332) (xy 175.249586 -53.850794) (xy 175.222215 -53.850338)
			(xy 175.168036 -53.842518) (xy 175.115533 -53.827026) (xy 175.065786 -53.804183) (xy 175.019819 -53.774456)
			(xy 174.998888 -53.756814) (xy 174.998634 -53.75656) (xy 174.991545 -53.750977) (xy 174.97463 -53.744729)
			(xy 174.965614 -53.744368) (xy 174.898558 -53.744368) (xy 174.889545 -53.74476) (xy 174.872628 -53.750984)
			(xy 174.865538 -53.75656) (xy 174.865538 -53.756814) (xy 174.865284 -53.756814) (xy 174.844333 -53.774429)
			(xy 174.798365 -53.804144) (xy 174.748622 -53.826985) (xy 174.696126 -53.842481) (xy 174.641954 -53.850316)
			(xy 174.614586 -53.850794) (xy 174.587334 -53.850335) (xy 174.533386 -53.842577) (xy 174.481091 -53.82722)
			(xy 174.431514 -53.804577) (xy 174.385664 -53.775109) (xy 174.344474 -53.739417) (xy 174.308782 -53.698225)
			(xy 174.279316 -53.652374) (xy 174.256675 -53.602796) (xy 174.24132 -53.5505) (xy 174.233564 -53.496552)
			(xy 161.943766 -53.496552) (xy 161.947341 -53.502115) (xy 161.969983 -53.551692) (xy 161.985338 -53.603987)
			(xy 161.993094 -53.657935) (xy 161.99358 -53.685186) (xy 161.993111 -53.712556) (xy 161.985294 -53.766735)
			(xy 161.969806 -53.819239) (xy 161.946965 -53.868986) (xy 161.917241 -53.914952) (xy 161.8996 -53.935884)
			(xy 161.899346 -53.936138) (xy 161.893773 -53.943233) (xy 161.887519 -53.960144) (xy 161.887154 -53.969158)
			(xy 161.887154 -54.036214) (xy 161.887493 -54.045233) (xy 161.893752 -54.06215) (xy 161.899346 -54.069234)
			(xy 161.8996 -54.069234) (xy 161.8996 -54.069488) (xy 161.917247 -54.090414) (xy 161.946958 -54.136388)
			(xy 161.969792 -54.186137) (xy 161.985281 -54.238639) (xy 161.993107 -54.292816) (xy 161.99358 -54.320186)
			(xy 161.993094 -54.347437) (xy 161.985338 -54.401385) (xy 161.969983 -54.45368) (xy 161.947341 -54.503257)
			(xy 161.917875 -54.549107) (xy 161.882184 -54.590298) (xy 161.840993 -54.625989) (xy 161.795143 -54.655455)
			(xy 161.745566 -54.678097) (xy 161.693271 -54.693452) (xy 161.639323 -54.701208) (xy 161.584821 -54.701208)
			(xy 161.530873 -54.693452) (xy 161.478578 -54.678097) (xy 161.429001 -54.655455) (xy 161.383151 -54.625989)
			(xy 161.34196 -54.590298) (xy 161.306269 -54.549107) (xy 161.276803 -54.503257) (xy 161.254161 -54.45368)
			(xy 161.238806 -54.401385) (xy 161.23105 -54.347437) (xy 161.230564 -54.320186) (xy 159.001998 -54.320186)
			(xy 158.992945 -54.339899) (xy 158.963221 -54.385867) (xy 158.94558 -54.4068) (xy 158.945326 -54.407054)
			(xy 158.939744 -54.414143) (xy 158.933496 -54.431058) (xy 158.933134 -54.440074) (xy 158.933134 -54.50713)
			(xy 158.933469 -54.516149) (xy 158.939731 -54.533066) (xy 158.945326 -54.54015) (xy 158.94558 -54.54015)
			(xy 158.94558 -54.540404) (xy 158.963231 -54.561326) (xy 158.992942 -54.607301) (xy 159.015776 -54.657051)
			(xy 159.031264 -54.709554) (xy 159.039088 -54.763732) (xy 159.039205 -54.770528) (xy 162.171126 -54.770528)
			(xy 162.171602 -54.743158) (xy 162.179417 -54.688979) (xy 162.194903 -54.636476) (xy 162.217743 -54.586729)
			(xy 162.247465 -54.540762) (xy 162.265106 -54.51983) (xy 162.26536 -54.519576) (xy 162.27097 -54.512506)
			(xy 162.277201 -54.495576) (xy 162.277552 -54.486556) (xy 162.277552 -54.4195) (xy 162.277205 -54.410482)
			(xy 162.270952 -54.393565) (xy 162.26536 -54.38648) (xy 162.265106 -54.38648) (xy 162.265106 -54.386226)
			(xy 162.247467 -54.365294) (xy 162.217755 -54.319321) (xy 162.194919 -54.269574) (xy 162.179428 -54.217073)
			(xy 162.1716 -54.162897) (xy 162.171126 -54.135528) (xy 162.171612 -54.108277) (xy 162.179368 -54.054329)
			(xy 162.194723 -54.002034) (xy 162.217365 -53.952457) (xy 162.246831 -53.906607) (xy 162.282522 -53.865416)
			(xy 162.323713 -53.829725) (xy 162.369563 -53.800259) (xy 162.41914 -53.777617) (xy 162.471435 -53.762262)
			(xy 162.525383 -53.754506) (xy 162.579885 -53.754506) (xy 162.633833 -53.762262) (xy 162.686128 -53.777617)
			(xy 162.735705 -53.800259) (xy 162.781555 -53.829725) (xy 162.822746 -53.865416) (xy 162.858437 -53.906607)
			(xy 162.887903 -53.952457) (xy 162.892978 -53.96357) (xy 166.872156 -53.96357) (xy 166.876227 -53.907948)
			(xy 166.888353 -53.853511) (xy 166.908276 -53.80142) (xy 166.935572 -53.752785) (xy 166.969658 -53.708642)
			(xy 167.009807 -53.669933) (xy 167.055165 -53.637482) (xy 167.104765 -53.611981) (xy 167.157549 -53.593974)
			(xy 167.212392 -53.583844) (xy 167.268126 -53.581807) (xy 167.323563 -53.587907) (xy 167.37752 -53.602013)
			(xy 167.428849 -53.623825) (xy 167.476455 -53.652879) (xy 167.519323 -53.688554) (xy 167.55654 -53.730091)
			(xy 167.587313 -53.776604) (xy 167.610985 -53.827101) (xy 167.627053 -53.880508) (xy 167.635173 -53.935684)
			(xy 167.635682 -53.96357) (xy 167.635173 -53.991456) (xy 167.627053 -54.046632) (xy 167.610985 -54.100039)
			(xy 167.587313 -54.150536) (xy 167.55654 -54.197049) (xy 167.519323 -54.238586) (xy 167.476455 -54.274261)
			(xy 167.428849 -54.303315) (xy 167.37752 -54.325127) (xy 167.323563 -54.339233) (xy 167.268126 -54.345333)
			(xy 167.212392 -54.343296) (xy 167.157549 -54.333166) (xy 167.104765 -54.315159) (xy 167.055165 -54.289658)
			(xy 167.009807 -54.257207) (xy 166.969658 -54.218498) (xy 166.935572 -54.174355) (xy 166.908276 -54.12572)
			(xy 166.888353 -54.073629) (xy 166.876227 -54.019192) (xy 166.872156 -53.96357) (xy 162.892978 -53.96357)
			(xy 162.910545 -54.002034) (xy 162.9259 -54.054329) (xy 162.933656 -54.108277) (xy 162.934142 -54.135528)
			(xy 162.933706 -54.162899) (xy 162.925883 -54.21708) (xy 162.910388 -54.269584) (xy 162.887539 -54.319331)
			(xy 162.857807 -54.365296) (xy 162.840162 -54.386226) (xy 162.839908 -54.38648) (xy 162.834325 -54.393569)
			(xy 162.828076 -54.410484) (xy 162.827716 -54.4195) (xy 162.827716 -54.486556) (xy 162.828091 -54.495571)
			(xy 162.834326 -54.512488) (xy 162.839908 -54.519576) (xy 162.840162 -54.519576) (xy 162.840162 -54.51983)
			(xy 162.857776 -54.540783) (xy 162.887493 -54.586749) (xy 162.910334 -54.636491) (xy 162.925831 -54.688988)
			(xy 162.933665 -54.74316) (xy 162.934142 -54.770528) (xy 162.933656 -54.797779) (xy 162.9259 -54.851727)
			(xy 162.910545 -54.904022) (xy 162.887903 -54.953599) (xy 162.865119 -54.989051) (xy 172.001168 -54.989051)
			(xy 172.001168 -54.934549) (xy 172.008924 -54.880602) (xy 172.024278 -54.828307) (xy 172.046919 -54.77873)
			(xy 172.076384 -54.732879) (xy 172.112074 -54.691688) (xy 172.153263 -54.655996) (xy 172.199112 -54.626528)
			(xy 172.248688 -54.603885) (xy 172.300982 -54.588528) (xy 172.354929 -54.580769) (xy 172.38218 -54.580282)
			(xy 172.410271 -54.580793) (xy 172.465847 -54.589017) (xy 172.519616 -54.605305) (xy 172.570413 -54.629305)
			(xy 172.61714 -54.660498) (xy 172.658786 -54.698208) (xy 172.694449 -54.741619) (xy 172.709332 -54.765448)
			(xy 172.714666 -54.774338) (xy 172.731684 -54.78653) (xy 172.824902 -54.80685) (xy 172.845476 -54.802532)
			(xy 172.854112 -54.79669) (xy 172.87817 -54.780681) (xy 172.930104 -54.755341) (xy 172.985264 -54.738118)
			(xy 173.042389 -54.729405) (xy 173.071282 -54.728872) (xy 173.098532 -54.729395) (xy 173.152477 -54.737148)
			(xy 173.20477 -54.7525) (xy 173.254346 -54.775138) (xy 173.300195 -54.8046) (xy 173.341385 -54.840288)
			(xy 173.377077 -54.881474) (xy 173.406544 -54.927321) (xy 173.429186 -54.976894) (xy 173.444543 -55.029186)
			(xy 173.452302 -55.08313) (xy 173.45279 -55.11038) (xy 173.452315 -55.13775) (xy 173.444499 -55.191929)
			(xy 173.429013 -55.244432) (xy 173.406173 -55.294179) (xy 173.37645 -55.340146) (xy 173.35881 -55.361078)
			(xy 173.358556 -55.361332) (xy 173.352986 -55.36843) (xy 173.346731 -55.385338) (xy 173.346364 -55.394352)
			(xy 173.346364 -55.461408) (xy 173.346725 -55.470424) (xy 173.35297 -55.487341) (xy 173.358556 -55.494428)
			(xy 173.35881 -55.494428) (xy 173.35881 -55.494682) (xy 173.37643 -55.515631) (xy 173.406152 -55.561597)
			(xy 173.428997 -55.611341) (xy 173.444493 -55.66384) (xy 173.452323 -55.718016) (xy 173.452325 -55.772754)
			(xy 173.444499 -55.82693) (xy 173.429007 -55.879431) (xy 173.406167 -55.929176) (xy 173.376448 -55.975145)
			(xy 173.35881 -55.996078) (xy 173.358556 -55.996332) (xy 173.352986 -56.00343) (xy 173.346731 -56.020338)
			(xy 173.346364 -56.029352) (xy 173.346364 -56.096408) (xy 173.346725 -56.105424) (xy 173.35297 -56.122341)
			(xy 173.358556 -56.129428) (xy 173.35881 -56.129428) (xy 173.35881 -56.129682) (xy 173.376456 -56.150609)
			(xy 173.406166 -56.196583) (xy 173.429001 -56.246332) (xy 173.44449 -56.298834) (xy 173.452317 -56.35301)
			(xy 173.45279 -56.38038) (xy 173.452304 -56.407631) (xy 173.444548 -56.461579) (xy 173.429193 -56.513874)
			(xy 173.406551 -56.563451) (xy 173.377085 -56.609301) (xy 173.341394 -56.650492) (xy 173.300203 -56.686183)
			(xy 173.254353 -56.715649) (xy 173.204776 -56.738291) (xy 173.152481 -56.753646) (xy 173.098533 -56.761402)
			(xy 173.044031 -56.761402) (xy 172.990083 -56.753646) (xy 172.937788 -56.738291) (xy 172.888211 -56.715649)
			(xy 172.842361 -56.686183) (xy 172.80117 -56.650492) (xy 172.765479 -56.609301) (xy 172.736013 -56.563451)
			(xy 172.713371 -56.513874) (xy 172.698016 -56.461579) (xy 172.69026 -56.407631) (xy 172.689774 -56.38038)
			(xy 172.69021 -56.353008) (xy 172.698033 -56.298827) (xy 172.713528 -56.246323) (xy 172.736376 -56.196577)
			(xy 172.766109 -56.150612) (xy 172.783754 -56.129682) (xy 172.784008 -56.129428) (xy 172.78959 -56.122338)
			(xy 172.795839 -56.105424) (xy 172.7962 -56.096408) (xy 172.7962 -56.029352) (xy 172.795818 -56.020338)
			(xy 172.789588 -56.003421) (xy 172.784008 -55.996332) (xy 172.783754 -55.996332) (xy 172.783754 -55.996078)
			(xy 172.766093 -55.975162) (xy 172.736367 -55.929192) (xy 172.713521 -55.879443) (xy 172.698025 -55.826938)
			(xy 172.690197 -55.772757) (xy 172.6902 -55.718013) (xy 172.698031 -55.663832) (xy 172.713531 -55.611329)
			(xy 172.736381 -55.561582) (xy 172.766111 -55.515614) (xy 172.783754 -55.494682) (xy 172.784008 -55.494428)
			(xy 172.78959 -55.487338) (xy 172.795839 -55.470424) (xy 172.7962 -55.461408) (xy 172.7962 -55.394352)
			(xy 172.795818 -55.385338) (xy 172.789588 -55.368421) (xy 172.784008 -55.361332) (xy 172.783754 -55.360824)
			(xy 172.772808 -55.348091) (xy 172.752968 -55.320999) (xy 172.74413 -55.306722) (xy 172.738796 -55.297832)
			(xy 172.721778 -55.28564) (xy 172.62856 -55.26532) (xy 172.607986 -55.269638) (xy 172.59935 -55.27548)
			(xy 172.575273 -55.291459) (xy 172.523346 -55.316807) (xy 172.468192 -55.334038) (xy 172.411071 -55.34276)
			(xy 172.38218 -55.343298) (xy 172.354929 -55.342831) (xy 172.300982 -55.335072) (xy 172.248688 -55.319715)
			(xy 172.199112 -55.297072) (xy 172.153263 -55.267604) (xy 172.112074 -55.231912) (xy 172.076384 -55.190721)
			(xy 172.046919 -55.14487) (xy 172.024278 -55.095293) (xy 172.008924 -55.042998) (xy 172.001168 -54.989051)
			(xy 162.865119 -54.989051) (xy 162.858437 -54.999449) (xy 162.822746 -55.04064) (xy 162.781555 -55.076331)
			(xy 162.735705 -55.105797) (xy 162.686128 -55.128439) (xy 162.633833 -55.143794) (xy 162.579885 -55.15155)
			(xy 162.525383 -55.15155) (xy 162.471435 -55.143794) (xy 162.41914 -55.128439) (xy 162.369563 -55.105797)
			(xy 162.323713 -55.076331) (xy 162.282522 -55.04064) (xy 162.246831 -54.999449) (xy 162.217365 -54.953599)
			(xy 162.194723 -54.904022) (xy 162.179368 -54.851727) (xy 162.171612 -54.797779) (xy 162.171126 -54.770528)
			(xy 159.039205 -54.770528) (xy 159.03956 -54.791102) (xy 159.039074 -54.818353) (xy 159.031318 -54.872301)
			(xy 159.015963 -54.924596) (xy 158.993321 -54.974173) (xy 158.963855 -55.020023) (xy 158.928164 -55.061214)
			(xy 158.886973 -55.096905) (xy 158.841123 -55.126371) (xy 158.791546 -55.149013) (xy 158.739251 -55.164368)
			(xy 158.685303 -55.172124) (xy 158.630801 -55.172124) (xy 158.576853 -55.164368) (xy 158.524558 -55.149013)
			(xy 158.474981 -55.126371) (xy 158.429131 -55.096905) (xy 158.38794 -55.061214) (xy 158.352249 -55.020023)
			(xy 158.322783 -54.974173) (xy 158.300141 -54.924596) (xy 158.284786 -54.872301) (xy 158.27703 -54.818353)
			(xy 158.276544 -54.791102) (xy 156.378945 -54.791102) (xy 156.372199 -54.827286) (xy 156.354908 -54.878504)
			(xy 156.330578 -54.926777) (xy 156.299693 -54.971144) (xy 156.281628 -54.991254) (xy 156.281374 -54.991508)
			(xy 156.269944 -55.003954) (xy 156.266134 -55.00751) (xy 156.228034 -55.041038) (xy 156.223462 -55.049928)
			(xy 156.209492 -55.077868) (xy 156.21 -55.090822) (xy 156.227272 -55.59044) (xy 156.231855 -55.722266)
			(xy 167.93413 -55.722266) (xy 167.938201 -55.666644) (xy 167.950327 -55.612207) (xy 167.97025 -55.560116)
			(xy 167.997546 -55.511481) (xy 168.031632 -55.467338) (xy 168.071781 -55.428629) (xy 168.117139 -55.396178)
			(xy 168.166739 -55.370677) (xy 168.219523 -55.35267) (xy 168.274366 -55.34254) (xy 168.3301 -55.340503)
			(xy 168.385537 -55.346603) (xy 168.439494 -55.360709) (xy 168.490823 -55.382521) (xy 168.538429 -55.411575)
			(xy 168.549575 -55.420851) (xy 170.324768 -55.420851) (xy 170.324768 -55.366349) (xy 170.332524 -55.312402)
			(xy 170.347878 -55.260107) (xy 170.370519 -55.21053) (xy 170.399984 -55.164679) (xy 170.435674 -55.123488)
			(xy 170.476863 -55.087796) (xy 170.522712 -55.058328) (xy 170.572288 -55.035685) (xy 170.624582 -55.020328)
			(xy 170.678529 -55.012569) (xy 170.70578 -55.012082) (xy 170.732093 -55.012569) (xy 170.784221 -55.0198)
			(xy 170.834863 -55.034116) (xy 170.883062 -55.055245) (xy 170.927906 -55.082787) (xy 170.968547 -55.116222)
			(xy 170.986704 -55.135272) (xy 170.994226 -55.142673) (xy 171.013506 -55.151199) (xy 171.024042 -55.151782)
			(xy 171.098718 -55.151782) (xy 171.109265 -55.151227) (xy 171.128561 -55.142711) (xy 171.136056 -55.135272)
			(xy 171.154186 -55.116191) (xy 171.194822 -55.082737) (xy 171.239668 -55.055182) (xy 171.287873 -55.034048)
			(xy 171.338525 -55.019736) (xy 171.390662 -55.012517) (xy 171.41698 -55.012082) (xy 171.444233 -55.012564)
			(xy 171.498185 -55.020318) (xy 171.550484 -55.035672) (xy 171.600065 -55.058313) (xy 171.645919 -55.08778)
			(xy 171.687113 -55.123472) (xy 171.722808 -55.164665) (xy 171.752277 -55.210517) (xy 171.774921 -55.260098)
			(xy 171.790277 -55.312396) (xy 171.798035 -55.366347) (xy 171.798035 -55.420853) (xy 171.790277 -55.474804)
			(xy 171.774921 -55.527102) (xy 171.752277 -55.576683) (xy 171.722808 -55.622535) (xy 171.687113 -55.663728)
			(xy 171.645919 -55.69942) (xy 171.600065 -55.728887) (xy 171.550484 -55.751528) (xy 171.498185 -55.766882)
			(xy 171.444233 -55.774636) (xy 171.41698 -55.775098) (xy 171.390666 -55.774645) (xy 171.338536 -55.767407)
			(xy 171.287893 -55.753085) (xy 171.239694 -55.73195) (xy 171.194851 -55.704402) (xy 171.154212 -55.670961)
			(xy 171.136056 -55.651908) (xy 171.128552 -55.644486) (xy 171.109259 -55.635973) (xy 171.098718 -55.635398)
			(xy 171.024042 -55.635398) (xy 171.013493 -55.635937) (xy 170.994198 -55.644465) (xy 170.986704 -55.651908)
			(xy 170.968541 -55.670956) (xy 170.927913 -55.704414) (xy 170.883074 -55.731973) (xy 170.834875 -55.753113)
			(xy 170.784229 -55.767432) (xy 170.732096 -55.774658) (xy 170.70578 -55.775098) (xy 170.678529 -55.774631)
			(xy 170.624582 -55.766872) (xy 170.572288 -55.751515) (xy 170.522712 -55.728872) (xy 170.476863 -55.699404)
			(xy 170.435674 -55.663712) (xy 170.399984 -55.622521) (xy 170.370519 -55.57667) (xy 170.347878 -55.527093)
			(xy 170.332524 -55.474798) (xy 170.324768 -55.420851) (xy 168.549575 -55.420851) (xy 168.581297 -55.44725)
			(xy 168.618514 -55.488787) (xy 168.649287 -55.5353) (xy 168.672959 -55.585797) (xy 168.689027 -55.639204)
			(xy 168.697147 -55.69438) (xy 168.697656 -55.722266) (xy 168.697147 -55.750152) (xy 168.689027 -55.805328)
			(xy 168.672959 -55.858735) (xy 168.649287 -55.909232) (xy 168.618514 -55.955745) (xy 168.581297 -55.997282)
			(xy 168.538429 -56.032957) (xy 168.490823 -56.062011) (xy 168.439494 -56.083823) (xy 168.385537 -56.097929)
			(xy 168.3301 -56.104029) (xy 168.274366 -56.101992) (xy 168.219523 -56.091862) (xy 168.166739 -56.073855)
			(xy 168.117139 -56.048354) (xy 168.071781 -56.015903) (xy 168.031632 -55.977194) (xy 167.997546 -55.933051)
			(xy 167.97025 -55.884416) (xy 167.950327 -55.832325) (xy 167.938201 -55.777888) (xy 167.93413 -55.722266)
			(xy 156.231855 -55.722266) (xy 156.235908 -55.838852) (xy 156.24175 -56.007254) (xy 156.242258 -56.019192)
			(xy 156.242766 -56.035448) (xy 156.255466 -56.397652) (xy 156.25826 -56.47436) (xy 156.260038 -56.527192)
			(xy 156.26207 -56.536082) (xy 156.264864 -56.544464) (xy 156.26666 -56.548414) (xy 156.27139 -56.555689)
			(xy 156.274262 -56.558942) (xy 156.275532 -56.560212) (xy 156.295709 -56.58171) (xy 156.329863 -56.629766)
			(xy 156.356216 -56.682505) (xy 156.374141 -56.738671) (xy 156.383211 -56.796926) (xy 156.383736 -56.826404)
			(xy 156.383736 -56.82742) (xy 156.383282 -56.853475) (xy 156.376126 -56.905093) (xy 156.362003 -56.955255)
			(xy 156.341217 -57.002934) (xy 163.66363 -57.002934) (xy 163.664128 -56.974842) (xy 163.672352 -56.919264)
			(xy 163.688641 -56.865494) (xy 163.712642 -56.814696) (xy 163.743837 -56.767969) (xy 163.78155 -56.726324)
			(xy 163.824965 -56.690663) (xy 163.848796 -56.675782) (xy 163.857686 -56.670448) (xy 163.869878 -56.65343)
			(xy 163.890198 -56.560212) (xy 163.88588 -56.539638) (xy 163.880038 -56.531002) (xy 163.864041 -56.506936)
			(xy 163.838697 -56.455006) (xy 163.82147 -56.399848) (xy 163.812754 -56.342724) (xy 163.81222 -56.313832)
			(xy 163.812685 -56.286579) (xy 163.820439 -56.232626) (xy 163.835792 -56.180327) (xy 163.858433 -56.130745)
			(xy 163.8879 -56.08489) (xy 163.923594 -56.043697) (xy 163.964787 -56.008002) (xy 164.010641 -55.978535)
			(xy 164.060223 -55.955893) (xy 164.112522 -55.940539) (xy 164.166475 -55.932785) (xy 164.193728 -55.932324)
			(xy 164.221099 -55.932768) (xy 164.275279 -55.94059) (xy 164.327783 -55.956084) (xy 164.377529 -55.978931)
			(xy 164.423495 -56.00866) (xy 164.444426 -56.026304) (xy 164.44468 -56.026558) (xy 164.451763 -56.032149)
			(xy 164.468683 -56.038392) (xy 164.4777 -56.03875) (xy 164.544756 -56.03875) (xy 164.553772 -56.038383)
			(xy 164.57069 -56.032144) (xy 164.577776 -56.026558) (xy 164.577776 -56.026304) (xy 164.57803 -56.026304)
			(xy 164.598963 -56.008663) (xy 164.644931 -55.978939) (xy 164.694677 -55.956093) (xy 164.747179 -55.940597)
			(xy 164.801357 -55.932768) (xy 164.856099 -55.932768) (xy 164.910277 -55.940597) (xy 164.962779 -55.956093)
			(xy 165.012525 -55.978939) (xy 165.058493 -56.008663) (xy 165.079426 -56.026304) (xy 165.07968 -56.026558)
			(xy 165.086763 -56.032149) (xy 165.103683 -56.038392) (xy 165.1127 -56.03875) (xy 165.179756 -56.03875)
			(xy 165.188772 -56.038383) (xy 165.20569 -56.032144) (xy 165.212776 -56.026558) (xy 165.212776 -56.026304)
			(xy 165.21303 -56.026304) (xy 165.233978 -56.008685) (xy 165.279946 -55.97897) (xy 165.32969 -55.95613)
			(xy 165.382187 -55.940634) (xy 165.43636 -55.932801) (xy 165.463728 -55.932324) (xy 165.49098 -55.932748)
			(xy 165.544929 -55.940508) (xy 165.597225 -55.955867) (xy 165.646803 -55.978512) (xy 165.692654 -56.007981)
			(xy 165.733844 -56.043676) (xy 165.769536 -56.084869) (xy 165.799002 -56.130722) (xy 165.821643 -56.180301)
			(xy 165.836998 -56.232598) (xy 165.844754 -56.286548) (xy 165.844754 -56.297068) (xy 166.18661 -56.297068)
			(xy 166.190681 -56.241446) (xy 166.202807 -56.187009) (xy 166.22273 -56.134918) (xy 166.250026 -56.086283)
			(xy 166.284112 -56.04214) (xy 166.324261 -56.003431) (xy 166.369619 -55.97098) (xy 166.419219 -55.945479)
			(xy 166.472003 -55.927472) (xy 166.526846 -55.917342) (xy 166.58258 -55.915305) (xy 166.638017 -55.921405)
			(xy 166.691974 -55.935511) (xy 166.743303 -55.957323) (xy 166.790909 -55.986377) (xy 166.833777 -56.022052)
			(xy 166.870994 -56.063589) (xy 166.901767 -56.110102) (xy 166.925439 -56.160599) (xy 166.941507 -56.214006)
			(xy 166.949627 -56.269182) (xy 166.950136 -56.297068) (xy 166.949627 -56.324954) (xy 166.941507 -56.38013)
			(xy 166.925439 -56.433537) (xy 166.901767 -56.484034) (xy 166.870994 -56.530547) (xy 166.833777 -56.572084)
			(xy 166.790909 -56.607759) (xy 166.743303 -56.636813) (xy 166.691974 -56.658625) (xy 166.638017 -56.672731)
			(xy 166.58258 -56.678831) (xy 166.526846 -56.676794) (xy 166.472003 -56.666664) (xy 166.419219 -56.648657)
			(xy 166.369619 -56.623156) (xy 166.324261 -56.590705) (xy 166.284112 -56.551996) (xy 166.250026 -56.507853)
			(xy 166.22273 -56.459218) (xy 166.202807 -56.407127) (xy 166.190681 -56.35269) (xy 166.18661 -56.297068)
			(xy 165.844754 -56.297068) (xy 165.844754 -56.341052) (xy 165.836998 -56.395002) (xy 165.821643 -56.447299)
			(xy 165.799002 -56.496878) (xy 165.769536 -56.542731) (xy 165.733844 -56.583924) (xy 165.692654 -56.619619)
			(xy 165.646803 -56.649088) (xy 165.597225 -56.671733) (xy 165.544929 -56.687092) (xy 165.49098 -56.694852)
			(xy 165.463728 -56.69534) (xy 165.436358 -56.694872) (xy 165.382178 -56.687057) (xy 165.329674 -56.671569)
			(xy 165.279927 -56.648727) (xy 165.233961 -56.619002) (xy 165.21303 -56.60136) (xy 165.212776 -56.601106)
			(xy 165.2057 -56.595504) (xy 165.188775 -56.589266) (xy 165.179756 -56.588914) (xy 165.1127 -56.588914)
			(xy 165.103683 -56.589268) (xy 165.086766 -56.595517) (xy 165.07968 -56.601106) (xy 165.07968 -56.60136)
			(xy 165.079426 -56.60136) (xy 165.058493 -56.619001) (xy 165.012525 -56.648725) (xy 164.962779 -56.671571)
			(xy 164.910277 -56.687067) (xy 164.856099 -56.694896) (xy 164.801357 -56.694896) (xy 164.747179 -56.687067)
			(xy 164.694677 -56.671571) (xy 164.644931 -56.648725) (xy 164.598963 -56.619001) (xy 164.57803 -56.60136)
			(xy 164.577776 -56.601106) (xy 164.5707 -56.595504) (xy 164.553775 -56.589266) (xy 164.544756 -56.588914)
			(xy 164.4777 -56.588914) (xy 164.468683 -56.589268) (xy 164.451766 -56.595517) (xy 164.44468 -56.601106)
			(xy 164.444172 -56.60136) (xy 164.431437 -56.612303) (xy 164.404346 -56.632145) (xy 164.39007 -56.640984)
			(xy 164.38118 -56.646318) (xy 164.368988 -56.663336) (xy 164.348668 -56.756554) (xy 164.352986 -56.777128)
			(xy 164.358828 -56.785764) (xy 164.374818 -56.809834) (xy 164.400162 -56.861764) (xy 164.417391 -56.91692)
			(xy 164.426109 -56.974042) (xy 164.426646 -57.002934) (xy 164.42616 -57.030185) (xy 164.418404 -57.084133)
			(xy 164.403049 -57.136428) (xy 164.380407 -57.186005) (xy 164.350941 -57.231855) (xy 164.31525 -57.273046)
			(xy 164.274059 -57.308737) (xy 164.228209 -57.338203) (xy 164.178632 -57.360845) (xy 164.126337 -57.3762)
			(xy 164.072389 -57.383956) (xy 164.017887 -57.383956) (xy 163.963939 -57.3762) (xy 163.911644 -57.360845)
			(xy 163.862067 -57.338203) (xy 163.816217 -57.308737) (xy 163.775026 -57.273046) (xy 163.739335 -57.231855)
			(xy 163.709869 -57.186005) (xy 163.687227 -57.136428) (xy 163.671872 -57.084133) (xy 163.664116 -57.030185)
			(xy 163.66363 -57.002934) (xy 156.341217 -57.002934) (xy 156.341178 -57.003024) (xy 156.31404 -57.047511)
			(xy 156.297884 -57.067958) (xy 156.29255 -57.074562) (xy 156.280104 -57.107582) (xy 156.280612 -57.117996)
			(xy 156.283152 -57.185052) (xy 156.283369 -57.188811) (xy 156.28477 -57.196208) (xy 156.285946 -57.199784)
			(xy 156.289502 -57.209944) (xy 156.295344 -57.217056) (xy 156.295598 -57.21731) (xy 156.30017 -57.222898)
			(xy 156.390594 -57.33288) (xy 156.396215 -57.340388) (xy 156.402106 -57.358176) (xy 156.4012 -57.376892)
			(xy 156.393617 -57.394028) (xy 156.387292 -57.400952) (xy 156.380688 -57.407556) (xy 156.381704 -57.421526)
			(xy 156.381704 -57.42305) (xy 156.382655 -57.432801) (xy 156.383673 -57.452369) (xy 156.383736 -57.462166)
			(xy 156.383736 -57.470548) (xy 156.383126 -57.48528) (xy 172.706028 -57.48528) (xy 172.710099 -57.429658)
			(xy 172.722225 -57.375221) (xy 172.742148 -57.32313) (xy 172.769444 -57.274495) (xy 172.80353 -57.230352)
			(xy 172.843679 -57.191643) (xy 172.889037 -57.159192) (xy 172.938637 -57.133691) (xy 172.991421 -57.115684)
			(xy 173.046264 -57.105554) (xy 173.101998 -57.103517) (xy 173.157435 -57.109617) (xy 173.211392 -57.123723)
			(xy 173.262721 -57.145535) (xy 173.310327 -57.174589) (xy 173.353195 -57.210264) (xy 173.390412 -57.251801)
			(xy 173.421185 -57.298314) (xy 173.444857 -57.348811) (xy 173.460925 -57.402218) (xy 173.469045 -57.457394)
			(xy 173.469554 -57.48528) (xy 173.469045 -57.513166) (xy 173.460925 -57.568342) (xy 173.444857 -57.621749)
			(xy 173.421185 -57.672246) (xy 173.390412 -57.718759) (xy 173.353195 -57.760296) (xy 173.310327 -57.795971)
			(xy 173.262721 -57.825025) (xy 173.211392 -57.846837) (xy 173.157435 -57.860943) (xy 173.101998 -57.867043)
			(xy 173.046264 -57.865006) (xy 172.991421 -57.854876) (xy 172.938637 -57.836869) (xy 172.889037 -57.811368)
			(xy 172.843679 -57.778917) (xy 172.80353 -57.740208) (xy 172.769444 -57.696065) (xy 172.742148 -57.64743)
			(xy 172.722225 -57.595339) (xy 172.710099 -57.540902) (xy 172.706028 -57.48528) (xy 156.383126 -57.48528)
			(xy 156.382579 -57.49847) (xy 156.373109 -57.553546) (xy 156.35571 -57.606653) (xy 156.330754 -57.656656)
			(xy 156.315156 -57.679844) (xy 156.313632 -57.681876) (xy 156.311092 -57.686194) (xy 156.306266 -57.692798)
			(xy 156.303726 -57.701434) (xy 156.301186 -57.709816) (xy 156.302456 -57.742582) (xy 156.302456 -57.74309)
			(xy 156.30525 -57.820814) (xy 156.306266 -57.850278) (xy 156.30646 -57.853899) (xy 156.307739 -57.861036)
			(xy 156.308806 -57.864502) (xy 156.3116 -57.87263) (xy 156.315664 -57.878472) (xy 156.319982 -57.884822)
			(xy 156.320236 -57.88533) (xy 156.326586 -57.894982) (xy 156.339933 -57.917389) (xy 156.361091 -57.96506)
			(xy 156.375566 -58.015166) (xy 156.383089 -58.066775) (xy 156.383736 -58.092848) (xy 156.383736 -58.096658)
			(xy 156.383329 -58.121562) (xy 156.376844 -58.170946) (xy 156.363991 -58.219066) (xy 156.344988 -58.265107)
			(xy 156.332936 -58.286904) (xy 156.329634 -58.292492) (xy 156.322522 -58.317892) (xy 156.322776 -58.32602)
			(xy 156.326078 -58.420508) (xy 156.329634 -58.52287) (xy 156.33192 -58.535824) (xy 156.333444 -58.541158)
			(xy 156.335984 -58.546238) (xy 156.336492 -58.547) (xy 156.336746 -58.547508) (xy 156.337254 -58.54827)
			(xy 156.351403 -58.575564) (xy 156.371767 -58.633566) (xy 156.379962 -58.679334) (xy 164.09543 -58.679334)
			(xy 164.095844 -58.653018) (xy 164.103088 -58.600887) (xy 164.117417 -58.550243) (xy 164.13856 -58.502044)
			(xy 164.166116 -58.457202) (xy 164.199564 -58.416565) (xy 164.21862 -58.39841) (xy 164.226022 -58.390889)
			(xy 164.234546 -58.371608) (xy 164.23513 -58.361072) (xy 164.23513 -58.286396) (xy 164.234608 -58.275846)
			(xy 164.226067 -58.256551) (xy 164.21862 -58.249058) (xy 164.199555 -58.230912) (xy 164.166098 -58.190281)
			(xy 164.13854 -58.145439) (xy 164.117403 -58.097236) (xy 164.103088 -58.046586) (xy 164.095866 -57.994451)
			(xy 164.09543 -57.968134) (xy 164.095916 -57.940883) (xy 164.103672 -57.886935) (xy 164.119027 -57.83464)
			(xy 164.141669 -57.785063) (xy 164.171135 -57.739213) (xy 164.206826 -57.698022) (xy 164.248017 -57.662331)
			(xy 164.293867 -57.632865) (xy 164.343444 -57.610223) (xy 164.395739 -57.594868) (xy 164.449687 -57.587112)
			(xy 164.504189 -57.587112) (xy 164.558137 -57.594868) (xy 164.610432 -57.610223) (xy 164.660009 -57.632865)
			(xy 164.705859 -57.662331) (xy 164.74705 -57.698022) (xy 164.782741 -57.739213) (xy 164.812207 -57.785063)
			(xy 164.834849 -57.83464) (xy 164.850204 -57.886935) (xy 164.85796 -57.940883) (xy 164.858446 -57.968134)
			(xy 164.858018 -57.99445) (xy 164.850778 -58.04658) (xy 164.84351 -58.072274) (xy 168.093642 -58.072274)
			(xy 168.097713 -58.016652) (xy 168.109839 -57.962215) (xy 168.129762 -57.910124) (xy 168.157058 -57.861489)
			(xy 168.191144 -57.817346) (xy 168.231293 -57.778637) (xy 168.276651 -57.746186) (xy 168.326251 -57.720685)
			(xy 168.379035 -57.702678) (xy 168.433878 -57.692548) (xy 168.489612 -57.690511) (xy 168.545049 -57.696611)
			(xy 168.599006 -57.710717) (xy 168.650335 -57.732529) (xy 168.697941 -57.761583) (xy 168.740809 -57.797258)
			(xy 168.778026 -57.838795) (xy 168.808799 -57.885308) (xy 168.832471 -57.935805) (xy 168.848539 -57.989212)
			(xy 168.856659 -58.044388) (xy 168.857168 -58.072274) (xy 168.857098 -58.076084) (xy 173.458122 -58.076084)
			(xy 173.462193 -58.020462) (xy 173.474319 -57.966025) (xy 173.494242 -57.913934) (xy 173.521538 -57.865299)
			(xy 173.555624 -57.821156) (xy 173.595773 -57.782447) (xy 173.641131 -57.749996) (xy 173.690731 -57.724495)
			(xy 173.743515 -57.706488) (xy 173.798358 -57.696358) (xy 173.854092 -57.694321) (xy 173.909529 -57.700421)
			(xy 173.963486 -57.714527) (xy 174.014815 -57.736339) (xy 174.062421 -57.765393) (xy 174.105289 -57.801068)
			(xy 174.142506 -57.842605) (xy 174.158842 -57.867296) (xy 175.743106 -57.867296) (xy 175.747177 -57.811674)
			(xy 175.759303 -57.757237) (xy 175.779226 -57.705146) (xy 175.806522 -57.656511) (xy 175.840608 -57.612368)
			(xy 175.880757 -57.573659) (xy 175.926115 -57.541208) (xy 175.975715 -57.515707) (xy 176.028499 -57.4977)
			(xy 176.083342 -57.48757) (xy 176.139076 -57.485533) (xy 176.194513 -57.491633) (xy 176.24847 -57.505739)
			(xy 176.299799 -57.527551) (xy 176.347405 -57.556605) (xy 176.390273 -57.59228) (xy 176.42749 -57.633817)
			(xy 176.458263 -57.68033) (xy 176.481935 -57.730827) (xy 176.498003 -57.784234) (xy 176.506123 -57.83941)
			(xy 176.506632 -57.867296) (xy 176.506123 -57.895182) (xy 176.498003 -57.950358) (xy 176.481935 -58.003765)
			(xy 176.458263 -58.054262) (xy 176.42749 -58.100775) (xy 176.390273 -58.142312) (xy 176.347405 -58.177987)
			(xy 176.299799 -58.207041) (xy 176.24847 -58.228853) (xy 176.194513 -58.242959) (xy 176.139076 -58.249059)
			(xy 176.083342 -58.247022) (xy 176.028499 -58.236892) (xy 175.975715 -58.218885) (xy 175.926115 -58.193384)
			(xy 175.880757 -58.160933) (xy 175.840608 -58.122224) (xy 175.806522 -58.078081) (xy 175.779226 -58.029446)
			(xy 175.759303 -57.977355) (xy 175.747177 -57.922918) (xy 175.743106 -57.867296) (xy 174.158842 -57.867296)
			(xy 174.173279 -57.889118) (xy 174.196951 -57.939615) (xy 174.213019 -57.993022) (xy 174.221139 -58.048198)
			(xy 174.221648 -58.076084) (xy 174.221139 -58.10397) (xy 174.213019 -58.159146) (xy 174.196951 -58.212553)
			(xy 174.173279 -58.26305) (xy 174.142506 -58.309563) (xy 174.105289 -58.3511) (xy 174.062421 -58.386775)
			(xy 174.014815 -58.415829) (xy 173.963486 -58.437641) (xy 173.909529 -58.451747) (xy 173.854092 -58.457847)
			(xy 173.798358 -58.45581) (xy 173.743515 -58.44568) (xy 173.690731 -58.427673) (xy 173.641131 -58.402172)
			(xy 173.595773 -58.369721) (xy 173.555624 -58.331012) (xy 173.521538 -58.286869) (xy 173.494242 -58.238234)
			(xy 173.474319 -58.186143) (xy 173.462193 -58.131706) (xy 173.458122 -58.076084) (xy 168.857098 -58.076084)
			(xy 168.856659 -58.10016) (xy 168.848539 -58.155336) (xy 168.832471 -58.208743) (xy 168.808799 -58.25924)
			(xy 168.778026 -58.305753) (xy 168.740809 -58.34729) (xy 168.697941 -58.382965) (xy 168.650335 -58.412019)
			(xy 168.599006 -58.433831) (xy 168.545049 -58.447937) (xy 168.489612 -58.454037) (xy 168.433878 -58.452)
			(xy 168.379035 -58.44187) (xy 168.326251 -58.423863) (xy 168.276651 -58.398362) (xy 168.231293 -58.365911)
			(xy 168.191144 -58.327202) (xy 168.157058 -58.283059) (xy 168.129762 -58.234424) (xy 168.109839 -58.182333)
			(xy 168.097713 -58.127896) (xy 168.093642 -58.072274) (xy 164.84351 -58.072274) (xy 164.836452 -58.097225)
			(xy 164.815312 -58.145424) (xy 164.787758 -58.190266) (xy 164.754312 -58.230903) (xy 164.735256 -58.249058)
			(xy 164.727879 -58.256601) (xy 164.719339 -58.275864) (xy 164.718746 -58.286396) (xy 164.718746 -58.361072)
			(xy 164.719263 -58.371623) (xy 164.727805 -58.390919) (xy 164.735256 -58.39841) (xy 164.75432 -58.416557)
			(xy 164.787774 -58.45719) (xy 164.815331 -58.502032) (xy 164.836467 -58.550234) (xy 164.839573 -58.561224)
			(xy 174.662336 -58.561224) (xy 174.666407 -58.505602) (xy 174.678533 -58.451165) (xy 174.698456 -58.399074)
			(xy 174.725752 -58.350439) (xy 174.759838 -58.306296) (xy 174.799987 -58.267587) (xy 174.845345 -58.235136)
			(xy 174.894945 -58.209635) (xy 174.947729 -58.191628) (xy 175.002572 -58.181498) (xy 175.058306 -58.179461)
			(xy 175.113743 -58.185561) (xy 175.1677 -58.199667) (xy 175.219029 -58.221479) (xy 175.266635 -58.250533)
			(xy 175.309503 -58.286208) (xy 175.34672 -58.327745) (xy 175.377493 -58.374258) (xy 175.401165 -58.424755)
			(xy 175.417233 -58.478162) (xy 175.425353 -58.533338) (xy 175.425862 -58.561224) (xy 175.425353 -58.58911)
			(xy 175.417233 -58.644286) (xy 175.401165 -58.697693) (xy 175.377493 -58.74819) (xy 175.34672 -58.794703)
			(xy 175.309503 -58.83624) (xy 175.266635 -58.871915) (xy 175.219029 -58.900969) (xy 175.1677 -58.922781)
			(xy 175.113743 -58.936887) (xy 175.058306 -58.942987) (xy 175.002572 -58.94095) (xy 174.947729 -58.93082)
			(xy 174.894945 -58.912813) (xy 174.845345 -58.887312) (xy 174.799987 -58.854861) (xy 174.759838 -58.816152)
			(xy 174.725752 -58.772009) (xy 174.698456 -58.723374) (xy 174.678533 -58.671283) (xy 174.666407 -58.616846)
			(xy 174.662336 -58.561224) (xy 164.839573 -58.561224) (xy 164.850783 -58.600883) (xy 164.858008 -58.653018)
			(xy 164.858446 -58.679334) (xy 164.85796 -58.706585) (xy 164.850204 -58.760533) (xy 164.834849 -58.812828)
			(xy 164.812207 -58.862405) (xy 164.782741 -58.908255) (xy 164.74705 -58.949446) (xy 164.705859 -58.985137)
			(xy 164.660009 -59.014603) (xy 164.610432 -59.037245) (xy 164.558137 -59.0526) (xy 164.504189 -59.060356)
			(xy 164.449687 -59.060356) (xy 164.395739 -59.0526) (xy 164.343444 -59.037245) (xy 164.293867 -59.014603)
			(xy 164.248017 -58.985137) (xy 164.206826 -58.949446) (xy 164.171135 -58.908255) (xy 164.141669 -58.862405)
			(xy 164.119027 -58.812828) (xy 164.103672 -58.760533) (xy 164.095916 -58.706585) (xy 164.09543 -58.679334)
			(xy 156.379962 -58.679334) (xy 156.382602 -58.694078) (xy 156.383736 -58.7248) (xy 156.383736 -58.732674)
			(xy 156.383215 -58.759709) (xy 156.37547 -58.813224) (xy 156.360232 -58.865104) (xy 156.349446 -58.8899)
			(xy 156.349192 -58.890408) (xy 156.347922 -58.893202) (xy 156.346144 -58.89879) (xy 156.343096 -58.90768)
			(xy 156.352399 -59.174634) (xy 173.1932 -59.174634) (xy 173.197271 -59.119012) (xy 173.209397 -59.064575)
			(xy 173.22932 -59.012484) (xy 173.256616 -58.963849) (xy 173.290702 -58.919706) (xy 173.330851 -58.880997)
			(xy 173.376209 -58.848546) (xy 173.425809 -58.823045) (xy 173.478593 -58.805038) (xy 173.533436 -58.794908)
			(xy 173.58917 -58.792871) (xy 173.644607 -58.798971) (xy 173.698564 -58.813077) (xy 173.749893 -58.834889)
			(xy 173.797499 -58.863943) (xy 173.840367 -58.899618) (xy 173.877584 -58.941155) (xy 173.908357 -58.987668)
			(xy 173.932029 -59.038165) (xy 173.948097 -59.091572) (xy 173.956217 -59.146748) (xy 173.956726 -59.174634)
			(xy 173.956217 -59.20252) (xy 173.948097 -59.257696) (xy 173.932029 -59.311103) (xy 173.908357 -59.3616)
			(xy 173.877584 -59.408113) (xy 173.840367 -59.44965) (xy 173.797499 -59.485325) (xy 173.749893 -59.514379)
			(xy 173.698564 -59.536191) (xy 173.644607 -59.550297) (xy 173.58917 -59.556397) (xy 173.533436 -59.55436)
			(xy 173.478593 -59.54423) (xy 173.425809 -59.526223) (xy 173.376209 -59.500722) (xy 173.330851 -59.468271)
			(xy 173.290702 -59.429562) (xy 173.256616 -59.385419) (xy 173.22932 -59.336784) (xy 173.209397 -59.284693)
			(xy 173.197271 -59.230256) (xy 173.1932 -59.174634) (xy 156.352399 -59.174634) (xy 156.369004 -59.651138)
			(xy 156.381867 -60.01925) (xy 164.235884 -60.01925) (xy 164.235884 -59.96475) (xy 164.24364 -59.910803)
			(xy 164.258994 -59.85851) (xy 164.281635 -59.808934) (xy 164.3111 -59.763085) (xy 164.34679 -59.721895)
			(xy 164.387978 -59.686204) (xy 164.433827 -59.656738) (xy 164.483403 -59.634097) (xy 164.535696 -59.618742)
			(xy 164.589642 -59.610984) (xy 164.616892 -59.610498) (xy 164.644262 -59.610969) (xy 164.698441 -59.618786)
			(xy 164.750944 -59.634274) (xy 164.800691 -59.657114) (xy 164.846658 -59.686837) (xy 164.86759 -59.704478)
			(xy 164.867844 -59.704732) (xy 164.87494 -59.710305) (xy 164.89185 -59.716559) (xy 164.900864 -59.716924)
			(xy 164.96792 -59.716924) (xy 164.976937 -59.716572) (xy 164.993854 -59.71032) (xy 165.00094 -59.704732)
			(xy 165.00094 -59.704478) (xy 165.001194 -59.704478) (xy 165.022127 -59.686837) (xy 165.068095 -59.657113)
			(xy 165.117841 -59.634267) (xy 165.170343 -59.618771) (xy 165.224521 -59.610942) (xy 165.279263 -59.610942)
			(xy 165.333441 -59.618771) (xy 165.385943 -59.634267) (xy 165.435689 -59.657113) (xy 165.481657 -59.686837)
			(xy 165.50259 -59.704478) (xy 165.502844 -59.704732) (xy 165.50994 -59.710305) (xy 165.52685 -59.716559)
			(xy 165.535864 -59.716924) (xy 165.60292 -59.716924) (xy 165.611937 -59.716572) (xy 165.628854 -59.71032)
			(xy 165.63594 -59.704732) (xy 165.63594 -59.704478) (xy 165.636194 -59.704478) (xy 165.657115 -59.686825)
			(xy 165.703091 -59.657116) (xy 165.752841 -59.634283) (xy 165.805344 -59.618795) (xy 165.859522 -59.61097)
			(xy 165.886892 -59.610498) (xy 165.914146 -59.610949) (xy 165.968098 -59.618705) (xy 166.020398 -59.634061)
			(xy 166.06998 -59.656703) (xy 166.115835 -59.686171) (xy 166.157029 -59.721865) (xy 166.192724 -59.763059)
			(xy 166.222193 -59.808913) (xy 166.244837 -59.858495) (xy 166.260193 -59.910794) (xy 166.267951 -59.964746)
			(xy 166.267951 -60.019254) (xy 166.260193 -60.073206) (xy 166.244837 -60.125505) (xy 166.222193 -60.175087)
			(xy 166.192724 -60.220941) (xy 166.157029 -60.262135) (xy 166.115835 -60.297829) (xy 166.06998 -60.327297)
			(xy 166.020398 -60.349939) (xy 165.968098 -60.365295) (xy 165.914146 -60.373051) (xy 165.886892 -60.373514)
			(xy 165.859522 -60.373049) (xy 165.805343 -60.365231) (xy 165.75284 -60.349741) (xy 165.703093 -60.326899)
			(xy 165.657126 -60.297175) (xy 165.636194 -60.279534) (xy 165.63594 -60.27928) (xy 165.628848 -60.273702)
			(xy 165.611935 -60.267451) (xy 165.60292 -60.267088) (xy 165.535864 -60.267088) (xy 165.526846 -60.26743)
			(xy 165.509929 -60.273688) (xy 165.502844 -60.27928) (xy 165.50259 -60.279534) (xy 165.481657 -60.297175)
			(xy 165.435689 -60.326899) (xy 165.385943 -60.349745) (xy 165.333441 -60.365241) (xy 165.279263 -60.37307)
			(xy 165.224521 -60.37307) (xy 165.170343 -60.365241) (xy 165.117841 -60.349745) (xy 165.068095 -60.326899)
			(xy 165.022127 -60.297175) (xy 165.001194 -60.279534) (xy 165.00094 -60.27928) (xy 164.993848 -60.273702)
			(xy 164.976935 -60.267451) (xy 164.96792 -60.267088) (xy 164.900864 -60.267088) (xy 164.891846 -60.26743)
			(xy 164.874929 -60.273688) (xy 164.867844 -60.27928) (xy 164.867844 -60.279534) (xy 164.86759 -60.279534)
			(xy 164.846677 -60.297197) (xy 164.800698 -60.326904) (xy 164.750946 -60.349735) (xy 164.698441 -60.36522)
			(xy 164.644262 -60.373043) (xy 164.616892 -60.373514) (xy 164.589642 -60.373016) (xy 164.535696 -60.365258)
			(xy 164.483403 -60.349903) (xy 164.433827 -60.327262) (xy 164.387978 -60.297796) (xy 164.34679 -60.262105)
			(xy 164.3111 -60.220915) (xy 164.281635 -60.175066) (xy 164.258994 -60.12549) (xy 164.24364 -60.073197)
			(xy 164.235884 -60.01925) (xy 156.381867 -60.01925) (xy 156.403326 -60.633356) (xy 175.89703 -60.633356)
			(xy 175.901101 -60.577734) (xy 175.913227 -60.523297) (xy 175.93315 -60.471206) (xy 175.960446 -60.422571)
			(xy 175.994532 -60.378428) (xy 176.034681 -60.339719) (xy 176.080039 -60.307268) (xy 176.129639 -60.281767)
			(xy 176.182423 -60.26376) (xy 176.237266 -60.25363) (xy 176.293 -60.251593) (xy 176.348437 -60.257693)
			(xy 176.402394 -60.271799) (xy 176.453723 -60.293611) (xy 176.501329 -60.322665) (xy 176.544197 -60.35834)
			(xy 176.581414 -60.399877) (xy 176.612187 -60.44639) (xy 176.635859 -60.496887) (xy 176.651927 -60.550294)
			(xy 176.660047 -60.60547) (xy 176.660556 -60.633356) (xy 176.660047 -60.661242) (xy 176.651927 -60.716418)
			(xy 176.635859 -60.769825) (xy 176.612187 -60.820322) (xy 176.581414 -60.866835) (xy 176.544197 -60.908372)
			(xy 176.501329 -60.944047) (xy 176.453723 -60.973101) (xy 176.402394 -60.994913) (xy 176.348437 -61.009019)
			(xy 176.293 -61.015119) (xy 176.237266 -61.013082) (xy 176.182423 -61.002952) (xy 176.129639 -60.984945)
			(xy 176.080039 -60.959444) (xy 176.034681 -60.926993) (xy 175.994532 -60.888284) (xy 175.960446 -60.844141)
			(xy 175.93315 -60.795506) (xy 175.913227 -60.743415) (xy 175.901101 -60.688978) (xy 175.89703 -60.633356)
			(xy 156.403326 -60.633356) (xy 156.433184 -61.487812) (xy 174.404526 -61.487812) (xy 174.408597 -61.43219)
			(xy 174.420723 -61.377753) (xy 174.440646 -61.325662) (xy 174.467942 -61.277027) (xy 174.502028 -61.232884)
			(xy 174.542177 -61.194175) (xy 174.587535 -61.161724) (xy 174.637135 -61.136223) (xy 174.689919 -61.118216)
			(xy 174.744762 -61.108086) (xy 174.800496 -61.106049) (xy 174.855933 -61.112149) (xy 174.90989 -61.126255)
			(xy 174.961219 -61.148067) (xy 175.008825 -61.177121) (xy 175.051693 -61.212796) (xy 175.08891 -61.254333)
			(xy 175.119683 -61.300846) (xy 175.143355 -61.351343) (xy 175.159423 -61.40475) (xy 175.167543 -61.459926)
			(xy 175.168052 -61.487812) (xy 175.167543 -61.515698) (xy 175.159423 -61.570874) (xy 175.143355 -61.624281)
			(xy 175.119683 -61.674778) (xy 175.08891 -61.721291) (xy 175.051693 -61.762828) (xy 175.008825 -61.798503)
			(xy 174.961219 -61.827557) (xy 174.90989 -61.849369) (xy 174.855933 -61.863475) (xy 174.800496 -61.869575)
			(xy 174.744762 -61.867538) (xy 174.689919 -61.857408) (xy 174.637135 -61.839401) (xy 174.587535 -61.8139)
			(xy 174.542177 -61.781449) (xy 174.502028 -61.74274) (xy 174.467942 -61.698597) (xy 174.440646 -61.649962)
			(xy 174.420723 -61.597871) (xy 174.408597 -61.543434) (xy 174.404526 -61.487812) (xy 156.433184 -61.487812)
			(xy 156.43479 -61.533786) (xy 156.455281 -62.121034) (xy 172.3423 -62.121034) (xy 172.346371 -62.065412)
			(xy 172.358497 -62.010975) (xy 172.37842 -61.958884) (xy 172.405716 -61.910249) (xy 172.439802 -61.866106)
			(xy 172.479951 -61.827397) (xy 172.525309 -61.794946) (xy 172.574909 -61.769445) (xy 172.627693 -61.751438)
			(xy 172.682536 -61.741308) (xy 172.73827 -61.739271) (xy 172.793707 -61.745371) (xy 172.847664 -61.759477)
			(xy 172.898993 -61.781289) (xy 172.946599 -61.810343) (xy 172.989467 -61.846018) (xy 173.026684 -61.887555)
			(xy 173.057457 -61.934068) (xy 173.081129 -61.984565) (xy 173.097197 -62.037972) (xy 173.105317 -62.093148)
			(xy 173.105826 -62.121034) (xy 173.105317 -62.14892) (xy 173.097197 -62.204096) (xy 173.081129 -62.257503)
			(xy 173.057457 -62.308) (xy 173.026684 -62.354513) (xy 172.989467 -62.39605) (xy 172.946599 -62.431725)
			(xy 172.898993 -62.460779) (xy 172.847664 -62.482591) (xy 172.793707 -62.496697) (xy 172.73827 -62.502797)
			(xy 172.682536 -62.50076) (xy 172.627693 -62.49063) (xy 172.574909 -62.472623) (xy 172.525309 -62.447122)
			(xy 172.479951 -62.414671) (xy 172.439802 -62.375962) (xy 172.405716 -62.331819) (xy 172.37842 -62.283184)
			(xy 172.358497 -62.231093) (xy 172.346371 -62.176656) (xy 172.3423 -62.121034) (xy 156.455281 -62.121034)
			(xy 156.48178 -62.880494) (xy 156.493448 -63.213552) (xy 164.220865 -63.213552) (xy 164.220865 -63.159048)
			(xy 164.228622 -63.105098) (xy 164.243978 -63.052801) (xy 164.266621 -63.003221) (xy 164.296088 -62.957369)
			(xy 164.331782 -62.916177) (xy 164.372974 -62.880485) (xy 164.418827 -62.851018) (xy 164.468406 -62.828376)
			(xy 164.520703 -62.813021) (xy 164.574654 -62.805265) (xy 164.601906 -62.804802) (xy 164.629276 -62.805264)
			(xy 164.683456 -62.813083) (xy 164.735959 -62.828573) (xy 164.785706 -62.851415) (xy 164.831672 -62.881141)
			(xy 164.852604 -62.898782) (xy 164.852858 -62.899036) (xy 164.859949 -62.904615) (xy 164.876863 -62.910865)
			(xy 164.885878 -62.911228) (xy 164.952934 -62.911228) (xy 164.961952 -62.910881) (xy 164.978868 -62.904626)
			(xy 164.985954 -62.899036) (xy 164.985954 -62.898782) (xy 164.986208 -62.898782) (xy 165.007141 -62.881141)
			(xy 165.053109 -62.851417) (xy 165.102855 -62.828571) (xy 165.155357 -62.813075) (xy 165.209535 -62.805246)
			(xy 165.264277 -62.805246) (xy 165.318455 -62.813075) (xy 165.370957 -62.828571) (xy 165.420703 -62.851417)
			(xy 165.466671 -62.881141) (xy 165.487604 -62.898782) (xy 165.487858 -62.899036) (xy 165.494949 -62.904615)
			(xy 165.511863 -62.910865) (xy 165.520878 -62.911228) (xy 165.587934 -62.911228) (xy 165.596952 -62.910881)
			(xy 165.613868 -62.904626) (xy 165.620954 -62.899036) (xy 165.620954 -62.898782) (xy 165.621208 -62.898782)
			(xy 165.642124 -62.881123) (xy 165.688101 -62.851415) (xy 165.737853 -62.828583) (xy 165.790357 -62.813096)
			(xy 165.844536 -62.805273) (xy 165.871906 -62.804802) (xy 165.899158 -62.805268) (xy 165.953106 -62.813026)
			(xy 166.005402 -62.828382) (xy 166.054979 -62.851024) (xy 166.10083 -62.880491) (xy 166.142021 -62.916183)
			(xy 166.177713 -62.957375) (xy 166.207179 -63.003226) (xy 166.22982 -63.052804) (xy 166.239636 -63.086234)
			(xy 169.515026 -63.086234) (xy 169.519097 -63.030612) (xy 169.531223 -62.976175) (xy 169.551146 -62.924084)
			(xy 169.578442 -62.875449) (xy 169.612528 -62.831306) (xy 169.652677 -62.792597) (xy 169.698035 -62.760146)
			(xy 169.747635 -62.734645) (xy 169.800419 -62.716638) (xy 169.855262 -62.706508) (xy 169.910996 -62.704471)
			(xy 169.966433 -62.710571) (xy 170.02039 -62.724677) (xy 170.071719 -62.746489) (xy 170.119325 -62.775543)
			(xy 170.162193 -62.811218) (xy 170.19941 -62.852755) (xy 170.230183 -62.899268) (xy 170.253855 -62.949765)
			(xy 170.269923 -63.003172) (xy 170.278043 -63.058348) (xy 170.278552 -63.086234) (xy 170.278043 -63.11412)
			(xy 170.269923 -63.169296) (xy 170.253855 -63.222703) (xy 170.230183 -63.2732) (xy 170.23003 -63.273432)
			(xy 171.67682 -63.273432) (xy 171.680891 -63.21781) (xy 171.693017 -63.163373) (xy 171.71294 -63.111282)
			(xy 171.740236 -63.062647) (xy 171.774322 -63.018504) (xy 171.814471 -62.979795) (xy 171.859829 -62.947344)
			(xy 171.909429 -62.921843) (xy 171.962213 -62.903836) (xy 172.017056 -62.893706) (xy 172.07279 -62.891669)
			(xy 172.128227 -62.897769) (xy 172.182184 -62.911875) (xy 172.233513 -62.933687) (xy 172.281119 -62.962741)
			(xy 172.323987 -62.998416) (xy 172.361204 -63.039953) (xy 172.391977 -63.086466) (xy 172.415649 -63.136963)
			(xy 172.431717 -63.19037) (xy 172.439837 -63.245546) (xy 172.440346 -63.273432) (xy 172.439837 -63.301318)
			(xy 172.431717 -63.356494) (xy 172.415649 -63.409901) (xy 172.391977 -63.460398) (xy 172.361204 -63.506911)
			(xy 172.323987 -63.548448) (xy 172.281119 -63.584123) (xy 172.233513 -63.613177) (xy 172.182184 -63.634989)
			(xy 172.128227 -63.649095) (xy 172.07279 -63.655195) (xy 172.017056 -63.653158) (xy 171.962213 -63.643028)
			(xy 171.909429 -63.625021) (xy 171.859829 -63.59952) (xy 171.814471 -63.567069) (xy 171.774322 -63.52836)
			(xy 171.740236 -63.484217) (xy 171.71294 -63.435582) (xy 171.693017 -63.383491) (xy 171.680891 -63.329054)
			(xy 171.67682 -63.273432) (xy 170.23003 -63.273432) (xy 170.19941 -63.319713) (xy 170.162193 -63.36125)
			(xy 170.119325 -63.396925) (xy 170.071719 -63.425979) (xy 170.02039 -63.447791) (xy 169.966433 -63.461897)
			(xy 169.910996 -63.467997) (xy 169.855262 -63.46596) (xy 169.800419 -63.45583) (xy 169.747635 -63.437823)
			(xy 169.698035 -63.412322) (xy 169.652677 -63.379871) (xy 169.612528 -63.341162) (xy 169.578442 -63.297019)
			(xy 169.551146 -63.248384) (xy 169.531223 -63.196293) (xy 169.519097 -63.141856) (xy 169.515026 -63.086234)
			(xy 166.239636 -63.086234) (xy 166.245176 -63.1051) (xy 166.252932 -63.159048) (xy 166.252932 -63.213552)
			(xy 166.245176 -63.2675) (xy 166.22982 -63.319796) (xy 166.207179 -63.369374) (xy 166.177713 -63.415225)
			(xy 166.142021 -63.456417) (xy 166.10083 -63.492109) (xy 166.054979 -63.521576) (xy 166.005402 -63.544218)
			(xy 165.953106 -63.559574) (xy 165.899158 -63.567332) (xy 165.871906 -63.567818) (xy 165.844535 -63.567368)
			(xy 165.790354 -63.55955) (xy 165.73785 -63.544058) (xy 165.688104 -63.521212) (xy 165.642138 -63.491482)
			(xy 165.621208 -63.473838) (xy 165.620954 -63.473584) (xy 165.613857 -63.468012) (xy 165.596948 -63.461757)
			(xy 165.587934 -63.461392) (xy 165.520878 -63.461392) (xy 165.51186 -63.46174) (xy 165.494944 -63.467994)
			(xy 165.487858 -63.473584) (xy 165.487604 -63.473838) (xy 165.466671 -63.491479) (xy 165.420703 -63.521203)
			(xy 165.370957 -63.544049) (xy 165.318455 -63.559545) (xy 165.264277 -63.567374) (xy 165.209535 -63.567374)
			(xy 165.155357 -63.559545) (xy 165.102855 -63.544049) (xy 165.053109 -63.521203) (xy 165.007141 -63.491479)
			(xy 164.986208 -63.473838) (xy 164.985954 -63.473584) (xy 164.978857 -63.468012) (xy 164.961948 -63.461757)
			(xy 164.952934 -63.461392) (xy 164.885878 -63.461392) (xy 164.87686 -63.46174) (xy 164.859944 -63.467994)
			(xy 164.852858 -63.473584) (xy 164.852858 -63.473838) (xy 164.852604 -63.473838) (xy 164.831686 -63.491495)
			(xy 164.785709 -63.521203) (xy 164.735958 -63.544035) (xy 164.683454 -63.559522) (xy 164.629276 -63.567346)
			(xy 164.601906 -63.567818) (xy 164.574654 -63.567335) (xy 164.520703 -63.559579) (xy 164.468406 -63.544224)
			(xy 164.418827 -63.521582) (xy 164.372974 -63.492115) (xy 164.331782 -63.456423) (xy 164.296088 -63.415231)
			(xy 164.266621 -63.369379) (xy 164.243978 -63.319799) (xy 164.228622 -63.267502) (xy 164.220865 -63.213552)
			(xy 156.493448 -63.213552) (xy 156.519118 -63.946278) (xy 156.533721 -64.312292) (xy 175.005998 -64.312292)
			(xy 175.010069 -64.25667) (xy 175.022195 -64.202233) (xy 175.042118 -64.150142) (xy 175.069414 -64.101507)
			(xy 175.1035 -64.057364) (xy 175.143649 -64.018655) (xy 175.189007 -63.986204) (xy 175.238607 -63.960703)
			(xy 175.291391 -63.942696) (xy 175.346234 -63.932566) (xy 175.401968 -63.930529) (xy 175.457405 -63.936629)
			(xy 175.511362 -63.950735) (xy 175.562691 -63.972547) (xy 175.610297 -64.001601) (xy 175.653165 -64.037276)
			(xy 175.690382 -64.078813) (xy 175.721155 -64.125326) (xy 175.744827 -64.175823) (xy 175.760895 -64.22923)
			(xy 175.769015 -64.284406) (xy 175.769524 -64.312292) (xy 175.769015 -64.340178) (xy 175.760895 -64.395354)
			(xy 175.744827 -64.448761) (xy 175.721155 -64.499258) (xy 175.690382 -64.545771) (xy 175.653165 -64.587308)
			(xy 175.610297 -64.622983) (xy 175.562691 -64.652037) (xy 175.511362 -64.673849) (xy 175.457405 -64.687955)
			(xy 175.401968 -64.694055) (xy 175.346234 -64.692018) (xy 175.291391 -64.681888) (xy 175.238607 -64.663881)
			(xy 175.189007 -64.63838) (xy 175.143649 -64.605929) (xy 175.1035 -64.56722) (xy 175.069414 -64.523077)
			(xy 175.042118 -64.474442) (xy 175.022195 -64.422351) (xy 175.010069 -64.367914) (xy 175.005998 -64.312292)
			(xy 156.533721 -64.312292) (xy 156.554678 -64.837564) (xy 156.564076 -65.070482) (xy 156.564076 -65.071498)
			(xy 156.566433 -65.100962) (xy 162.232592 -65.100962) (xy 162.236663 -65.04534) (xy 162.248789 -64.990903)
			(xy 162.268712 -64.938812) (xy 162.296008 -64.890177) (xy 162.330094 -64.846034) (xy 162.370243 -64.807325)
			(xy 162.415601 -64.774874) (xy 162.465201 -64.749373) (xy 162.517985 -64.731366) (xy 162.572828 -64.721236)
			(xy 162.628562 -64.719199) (xy 162.683999 -64.725299) (xy 162.737956 -64.739405) (xy 162.789285 -64.761217)
			(xy 162.836891 -64.790271) (xy 162.879759 -64.825946) (xy 162.916976 -64.867483) (xy 162.947749 -64.913996)
			(xy 162.971421 -64.964493) (xy 162.987489 -65.0179) (xy 162.995609 -65.073076) (xy 162.996118 -65.100962)
			(xy 162.995609 -65.128848) (xy 162.987489 -65.184024) (xy 162.971421 -65.237431) (xy 162.947749 -65.287928)
			(xy 162.916976 -65.334441) (xy 162.879759 -65.375978) (xy 162.836891 -65.411653) (xy 162.789285 -65.440707)
			(xy 162.737956 -65.462519) (xy 162.683999 -65.476625) (xy 162.628562 -65.482725) (xy 162.572828 -65.480688)
			(xy 162.517985 -65.470558) (xy 162.465201 -65.452551) (xy 162.415601 -65.42705) (xy 162.370243 -65.394599)
			(xy 162.330094 -65.35589) (xy 162.296008 -65.311747) (xy 162.268712 -65.263112) (xy 162.248789 -65.211021)
			(xy 162.236663 -65.156584) (xy 162.232592 -65.100962) (xy 156.566433 -65.100962) (xy 156.586428 -65.350898)
			(xy 156.591762 -65.354454) (xy 156.595318 -65.356486) (xy 156.605224 -65.362836) (xy 156.615892 -65.369694)
			(xy 156.640022 -65.385188) (xy 156.64434 -65.387728) (xy 156.650191 -65.390963) (xy 156.66306 -65.394564)
			(xy 156.66974 -65.39484) (xy 156.690568 -65.39484) (xy 156.696664 -65.394332) (xy 156.709618 -65.3923)
			(xy 156.712158 -65.391538) (xy 156.713682 -65.39103) (xy 156.741377 -65.383016) (xy 156.798392 -65.374467)
			(xy 156.82722 -65.374012) (xy 156.831538 -65.374012) (xy 156.858661 -65.374684) (xy 156.912311 -65.382756)
			(xy 156.964277 -65.398347) (xy 157.01351 -65.421143) (xy 157.059016 -65.450684) (xy 157.099879 -65.486374)
			(xy 157.135272 -65.527493) (xy 157.164484 -65.573212) (xy 157.186923 -65.622608) (xy 157.202138 -65.674686)
			(xy 157.209822 -65.728393) (xy 157.210252 -65.75552) (xy 157.209765 -65.782771) (xy 157.202006 -65.836719)
			(xy 157.18665 -65.889014) (xy 157.164008 -65.938592) (xy 157.134542 -65.984443) (xy 157.098851 -66.025634)
			(xy 157.057662 -66.061328) (xy 157.011813 -66.090797) (xy 156.962237 -66.113441) (xy 156.909943 -66.128801)
			(xy 156.855995 -66.136563) (xy 156.828744 -66.137028) (xy 156.810083 -66.136836) (xy 156.772934 -66.133271)
			(xy 156.754576 -66.129916) (xy 156.742638 -66.12763) (xy 156.731462 -66.130678) (xy 156.725733 -66.132367)
			(xy 156.715213 -66.138019) (xy 156.710634 -66.141854) (xy 156.68117 -66.168524) (xy 156.672788 -66.176144)
			(xy 156.664529 -66.184412) (xy 156.655936 -66.206117) (xy 156.656278 -66.2178) (xy 156.69387 -66.687954)
			(xy 156.699966 -66.690494) (xy 156.720794 -66.69786) (xy 156.721302 -66.698368) (xy 156.74213 -66.714624)
			(xy 156.74901 -66.71966) (xy 156.765105 -66.725259) (xy 156.773626 -66.725546) (xy 156.783786 -66.725546)
			(xy 156.78785 -66.725038) (xy 156.797765 -66.723501) (xy 156.817714 -66.721343) (xy 156.827728 -66.72072)
			(xy 156.844238 -66.720212) (xy 156.85516 -66.720212) (xy 156.886237 -66.721428) (xy 156.947399 -66.732691)
			(xy 157.00593 -66.753706) (xy 157.060288 -66.783918) (xy 157.08503 -66.802762) (xy 157.09011 -66.806826)
			(xy 157.097984 -66.810382) (xy 157.102612 -66.812156) (xy 157.112333 -66.814078) (xy 157.117288 -66.814192)
			(xy 157.138624 -66.814192) (xy 157.144064 -66.814334) (xy 157.154696 -66.81664) (xy 157.159706 -66.818764)
			(xy 157.173168 -66.82486) (xy 157.181831 -66.828483) (xy 157.200555 -66.829722) (xy 157.218459 -66.824102)
			(xy 157.226 -66.81851) (xy 157.233112 -66.812922) (xy 157.237684 -66.809366) (xy 157.238446 -66.808858)
			(xy 157.259088 -66.792218) (xy 157.304101 -66.764201) (xy 157.35256 -66.742686) (xy 157.40353 -66.728086)
			(xy 157.456031 -66.720683) (xy 157.48254 -66.720212) (xy 157.482794 -66.720212) (xy 157.510047 -66.720675)
			(xy 157.563997 -66.728431) (xy 157.616295 -66.743787) (xy 157.665874 -66.766429) (xy 157.711727 -66.795898)
			(xy 157.752918 -66.831592) (xy 157.788611 -66.872785) (xy 157.818077 -66.918638) (xy 157.840718 -66.968219)
			(xy 157.856072 -67.020517) (xy 157.863826 -67.074467) (xy 157.864302 -67.10172) (xy 157.863827 -67.128797)
			(xy 157.856166 -67.182407) (xy 157.841001 -67.234395) (xy 157.818637 -67.283716) (xy 157.789522 -67.329378)
			(xy 157.754243 -67.370465) (xy 157.713509 -67.406149) (xy 157.668137 -67.435715) (xy 157.619041 -67.458568)
			(xy 157.567206 -67.474247) (xy 157.513675 -67.48244) (xy 157.486604 -67.483228) (xy 157.482286 -67.483228)
			(xy 157.452376 -67.482623) (xy 157.393293 -67.47325) (xy 157.336393 -67.454783) (xy 157.283068 -67.427672)
			(xy 157.258512 -67.410584) (xy 157.25013 -67.404234) (xy 157.245304 -67.400424) (xy 157.236668 -67.39509)
			(xy 157.235652 -67.394582) (xy 157.230326 -67.392123) (xy 157.21891 -67.389432) (xy 157.213046 -67.389248)
			(xy 157.191964 -67.389248) (xy 157.186525 -67.389104) (xy 157.175894 -67.386793) (xy 157.170882 -67.384676)
			(xy 157.15742 -67.37858) (xy 157.148758 -67.374957) (xy 157.130036 -67.373722) (xy 157.112136 -67.379348)
			(xy 157.104588 -67.38493) (xy 157.097476 -67.390518) (xy 157.092904 -67.394074) (xy 157.092142 -67.394582)
			(xy 157.071501 -67.411224) (xy 157.026488 -67.439243) (xy 156.97803 -67.460761) (xy 156.927059 -67.475361)
			(xy 156.874558 -67.482764) (xy 156.848048 -67.483228) (xy 156.84119 -67.483228) (xy 156.833316 -67.48399)
			(xy 156.82624 -67.485551) (xy 156.82134 -67.488054) (xy 160.87928 -67.488054) (xy 160.883351 -67.432432)
			(xy 160.895477 -67.377995) (xy 160.9154 -67.325904) (xy 160.942696 -67.277269) (xy 160.976782 -67.233126)
			(xy 161.016931 -67.194417) (xy 161.062289 -67.161966) (xy 161.111889 -67.136465) (xy 161.164673 -67.118458)
			(xy 161.219516 -67.108328) (xy 161.27525 -67.106291) (xy 161.330687 -67.112391) (xy 161.384644 -67.126497)
			(xy 161.435973 -67.148309) (xy 161.483579 -67.177363) (xy 161.526447 -67.213038) (xy 161.563664 -67.254575)
			(xy 161.594437 -67.301088) (xy 161.618109 -67.351585) (xy 161.634177 -67.404992) (xy 161.642297 -67.460168)
			(xy 161.642806 -67.488054) (xy 161.642297 -67.51594) (xy 161.639112 -67.537584) (xy 162.171378 -67.537584)
			(xy 162.175449 -67.481962) (xy 162.187575 -67.427525) (xy 162.207498 -67.375434) (xy 162.234794 -67.326799)
			(xy 162.26888 -67.282656) (xy 162.309029 -67.243947) (xy 162.354387 -67.211496) (xy 162.403987 -67.185995)
			(xy 162.456771 -67.167988) (xy 162.511614 -67.157858) (xy 162.567348 -67.155821) (xy 162.622785 -67.161921)
			(xy 162.676742 -67.176027) (xy 162.728071 -67.197839) (xy 162.775677 -67.226893) (xy 162.818545 -67.262568)
			(xy 162.855762 -67.304105) (xy 162.886535 -67.350618) (xy 162.910207 -67.401115) (xy 162.926275 -67.454522)
			(xy 162.934395 -67.509698) (xy 162.934904 -67.537584) (xy 162.934395 -67.56547) (xy 162.93035 -67.592956)
			(xy 163.445442 -67.592956) (xy 163.449513 -67.537334) (xy 163.461639 -67.482897) (xy 163.481562 -67.430806)
			(xy 163.508858 -67.382171) (xy 163.542944 -67.338028) (xy 163.583093 -67.299319) (xy 163.628451 -67.266868)
			(xy 163.678051 -67.241367) (xy 163.730835 -67.22336) (xy 163.785678 -67.21323) (xy 163.841412 -67.211193)
			(xy 163.896849 -67.217293) (xy 163.950806 -67.231399) (xy 164.002135 -67.253211) (xy 164.049741 -67.282265)
			(xy 164.092609 -67.31794) (xy 164.129826 -67.359477) (xy 164.160599 -67.40599) (xy 164.184271 -67.456487)
			(xy 164.200339 -67.509894) (xy 164.208456 -67.565048) (xy 166.546816 -67.565048) (xy 166.546816 -67.510552)
			(xy 166.554571 -67.456611) (xy 166.569924 -67.404323) (xy 166.592562 -67.354752) (xy 166.622024 -67.308907)
			(xy 166.65771 -67.267721) (xy 166.698894 -67.232033) (xy 166.744738 -67.20257) (xy 166.794308 -67.17993)
			(xy 166.846596 -67.164575) (xy 166.900536 -67.156817) (xy 166.927784 -67.15633) (xy 166.955154 -67.156798)
			(xy 167.009334 -67.164614) (xy 167.061837 -67.180103) (xy 167.111584 -67.202944) (xy 167.157551 -67.232669)
			(xy 167.178482 -67.25031) (xy 167.178736 -67.250564) (xy 167.185831 -67.256137) (xy 167.202742 -67.26239)
			(xy 167.211756 -67.262756) (xy 167.278812 -67.262756) (xy 167.287831 -67.262414) (xy 167.304748 -67.256157)
			(xy 167.311832 -67.250564) (xy 167.311832 -67.25031) (xy 167.312086 -67.25031) (xy 167.333014 -67.232666)
			(xy 167.378988 -67.202954) (xy 167.428736 -67.180119) (xy 167.481238 -67.164629) (xy 167.535415 -67.156803)
			(xy 167.562784 -67.15633) (xy 167.59004 -67.156716) (xy 167.643998 -67.164472) (xy 167.696303 -67.179828)
			(xy 167.745891 -67.202472) (xy 167.79175 -67.231942) (xy 167.832949 -67.26764) (xy 167.868648 -67.308837)
			(xy 167.898121 -67.354695) (xy 167.920766 -67.404282) (xy 167.936125 -67.456586) (xy 167.943883 -67.510544)
			(xy 167.943883 -67.565056) (xy 167.936125 -67.619014) (xy 167.920766 -67.671318) (xy 167.898121 -67.720905)
			(xy 167.868648 -67.766763) (xy 167.832949 -67.80796) (xy 167.79175 -67.843658) (xy 167.745891 -67.873128)
			(xy 167.696303 -67.895772) (xy 167.643998 -67.911128) (xy 167.59004 -67.918884) (xy 167.562784 -67.919346)
			(xy 167.535413 -67.918902) (xy 167.481232 -67.911081) (xy 167.428728 -67.895588) (xy 167.378982 -67.872741)
			(xy 167.333016 -67.84301) (xy 167.312086 -67.825366) (xy 167.311832 -67.825112) (xy 167.304739 -67.819534)
			(xy 167.287827 -67.813282) (xy 167.278812 -67.81292) (xy 167.211756 -67.81292) (xy 167.202741 -67.8133)
			(xy 167.185824 -67.819531) (xy 167.178736 -67.825112) (xy 167.178736 -67.825366) (xy 167.178482 -67.825366)
			(xy 167.157525 -67.842975) (xy 167.11156 -67.872692) (xy 167.061819 -67.895535) (xy 167.009323 -67.911033)
			(xy 166.955152 -67.918868) (xy 166.927784 -67.919346) (xy 166.900536 -67.918783) (xy 166.846596 -67.911025)
			(xy 166.794308 -67.89567) (xy 166.744738 -67.87303) (xy 166.698894 -67.843567) (xy 166.65771 -67.807879)
			(xy 166.622024 -67.766693) (xy 166.592562 -67.720848) (xy 166.569924 -67.671277) (xy 166.554571 -67.618989)
			(xy 166.546816 -67.565048) (xy 164.208456 -67.565048) (xy 164.208459 -67.56507) (xy 164.208968 -67.592956)
			(xy 164.208459 -67.620842) (xy 164.200339 -67.676018) (xy 164.184271 -67.729425) (xy 164.160599 -67.779922)
			(xy 164.129826 -67.826435) (xy 164.092609 -67.867972) (xy 164.049741 -67.903647) (xy 164.002135 -67.932701)
			(xy 163.950806 -67.954513) (xy 163.896849 -67.968619) (xy 163.841412 -67.974719) (xy 163.785678 -67.972682)
			(xy 163.730835 -67.962552) (xy 163.678051 -67.944545) (xy 163.628451 -67.919044) (xy 163.583093 -67.886593)
			(xy 163.542944 -67.847884) (xy 163.508858 -67.803741) (xy 163.481562 -67.755106) (xy 163.461639 -67.703015)
			(xy 163.449513 -67.648578) (xy 163.445442 -67.592956) (xy 162.93035 -67.592956) (xy 162.926275 -67.620646)
			(xy 162.910207 -67.674053) (xy 162.886535 -67.72455) (xy 162.855762 -67.771063) (xy 162.818545 -67.8126)
			(xy 162.775677 -67.848275) (xy 162.728071 -67.877329) (xy 162.676742 -67.899141) (xy 162.622785 -67.913247)
			(xy 162.567348 -67.919347) (xy 162.511614 -67.91731) (xy 162.456771 -67.90718) (xy 162.403987 -67.889173)
			(xy 162.354387 -67.863672) (xy 162.309029 -67.831221) (xy 162.26888 -67.792512) (xy 162.234794 -67.748369)
			(xy 162.207498 -67.699734) (xy 162.187575 -67.647643) (xy 162.175449 -67.593206) (xy 162.171378 -67.537584)
			(xy 161.639112 -67.537584) (xy 161.634177 -67.571116) (xy 161.618109 -67.624523) (xy 161.594437 -67.67502)
			(xy 161.563664 -67.721533) (xy 161.526447 -67.76307) (xy 161.483579 -67.798745) (xy 161.435973 -67.827799)
			(xy 161.384644 -67.849611) (xy 161.330687 -67.863717) (xy 161.27525 -67.869817) (xy 161.219516 -67.86778)
			(xy 161.164673 -67.85765) (xy 161.111889 -67.839643) (xy 161.062289 -67.814142) (xy 161.016931 -67.781691)
			(xy 160.976782 -67.742982) (xy 160.942696 -67.698839) (xy 160.9154 -67.650204) (xy 160.895477 -67.598113)
			(xy 160.883351 -67.543676) (xy 160.87928 -67.488054) (xy 156.82134 -67.488054) (xy 156.813342 -67.49214)
			(xy 156.807916 -67.496944) (xy 156.79039 -67.515486) (xy 156.789882 -67.515994) (xy 156.77769 -67.529202)
			(xy 156.770991 -67.537267) (xy 156.764184 -67.557074) (xy 156.764482 -67.567556) (xy 156.846273 -68.586604)
			(xy 158.725362 -68.586604) (xy 158.725815 -68.559233) (xy 158.733634 -68.505053) (xy 158.749125 -68.452549)
			(xy 158.77197 -68.402802) (xy 158.801699 -68.356837) (xy 158.819342 -68.335906) (xy 158.819596 -68.335652)
			(xy 158.825167 -68.328554) (xy 158.831423 -68.311646) (xy 158.831788 -68.302632) (xy 158.831788 -68.235576)
			(xy 158.831445 -68.226558) (xy 158.825188 -68.209641) (xy 158.819596 -68.202556) (xy 158.819342 -68.202556)
			(xy 158.819342 -68.202302) (xy 158.801697 -68.181375) (xy 158.771985 -68.135401) (xy 158.749149 -68.085653)
			(xy 158.73366 -68.033151) (xy 158.725834 -67.978974) (xy 158.725362 -67.951604) (xy 158.725881 -67.924354)
			(xy 158.733637 -67.870409) (xy 158.74899 -67.818117) (xy 158.771628 -67.768542) (xy 158.801091 -67.722693)
			(xy 158.836779 -67.681503) (xy 158.877966 -67.645812) (xy 158.923812 -67.616345) (xy 158.973385 -67.593702)
			(xy 159.025676 -67.578344) (xy 159.07962 -67.570584) (xy 159.10687 -67.570096) (xy 159.133185 -67.570518)
			(xy 159.185316 -67.577762) (xy 159.235959 -67.59209) (xy 159.284158 -67.613231) (xy 159.329001 -67.640785)
			(xy 159.369639 -67.674231) (xy 159.387794 -67.693286) (xy 159.395318 -67.700685) (xy 159.414596 -67.709211)
			(xy 159.425132 -67.709796) (xy 159.499808 -67.709796) (xy 159.51036 -67.709286) (xy 159.529655 -67.700738)
			(xy 159.537146 -67.693286) (xy 159.555283 -67.674212) (xy 159.595917 -67.640757) (xy 159.640762 -67.613201)
			(xy 159.688966 -67.592066) (xy 159.739616 -67.577752) (xy 159.791753 -67.570532) (xy 159.81807 -67.570096)
			(xy 159.84544 -67.570581) (xy 159.899618 -67.578394) (xy 159.952121 -67.593879) (xy 160.001868 -67.616716)
			(xy 160.047836 -67.646437) (xy 160.068768 -67.664076) (xy 160.069022 -67.66433) (xy 160.076096 -67.669935)
			(xy 160.093022 -67.67617) (xy 160.102042 -67.676522) (xy 160.169098 -67.676522) (xy 160.178114 -67.676159)
			(xy 160.195031 -67.669915) (xy 160.202118 -67.66433) (xy 160.202118 -67.664076) (xy 160.202372 -67.664076)
			(xy 160.223301 -67.646433) (xy 160.269275 -67.616722) (xy 160.319023 -67.593888) (xy 160.371524 -67.578397)
			(xy 160.425701 -67.57057) (xy 160.45307 -67.570096) (xy 160.480322 -67.570583) (xy 160.534273 -67.578336)
			(xy 160.58657 -67.593689) (xy 160.636151 -67.616328) (xy 160.682004 -67.645793) (xy 160.723197 -67.681484)
			(xy 160.758891 -67.722675) (xy 160.78836 -67.768527) (xy 160.811002 -67.818105) (xy 160.826358 -67.870402)
			(xy 160.834115 -67.924352) (xy 160.834578 -67.951604) (xy 160.83412 -67.978975) (xy 160.826301 -68.033154)
			(xy 160.81081 -68.085658) (xy 160.787967 -68.135404) (xy 160.75824 -68.181371) (xy 160.740598 -68.202302)
			(xy 160.740344 -68.202556) (xy 160.734763 -68.209646) (xy 160.728514 -68.22656) (xy 160.728152 -68.235576)
			(xy 160.728152 -68.302632) (xy 160.728482 -68.311652) (xy 160.734747 -68.328569) (xy 160.740344 -68.335652)
			(xy 160.740598 -68.335652) (xy 160.740598 -68.335906) (xy 160.758253 -68.356825) (xy 160.787963 -68.402802)
			(xy 160.810795 -68.452552) (xy 160.826283 -68.505056) (xy 160.834106 -68.559234) (xy 160.834578 -68.586604)
			(xy 160.834148 -68.613858) (xy 160.82639 -68.667812) (xy 160.811032 -68.720112) (xy 160.794399 -68.75653)
			(xy 164.270436 -68.75653) (xy 164.270911 -68.72916) (xy 164.278725 -68.674981) (xy 164.294212 -68.622478)
			(xy 164.317052 -68.572731) (xy 164.346775 -68.526764) (xy 164.364416 -68.505832) (xy 164.36467 -68.505578)
			(xy 164.37028 -68.498508) (xy 164.376511 -68.481578) (xy 164.376862 -68.472558) (xy 164.376862 -68.405502)
			(xy 164.376512 -68.396484) (xy 164.37026 -68.379567) (xy 164.36467 -68.372482) (xy 164.364416 -68.372482)
			(xy 164.364416 -68.372228) (xy 164.346779 -68.351294) (xy 164.317066 -68.305322) (xy 164.29423 -68.255575)
			(xy 164.278738 -68.203075) (xy 164.27091 -68.148899) (xy 164.270436 -68.12153) (xy 164.270883 -68.094276)
			(xy 164.278637 -68.040322) (xy 164.293992 -67.988021) (xy 164.316634 -67.938438) (xy 164.346103 -67.892583)
			(xy 164.381799 -67.851389) (xy 164.422994 -67.815695) (xy 164.468851 -67.786227) (xy 164.518434 -67.763587)
			(xy 164.570736 -67.748234) (xy 164.62469 -67.740482) (xy 164.651944 -67.740022) (xy 164.679313 -67.740516)
			(xy 164.733491 -67.748326) (xy 164.785994 -67.763808) (xy 164.835742 -67.786644) (xy 164.88171 -67.816363)
			(xy 164.902642 -67.834002) (xy 164.902896 -67.834256) (xy 164.909975 -67.839854) (xy 164.926898 -67.846092)
			(xy 164.935916 -67.846448) (xy 165.002972 -67.846448) (xy 165.011989 -67.846089) (xy 165.028906 -67.839844)
			(xy 165.035992 -67.834256) (xy 165.035992 -67.834002) (xy 165.036246 -67.834002) (xy 165.057188 -67.816375)
			(xy 165.103158 -67.786661) (xy 165.152903 -67.763823) (xy 165.205401 -67.748329) (xy 165.259575 -67.740498)
			(xy 165.286944 -67.740022) (xy 165.313259 -67.740453) (xy 165.36539 -67.747694) (xy 165.416033 -67.76202)
			(xy 165.464232 -67.783159) (xy 165.509075 -67.810712) (xy 165.549713 -67.844157) (xy 165.567868 -67.863212)
			(xy 165.575398 -67.870603) (xy 165.594672 -67.879133) (xy 165.605206 -67.879722) (xy 165.679882 -67.879722)
			(xy 165.690431 -67.87919) (xy 165.709726 -67.870656) (xy 165.71722 -67.863212) (xy 165.735375 -67.844156)
			(xy 165.776005 -67.810698) (xy 165.820845 -67.783139) (xy 165.869046 -67.762001) (xy 165.919694 -67.747684)
			(xy 165.971828 -67.74046) (xy 165.998144 -67.740022) (xy 166.025398 -67.740437) (xy 166.07935 -67.7482)
			(xy 166.131647 -67.763562) (xy 166.181227 -67.786211) (xy 166.227078 -67.815685) (xy 166.268269 -67.851383)
			(xy 166.30396 -67.892581) (xy 166.333425 -67.938438) (xy 166.356063 -67.988022) (xy 166.371415 -68.040323)
			(xy 166.379168 -68.094276) (xy 166.379652 -68.12153) (xy 166.379215 -68.148901) (xy 166.371392 -68.203082)
			(xy 166.355897 -68.255586) (xy 166.333048 -68.305333) (xy 166.303317 -68.351298) (xy 166.285672 -68.372228)
			(xy 166.285418 -68.372482) (xy 166.279835 -68.379571) (xy 166.273586 -68.396486) (xy 166.273226 -68.405502)
			(xy 166.273226 -68.472558) (xy 166.273598 -68.481574) (xy 166.279834 -68.498491) (xy 166.285418 -68.505578)
			(xy 166.285672 -68.505578) (xy 166.285672 -68.505832) (xy 166.303288 -68.526782) (xy 166.333005 -68.57275)
			(xy 166.355845 -68.622493) (xy 166.371342 -68.674989) (xy 166.379175 -68.729162) (xy 166.379652 -68.75653)
			(xy 166.37915 -68.78378) (xy 166.371391 -68.837725) (xy 166.356034 -68.890017) (xy 166.333393 -68.939591)
			(xy 166.303927 -68.985439) (xy 166.268238 -69.026628) (xy 166.22705 -69.062319) (xy 166.181203 -69.091786)
			(xy 166.13163 -69.114429) (xy 166.079339 -69.129788) (xy 166.025394 -69.137549) (xy 165.998144 -69.138038)
			(xy 165.971828 -69.137628) (xy 165.919696 -69.130384) (xy 165.869051 -69.116055) (xy 165.820852 -69.094912)
			(xy 165.77601 -69.067355) (xy 165.735374 -69.033905) (xy 165.71722 -69.014848) (xy 165.709686 -69.00746)
			(xy 165.690416 -68.998926) (xy 165.679882 -68.998338) (xy 165.605206 -68.998338) (xy 165.594653 -68.998846)
			(xy 165.575358 -69.007395) (xy 165.567868 -69.014848) (xy 165.54973 -69.033921) (xy 165.509096 -69.067375)
			(xy 165.464251 -69.09493) (xy 165.416047 -69.116065) (xy 165.365397 -69.130379) (xy 165.313261 -69.137601)
			(xy 165.286944 -69.138038) (xy 165.259574 -69.137561) (xy 165.205395 -69.129748) (xy 165.152891 -69.114263)
			(xy 165.103144 -69.091423) (xy 165.057177 -69.061699) (xy 165.036246 -69.044058) (xy 165.035992 -69.043804)
			(xy 165.028912 -69.038208) (xy 165.01199 -69.031967) (xy 165.002972 -69.031612) (xy 164.935916 -69.031612)
			(xy 164.9269 -69.031974) (xy 164.909982 -69.038218) (xy 164.902896 -69.043804) (xy 164.902896 -69.044058)
			(xy 164.902642 -69.044058) (xy 164.8817 -69.061684) (xy 164.83573 -69.0914) (xy 164.785985 -69.114239)
			(xy 164.733487 -69.129733) (xy 164.679313 -69.137563) (xy 164.651944 -69.138038) (xy 164.624694 -69.137504)
			(xy 164.570747 -69.129754) (xy 164.518452 -69.114405) (xy 164.468874 -69.09177) (xy 164.423022 -69.062309)
			(xy 164.38183 -69.026623) (xy 164.346135 -68.985437) (xy 164.316666 -68.939591) (xy 164.294021 -68.890017)
			(xy 164.278662 -68.837726) (xy 164.270901 -68.78378) (xy 164.270436 -68.75653) (xy 160.794399 -68.75653)
			(xy 160.788387 -68.769694) (xy 160.758916 -68.815549) (xy 160.723218 -68.856742) (xy 160.682022 -68.892436)
			(xy 160.636165 -68.921903) (xy 160.58658 -68.944544) (xy 160.534279 -68.959897) (xy 160.480324 -68.967651)
			(xy 160.45307 -68.968112) (xy 160.425699 -68.967661) (xy 160.37152 -68.959839) (xy 160.319017 -68.944346)
			(xy 160.26927 -68.921501) (xy 160.223304 -68.891774) (xy 160.202372 -68.874132) (xy 160.202118 -68.873878)
			(xy 160.195032 -68.86829) (xy 160.178115 -68.862045) (xy 160.169098 -68.861686) (xy 160.102042 -68.861686)
			(xy 160.093028 -68.862066) (xy 160.076111 -68.868298) (xy 160.069022 -68.873878) (xy 160.069022 -68.874132)
			(xy 160.068768 -68.874132) (xy 160.047825 -68.891758) (xy 160.001855 -68.92147) (xy 159.95211 -68.944308)
			(xy 159.899612 -68.959803) (xy 159.845438 -68.967635) (xy 159.81807 -68.968112) (xy 159.791756 -68.967661)
			(xy 159.739626 -68.960422) (xy 159.688984 -68.9461) (xy 159.640785 -68.924964) (xy 159.595942 -68.897415)
			(xy 159.555302 -68.863974) (xy 159.537146 -68.844922) (xy 159.529643 -68.837498) (xy 159.510349 -68.828986)
			(xy 159.499808 -68.828412) (xy 159.425132 -68.828412) (xy 159.414582 -68.828941) (xy 159.395287 -68.837476)
			(xy 159.387794 -68.844922) (xy 159.369639 -68.863978) (xy 159.329008 -68.897434) (xy 159.284168 -68.924992)
			(xy 159.235967 -68.946131) (xy 159.18532 -68.960448) (xy 159.133186 -68.967673) (xy 159.10687 -68.968112)
			(xy 159.079618 -68.96765) (xy 159.02567 -68.95989) (xy 158.973375 -68.944531) (xy 158.923798 -68.921887)
			(xy 158.877948 -68.892418) (xy 158.836758 -68.856724) (xy 158.801067 -68.815531) (xy 158.771601 -68.769679)
			(xy 158.74896 -68.720101) (xy 158.733605 -68.667805) (xy 158.725848 -68.613856) (xy 158.725362 -68.586604)
			(xy 156.846273 -68.586604) (xy 157.084592 -71.555864) (xy 161.29457 -71.555864) (xy 161.298641 -71.500242)
			(xy 161.310767 -71.445805) (xy 161.33069 -71.393714) (xy 161.357986 -71.345079) (xy 161.392072 -71.300936)
			(xy 161.432221 -71.262227) (xy 161.477579 -71.229776) (xy 161.527179 -71.204275) (xy 161.579963 -71.186268)
			(xy 161.634806 -71.176138) (xy 161.69054 -71.174101) (xy 161.745977 -71.180201) (xy 161.799934 -71.194307)
			(xy 161.851263 -71.216119) (xy 161.898869 -71.245173) (xy 161.941737 -71.280848) (xy 161.978954 -71.322385)
			(xy 162.009727 -71.368898) (xy 162.033399 -71.419395) (xy 162.049467 -71.472802) (xy 162.057587 -71.527978)
			(xy 162.058096 -71.555864) (xy 162.057587 -71.58375) (xy 162.051748 -71.623428) (xy 162.803584 -71.623428)
			(xy 162.807655 -71.567806) (xy 162.819781 -71.513369) (xy 162.839704 -71.461278) (xy 162.867 -71.412643)
			(xy 162.901086 -71.3685) (xy 162.941235 -71.329791) (xy 162.986593 -71.29734) (xy 163.036193 -71.271839)
			(xy 163.088977 -71.253832) (xy 163.14382 -71.243702) (xy 163.199554 -71.241665) (xy 163.254991 -71.247765)
			(xy 163.308948 -71.261871) (xy 163.360277 -71.283683) (xy 163.407883 -71.312737) (xy 163.450751 -71.348412)
			(xy 163.487968 -71.389949) (xy 163.518741 -71.436462) (xy 163.542413 -71.486959) (xy 163.558481 -71.540366)
			(xy 163.566601 -71.595542) (xy 163.56711 -71.623428) (xy 163.566601 -71.651314) (xy 163.558481 -71.70649)
			(xy 163.542413 -71.759897) (xy 163.518741 -71.810394) (xy 163.487968 -71.856907) (xy 163.450751 -71.898444)
			(xy 163.407883 -71.934119) (xy 163.360277 -71.963173) (xy 163.308948 -71.984985) (xy 163.254991 -71.999091)
			(xy 163.199554 -72.005191) (xy 163.14382 -72.003154) (xy 163.088977 -71.993024) (xy 163.036193 -71.975017)
			(xy 162.986593 -71.949516) (xy 162.941235 -71.917065) (xy 162.901086 -71.878356) (xy 162.867 -71.834213)
			(xy 162.839704 -71.785578) (xy 162.819781 -71.733487) (xy 162.807655 -71.67905) (xy 162.803584 -71.623428)
			(xy 162.051748 -71.623428) (xy 162.049467 -71.638926) (xy 162.033399 -71.692333) (xy 162.009727 -71.74283)
			(xy 161.978954 -71.789343) (xy 161.941737 -71.83088) (xy 161.898869 -71.866555) (xy 161.851263 -71.895609)
			(xy 161.799934 -71.917421) (xy 161.745977 -71.931527) (xy 161.69054 -71.937627) (xy 161.634806 -71.93559)
			(xy 161.579963 -71.92546) (xy 161.527179 -71.907453) (xy 161.477579 -71.881952) (xy 161.432221 -71.849501)
			(xy 161.392072 -71.810792) (xy 161.357986 -71.766649) (xy 161.33069 -71.718014) (xy 161.310767 -71.665923)
			(xy 161.298641 -71.611486) (xy 161.29457 -71.555864) (xy 157.084592 -71.555864) (xy 158.262143 -86.227158)
			(xy 173.06366 -86.227158) (xy 173.067731 -86.171536) (xy 173.079857 -86.117099) (xy 173.09978 -86.065008)
			(xy 173.127076 -86.016373) (xy 173.161162 -85.97223) (xy 173.201311 -85.933521) (xy 173.246669 -85.90107)
			(xy 173.296269 -85.875569) (xy 173.349053 -85.857562) (xy 173.403896 -85.847432) (xy 173.45963 -85.845395)
			(xy 173.515067 -85.851495) (xy 173.569024 -85.865601) (xy 173.620353 -85.887413) (xy 173.667959 -85.916467)
			(xy 173.710827 -85.952142) (xy 173.748044 -85.993679) (xy 173.778817 -86.040192) (xy 173.802489 -86.090689)
			(xy 173.818557 -86.144096) (xy 173.826677 -86.199272) (xy 173.827186 -86.227158) (xy 173.826695 -86.254082)
			(xy 174.747426 -86.254082) (xy 174.751497 -86.19846) (xy 174.763623 -86.144023) (xy 174.783546 -86.091932)
			(xy 174.810842 -86.043297) (xy 174.844928 -85.999154) (xy 174.885077 -85.960445) (xy 174.930435 -85.927994)
			(xy 174.980035 -85.902493) (xy 175.032819 -85.884486) (xy 175.087662 -85.874356) (xy 175.143396 -85.872319)
			(xy 175.198833 -85.878419) (xy 175.25279 -85.892525) (xy 175.304119 -85.914337) (xy 175.351725 -85.943391)
			(xy 175.394593 -85.979066) (xy 175.43181 -86.020603) (xy 175.462583 -86.067116) (xy 175.486255 -86.117613)
			(xy 175.502323 -86.17102) (xy 175.510443 -86.226196) (xy 175.510952 -86.254082) (xy 175.510443 -86.281968)
			(xy 175.502323 -86.337144) (xy 175.486255 -86.390551) (xy 175.462583 -86.441048) (xy 175.43181 -86.487561)
			(xy 175.394593 -86.529098) (xy 175.351725 -86.564773) (xy 175.304119 -86.593827) (xy 175.25279 -86.615639)
			(xy 175.198833 -86.629745) (xy 175.143396 -86.635845) (xy 175.087662 -86.633808) (xy 175.032819 -86.623678)
			(xy 174.980035 -86.605671) (xy 174.930435 -86.58017) (xy 174.885077 -86.547719) (xy 174.844928 -86.50901)
			(xy 174.810842 -86.464867) (xy 174.783546 -86.416232) (xy 174.763623 -86.364141) (xy 174.751497 -86.309704)
			(xy 174.747426 -86.254082) (xy 173.826695 -86.254082) (xy 173.826677 -86.255044) (xy 173.818557 -86.31022)
			(xy 173.802489 -86.363627) (xy 173.778817 -86.414124) (xy 173.748044 -86.460637) (xy 173.710827 -86.502174)
			(xy 173.667959 -86.537849) (xy 173.620353 -86.566903) (xy 173.569024 -86.588715) (xy 173.515067 -86.602821)
			(xy 173.45963 -86.608921) (xy 173.403896 -86.606884) (xy 173.349053 -86.596754) (xy 173.296269 -86.578747)
			(xy 173.246669 -86.553246) (xy 173.201311 -86.520795) (xy 173.161162 -86.482086) (xy 173.127076 -86.437943)
			(xy 173.09978 -86.389308) (xy 173.079857 -86.337217) (xy 173.067731 -86.28278) (xy 173.06366 -86.227158)
			(xy 158.262143 -86.227158) (xy 158.987258 -95.261486) (xy 163.375394 -95.261486) (xy 163.375394 -95.168314)
			(xy 163.383515 -95.075496) (xy 163.399694 -94.983738) (xy 163.423808 -94.893741) (xy 163.455675 -94.806187)
			(xy 163.495052 -94.721744) (xy 163.541638 -94.641054) (xy 163.595079 -94.564731) (xy 163.654969 -94.493357)
			(xy 163.720852 -94.427473) (xy 163.792226 -94.367583) (xy 163.868549 -94.314141) (xy 163.949238 -94.267554)
			(xy 164.033681 -94.228178) (xy 164.121235 -94.19631) (xy 164.211233 -94.172195) (xy 164.30299 -94.156015)
			(xy 164.395808 -94.147894) (xy 164.442394 -94.147386) (xy 164.442648 -94.147386) (xy 164.489237 -94.1478)
			(xy 164.582061 -94.155925) (xy 164.673824 -94.172109) (xy 164.763826 -94.196229) (xy 164.851385 -94.228101)
			(xy 164.935832 -94.267483) (xy 165.016526 -94.314074) (xy 165.092852 -94.367522) (xy 165.164229 -94.427418)
			(xy 165.230115 -94.493306) (xy 165.290008 -94.564687) (xy 165.343451 -94.641015) (xy 165.390039 -94.721711)
			(xy 165.429417 -94.80616) (xy 165.461286 -94.893719) (xy 165.485401 -94.983723) (xy 165.501581 -95.075487)
			(xy 165.509702 -95.168311) (xy 165.509702 -95.261489) (xy 165.501581 -95.354313) (xy 165.485401 -95.446077)
			(xy 165.461286 -95.536081) (xy 165.430806 -95.619824) (xy 174.129952 -95.619824) (xy 174.134023 -95.564202)
			(xy 174.146149 -95.509765) (xy 174.166072 -95.457674) (xy 174.193368 -95.409039) (xy 174.227454 -95.364896)
			(xy 174.267603 -95.326187) (xy 174.312961 -95.293736) (xy 174.362561 -95.268235) (xy 174.415345 -95.250228)
			(xy 174.470188 -95.240098) (xy 174.525922 -95.238061) (xy 174.581359 -95.244161) (xy 174.635316 -95.258267)
			(xy 174.686645 -95.280079) (xy 174.734251 -95.309133) (xy 174.777119 -95.344808) (xy 174.814336 -95.386345)
			(xy 174.845109 -95.432858) (xy 174.868781 -95.483355) (xy 174.884849 -95.536762) (xy 174.892969 -95.591938)
			(xy 174.893478 -95.619824) (xy 174.892969 -95.64771) (xy 174.884849 -95.702886) (xy 174.868781 -95.756293)
			(xy 174.845109 -95.80679) (xy 174.814336 -95.853303) (xy 174.777119 -95.89484) (xy 174.734251 -95.930515)
			(xy 174.686645 -95.959569) (xy 174.635316 -95.981381) (xy 174.581359 -95.995487) (xy 174.525922 -96.001587)
			(xy 174.470188 -95.99955) (xy 174.415345 -95.98942) (xy 174.362561 -95.971413) (xy 174.312961 -95.945912)
			(xy 174.267603 -95.913461) (xy 174.227454 -95.874752) (xy 174.193368 -95.830609) (xy 174.166072 -95.781974)
			(xy 174.146149 -95.729883) (xy 174.134023 -95.675446) (xy 174.129952 -95.619824) (xy 165.430806 -95.619824)
			(xy 165.429417 -95.62364) (xy 165.390039 -95.708089) (xy 165.343451 -95.788785) (xy 165.290008 -95.865113)
			(xy 165.230115 -95.936494) (xy 165.164229 -96.002382) (xy 165.092852 -96.062278) (xy 165.016526 -96.115726)
			(xy 164.935832 -96.162317) (xy 164.851385 -96.201699) (xy 164.763826 -96.233571) (xy 164.673824 -96.257691)
			(xy 164.582061 -96.273875) (xy 164.489237 -96.282) (xy 164.442648 -96.28251) (xy 164.442394 -96.28251)
			(xy 164.395808 -96.281906) (xy 164.30299 -96.273785) (xy 164.211233 -96.257605) (xy 164.121235 -96.23349)
			(xy 164.033681 -96.201622) (xy 163.949238 -96.162246) (xy 163.868549 -96.115659) (xy 163.792226 -96.062217)
			(xy 163.720852 -96.002327) (xy 163.654969 -95.936443) (xy 163.595079 -95.865069) (xy 163.541638 -95.788746)
			(xy 163.495052 -95.708056) (xy 163.455675 -95.623613) (xy 163.423808 -95.536059) (xy 163.399694 -95.446062)
			(xy 163.383515 -95.354304) (xy 163.375394 -95.261486) (xy 158.987258 -95.261486) (xy 159.131265 -97.055686)
			(xy 167.705276 -97.055686) (xy 167.709347 -97.000064) (xy 167.721473 -96.945627) (xy 167.741396 -96.893536)
			(xy 167.768692 -96.844901) (xy 167.802778 -96.800758) (xy 167.842927 -96.762049) (xy 167.888285 -96.729598)
			(xy 167.937885 -96.704097) (xy 167.990669 -96.68609) (xy 168.045512 -96.67596) (xy 168.101246 -96.673923)
			(xy 168.156683 -96.680023) (xy 168.21064 -96.694129) (xy 168.261969 -96.715941) (xy 168.309575 -96.744995)
			(xy 168.352443 -96.78067) (xy 168.38966 -96.822207) (xy 168.420433 -96.86872) (xy 168.444105 -96.919217)
			(xy 168.460173 -96.972624) (xy 168.468293 -97.0278) (xy 168.468802 -97.055686) (xy 168.468293 -97.083572)
			(xy 168.460173 -97.138748) (xy 168.444105 -97.192155) (xy 168.420433 -97.242652) (xy 168.38966 -97.289165)
			(xy 168.352443 -97.330702) (xy 168.309575 -97.366377) (xy 168.261969 -97.395431) (xy 168.21064 -97.417243)
			(xy 168.156683 -97.431349) (xy 168.101246 -97.437449) (xy 168.045512 -97.435412) (xy 167.990669 -97.425282)
			(xy 167.937885 -97.407275) (xy 167.888285 -97.381774) (xy 167.842927 -97.349323) (xy 167.802778 -97.310614)
			(xy 167.768692 -97.266471) (xy 167.741396 -97.217836) (xy 167.721473 -97.165745) (xy 167.709347 -97.111308)
			(xy 167.705276 -97.055686) (xy 159.131265 -97.055686) (xy 159.381735 -100.17633) (xy 169.739056 -100.17633)
			(xy 169.739056 -99.31273) (xy 169.739546 -99.282746) (xy 169.747374 -99.22329) (xy 169.762895 -99.165365)
			(xy 169.785844 -99.109961) (xy 169.815828 -99.058027) (xy 169.852334 -99.010451) (xy 169.894739 -98.968046)
			(xy 169.942315 -98.93154) (xy 169.994249 -98.901556) (xy 170.049653 -98.878607) (xy 170.107578 -98.863086)
			(xy 170.167034 -98.855258) (xy 170.227002 -98.855258) (xy 170.286458 -98.863086) (xy 170.344383 -98.878607)
			(xy 170.399787 -98.901556) (xy 170.451721 -98.93154) (xy 170.499297 -98.968046) (xy 170.541702 -99.010451)
			(xy 170.578208 -99.058027) (xy 170.608192 -99.109961) (xy 170.631141 -99.165365) (xy 170.646662 -99.22329)
			(xy 170.65449 -99.282746) (xy 170.65498 -99.31273) (xy 170.65498 -100.17633) (xy 170.65449 -100.206314)
			(xy 170.646662 -100.26577) (xy 170.631141 -100.323695) (xy 170.608192 -100.379099) (xy 170.578208 -100.431033)
			(xy 170.541702 -100.478609) (xy 170.499297 -100.521014) (xy 170.451721 -100.55752) (xy 170.399787 -100.587504)
			(xy 170.344383 -100.610453) (xy 170.286458 -100.625974) (xy 170.227002 -100.633802) (xy 170.167034 -100.633802)
			(xy 170.107578 -100.625974) (xy 170.049653 -100.610453) (xy 169.994249 -100.587504) (xy 169.942315 -100.55752)
			(xy 169.894739 -100.521014) (xy 169.852334 -100.478609) (xy 169.815828 -100.431033) (xy 169.785844 -100.379099)
			(xy 169.762895 -100.323695) (xy 169.747374 -100.26577) (xy 169.739546 -100.206314) (xy 169.739056 -100.17633)
			(xy 159.381735 -100.17633) (xy 159.526215 -101.976428) (xy 167.884856 -101.976428) (xy 167.884856 -101.112828)
			(xy 167.885346 -101.082844) (xy 167.893174 -101.023388) (xy 167.908695 -100.965463) (xy 167.931644 -100.910059)
			(xy 167.961628 -100.858125) (xy 167.998134 -100.810549) (xy 168.040539 -100.768144) (xy 168.088115 -100.731638)
			(xy 168.140049 -100.701654) (xy 168.195453 -100.678705) (xy 168.253378 -100.663184) (xy 168.312834 -100.655356)
			(xy 168.372802 -100.655356) (xy 168.432258 -100.663184) (xy 168.490183 -100.678705) (xy 168.545587 -100.701654)
			(xy 168.597521 -100.731638) (xy 168.642788 -100.766372) (xy 173.697644 -100.766372) (xy 173.701715 -100.71075)
			(xy 173.713841 -100.656313) (xy 173.733764 -100.604222) (xy 173.76106 -100.555587) (xy 173.795146 -100.511444)
			(xy 173.835295 -100.472735) (xy 173.880653 -100.440284) (xy 173.930253 -100.414783) (xy 173.983037 -100.396776)
			(xy 174.03788 -100.386646) (xy 174.093614 -100.384609) (xy 174.149051 -100.390709) (xy 174.203008 -100.404815)
			(xy 174.254337 -100.426627) (xy 174.301943 -100.455681) (xy 174.344811 -100.491356) (xy 174.382028 -100.532893)
			(xy 174.412801 -100.579406) (xy 174.436473 -100.629903) (xy 174.452541 -100.68331) (xy 174.460661 -100.738486)
			(xy 174.46117 -100.766372) (xy 174.460661 -100.794258) (xy 174.452541 -100.849434) (xy 174.436473 -100.902841)
			(xy 174.412801 -100.953338) (xy 174.382028 -100.999851) (xy 174.344811 -101.041388) (xy 174.301943 -101.077063)
			(xy 174.254337 -101.106117) (xy 174.203008 -101.127929) (xy 174.149051 -101.142035) (xy 174.093614 -101.148135)
			(xy 174.03788 -101.146098) (xy 173.983037 -101.135968) (xy 173.930253 -101.117961) (xy 173.880653 -101.09246)
			(xy 173.835295 -101.060009) (xy 173.795146 -101.0213) (xy 173.76106 -100.977157) (xy 173.733764 -100.928522)
			(xy 173.713841 -100.876431) (xy 173.701715 -100.821994) (xy 173.697644 -100.766372) (xy 168.642788 -100.766372)
			(xy 168.645097 -100.768144) (xy 168.687502 -100.810549) (xy 168.724008 -100.858125) (xy 168.753992 -100.910059)
			(xy 168.776941 -100.965463) (xy 168.792462 -101.023388) (xy 168.80029 -101.082844) (xy 168.80078 -101.112828)
			(xy 168.80078 -101.976428) (xy 168.80029 -102.006412) (xy 168.792462 -102.065868) (xy 168.776941 -102.123793)
			(xy 168.753992 -102.179197) (xy 168.724008 -102.231131) (xy 168.687502 -102.278707) (xy 168.645097 -102.321112)
			(xy 168.597521 -102.357618) (xy 168.545587 -102.387602) (xy 168.490183 -102.410551) (xy 168.432258 -102.426072)
			(xy 168.372802 -102.4339) (xy 168.312834 -102.4339) (xy 168.253378 -102.426072) (xy 168.195453 -102.410551)
			(xy 168.140049 -102.387602) (xy 168.088115 -102.357618) (xy 168.040539 -102.321112) (xy 167.998134 -102.278707)
			(xy 167.961628 -102.231131) (xy 167.931644 -102.179197) (xy 167.908695 -102.123793) (xy 167.893174 -102.065868)
			(xy 167.885346 -102.006412) (xy 167.884856 -101.976428) (xy 159.526215 -101.976428) (xy 159.670674 -103.776272)
			(xy 169.739056 -103.776272) (xy 169.739056 -102.912672) (xy 169.739546 -102.882688) (xy 169.747374 -102.823232)
			(xy 169.762895 -102.765307) (xy 169.785844 -102.709903) (xy 169.815828 -102.657969) (xy 169.852334 -102.610393)
			(xy 169.894739 -102.567988) (xy 169.942315 -102.531482) (xy 169.994249 -102.501498) (xy 170.049653 -102.478549)
			(xy 170.107578 -102.463028) (xy 170.167034 -102.4552) (xy 170.227002 -102.4552) (xy 170.286458 -102.463028)
			(xy 170.344383 -102.478549) (xy 170.399787 -102.501498) (xy 170.451721 -102.531482) (xy 170.499297 -102.567988)
			(xy 170.541702 -102.610393) (xy 170.578208 -102.657969) (xy 170.608192 -102.709903) (xy 170.631141 -102.765307)
			(xy 170.646662 -102.823232) (xy 170.65449 -102.882688) (xy 170.65498 -102.912672) (xy 170.65498 -103.776272)
			(xy 170.65449 -103.806256) (xy 170.646662 -103.865712) (xy 170.631141 -103.923637) (xy 170.608192 -103.979041)
			(xy 170.578208 -104.030975) (xy 170.541702 -104.078551) (xy 170.499297 -104.120956) (xy 170.451721 -104.157462)
			(xy 170.399787 -104.187446) (xy 170.344383 -104.210395) (xy 170.286458 -104.225916) (xy 170.227002 -104.233744)
			(xy 170.167034 -104.233744) (xy 170.107578 -104.225916) (xy 170.049653 -104.210395) (xy 169.994249 -104.187446)
			(xy 169.942315 -104.157462) (xy 169.894739 -104.120956) (xy 169.852334 -104.078551) (xy 169.815828 -104.030975)
			(xy 169.785844 -103.979041) (xy 169.762895 -103.923637) (xy 169.747374 -103.865712) (xy 169.739546 -103.806256)
			(xy 169.739056 -103.776272) (xy 159.670674 -103.776272) (xy 159.70631 -104.220264) (xy 159.709104 -104.269794)
			(xy 159.748717 -105.57637) (xy 167.884856 -105.57637) (xy 167.884856 -104.71277) (xy 167.885346 -104.682786)
			(xy 167.893174 -104.62333) (xy 167.908695 -104.565405) (xy 167.931644 -104.510001) (xy 167.961628 -104.458067)
			(xy 167.998134 -104.410491) (xy 168.040539 -104.368086) (xy 168.088115 -104.33158) (xy 168.140049 -104.301596)
			(xy 168.195453 -104.278647) (xy 168.253378 -104.263126) (xy 168.312834 -104.255298) (xy 168.372802 -104.255298)
			(xy 168.432258 -104.263126) (xy 168.490183 -104.278647) (xy 168.545587 -104.301596) (xy 168.597521 -104.33158)
			(xy 168.645097 -104.368086) (xy 168.687502 -104.410491) (xy 168.724008 -104.458067) (xy 168.753992 -104.510001)
			(xy 168.776941 -104.565405) (xy 168.792462 -104.62333) (xy 168.80029 -104.682786) (xy 168.80078 -104.71277)
			(xy 168.80078 -105.57637) (xy 168.80029 -105.606354) (xy 168.792462 -105.66581) (xy 168.776941 -105.723735)
			(xy 168.753992 -105.779139) (xy 168.724008 -105.831073) (xy 168.687502 -105.878649) (xy 168.645097 -105.921054)
			(xy 168.597521 -105.95756) (xy 168.545587 -105.987544) (xy 168.490183 -106.010493) (xy 168.432258 -106.026014)
			(xy 168.372802 -106.033842) (xy 168.312834 -106.033842) (xy 168.253378 -106.026014) (xy 168.195453 -106.010493)
			(xy 168.140049 -105.987544) (xy 168.088115 -105.95756) (xy 168.040539 -105.921054) (xy 167.998134 -105.878649)
			(xy 167.961628 -105.831073) (xy 167.931644 -105.779139) (xy 167.908695 -105.723735) (xy 167.893174 -105.66581)
			(xy 167.885346 -105.606354) (xy 167.884856 -105.57637) (xy 159.748717 -105.57637) (xy 159.803285 -107.376214)
			(xy 169.739056 -107.376214) (xy 169.739056 -106.512614) (xy 169.739546 -106.48263) (xy 169.747374 -106.423174)
			(xy 169.762895 -106.365249) (xy 169.785844 -106.309845) (xy 169.815828 -106.257911) (xy 169.852334 -106.210335)
			(xy 169.894739 -106.16793) (xy 169.942315 -106.131424) (xy 169.994249 -106.10144) (xy 170.049653 -106.078491)
			(xy 170.107578 -106.06297) (xy 170.167034 -106.055142) (xy 170.227002 -106.055142) (xy 170.286458 -106.06297)
			(xy 170.344383 -106.078491) (xy 170.399787 -106.10144) (xy 170.451721 -106.131424) (xy 170.499297 -106.16793)
			(xy 170.541702 -106.210335) (xy 170.578208 -106.257911) (xy 170.608192 -106.309845) (xy 170.631141 -106.365249)
			(xy 170.646662 -106.423174) (xy 170.65449 -106.48263) (xy 170.65498 -106.512614) (xy 170.65498 -107.376214)
			(xy 170.65449 -107.406198) (xy 170.646662 -107.465654) (xy 170.631141 -107.523579) (xy 170.608192 -107.578983)
			(xy 170.578208 -107.630917) (xy 170.541702 -107.678493) (xy 170.499297 -107.720898) (xy 170.451721 -107.757404)
			(xy 170.399787 -107.787388) (xy 170.344383 -107.810337) (xy 170.286458 -107.825858) (xy 170.227002 -107.833686)
			(xy 170.167034 -107.833686) (xy 170.107578 -107.825858) (xy 170.049653 -107.810337) (xy 169.994249 -107.787388)
			(xy 169.942315 -107.757404) (xy 169.894739 -107.720898) (xy 169.852334 -107.678493) (xy 169.815828 -107.630917)
			(xy 169.785844 -107.578983) (xy 169.762895 -107.523579) (xy 169.747374 -107.465654) (xy 169.739546 -107.406198)
			(xy 169.739056 -107.376214) (xy 159.803285 -107.376214) (xy 159.857861 -109.176312) (xy 167.884856 -109.176312)
			(xy 167.884856 -108.312712) (xy 167.885346 -108.282728) (xy 167.893174 -108.223272) (xy 167.908695 -108.165347)
			(xy 167.931644 -108.109943) (xy 167.961628 -108.058009) (xy 167.998134 -108.010433) (xy 168.040539 -107.968028)
			(xy 168.088115 -107.931522) (xy 168.140049 -107.901538) (xy 168.195453 -107.878589) (xy 168.253378 -107.863068)
			(xy 168.312834 -107.85524) (xy 168.372802 -107.85524) (xy 168.432258 -107.863068) (xy 168.490183 -107.878589)
			(xy 168.545587 -107.901538) (xy 168.597521 -107.931522) (xy 168.645097 -107.968028) (xy 168.687502 -108.010433)
			(xy 168.724008 -108.058009) (xy 168.753992 -108.109943) (xy 168.776941 -108.165347) (xy 168.792462 -108.223272)
			(xy 168.80029 -108.282728) (xy 168.80078 -108.312712) (xy 168.80078 -109.176312) (xy 168.80029 -109.206296)
			(xy 168.792462 -109.265752) (xy 168.776941 -109.323677) (xy 168.753992 -109.379081) (xy 168.724008 -109.431015)
			(xy 168.687502 -109.478591) (xy 168.645097 -109.520996) (xy 168.597521 -109.557502) (xy 168.545587 -109.587486)
			(xy 168.490183 -109.610435) (xy 168.432258 -109.625956) (xy 168.372802 -109.633784) (xy 168.312834 -109.633784)
			(xy 168.253378 -109.625956) (xy 168.195453 -109.610435) (xy 168.140049 -109.587486) (xy 168.088115 -109.557502)
			(xy 168.040539 -109.520996) (xy 167.998134 -109.478591) (xy 167.961628 -109.431015) (xy 167.931644 -109.379081)
			(xy 167.908695 -109.323677) (xy 167.893174 -109.265752) (xy 167.885346 -109.206296) (xy 167.884856 -109.176312)
			(xy 159.857861 -109.176312) (xy 159.912437 -110.97641) (xy 169.739056 -110.97641) (xy 169.739056 -110.11281)
			(xy 169.739546 -110.082826) (xy 169.747374 -110.02337) (xy 169.762895 -109.965445) (xy 169.785844 -109.910041)
			(xy 169.815828 -109.858107) (xy 169.852334 -109.810531) (xy 169.894739 -109.768126) (xy 169.942315 -109.73162)
			(xy 169.994249 -109.701636) (xy 170.049653 -109.678687) (xy 170.107578 -109.663166) (xy 170.167034 -109.655338)
			(xy 170.227002 -109.655338) (xy 170.286458 -109.663166) (xy 170.344383 -109.678687) (xy 170.399787 -109.701636)
			(xy 170.451721 -109.73162) (xy 170.499297 -109.768126) (xy 170.541702 -109.810531) (xy 170.578208 -109.858107)
			(xy 170.608192 -109.910041) (xy 170.631141 -109.965445) (xy 170.646662 -110.02337) (xy 170.65449 -110.082826)
			(xy 170.65498 -110.11281) (xy 170.65498 -110.97641) (xy 170.65449 -111.006394) (xy 170.646662 -111.06585)
			(xy 170.631141 -111.123775) (xy 170.608192 -111.179179) (xy 170.578208 -111.231113) (xy 170.541702 -111.278689)
			(xy 170.499297 -111.321094) (xy 170.451721 -111.3576) (xy 170.399787 -111.387584) (xy 170.344383 -111.410533)
			(xy 170.286458 -111.426054) (xy 170.227002 -111.433882) (xy 170.167034 -111.433882) (xy 170.107578 -111.426054)
			(xy 170.049653 -111.410533) (xy 169.994249 -111.387584) (xy 169.942315 -111.3576) (xy 169.894739 -111.321094)
			(xy 169.852334 -111.278689) (xy 169.815828 -111.231113) (xy 169.785844 -111.179179) (xy 169.762895 -111.123775)
			(xy 169.747374 -111.06585) (xy 169.739546 -111.006394) (xy 169.739056 -110.97641) (xy 159.912437 -110.97641)
			(xy 159.967012 -112.776508) (xy 167.884856 -112.776508) (xy 167.884856 -111.912908) (xy 167.885346 -111.882924)
			(xy 167.893174 -111.823468) (xy 167.908695 -111.765543) (xy 167.931644 -111.710139) (xy 167.961628 -111.658205)
			(xy 167.998134 -111.610629) (xy 168.040539 -111.568224) (xy 168.088115 -111.531718) (xy 168.140049 -111.501734)
			(xy 168.195453 -111.478785) (xy 168.253378 -111.463264) (xy 168.312834 -111.455436) (xy 168.372802 -111.455436)
			(xy 168.432258 -111.463264) (xy 168.490183 -111.478785) (xy 168.545587 -111.501734) (xy 168.597521 -111.531718)
			(xy 168.645097 -111.568224) (xy 168.687502 -111.610629) (xy 168.724008 -111.658205) (xy 168.753992 -111.710139)
			(xy 168.776941 -111.765543) (xy 168.792462 -111.823468) (xy 168.80029 -111.882924) (xy 168.80078 -111.912908)
			(xy 168.80078 -112.776508) (xy 168.80029 -112.806492) (xy 168.792462 -112.865948) (xy 168.776941 -112.923873)
			(xy 168.753992 -112.979277) (xy 168.724008 -113.031211) (xy 168.687502 -113.078787) (xy 168.645097 -113.121192)
			(xy 168.597521 -113.157698) (xy 168.545587 -113.187682) (xy 168.490183 -113.210631) (xy 168.432258 -113.226152)
			(xy 168.372802 -113.23398) (xy 168.312834 -113.23398) (xy 168.253378 -113.226152) (xy 168.195453 -113.210631)
			(xy 168.140049 -113.187682) (xy 168.088115 -113.157698) (xy 168.040539 -113.121192) (xy 167.998134 -113.078787)
			(xy 167.961628 -113.031211) (xy 167.931644 -112.979277) (xy 167.908695 -112.923873) (xy 167.893174 -112.865948)
			(xy 167.885346 -112.806492) (xy 167.884856 -112.776508) (xy 159.967012 -112.776508) (xy 160.05926 -115.819174)
			(xy 171.947076 -115.819174) (xy 171.951147 -115.763552) (xy 171.963273 -115.709115) (xy 171.983196 -115.657024)
			(xy 172.010492 -115.608389) (xy 172.044578 -115.564246) (xy 172.084727 -115.525537) (xy 172.130085 -115.493086)
			(xy 172.179685 -115.467585) (xy 172.232469 -115.449578) (xy 172.287312 -115.439448) (xy 172.343046 -115.437411)
			(xy 172.398483 -115.443511) (xy 172.45244 -115.457617) (xy 172.503769 -115.479429) (xy 172.551375 -115.508483)
			(xy 172.594243 -115.544158) (xy 172.63146 -115.585695) (xy 172.662233 -115.632208) (xy 172.685905 -115.682705)
			(xy 172.701973 -115.736112) (xy 172.710093 -115.791288) (xy 172.710602 -115.819174) (xy 172.710093 -115.84706)
			(xy 172.701973 -115.902236) (xy 172.685905 -115.955643) (xy 172.662233 -116.00614) (xy 172.63146 -116.052653)
			(xy 172.594243 -116.09419) (xy 172.551375 -116.129865) (xy 172.503769 -116.158919) (xy 172.45244 -116.180731)
			(xy 172.398483 -116.194837) (xy 172.343046 -116.200937) (xy 172.287312 -116.1989) (xy 172.232469 -116.18877)
			(xy 172.179685 -116.170763) (xy 172.130085 -116.145262) (xy 172.084727 -116.112811) (xy 172.044578 -116.074102)
			(xy 172.010492 -116.029959) (xy 171.983196 -115.981324) (xy 171.963273 -115.929233) (xy 171.951147 -115.874796)
			(xy 171.947076 -115.819174) (xy 160.05926 -115.819174) (xy 160.133419 -118.265194) (xy 171.12818 -118.265194)
			(xy 171.132251 -118.209572) (xy 171.144377 -118.155135) (xy 171.1643 -118.103044) (xy 171.191596 -118.054409)
			(xy 171.225682 -118.010266) (xy 171.265831 -117.971557) (xy 171.311189 -117.939106) (xy 171.360789 -117.913605)
			(xy 171.413573 -117.895598) (xy 171.468416 -117.885468) (xy 171.52415 -117.883431) (xy 171.579587 -117.889531)
			(xy 171.633544 -117.903637) (xy 171.684873 -117.925449) (xy 171.732479 -117.954503) (xy 171.775347 -117.990178)
			(xy 171.812564 -118.031715) (xy 171.843337 -118.078228) (xy 171.867009 -118.128725) (xy 171.883077 -118.182132)
			(xy 171.891197 -118.237308) (xy 171.891706 -118.265194) (xy 171.891197 -118.29308) (xy 171.883077 -118.348256)
			(xy 171.867009 -118.401663) (xy 171.843337 -118.45216) (xy 171.812564 -118.498673) (xy 171.775347 -118.54021)
			(xy 171.732479 -118.575885) (xy 171.684873 -118.604939) (xy 171.633544 -118.626751) (xy 171.579587 -118.640857)
			(xy 171.52415 -118.646957) (xy 171.468416 -118.64492) (xy 171.413573 -118.63479) (xy 171.360789 -118.616783)
			(xy 171.311189 -118.591282) (xy 171.265831 -118.558831) (xy 171.225682 -118.520122) (xy 171.191596 -118.475979)
			(xy 171.1643 -118.427344) (xy 171.144377 -118.375253) (xy 171.132251 -118.320816) (xy 171.12818 -118.265194)
			(xy 160.133419 -118.265194) (xy 160.171892 -119.534178) (xy 160.1724 -119.563896) (xy 160.1724 -119.564912)
			(xy 160.172146 -119.574564) (xy 160.172146 -119.575072) (xy 160.166654 -120.086374) (xy 169.739056 -120.086374)
			(xy 169.739056 -119.222774) (xy 169.739546 -119.19279) (xy 169.747374 -119.133334) (xy 169.762895 -119.075409)
			(xy 169.785844 -119.020005) (xy 169.815828 -118.968071) (xy 169.852334 -118.920495) (xy 169.894739 -118.87809)
			(xy 169.942315 -118.841584) (xy 169.994249 -118.8116) (xy 170.049653 -118.788651) (xy 170.107578 -118.77313)
			(xy 170.167034 -118.765302) (xy 170.227002 -118.765302) (xy 170.286458 -118.77313) (xy 170.344383 -118.788651)
			(xy 170.399787 -118.8116) (xy 170.451721 -118.841584) (xy 170.499297 -118.87809) (xy 170.541702 -118.920495)
			(xy 170.578208 -118.968071) (xy 170.608192 -119.020005) (xy 170.631141 -119.075409) (xy 170.646662 -119.133334)
			(xy 170.65449 -119.19279) (xy 170.65498 -119.222774) (xy 170.65498 -120.086374) (xy 170.65449 -120.116358)
			(xy 170.646662 -120.175814) (xy 170.631141 -120.233739) (xy 170.608192 -120.289143) (xy 170.578208 -120.341077)
			(xy 170.541702 -120.388653) (xy 170.499297 -120.431058) (xy 170.451721 -120.467564) (xy 170.399787 -120.497548)
			(xy 170.344383 -120.520497) (xy 170.286458 -120.536018) (xy 170.227002 -120.543846) (xy 170.167034 -120.543846)
			(xy 170.107578 -120.536018) (xy 170.049653 -120.520497) (xy 169.994249 -120.497548) (xy 169.942315 -120.467564)
			(xy 169.894739 -120.431058) (xy 169.852334 -120.388653) (xy 169.815828 -120.341077) (xy 169.785844 -120.289143)
			(xy 169.762895 -120.233739) (xy 169.747374 -120.175814) (xy 169.739546 -120.116358) (xy 169.739056 -120.086374)
			(xy 160.166654 -120.086374) (xy 160.147321 -121.886472) (xy 167.884856 -121.886472) (xy 167.884856 -121.022872)
			(xy 167.885346 -120.992888) (xy 167.893174 -120.933432) (xy 167.908695 -120.875507) (xy 167.931644 -120.820103)
			(xy 167.961628 -120.768169) (xy 167.998134 -120.720593) (xy 168.040539 -120.678188) (xy 168.088115 -120.641682)
			(xy 168.140049 -120.611698) (xy 168.195453 -120.588749) (xy 168.253378 -120.573228) (xy 168.312834 -120.5654)
			(xy 168.372802 -120.5654) (xy 168.432258 -120.573228) (xy 168.490183 -120.588749) (xy 168.545587 -120.611698)
			(xy 168.597521 -120.641682) (xy 168.645097 -120.678188) (xy 168.687502 -120.720593) (xy 168.724008 -120.768169)
			(xy 168.753992 -120.820103) (xy 168.776941 -120.875507) (xy 168.792462 -120.933432) (xy 168.80029 -120.992888)
			(xy 168.80078 -121.022872) (xy 168.80078 -121.886472) (xy 168.80029 -121.916456) (xy 168.792462 -121.975912)
			(xy 168.776941 -122.033837) (xy 168.753992 -122.089241) (xy 168.724008 -122.141175) (xy 168.687502 -122.188751)
			(xy 168.645097 -122.231156) (xy 168.597521 -122.267662) (xy 168.545587 -122.297646) (xy 168.490183 -122.320595)
			(xy 168.432258 -122.336116) (xy 168.372802 -122.343944) (xy 168.312834 -122.343944) (xy 168.253378 -122.336116)
			(xy 168.195453 -122.320595) (xy 168.140049 -122.297646) (xy 168.088115 -122.267662) (xy 168.040539 -122.231156)
			(xy 167.998134 -122.188751) (xy 167.961628 -122.141175) (xy 167.931644 -122.089241) (xy 167.908695 -122.033837)
			(xy 167.893174 -121.975912) (xy 167.885346 -121.916456) (xy 167.884856 -121.886472) (xy 160.147321 -121.886472)
			(xy 160.12799 -123.686316) (xy 169.739056 -123.686316) (xy 169.739056 -122.822716) (xy 169.739546 -122.792732)
			(xy 169.747374 -122.733276) (xy 169.762895 -122.675351) (xy 169.785844 -122.619947) (xy 169.815828 -122.568013)
			(xy 169.852334 -122.520437) (xy 169.894739 -122.478032) (xy 169.942315 -122.441526) (xy 169.994249 -122.411542)
			(xy 170.049653 -122.388593) (xy 170.107578 -122.373072) (xy 170.167034 -122.365244) (xy 170.227002 -122.365244)
			(xy 170.286458 -122.373072) (xy 170.344383 -122.388593) (xy 170.399787 -122.411542) (xy 170.451721 -122.441526)
			(xy 170.499297 -122.478032) (xy 170.541702 -122.520437) (xy 170.578208 -122.568013) (xy 170.608192 -122.619947)
			(xy 170.631141 -122.675351) (xy 170.646662 -122.733276) (xy 170.65449 -122.792732) (xy 170.65498 -122.822716)
			(xy 170.65498 -123.686316) (xy 170.65449 -123.7163) (xy 170.646662 -123.775756) (xy 170.631141 -123.833681)
			(xy 170.608192 -123.889085) (xy 170.578208 -123.941019) (xy 170.541702 -123.988595) (xy 170.499297 -124.031)
			(xy 170.451721 -124.067506) (xy 170.399787 -124.09749) (xy 170.344383 -124.120439) (xy 170.286458 -124.13596)
			(xy 170.227002 -124.143788) (xy 170.167034 -124.143788) (xy 170.107578 -124.13596) (xy 170.049653 -124.120439)
			(xy 169.994249 -124.09749) (xy 169.942315 -124.067506) (xy 169.894739 -124.031) (xy 169.852334 -123.988595)
			(xy 169.815828 -123.941019) (xy 169.785844 -123.889085) (xy 169.762895 -123.833681) (xy 169.747374 -123.775756)
			(xy 169.739546 -123.7163) (xy 169.739056 -123.686316) (xy 160.12799 -123.686316) (xy 160.117536 -124.659644)
			(xy 160.108619 -125.486414) (xy 167.884856 -125.486414) (xy 167.884856 -124.622814) (xy 167.885346 -124.59283)
			(xy 167.893174 -124.533374) (xy 167.908695 -124.475449) (xy 167.931644 -124.420045) (xy 167.961628 -124.368111)
			(xy 167.998134 -124.320535) (xy 168.040539 -124.27813) (xy 168.088115 -124.241624) (xy 168.140049 -124.21164)
			(xy 168.195453 -124.188691) (xy 168.253378 -124.17317) (xy 168.312834 -124.165342) (xy 168.372802 -124.165342)
			(xy 168.432258 -124.17317) (xy 168.490183 -124.188691) (xy 168.545587 -124.21164) (xy 168.597521 -124.241624)
			(xy 168.645097 -124.27813) (xy 168.687502 -124.320535) (xy 168.724008 -124.368111) (xy 168.753992 -124.420045)
			(xy 168.776941 -124.475449) (xy 168.792462 -124.533374) (xy 168.80029 -124.59283) (xy 168.80078 -124.622814)
			(xy 168.80078 -125.486414) (xy 168.80029 -125.516398) (xy 168.792462 -125.575854) (xy 168.776941 -125.633779)
			(xy 168.753992 -125.689183) (xy 168.724008 -125.741117) (xy 168.687502 -125.788693) (xy 168.645097 -125.831098)
			(xy 168.597521 -125.867604) (xy 168.545587 -125.897588) (xy 168.490183 -125.920537) (xy 168.432258 -125.936058)
			(xy 168.372802 -125.943886) (xy 168.312834 -125.943886) (xy 168.253378 -125.936058) (xy 168.195453 -125.920537)
			(xy 168.140049 -125.897588) (xy 168.088115 -125.867604) (xy 168.040539 -125.831098) (xy 167.998134 -125.788693)
			(xy 167.961628 -125.741117) (xy 167.931644 -125.689183) (xy 167.908695 -125.633779) (xy 167.893174 -125.575854)
			(xy 167.885346 -125.516398) (xy 167.884856 -125.486414) (xy 160.108619 -125.486414) (xy 160.045953 -131.29641)
			(xy 169.739056 -131.29641) (xy 169.739056 -130.43281) (xy 169.739546 -130.402826) (xy 169.747374 -130.34337)
			(xy 169.762895 -130.285445) (xy 169.785844 -130.230041) (xy 169.815828 -130.178107) (xy 169.852334 -130.130531)
			(xy 169.894739 -130.088126) (xy 169.942315 -130.05162) (xy 169.994249 -130.021636) (xy 170.049653 -129.998687)
			(xy 170.107578 -129.983166) (xy 170.167034 -129.975338) (xy 170.227002 -129.975338) (xy 170.286458 -129.983166)
			(xy 170.344383 -129.998687) (xy 170.399787 -130.021636) (xy 170.451721 -130.05162) (xy 170.499297 -130.088126)
			(xy 170.541702 -130.130531) (xy 170.578208 -130.178107) (xy 170.608192 -130.230041) (xy 170.631141 -130.285445)
			(xy 170.646662 -130.34337) (xy 170.65449 -130.402826) (xy 170.65498 -130.43281) (xy 170.65498 -131.29641)
			(xy 170.65449 -131.326394) (xy 170.646662 -131.38585) (xy 170.631141 -131.443775) (xy 170.608192 -131.499179)
			(xy 170.578208 -131.551113) (xy 170.541702 -131.598689) (xy 170.499297 -131.641094) (xy 170.451721 -131.6776)
			(xy 170.399787 -131.707584) (xy 170.344383 -131.730533) (xy 170.286458 -131.746054) (xy 170.227002 -131.753882)
			(xy 170.167034 -131.753882) (xy 170.107578 -131.746054) (xy 170.049653 -131.730533) (xy 169.994249 -131.707584)
			(xy 169.942315 -131.6776) (xy 169.894739 -131.641094) (xy 169.852334 -131.598689) (xy 169.815828 -131.551113)
			(xy 169.785844 -131.499179) (xy 169.762895 -131.443775) (xy 169.747374 -131.38585) (xy 169.739546 -131.326394)
			(xy 169.739056 -131.29641) (xy 160.045953 -131.29641) (xy 160.0454 -131.347718) (xy 160.026582 -133.096508)
			(xy 167.884856 -133.096508) (xy 167.884856 -132.232908) (xy 167.885346 -132.202924) (xy 167.893174 -132.143468)
			(xy 167.908695 -132.085543) (xy 167.931644 -132.030139) (xy 167.961628 -131.978205) (xy 167.998134 -131.930629)
			(xy 168.040539 -131.888224) (xy 168.088115 -131.851718) (xy 168.140049 -131.821734) (xy 168.195453 -131.798785)
			(xy 168.253378 -131.783264) (xy 168.312834 -131.775436) (xy 168.372802 -131.775436) (xy 168.432258 -131.783264)
			(xy 168.490183 -131.798785) (xy 168.545587 -131.821734) (xy 168.597521 -131.851718) (xy 168.645097 -131.888224)
			(xy 168.687502 -131.930629) (xy 168.724008 -131.978205) (xy 168.753992 -132.030139) (xy 168.776941 -132.085543)
			(xy 168.792462 -132.143468) (xy 168.80029 -132.202924) (xy 168.80078 -132.232908) (xy 168.80078 -133.096508)
			(xy 168.80029 -133.126492) (xy 168.792462 -133.185948) (xy 168.776941 -133.243873) (xy 168.753992 -133.299277)
			(xy 168.724008 -133.351211) (xy 168.687502 -133.398787) (xy 168.645097 -133.441192) (xy 168.597521 -133.477698)
			(xy 168.545587 -133.507682) (xy 168.490183 -133.530631) (xy 168.432258 -133.546152) (xy 168.372802 -133.55398)
			(xy 168.312834 -133.55398) (xy 168.253378 -133.546152) (xy 168.195453 -133.530631) (xy 168.140049 -133.507682)
			(xy 168.088115 -133.477698) (xy 168.040539 -133.441192) (xy 167.998134 -133.398787) (xy 167.961628 -133.351211)
			(xy 167.931644 -133.299277) (xy 167.908695 -133.243873) (xy 167.893174 -133.185948) (xy 167.885346 -133.126492)
			(xy 167.884856 -133.096508) (xy 160.026582 -133.096508) (xy 160.007215 -134.896352) (xy 169.739056 -134.896352)
			(xy 169.739056 -134.032752) (xy 169.739546 -134.002768) (xy 169.747374 -133.943312) (xy 169.762895 -133.885387)
			(xy 169.785844 -133.829983) (xy 169.815828 -133.778049) (xy 169.852334 -133.730473) (xy 169.894739 -133.688068)
			(xy 169.942315 -133.651562) (xy 169.994249 -133.621578) (xy 170.049653 -133.598629) (xy 170.107578 -133.583108)
			(xy 170.167034 -133.57528) (xy 170.227002 -133.57528) (xy 170.286458 -133.583108) (xy 170.344383 -133.598629)
			(xy 170.399787 -133.621578) (xy 170.451721 -133.651562) (xy 170.499297 -133.688068) (xy 170.541702 -133.730473)
			(xy 170.578208 -133.778049) (xy 170.608192 -133.829983) (xy 170.631141 -133.885387) (xy 170.646662 -133.943312)
			(xy 170.65449 -134.002768) (xy 170.65498 -134.032752) (xy 170.65498 -134.896352) (xy 170.65449 -134.926336)
			(xy 170.646662 -134.985792) (xy 170.631141 -135.043717) (xy 170.608192 -135.099121) (xy 170.578208 -135.151055)
			(xy 170.541702 -135.198631) (xy 170.499297 -135.241036) (xy 170.451721 -135.277542) (xy 170.399787 -135.307526)
			(xy 170.344383 -135.330475) (xy 170.286458 -135.345996) (xy 170.227002 -135.353824) (xy 170.167034 -135.353824)
			(xy 170.107578 -135.345996) (xy 170.049653 -135.330475) (xy 169.994249 -135.307526) (xy 169.942315 -135.277542)
			(xy 169.894739 -135.241036) (xy 169.852334 -135.198631) (xy 169.815828 -135.151055) (xy 169.785844 -135.099121)
			(xy 169.762895 -135.043717) (xy 169.747374 -134.985792) (xy 169.739546 -134.926336) (xy 169.739056 -134.896352)
			(xy 160.007215 -134.896352) (xy 159.987845 -136.69645) (xy 167.884856 -136.69645) (xy 167.884856 -135.83285)
			(xy 167.885346 -135.802866) (xy 167.893174 -135.74341) (xy 167.908695 -135.685485) (xy 167.931644 -135.630081)
			(xy 167.961628 -135.578147) (xy 167.998134 -135.530571) (xy 168.040539 -135.488166) (xy 168.088115 -135.45166)
			(xy 168.140049 -135.421676) (xy 168.195453 -135.398727) (xy 168.253378 -135.383206) (xy 168.312834 -135.375378)
			(xy 168.372802 -135.375378) (xy 168.432258 -135.383206) (xy 168.490183 -135.398727) (xy 168.545587 -135.421676)
			(xy 168.597521 -135.45166) (xy 168.645097 -135.488166) (xy 168.687502 -135.530571) (xy 168.724008 -135.578147)
			(xy 168.753992 -135.630081) (xy 168.776941 -135.685485) (xy 168.792462 -135.74341) (xy 168.80029 -135.802866)
			(xy 168.80078 -135.83285) (xy 168.80078 -136.69645) (xy 168.80029 -136.726434) (xy 168.792462 -136.78589)
			(xy 168.776941 -136.843815) (xy 168.753992 -136.899219) (xy 168.724008 -136.951153) (xy 168.687502 -136.998729)
			(xy 168.645097 -137.041134) (xy 168.597521 -137.07764) (xy 168.545587 -137.107624) (xy 168.490183 -137.130573)
			(xy 168.432258 -137.146094) (xy 168.372802 -137.153922) (xy 168.312834 -137.153922) (xy 168.253378 -137.146094)
			(xy 168.195453 -137.130573) (xy 168.140049 -137.107624) (xy 168.088115 -137.07764) (xy 168.040539 -137.041134)
			(xy 167.998134 -136.998729) (xy 167.961628 -136.951153) (xy 167.931644 -136.899219) (xy 167.908695 -136.843815)
			(xy 167.893174 -136.78589) (xy 167.885346 -136.726434) (xy 167.884856 -136.69645) (xy 159.987845 -136.69645)
			(xy 159.981392 -137.296144) (xy 159.981522 -137.303293) (xy 159.985249 -137.317093) (xy 159.988758 -137.323322)
			(xy 159.993757 -137.330662) (xy 160.00766 -137.34169) (xy 160.015936 -137.344912) (xy 160.1089 -137.376154)
			(xy 160.112435 -137.377175) (xy 160.119701 -137.378325) (xy 160.123378 -137.37844) (xy 160.163764 -137.35812)
			(xy 160.170368 -137.349992) (xy 160.190458 -137.325318) (xy 160.236326 -137.28122) (xy 160.287857 -137.243896)
			(xy 160.344059 -137.214066) (xy 160.403849 -137.192303) (xy 160.466077 -137.179027) (xy 160.497774 -137.176256)
			(xy 160.498282 -137.176256) (xy 160.514538 -137.174986) (xy 160.529524 -137.174986) (xy 160.559531 -137.175406)
			(xy 160.619043 -137.183144) (xy 160.677033 -137.19859) (xy 160.732509 -137.22148) (xy 160.78452 -137.251419)
			(xy 160.832174 -137.287897) (xy 160.874655 -137.330286) (xy 160.911235 -137.377862) (xy 160.941286 -137.429809)
			(xy 160.964294 -137.485236) (xy 160.979864 -137.543193) (xy 160.987731 -137.602688) (xy 160.988248 -137.632694)
			(xy 160.988248 -138.496548) (xy 160.987758 -138.526532) (xy 160.98281 -138.564112) (xy 162.791138 -138.564112)
			(xy 162.795209 -138.50849) (xy 162.807335 -138.454053) (xy 162.827258 -138.401962) (xy 162.854554 -138.353327)
			(xy 162.88864 -138.309184) (xy 162.928789 -138.270475) (xy 162.974147 -138.238024) (xy 163.023747 -138.212523)
			(xy 163.076531 -138.194516) (xy 163.131374 -138.184386) (xy 163.187108 -138.182349) (xy 163.242545 -138.188449)
			(xy 163.296502 -138.202555) (xy 163.347831 -138.224367) (xy 163.395437 -138.253421) (xy 163.438305 -138.289096)
			(xy 163.475522 -138.330633) (xy 163.506295 -138.377146) (xy 163.529967 -138.427643) (xy 163.546035 -138.48105)
			(xy 163.554155 -138.536226) (xy 163.554664 -138.564112) (xy 163.554155 -138.591998) (xy 163.546035 -138.647174)
			(xy 163.529967 -138.700581) (xy 163.506295 -138.751078) (xy 163.475522 -138.797591) (xy 163.438305 -138.839128)
			(xy 163.395437 -138.874803) (xy 163.347831 -138.903857) (xy 163.296502 -138.925669) (xy 163.242545 -138.939775)
			(xy 163.187108 -138.945875) (xy 163.131374 -138.943838) (xy 163.076531 -138.933708) (xy 163.023747 -138.915701)
			(xy 162.974147 -138.8902) (xy 162.928789 -138.857749) (xy 162.88864 -138.81904) (xy 162.854554 -138.774897)
			(xy 162.827258 -138.726262) (xy 162.807335 -138.674171) (xy 162.795209 -138.619734) (xy 162.791138 -138.564112)
			(xy 160.98281 -138.564112) (xy 160.97993 -138.585988) (xy 160.964409 -138.643913) (xy 160.94146 -138.699317)
			(xy 160.911476 -138.751251) (xy 160.87497 -138.798827) (xy 160.832565 -138.841232) (xy 160.784989 -138.877738)
			(xy 160.733055 -138.907722) (xy 160.677651 -138.930671) (xy 160.619726 -138.946192) (xy 160.56027 -138.95402)
			(xy 160.500302 -138.95402) (xy 160.440846 -138.946192) (xy 160.382921 -138.930671) (xy 160.327517 -138.907722)
			(xy 160.275583 -138.877738) (xy 160.228007 -138.841232) (xy 160.185602 -138.798827) (xy 160.149096 -138.751251)
			(xy 160.119112 -138.699317) (xy 160.096163 -138.643913) (xy 160.080642 -138.585988) (xy 160.072814 -138.526532)
			(xy 160.072324 -138.496548) (xy 160.072324 -138.30808) (xy 160.072324 -138.307826) (xy 160.071796 -138.297884)
			(xy 160.064136 -138.27953) (xy 160.050073 -138.265467) (xy 160.031719 -138.257805) (xy 160.021778 -138.25728)
			(xy 160.021016 -138.25728) (xy 160.011108 -138.257804) (xy 159.992806 -138.265419) (xy 159.978756 -138.279401)
			(xy 159.971053 -138.297666) (xy 159.97047 -138.307572) (xy 159.966914 -138.642598) (xy 159.962088 -139.075668)
			(xy 159.95777 -139.464288) (xy 159.957516 -139.487656) (xy 159.957887 -139.498449) (xy 159.966565 -139.518201)
			(xy 159.97428 -139.525756) (xy 159.987742 -139.537948) (xy 159.991362 -139.541138) (xy 159.999546 -139.546248)
			(xy 160.003998 -139.548108) (xy 160.006284 -139.54887) (xy 160.011364 -139.55014) (xy 160.011872 -139.55014)
			(xy 160.022032 -139.55141) (xy 160.054544 -139.549124) (xy 160.055052 -139.549124) (xy 160.062164 -139.54887)
			(xy 160.066736 -139.54887) (xy 160.071054 -139.54887) (xy 160.071308 -139.54887) (xy 160.096925 -139.54928)
			(xy 160.147699 -139.556133) (xy 160.197097 -139.569729) (xy 160.244228 -139.589821) (xy 160.288241 -139.616048)
			(xy 160.308544 -139.631674) (xy 160.31337 -139.635484) (xy 160.320736 -139.638786) (xy 160.325476 -139.640653)
			(xy 160.335456 -139.642693) (xy 160.340548 -139.64285) (xy 160.361884 -139.64285) (xy 160.367324 -139.642989)
			(xy 160.377959 -139.645289) (xy 160.382966 -139.647422) (xy 160.396428 -139.653518) (xy 160.405088 -139.657132)
			(xy 160.423802 -139.658352) (xy 160.441688 -139.652714) (xy 160.44926 -139.647168) (xy 160.456372 -139.64158)
			(xy 160.460944 -139.638024) (xy 160.461706 -139.637516) (xy 160.482348 -139.620877) (xy 160.527362 -139.592863)
			(xy 160.57582 -139.571352) (xy 160.626791 -139.556758) (xy 160.679291 -139.549362) (xy 160.7058 -139.54887)
			(xy 160.706054 -139.54887) (xy 160.706562 -139.54887) (xy 160.733709 -139.549367) (xy 160.787451 -139.557101)
			(xy 160.839553 -139.572376) (xy 160.888964 -139.594884) (xy 160.934685 -139.624168) (xy 160.975792 -139.659639)
			(xy 161.011456 -139.700579) (xy 161.026602 -139.723114) (xy 161.027618 -139.724638) (xy 161.040524 -139.745536)
			(xy 161.061441 -139.789977) (xy 161.076467 -139.83674) (xy 161.085354 -139.885047) (xy 161.087054 -139.90955)
			(xy 161.087562 -139.92606) (xy 161.087562 -139.939522) (xy 161.087308 -139.942316) (xy 161.085932 -139.970766)
			(xy 161.075783 -140.026811) (xy 161.057404 -140.08072) (xy 161.031204 -140.131292) (xy 161.014918 -140.15466)
			(xy 161.008568 -140.163042) (xy 161.004758 -140.167868) (xy 160.999424 -140.176504) (xy 160.998916 -140.17752)
			(xy 160.996452 -140.182845) (xy 160.993754 -140.194261) (xy 160.993582 -140.200126) (xy 160.993582 -140.221208)
			(xy 160.993441 -140.226648) (xy 160.991138 -140.237282) (xy 160.98901 -140.24229) (xy 160.982914 -140.255752)
			(xy 160.979289 -140.264416) (xy 160.978046 -140.283142) (xy 160.983659 -140.301051) (xy 160.989264 -140.308584)
			(xy 160.994852 -140.315696) (xy 160.998408 -140.320268) (xy 160.998916 -140.32103) (xy 161.014695 -140.340538)
			(xy 161.041537 -140.382931) (xy 161.062586 -140.428478) (xy 161.07748 -140.476392) (xy 161.085961 -140.525845)
			(xy 161.087308 -140.5509) (xy 161.087562 -140.564108) (xy 161.087562 -140.566648) (xy 161.086989 -140.594251)
			(xy 161.078859 -140.64886) (xy 161.062936 -140.701724) (xy 161.039552 -140.751737) (xy 161.009198 -140.797854)
			(xy 160.972507 -140.839109) (xy 160.951672 -140.857224) (xy 160.931187 -140.873873) (xy 160.886498 -140.901969)
			(xy 160.838366 -140.923646) (xy 160.787709 -140.938491) (xy 160.735491 -140.946223) (xy 160.709102 -140.946886)
			(xy 160.705546 -140.946886) (xy 160.675637 -140.946278) (xy 160.616558 -140.936898) (xy 160.559662 -140.918424)
			(xy 160.506343 -140.891307) (xy 160.481772 -140.874242) (xy 160.47339 -140.867892) (xy 160.468564 -140.864082)
			(xy 160.459928 -140.858748) (xy 160.458912 -140.85824) (xy 160.453585 -140.855783) (xy 160.442169 -140.853098)
			(xy 160.436306 -140.852906) (xy 160.415224 -140.852906) (xy 160.409783 -140.852769) (xy 160.399146 -140.850472)
			(xy 160.394142 -140.848334) (xy 160.38068 -140.842238) (xy 160.372019 -140.838625) (xy 160.353304 -140.837404)
			(xy 160.335415 -140.843035) (xy 160.327848 -140.848588) (xy 160.320736 -140.854176) (xy 160.316164 -140.857732)
			(xy 160.315402 -140.85824) (xy 160.294759 -140.874877) (xy 160.249745 -140.902888) (xy 160.201286 -140.924397)
			(xy 160.150316 -140.93899) (xy 160.097816 -140.946386) (xy 160.071308 -140.946886) (xy 160.0708 -140.946886)
			(xy 160.070038 -140.946886) (xy 160.056208 -140.946742) (xy 160.028621 -140.944711) (xy 160.01492 -140.942822)
			(xy 160.012126 -140.942314) (xy 160.007046 -140.94206) (xy 159.997462 -140.941987) (xy 159.979323 -140.948134)
			(xy 159.97174 -140.953998) (xy 159.959294 -140.964666) (xy 159.951391 -140.97195) (xy 159.942047 -140.991285)
			(xy 159.94126 -141.002004) (xy 159.924085 -142.60068) (xy 167.705532 -142.60068) (xy 167.705995 -142.573275)
			(xy 167.713846 -142.51903) (xy 167.729383 -142.466469) (xy 167.752287 -142.416674) (xy 167.782085 -142.370671)
			(xy 167.799766 -142.349728) (xy 167.80002 -142.349474) (xy 167.805584 -142.342372) (xy 167.811844 -142.325467)
			(xy 167.812212 -142.316454) (xy 167.812212 -142.249144) (xy 167.811831 -142.24013) (xy 167.8056 -142.223213)
			(xy 167.80002 -142.216124) (xy 167.799512 -142.215616) (xy 167.781869 -142.194687) (xy 167.752157 -142.148714)
			(xy 167.729322 -142.098965) (xy 167.713832 -142.046464) (xy 167.706005 -141.992287) (xy 167.705532 -141.964918)
			(xy 167.706018 -141.937667) (xy 167.713774 -141.883719) (xy 167.729129 -141.831424) (xy 167.751771 -141.781847)
			(xy 167.781237 -141.735997) (xy 167.816928 -141.694806) (xy 167.858119 -141.659115) (xy 167.903969 -141.629649)
			(xy 167.953546 -141.607007) (xy 168.005841 -141.591652) (xy 168.059789 -141.583896) (xy 168.114291 -141.583896)
			(xy 168.168239 -141.591652) (xy 168.220534 -141.607007) (xy 168.270111 -141.629649) (xy 168.315961 -141.659115)
			(xy 168.357152 -141.694806) (xy 168.392843 -141.735997) (xy 168.422309 -141.781847) (xy 168.444951 -141.831424)
			(xy 168.460306 -141.883719) (xy 168.468062 -141.937667) (xy 168.468548 -141.964918) (xy 168.468089 -141.992323)
			(xy 168.460238 -142.046568) (xy 168.4447 -142.09913) (xy 168.421795 -142.148925) (xy 168.391996 -142.194927)
			(xy 168.374314 -142.21587) (xy 168.37406 -142.216124) (xy 168.368452 -142.223196) (xy 168.362219 -142.240124)
			(xy 168.361868 -142.249144) (xy 168.361868 -142.316454) (xy 168.362254 -142.325468) (xy 168.368482 -142.342385)
			(xy 168.37406 -142.349474) (xy 168.374568 -142.349982) (xy 168.392207 -142.370914) (xy 168.42192 -142.416886)
			(xy 168.444757 -142.466634) (xy 168.460247 -142.519135) (xy 168.468075 -142.573311) (xy 168.468548 -142.60068)
			(xy 168.468062 -142.627931) (xy 168.460306 -142.681879) (xy 168.444951 -142.734174) (xy 168.422309 -142.783751)
			(xy 168.392843 -142.829601) (xy 168.357152 -142.870792) (xy 168.315961 -142.906483) (xy 168.270111 -142.935949)
			(xy 168.220534 -142.958591) (xy 168.168239 -142.973946) (xy 168.114291 -142.981702) (xy 168.059789 -142.981702)
			(xy 168.005841 -142.973946) (xy 167.953546 -142.958591) (xy 167.903969 -142.935949) (xy 167.858119 -142.906483)
			(xy 167.816928 -142.870792) (xy 167.781237 -142.829601) (xy 167.751771 -142.783751) (xy 167.729129 -142.734174)
			(xy 167.713774 -142.681879) (xy 167.706018 -142.627931) (xy 167.705532 -142.60068) (xy 159.924085 -142.60068)
			(xy 159.91713 -143.248126) (xy 159.910018 -143.902684) (xy 159.905954 -144.27962) (xy 159.90607 -144.286625)
			(xy 159.909678 -144.300158) (xy 159.913066 -144.30629) (xy 159.918908 -144.314164) (xy 159.932624 -144.329404)
			(xy 159.965644 -144.365726) (xy 159.968894 -144.369183) (xy 159.976436 -144.374937) (xy 159.98063 -144.377156)
			(xy 159.98825 -144.380966) (xy 159.997394 -144.381982) (xy 159.99841 -144.381982) (xy 160.00984 -144.383252)
			(xy 160.010094 -144.383252) (xy 160.018801 -144.383896) (xy 160.035807 -144.379998) (xy 160.043368 -144.375632)
			(xy 160.10255 -144.33423) (xy 160.108827 -144.329295) (xy 160.118162 -144.316352) (xy 160.120838 -144.30883)
			(xy 160.1216 -144.305274) (xy 160.128617 -144.277743) (xy 160.149692 -144.224982) (xy 160.178356 -144.17593)
			(xy 160.213978 -144.131671) (xy 160.255768 -144.093182) (xy 160.302803 -144.061316) (xy 160.354044 -144.036777)
			(xy 160.408357 -144.020107) (xy 160.464541 -144.011675) (xy 160.492948 -144.011142) (xy 160.493202 -144.011142)
			(xy 160.517822 -144.011531) (xy 160.566654 -144.017866) (xy 160.614269 -144.030417) (xy 160.63722 -144.039336)
			(xy 160.648396 -144.043908) (xy 160.672018 -144.04213) (xy 160.752028 -143.994632) (xy 160.761824 -143.988187)
			(xy 160.774652 -143.968592) (xy 160.776666 -143.95704) (xy 160.776666 -143.956786) (xy 160.780321 -143.929218)
			(xy 160.794586 -143.875469) (xy 160.816501 -143.82436) (xy 160.845602 -143.776973) (xy 160.881273 -143.734312)
			(xy 160.922758 -143.69728) (xy 160.969179 -143.666661) (xy 161.019553 -143.643105) (xy 161.072813 -143.62711)
			(xy 161.12783 -143.619014) (xy 161.155634 -143.618458) (xy 161.158682 -143.618458) (xy 161.185923 -143.618942)
			(xy 161.239853 -143.626689) (xy 161.292131 -143.64203) (xy 161.341696 -143.664651) (xy 161.387539 -143.694093)
			(xy 161.428727 -143.729756) (xy 161.464424 -143.770916) (xy 161.493902 -143.816735) (xy 161.516563 -143.866282)
			(xy 161.531945 -143.918548) (xy 161.539736 -143.972471) (xy 161.54019 -143.999712) (xy 161.54019 -144.00022)
			(xy 161.538666 -144.032732) (xy 161.538412 -144.036288) (xy 161.538412 -144.03832) (xy 161.538666 -144.041876)
			(xy 161.54019 -144.075658) (xy 161.54019 -144.076166) (xy 161.539739 -144.102887) (xy 161.532283 -144.155806)
			(xy 161.517525 -144.20717) (xy 161.495754 -144.255977) (xy 161.467394 -144.301273) (xy 161.432999 -144.342176)
			(xy 161.413444 -144.360392) (xy 161.405316 -144.367758) (xy 161.400998 -144.37741) (xy 161.397696 -144.384522)
			(xy 161.394394 -144.411192) (xy 161.39414 -144.412716) (xy 161.404046 -144.42821) (xy 161.418344 -144.451372)
			(xy 161.440944 -144.500888) (xy 161.456276 -144.553114) (xy 161.464027 -144.606989) (xy 161.464498 -144.634204)
			(xy 161.46399 -144.656048) (xy 161.464244 -144.66316) (xy 161.465559 -144.674735) (xy 161.466959 -144.697992)
			(xy 161.467038 -144.709642) (xy 161.467038 -144.710404) (xy 161.466549 -144.737825) (xy 161.458747 -144.792108)
			(xy 161.443302 -144.84473) (xy 161.420529 -144.894619) (xy 161.390889 -144.940761) (xy 161.354988 -144.982218)
			(xy 161.313554 -145.018145) (xy 161.26743 -145.047813) (xy 161.217555 -145.070618) (xy 161.164943 -145.086096)
			(xy 161.110664 -145.093932) (xy 161.083244 -145.094452) (xy 161.08299 -145.094452) (xy 161.072615 -145.094307)
			(xy 161.051903 -145.093038) (xy 161.041588 -145.091912) (xy 161.031682 -145.090896) (xy 161.022792 -145.093182)
			(xy 161.01903 -145.094261) (xy 161.011881 -145.097448) (xy 161.008568 -145.099532) (xy 160.970976 -145.127218)
			(xy 160.970214 -145.12798) (xy 160.963864 -145.13306) (xy 160.956244 -145.141442) (xy 160.954212 -145.144744)
			(xy 160.952219 -145.148013) (xy 160.949158 -145.15503) (xy 160.948116 -145.158714) (xy 160.943472 -145.186373)
			(xy 160.927382 -145.240101) (xy 160.90384 -145.291005) (xy 160.873319 -145.338058) (xy 160.836438 -145.380309)
			(xy 160.793939 -145.416907) (xy 160.746683 -145.447111) (xy 160.695622 -145.470312) (xy 160.641788 -145.48604)
			(xy 160.586268 -145.49398) (xy 160.558226 -145.494502) (xy 160.52904 -145.493968) (xy 160.471309 -145.485348)
			(xy 160.415481 -145.468306) (xy 160.362777 -145.443216) (xy 160.314351 -145.410627) (xy 160.271261 -145.371251)
			(xy 160.23445 -145.325951) (xy 160.204723 -145.275716) (xy 160.193228 -145.248884) (xy 160.192466 -145.246852)
			(xy 160.190688 -145.243296) (xy 160.186741 -145.236766) (xy 160.175769 -145.226172) (xy 160.169098 -145.222468)
			(xy 160.147 -145.212816) (xy 160.146492 -145.212816) (xy 160.132776 -145.206974) (xy 160.126824 -145.205017)
			(xy 160.114363 -145.203727) (xy 160.108138 -145.204434) (xy 160.097724 -145.206466) (xy 160.093914 -145.207736)
			(xy 160.093406 -145.20799) (xy 160.076388 -145.213578) (xy 160.060894 -145.217896) (xy 160.056576 -145.218912)
			(xy 160.051496 -145.220182) (xy 160.043876 -145.22577) (xy 160.040006 -145.228679) (xy 160.033358 -145.235715)
			(xy 160.030668 -145.23974) (xy 160.026858 -145.24609) (xy 160.024455 -145.249817) (xy 160.018577 -145.256455)
			(xy 160.015174 -145.259298) (xy 160.01492 -145.259552) (xy 160.014158 -145.26006) (xy 160.00349 -145.270728)
			(xy 160.00095 -145.274538) (xy 160.000442 -145.275554) (xy 160.001458 -145.30578) (xy 159.999934 -145.338546)
			(xy 159.999934 -145.3388) (xy 159.99968 -145.34388) (xy 160.000442 -145.351246) (xy 160.001688 -145.369271)
			(xy 160.001182 -145.4054) (xy 159.999426 -145.423382) (xy 159.995666 -145.452908) (xy 159.980174 -145.510373)
			(xy 159.955953 -145.564739) (xy 159.923591 -145.614689) (xy 159.904176 -145.63725) (xy 159.897572 -145.644616)
			(xy 159.894524 -145.652998) (xy 159.893046 -145.657166) (xy 159.89139 -145.665851) (xy 159.891222 -145.67027)
			(xy 159.8803 -146.644868) (xy 159.879538 -146.72564) (xy 159.879538 -146.729196) (xy 159.880197 -146.739864)
			(xy 164.805868 -146.739864) (xy 164.806356 -146.704455) (xy 164.814898 -146.634154) (xy 164.831854 -146.565396)
			(xy 164.856976 -146.499184) (xy 164.889898 -146.436483) (xy 164.930138 -146.378209) (xy 164.977111 -146.325212)
			(xy 165.030131 -146.278264) (xy 165.088425 -146.238052) (xy 165.151141 -146.20516) (xy 165.217366 -146.18007)
			(xy 165.286132 -146.163147) (xy 165.356437 -146.154639) (xy 165.391846 -146.15414) (xy 165.424718 -146.154593)
			(xy 165.49005 -146.161936) (xy 165.554149 -146.176547) (xy 165.616209 -146.198242) (xy 165.675451 -146.226748)
			(xy 165.731129 -146.261707) (xy 165.782542 -146.30268) (xy 165.80612 -146.32559) (xy 166.276528 -146.795998)
			(xy 166.643556 -146.795998) (xy 166.647627 -146.740376) (xy 166.659753 -146.685939) (xy 166.679676 -146.633848)
			(xy 166.706972 -146.585213) (xy 166.741058 -146.54107) (xy 166.781207 -146.502361) (xy 166.826565 -146.46991)
			(xy 166.876165 -146.444409) (xy 166.928949 -146.426402) (xy 166.983792 -146.416272) (xy 167.039526 -146.414235)
			(xy 167.094963 -146.420335) (xy 167.14892 -146.434441) (xy 167.200249 -146.456253) (xy 167.247855 -146.485307)
			(xy 167.290723 -146.520982) (xy 167.32794 -146.562519) (xy 167.358713 -146.609032) (xy 167.382385 -146.659529)
			(xy 167.398453 -146.712936) (xy 167.406573 -146.768112) (xy 167.407082 -146.795998) (xy 167.406573 -146.823884)
			(xy 167.398453 -146.87906) (xy 167.382385 -146.932467) (xy 167.358713 -146.982964) (xy 167.32794 -147.029477)
			(xy 167.290723 -147.071014) (xy 167.247855 -147.106689) (xy 167.200249 -147.135743) (xy 167.14892 -147.157555)
			(xy 167.094963 -147.171661) (xy 167.039526 -147.177761) (xy 166.983792 -147.175724) (xy 166.928949 -147.165594)
			(xy 166.876165 -147.147587) (xy 166.826565 -147.122086) (xy 166.781207 -147.089635) (xy 166.741058 -147.050926)
			(xy 166.706972 -147.006783) (xy 166.679676 -146.958148) (xy 166.659753 -146.906057) (xy 166.647627 -146.85162)
			(xy 166.643556 -146.795998) (xy 166.276528 -146.795998) (xy 166.97452 -147.49399) (xy 166.997439 -147.517566)
			(xy 167.038435 -147.568977) (xy 167.073423 -147.624651) (xy 167.101963 -147.683889) (xy 167.123697 -147.745948)
			(xy 167.138352 -147.810049) (xy 167.145746 -147.875387) (xy 167.146224 -147.908264) (xy 167.146224 -149.581362)
			(xy 167.163242 -149.606762) (xy 167.177466 -149.612604) (xy 167.186897 -149.616049) (xy 167.206963 -149.615997)
			(xy 167.225474 -149.608255) (xy 167.232838 -149.601428) (xy 168.772586 -148.06168) (xy 168.779425 -148.054279)
			(xy 168.787146 -148.035681) (xy 168.787572 -148.025612) (xy 168.787572 -141.677644) (xy 168.787131 -141.667576)
			(xy 168.779422 -141.648978) (xy 168.772586 -141.641576) (xy 167.672766 -140.541756) (xy 167.649845 -140.518212)
			(xy 167.608879 -140.466833) (xy 167.573924 -140.41119) (xy 167.545419 -140.351983) (xy 167.523722 -140.289957)
			(xy 167.509107 -140.225891) (xy 167.501756 -140.160592) (xy 167.501316 -140.127736) (xy 167.501316 -140.127482)
			(xy 167.501839 -140.092079) (xy 167.510373 -140.021789) (xy 167.527316 -139.953039) (xy 167.552419 -139.886832)
			(xy 167.585317 -139.824132) (xy 167.625531 -139.765853) (xy 167.672474 -139.712845) (xy 167.725463 -139.66588)
			(xy 167.783725 -139.625642) (xy 167.846411 -139.592718) (xy 167.912608 -139.567588) (xy 167.98135 -139.550617)
			(xy 168.051637 -139.542054) (xy 168.08704 -139.541504) (xy 168.11992 -139.541982) (xy 168.185267 -139.549342)
			(xy 168.249377 -139.563978) (xy 168.311445 -139.585704) (xy 168.370687 -139.614246) (xy 168.426359 -139.649247)
			(xy 168.477759 -139.690264) (xy 168.501314 -139.713208) (xy 169.787824 -140.999718) (xy 169.810757 -141.023281)
			(xy 169.851752 -141.074694) (xy 169.886738 -141.13037) (xy 169.915276 -141.189611) (xy 169.937008 -141.251672)
			(xy 169.951661 -141.315775) (xy 169.959051 -141.381114) (xy 169.959528 -141.413992) (xy 169.959528 -148.289264)
			(xy 169.959085 -148.322145) (xy 169.951721 -148.387494) (xy 169.937081 -148.451606) (xy 169.91535 -148.513674)
			(xy 169.886802 -148.572916) (xy 169.851795 -148.628586) (xy 169.810771 -148.679984) (xy 169.787824 -148.703538)
			(xy 167.792146 -150.699216) (xy 167.785313 -150.706622) (xy 167.777588 -150.725216) (xy 167.77716 -150.735284)
			(xy 167.77716 -150.738078) (xy 167.777679 -150.749609) (xy 167.787636 -150.770406) (xy 167.80566 -150.784786)
			(xy 167.816784 -150.787862) (xy 167.843104 -150.794331) (xy 167.893758 -150.813599) (xy 167.941175 -150.839844)
			(xy 167.984399 -150.872537) (xy 168.02256 -150.911019) (xy 168.054889 -150.954516) (xy 168.080736 -151.002151)
			(xy 168.099579 -151.052965) (xy 168.111039 -151.105935) (xy 168.114885 -151.159994) (xy 168.111041 -151.214053)
			(xy 168.10175 -151.257) (xy 168.676826 -151.257) (xy 168.680897 -151.201378) (xy 168.693023 -151.146941)
			(xy 168.712946 -151.09485) (xy 168.740242 -151.046215) (xy 168.774328 -151.002072) (xy 168.814477 -150.963363)
			(xy 168.859835 -150.930912) (xy 168.909435 -150.905411) (xy 168.962219 -150.887404) (xy 169.017062 -150.877274)
			(xy 169.072796 -150.875237) (xy 169.128233 -150.881337) (xy 169.18219 -150.895443) (xy 169.233519 -150.917255)
			(xy 169.281125 -150.946309) (xy 169.323993 -150.981984) (xy 169.36121 -151.023521) (xy 169.391983 -151.070034)
			(xy 169.415655 -151.120531) (xy 169.431723 -151.173938) (xy 169.439843 -151.229114) (xy 169.440352 -151.257)
			(xy 169.439843 -151.284886) (xy 169.431723 -151.340062) (xy 169.415655 -151.393469) (xy 169.391983 -151.443966)
			(xy 169.36121 -151.490479) (xy 169.323993 -151.532016) (xy 169.281125 -151.567691) (xy 169.233519 -151.596745)
			(xy 169.18219 -151.618557) (xy 169.128233 -151.632663) (xy 169.072796 -151.638763) (xy 169.017062 -151.636726)
			(xy 168.962219 -151.626596) (xy 168.909435 -151.608589) (xy 168.859835 -151.583088) (xy 168.814477 -151.550637)
			(xy 168.774328 -151.511928) (xy 168.740242 -151.467785) (xy 168.712946 -151.41915) (xy 168.693023 -151.367059)
			(xy 168.680897 -151.312622) (xy 168.676826 -151.257) (xy 168.10175 -151.257) (xy 168.099582 -151.267023)
			(xy 168.080741 -151.317838) (xy 168.054896 -151.365474) (xy 168.022568 -151.408972) (xy 167.984408 -151.447455)
			(xy 167.941185 -151.480149) (xy 167.893769 -151.506395) (xy 167.843115 -151.525665) (xy 167.816784 -151.532082)
			(xy 167.805653 -151.535153) (xy 167.787609 -151.549524) (xy 167.777648 -151.57033) (xy 167.77716 -151.581866)
			(xy 167.77716 -152.538176) (xy 167.777681 -152.549707) (xy 167.787637 -152.570504) (xy 167.80566 -152.584884)
			(xy 167.816784 -152.58796) (xy 167.843103 -152.594433) (xy 167.893757 -152.613701) (xy 167.941173 -152.639946)
			(xy 167.984397 -152.672638) (xy 168.022558 -152.71112) (xy 168.054887 -152.754617) (xy 168.080734 -152.802251)
			(xy 168.099577 -152.853065) (xy 168.111037 -152.906035) (xy 168.114883 -152.960093) (xy 168.111039 -153.014152)
			(xy 168.099581 -153.067122) (xy 168.080739 -153.117937) (xy 168.054895 -153.165572) (xy 168.022567 -153.20907)
			(xy 167.984407 -153.247553) (xy 167.941184 -153.280247) (xy 167.893769 -153.306493) (xy 167.843115 -153.325763)
			(xy 167.816784 -153.33218) (xy 167.805653 -153.335253) (xy 167.78761 -153.349623) (xy 167.777649 -153.370428)
			(xy 167.77716 -153.381964) (xy 167.77716 -153.560018) (xy 168.549826 -153.560018) (xy 168.553897 -153.504396)
			(xy 168.566023 -153.449959) (xy 168.585946 -153.397868) (xy 168.613242 -153.349233) (xy 168.647328 -153.30509)
			(xy 168.687477 -153.266381) (xy 168.732835 -153.23393) (xy 168.782435 -153.208429) (xy 168.835219 -153.190422)
			(xy 168.890062 -153.180292) (xy 168.945796 -153.178255) (xy 169.001233 -153.184355) (xy 169.05519 -153.198461)
			(xy 169.106519 -153.220273) (xy 169.154125 -153.249327) (xy 169.196993 -153.285002) (xy 169.23421 -153.326539)
			(xy 169.264983 -153.373052) (xy 169.288655 -153.423549) (xy 169.304723 -153.476956) (xy 169.312843 -153.532132)
			(xy 169.313352 -153.560018) (xy 169.312843 -153.587904) (xy 169.304723 -153.64308) (xy 169.288655 -153.696487)
			(xy 169.264983 -153.746984) (xy 169.23421 -153.793497) (xy 169.196993 -153.835034) (xy 169.154125 -153.870709)
			(xy 169.106519 -153.899763) (xy 169.05519 -153.921575) (xy 169.001233 -153.935681) (xy 168.945796 -153.941781)
			(xy 168.890062 -153.939744) (xy 168.835219 -153.929614) (xy 168.782435 -153.911607) (xy 168.732835 -153.886106)
			(xy 168.687477 -153.853655) (xy 168.647328 -153.814946) (xy 168.613242 -153.770803) (xy 168.585946 -153.722168)
			(xy 168.566023 -153.670077) (xy 168.553897 -153.61564) (xy 168.549826 -153.560018) (xy 167.77716 -153.560018)
			(xy 167.77716 -153.709878) (xy 167.777495 -153.71926) (xy 167.784303 -153.736746) (xy 167.790368 -153.743914)
			(xy 167.81018 -153.765758) (xy 167.816408 -153.77213) (xy 167.83214 -153.780468) (xy 167.840914 -153.782014)
			(xy 167.867946 -153.786285) (xy 167.920533 -153.801428) (xy 167.970416 -153.82393) (xy 168.016573 -153.853329)
			(xy 168.058055 -153.889022) (xy 168.094011 -153.930275) (xy 168.123704 -153.976243) (xy 168.146524 -154.025982)
			(xy 168.162003 -154.078471) (xy 168.169823 -154.132633) (xy 168.169823 -154.187357) (xy 168.162005 -154.24152)
			(xy 168.146527 -154.294009) (xy 168.123708 -154.343749) (xy 168.094017 -154.389717) (xy 168.058061 -154.430972)
			(xy 168.01658 -154.466665) (xy 167.970425 -154.496065) (xy 167.920542 -154.518569) (xy 167.867955 -154.533713)
			(xy 167.840914 -154.537918) (xy 167.83216 -154.539529) (xy 167.816438 -154.547844) (xy 167.81018 -154.554174)
			(xy 167.790368 -154.576018) (xy 167.784393 -154.583235) (xy 167.777629 -154.600695) (xy 167.77716 -154.610054)
			(xy 167.77716 -154.958288) (xy 168.843958 -154.958288) (xy 168.848029 -154.902666) (xy 168.860155 -154.848229)
			(xy 168.880078 -154.796138) (xy 168.907374 -154.747503) (xy 168.94146 -154.70336) (xy 168.981609 -154.664651)
			(xy 169.026967 -154.6322) (xy 169.076567 -154.606699) (xy 169.129351 -154.588692) (xy 169.184194 -154.578562)
			(xy 169.239928 -154.576525) (xy 169.295365 -154.582625) (xy 169.349322 -154.596731) (xy 169.400651 -154.618543)
			(xy 169.448257 -154.647597) (xy 169.491125 -154.683272) (xy 169.528342 -154.724809) (xy 169.559115 -154.771322)
			(xy 169.582787 -154.821819) (xy 169.598855 -154.875226) (xy 169.606975 -154.930402) (xy 169.607484 -154.958288)
			(xy 169.606975 -154.986174) (xy 169.598855 -155.04135) (xy 169.582787 -155.094757) (xy 169.559115 -155.145254)
			(xy 169.528342 -155.191767) (xy 169.491125 -155.233304) (xy 169.448257 -155.268979) (xy 169.400651 -155.298033)
			(xy 169.349322 -155.319845) (xy 169.295365 -155.333951) (xy 169.239928 -155.340051) (xy 169.184194 -155.338014)
			(xy 169.129351 -155.327884) (xy 169.076567 -155.309877) (xy 169.026967 -155.284376) (xy 168.981609 -155.251925)
			(xy 168.94146 -155.213216) (xy 168.907374 -155.169073) (xy 168.880078 -155.120438) (xy 168.860155 -155.068347)
			(xy 168.848029 -155.01391) (xy 168.843958 -154.958288) (xy 167.77716 -154.958288) (xy 167.77716 -155.116276)
			(xy 167.777541 -155.125893) (xy 167.784592 -155.143784) (xy 167.790876 -155.151074) (xy 167.84574 -155.208986)
			(xy 167.862758 -155.217114) (xy 167.872664 -155.217622) (xy 167.900049 -155.219789) (xy 167.95385 -155.230871)
			(xy 168.005504 -155.249558) (xy 168.053944 -155.275461) (xy 168.098165 -155.308047) (xy 168.137255 -155.346639)
			(xy 168.170403 -155.39044) (xy 168.196925 -155.438544) (xy 168.216271 -155.489955) (xy 168.228041 -155.54361)
			(xy 168.231992 -155.598398) (xy 168.228042 -155.653186) (xy 168.216272 -155.706841) (xy 168.196927 -155.758253)
			(xy 168.170406 -155.806357) (xy 168.137258 -155.850158) (xy 168.098168 -155.888751) (xy 168.053947 -155.921337)
			(xy 168.005508 -155.947241) (xy 167.953854 -155.965928) (xy 167.900053 -155.977011) (xy 167.872664 -155.979114)
			(xy 167.863135 -155.980123) (xy 167.845777 -155.988208) (xy 167.838882 -155.994862) (xy 167.790876 -156.045662)
			(xy 167.784613 -156.052963) (xy 167.777569 -156.070849) (xy 167.77716 -156.08046) (xy 167.77716 -156.544518)
			(xy 168.827702 -156.544518) (xy 168.831773 -156.488896) (xy 168.843899 -156.434459) (xy 168.863822 -156.382368)
			(xy 168.891118 -156.333733) (xy 168.925204 -156.28959) (xy 168.965353 -156.250881) (xy 169.010711 -156.21843)
			(xy 169.060311 -156.192929) (xy 169.113095 -156.174922) (xy 169.167938 -156.164792) (xy 169.223672 -156.162755)
			(xy 169.279109 -156.168855) (xy 169.333066 -156.182961) (xy 169.384395 -156.204773) (xy 169.432001 -156.233827)
			(xy 169.474869 -156.269502) (xy 169.512086 -156.311039) (xy 169.542859 -156.357552) (xy 169.566531 -156.408049)
			(xy 169.582599 -156.461456) (xy 169.590719 -156.516632) (xy 169.591228 -156.544518) (xy 169.590719 -156.572404)
			(xy 169.582599 -156.62758) (xy 169.566531 -156.680987) (xy 169.542859 -156.731484) (xy 169.512086 -156.777997)
			(xy 169.474869 -156.819534) (xy 169.432001 -156.855209) (xy 169.384395 -156.884263) (xy 169.333066 -156.906075)
			(xy 169.279109 -156.920181) (xy 169.223672 -156.926281) (xy 169.167938 -156.924244) (xy 169.113095 -156.914114)
			(xy 169.060311 -156.896107) (xy 169.010711 -156.870606) (xy 168.965353 -156.838155) (xy 168.925204 -156.799446)
			(xy 168.891118 -156.755303) (xy 168.863822 -156.706668) (xy 168.843899 -156.654577) (xy 168.831773 -156.60014)
			(xy 168.827702 -156.544518) (xy 167.77716 -156.544518) (xy 167.77716 -156.644086) (xy 167.777574 -156.65334)
			(xy 167.784088 -156.670661) (xy 167.79634 -156.684529) (xy 167.812726 -156.693128) (xy 167.821864 -156.694632)
			(xy 167.822118 -156.694632) (xy 167.849676 -156.698295) (xy 167.903403 -156.712573) (xy 167.954488 -156.734498)
			(xy 168.001849 -156.763607) (xy 168.044483 -156.799282) (xy 168.081488 -156.840768) (xy 168.112078 -156.887186)
			(xy 168.135607 -156.937553) (xy 168.151575 -156.990802) (xy 168.159644 -157.045804) (xy 168.159644 -157.101396)
			(xy 168.151575 -157.156398) (xy 168.135607 -157.209647) (xy 168.112078 -157.260014) (xy 168.081488 -157.306432)
			(xy 168.044483 -157.347918) (xy 168.001849 -157.383593) (xy 167.954488 -157.412702) (xy 167.903403 -157.434627)
			(xy 167.849676 -157.448905) (xy 167.822118 -157.452568) (xy 167.821864 -157.452568) (xy 167.812737 -157.454095)
			(xy 167.796383 -157.462727) (xy 167.784134 -157.47658) (xy 167.777571 -157.493869) (xy 167.77716 -157.503114)
			(xy 167.77716 -164.09797) (xy 168.691304 -164.09797) (xy 168.695375 -164.042348) (xy 168.707501 -163.987911)
			(xy 168.727424 -163.93582) (xy 168.75472 -163.887185) (xy 168.788806 -163.843042) (xy 168.828955 -163.804333)
			(xy 168.874313 -163.771882) (xy 168.923913 -163.746381) (xy 168.976697 -163.728374) (xy 169.03154 -163.718244)
			(xy 169.087274 -163.716207) (xy 169.142711 -163.722307) (xy 169.196668 -163.736413) (xy 169.247997 -163.758225)
			(xy 169.295603 -163.787279) (xy 169.338471 -163.822954) (xy 169.375688 -163.864491) (xy 169.406461 -163.911004)
			(xy 169.430133 -163.961501) (xy 169.446201 -164.014908) (xy 169.454321 -164.070084) (xy 169.45483 -164.09797)
			(xy 169.454321 -164.125856) (xy 169.446201 -164.181032) (xy 169.430133 -164.234439) (xy 169.406461 -164.284936)
			(xy 169.375688 -164.331449) (xy 169.338471 -164.372986) (xy 169.295603 -164.408661) (xy 169.247997 -164.437715)
			(xy 169.196668 -164.459527) (xy 169.142711 -164.473633) (xy 169.087274 -164.479733) (xy 169.03154 -164.477696)
			(xy 168.976697 -164.467566) (xy 168.923913 -164.449559) (xy 168.874313 -164.424058) (xy 168.828955 -164.391607)
			(xy 168.788806 -164.352898) (xy 168.75472 -164.308755) (xy 168.727424 -164.26012) (xy 168.707501 -164.208029)
			(xy 168.695375 -164.153592) (xy 168.691304 -164.09797) (xy 167.77716 -164.09797) (xy 167.77716 -164.198046)
			(xy 167.776672 -164.231208) (xy 167.769177 -164.297107) (xy 167.754286 -164.361737) (xy 167.732192 -164.424273)
			(xy 167.703176 -164.483913) (xy 167.667611 -164.539894) (xy 167.62595 -164.591501) (xy 167.602662 -164.615114)
			(xy 167.595804 -164.621972) (xy 167.58793 -164.639244) (xy 167.584374 -164.717984) (xy 167.584382 -164.72744)
			(xy 167.590512 -164.745314) (xy 167.596312 -164.752782) (xy 167.617957 -164.77922) (xy 167.655594 -164.83625)
			(xy 167.686334 -164.897274) (xy 167.709761 -164.961462) (xy 167.725555 -165.027941) (xy 167.733502 -165.095807)
			(xy 167.73398 -165.129972) (xy 167.73398 -165.130226) (xy 167.733469 -165.16563) (xy 167.724933 -165.23592)
			(xy 167.70799 -165.30467) (xy 167.682886 -165.370878) (xy 167.649987 -165.433578) (xy 167.609772 -165.491856)
			(xy 167.562827 -165.544865) (xy 167.509838 -165.59183) (xy 167.451575 -165.632068) (xy 167.388888 -165.664991)
			(xy 167.32269 -165.690121) (xy 167.253947 -165.707092) (xy 167.183659 -165.715655) (xy 167.148256 -165.716204)
			(xy 167.130476 -165.716204) (xy 167.097595 -165.715779) (xy 167.032246 -165.708409) (xy 166.968134 -165.693764)
			(xy 166.906067 -165.67203) (xy 166.846825 -165.643479) (xy 166.791154 -165.608472) (xy 166.739756 -165.567448)
			(xy 166.716202 -165.5445) (xy 166.145972 -164.97427) (xy 166.12308 -164.950668) (xy 166.082083 -164.899262)
			(xy 166.047092 -164.843593) (xy 166.018549 -164.784359) (xy 165.99681 -164.722304) (xy 165.982149 -164.658207)
			(xy 165.97475 -164.592872) (xy 165.974268 -164.559996) (xy 165.974268 -148.171916) (xy 165.973843 -148.161847)
			(xy 165.966123 -148.143248) (xy 165.959282 -148.135848) (xy 164.977572 -147.154138) (xy 164.954665 -147.13055)
			(xy 164.913668 -147.079142) (xy 164.87868 -147.02347) (xy 164.850138 -146.964234) (xy 164.828402 -146.902176)
			(xy 164.813744 -146.838077) (xy 164.806348 -146.772741) (xy 164.805868 -146.739864) (xy 159.880197 -146.739864)
			(xy 159.919162 -147.3708) (xy 160.26892 -153.05786) (xy 160.26892 -153.058876) (xy 160.423577 -155.0416)
			(xy 164.263576 -155.0416) (xy 164.267647 -154.985978) (xy 164.279773 -154.931541) (xy 164.299696 -154.87945)
			(xy 164.326992 -154.830815) (xy 164.361078 -154.786672) (xy 164.401227 -154.747963) (xy 164.446585 -154.715512)
			(xy 164.496185 -154.690011) (xy 164.548969 -154.672004) (xy 164.603812 -154.661874) (xy 164.659546 -154.659837)
			(xy 164.714983 -154.665937) (xy 164.76894 -154.680043) (xy 164.820269 -154.701855) (xy 164.867875 -154.730909)
			(xy 164.910743 -154.766584) (xy 164.94796 -154.808121) (xy 164.978733 -154.854634) (xy 165.002405 -154.905131)
			(xy 165.018473 -154.958538) (xy 165.026593 -155.013714) (xy 165.027102 -155.0416) (xy 165.026593 -155.069486)
			(xy 165.018473 -155.124662) (xy 165.002405 -155.178069) (xy 164.978733 -155.228566) (xy 164.94796 -155.275079)
			(xy 164.910743 -155.316616) (xy 164.867875 -155.352291) (xy 164.820269 -155.381345) (xy 164.76894 -155.403157)
			(xy 164.714983 -155.417263) (xy 164.659546 -155.423363) (xy 164.603812 -155.421326) (xy 164.548969 -155.411196)
			(xy 164.496185 -155.393189) (xy 164.446585 -155.367688) (xy 164.401227 -155.335237) (xy 164.361078 -155.296528)
			(xy 164.326992 -155.252385) (xy 164.299696 -155.20375) (xy 164.279773 -155.151659) (xy 164.267647 -155.097222)
			(xy 164.263576 -155.0416) (xy 160.423577 -155.0416) (xy 160.824782 -160.1851) (xy 161.624277 -160.1851)
			(xy 161.628232 -160.093263) (xy 161.640067 -160.002106) (xy 161.659694 -159.912303) (xy 161.686968 -159.824521)
			(xy 161.721688 -159.739407) (xy 161.763596 -159.657594) (xy 161.812382 -159.579686) (xy 161.867685 -159.506261)
			(xy 161.929095 -159.437861) (xy 161.996157 -159.374994) (xy 162.068376 -159.318124) (xy 162.145216 -159.267673)
			(xy 162.226109 -159.224014) (xy 162.310455 -159.187471) (xy 162.397631 -159.158314) (xy 162.48699 -159.13676)
			(xy 162.577871 -159.122966) (xy 162.669602 -159.117036) (xy 162.761503 -159.119014) (xy 162.852894 -159.128885)
			(xy 162.943098 -159.146575) (xy 163.031447 -159.171955) (xy 163.117287 -159.204835) (xy 163.199983 -159.244973)
			(xy 163.278923 -159.292072) (xy 163.353521 -159.345782) (xy 163.423227 -159.405706) (xy 163.487522 -159.4714)
			(xy 163.545933 -159.542378) (xy 163.598025 -159.618115) (xy 163.643414 -159.69805) (xy 163.681764 -159.78159)
			(xy 163.712789 -159.868118) (xy 163.736262 -159.956993) (xy 163.752008 -160.047557) (xy 163.75991 -160.139139)
			(xy 163.760404 -160.1851) (xy 163.75991 -160.231061) (xy 163.752008 -160.322643) (xy 163.736262 -160.413207)
			(xy 163.712789 -160.502082) (xy 163.681764 -160.58861) (xy 163.643414 -160.67215) (xy 163.598025 -160.752085)
			(xy 163.545933 -160.827822) (xy 163.487522 -160.8988) (xy 163.423227 -160.964494) (xy 163.353521 -161.024418)
			(xy 163.278923 -161.078128) (xy 163.199983 -161.125227) (xy 163.117287 -161.165365) (xy 163.031447 -161.198245)
			(xy 162.943098 -161.223625) (xy 162.852894 -161.241315) (xy 162.761503 -161.251186) (xy 162.669602 -161.253164)
			(xy 162.577871 -161.247234) (xy 162.48699 -161.23344) (xy 162.397631 -161.211886) (xy 162.310455 -161.182729)
			(xy 162.226109 -161.146186) (xy 162.145216 -161.102527) (xy 162.068376 -161.052076) (xy 161.996157 -160.995206)
			(xy 161.929095 -160.932339) (xy 161.867685 -160.863939) (xy 161.812382 -160.790514) (xy 161.763596 -160.712606)
			(xy 161.721688 -160.630793) (xy 161.686968 -160.545679) (xy 161.659694 -160.457897) (xy 161.640067 -160.368094)
			(xy 161.628232 -160.276937) (xy 161.624277 -160.1851) (xy 160.824782 -160.1851) (xy 161.465343 -168.397174)
			(xy 166.7416 -168.397174) (xy 166.745671 -168.341552) (xy 166.757797 -168.287115) (xy 166.77772 -168.235024)
			(xy 166.805016 -168.186389) (xy 166.839102 -168.142246) (xy 166.879251 -168.103537) (xy 166.924609 -168.071086)
			(xy 166.974209 -168.045585) (xy 167.026993 -168.027578) (xy 167.081836 -168.017448) (xy 167.13757 -168.015411)
			(xy 167.193007 -168.021511) (xy 167.246964 -168.035617) (xy 167.298293 -168.057429) (xy 167.345899 -168.086483)
			(xy 167.388767 -168.122158) (xy 167.425984 -168.163695) (xy 167.456757 -168.210208) (xy 167.480429 -168.260705)
			(xy 167.496497 -168.314112) (xy 167.504617 -168.369288) (xy 167.505126 -168.397174) (xy 167.504617 -168.42506)
			(xy 167.496497 -168.480236) (xy 167.480429 -168.533643) (xy 167.456757 -168.58414) (xy 167.425984 -168.630653)
			(xy 167.388767 -168.67219) (xy 167.345899 -168.707865) (xy 167.298293 -168.736919) (xy 167.246964 -168.758731)
			(xy 167.193007 -168.772837) (xy 167.13757 -168.778937) (xy 167.081836 -168.7769) (xy 167.026993 -168.76677)
			(xy 166.974209 -168.748763) (xy 166.924609 -168.723262) (xy 166.879251 -168.690811) (xy 166.839102 -168.652102)
			(xy 166.805016 -168.607959) (xy 166.77772 -168.559324) (xy 166.757797 -168.507233) (xy 166.745671 -168.452796)
			(xy 166.7416 -168.397174) (xy 161.465343 -168.397174) (xy 161.530606 -169.23385) (xy 167.78935 -169.23385)
			(xy 167.793421 -169.178228) (xy 167.805547 -169.123791) (xy 167.82547 -169.0717) (xy 167.852766 -169.023065)
			(xy 167.886852 -168.978922) (xy 167.927001 -168.940213) (xy 167.972359 -168.907762) (xy 168.021959 -168.882261)
			(xy 168.074743 -168.864254) (xy 168.129586 -168.854124) (xy 168.18532 -168.852087) (xy 168.240757 -168.858187)
			(xy 168.294714 -168.872293) (xy 168.346043 -168.894105) (xy 168.393649 -168.923159) (xy 168.436517 -168.958834)
			(xy 168.473734 -169.000371) (xy 168.504507 -169.046884) (xy 168.528179 -169.097381) (xy 168.544247 -169.150788)
			(xy 168.552367 -169.205964) (xy 168.552876 -169.23385) (xy 168.552367 -169.261736) (xy 168.544247 -169.316912)
			(xy 168.528179 -169.370319) (xy 168.504507 -169.420816) (xy 168.473734 -169.467329) (xy 168.436517 -169.508866)
			(xy 168.393649 -169.544541) (xy 168.346043 -169.573595) (xy 168.294714 -169.595407) (xy 168.240757 -169.609513)
			(xy 168.18532 -169.615613) (xy 168.129586 -169.613576) (xy 168.074743 -169.603446) (xy 168.021959 -169.585439)
			(xy 167.972359 -169.559938) (xy 167.927001 -169.527487) (xy 167.886852 -169.488778) (xy 167.852766 -169.444635)
			(xy 167.82547 -169.396) (xy 167.805547 -169.343909) (xy 167.793421 -169.289472) (xy 167.78935 -169.23385)
			(xy 161.530606 -169.23385) (xy 161.567814 -169.710862) (xy 164.961314 -169.710862) (xy 164.965385 -169.65524)
			(xy 164.977511 -169.600803) (xy 164.997434 -169.548712) (xy 165.02473 -169.500077) (xy 165.058816 -169.455934)
			(xy 165.098965 -169.417225) (xy 165.144323 -169.384774) (xy 165.193923 -169.359273) (xy 165.246707 -169.341266)
			(xy 165.30155 -169.331136) (xy 165.357284 -169.329099) (xy 165.412721 -169.335199) (xy 165.466678 -169.349305)
			(xy 165.518007 -169.371117) (xy 165.565613 -169.400171) (xy 165.608481 -169.435846) (xy 165.645698 -169.477383)
			(xy 165.676471 -169.523896) (xy 165.700143 -169.574393) (xy 165.716211 -169.6278) (xy 165.724331 -169.682976)
			(xy 165.72484 -169.710862) (xy 165.724331 -169.738748) (xy 165.716211 -169.793924) (xy 165.700143 -169.847331)
			(xy 165.676471 -169.897828) (xy 165.645698 -169.944341) (xy 165.608481 -169.985878) (xy 165.565613 -170.021553)
			(xy 165.518007 -170.050607) (xy 165.466678 -170.072419) (xy 165.412721 -170.086525) (xy 165.357284 -170.092625)
			(xy 165.30155 -170.090588) (xy 165.246707 -170.080458) (xy 165.193923 -170.062451) (xy 165.144323 -170.03695)
			(xy 165.098965 -170.004499) (xy 165.058816 -169.96579) (xy 165.02473 -169.921647) (xy 164.997434 -169.873012)
			(xy 164.977511 -169.820921) (xy 164.965385 -169.766484) (xy 164.961314 -169.710862) (xy 161.567814 -169.710862)
			(xy 162.037333 -175.730154) (xy 167.057068 -175.730154) (xy 167.061139 -175.674532) (xy 167.073265 -175.620095)
			(xy 167.093188 -175.568004) (xy 167.120484 -175.519369) (xy 167.15457 -175.475226) (xy 167.194719 -175.436517)
			(xy 167.240077 -175.404066) (xy 167.289677 -175.378565) (xy 167.342461 -175.360558) (xy 167.397304 -175.350428)
			(xy 167.453038 -175.348391) (xy 167.508475 -175.354491) (xy 167.562432 -175.368597) (xy 167.613761 -175.390409)
			(xy 167.661367 -175.419463) (xy 167.704235 -175.455138) (xy 167.741452 -175.496675) (xy 167.772225 -175.543188)
			(xy 167.795897 -175.593685) (xy 167.811965 -175.647092) (xy 167.820085 -175.702268) (xy 167.820594 -175.730154)
			(xy 167.820085 -175.75804) (xy 167.811965 -175.813216) (xy 167.795897 -175.866623) (xy 167.772225 -175.91712)
			(xy 167.741452 -175.963633) (xy 167.704235 -176.00517) (xy 167.661367 -176.040845) (xy 167.613761 -176.069899)
			(xy 167.562432 -176.091711) (xy 167.508475 -176.105817) (xy 167.453038 -176.111917) (xy 167.397304 -176.10988)
			(xy 167.342461 -176.09975) (xy 167.289677 -176.081743) (xy 167.240077 -176.056242) (xy 167.194719 -176.023791)
			(xy 167.15457 -175.985082) (xy 167.120484 -175.940939) (xy 167.093188 -175.892304) (xy 167.073265 -175.840213)
			(xy 167.061139 -175.785776) (xy 167.057068 -175.730154) (xy 162.037333 -175.730154) (xy 162.349203 -179.728368)
			(xy 167.516554 -179.728368) (xy 167.520625 -179.672746) (xy 167.532751 -179.618309) (xy 167.552674 -179.566218)
			(xy 167.57997 -179.517583) (xy 167.614056 -179.47344) (xy 167.654205 -179.434731) (xy 167.699563 -179.40228)
			(xy 167.749163 -179.376779) (xy 167.801947 -179.358772) (xy 167.85679 -179.348642) (xy 167.912524 -179.346605)
			(xy 167.967961 -179.352705) (xy 168.021918 -179.366811) (xy 168.073247 -179.388623) (xy 168.120853 -179.417677)
			(xy 168.163721 -179.453352) (xy 168.200938 -179.494889) (xy 168.231711 -179.541402) (xy 168.255383 -179.591899)
			(xy 168.271451 -179.645306) (xy 168.279571 -179.700482) (xy 168.28008 -179.728368) (xy 168.279571 -179.756254)
			(xy 168.271451 -179.81143) (xy 168.255383 -179.864837) (xy 168.231711 -179.915334) (xy 168.200938 -179.961847)
			(xy 168.163721 -180.003384) (xy 168.120853 -180.039059) (xy 168.073247 -180.068113) (xy 168.021918 -180.089925)
			(xy 167.967961 -180.104031) (xy 167.912524 -180.110131) (xy 167.85679 -180.108094) (xy 167.801947 -180.097964)
			(xy 167.749163 -180.079957) (xy 167.699563 -180.054456) (xy 167.654205 -180.022005) (xy 167.614056 -179.983296)
			(xy 167.57997 -179.939153) (xy 167.552674 -179.890518) (xy 167.532751 -179.838427) (xy 167.520625 -179.78399)
			(xy 167.516554 -179.728368) (xy 162.349203 -179.728368) (xy 162.497262 -181.62651) (xy 162.918648 -187.027566)
			(xy 163.759388 -197.806564) (xy 163.760548 -197.815987) (xy 163.768858 -197.833045) (xy 163.782791 -197.845923)
			(xy 163.800449 -197.852867) (xy 163.809934 -197.8533) (xy 169.998644 -197.8533) (xy 170.005502 -197.852792)
			(xy 170.01742 -197.850545) (xy 170.037325 -197.836753) (xy 170.043602 -197.826376) (xy 170.045706 -197.822184)
			(xy 170.048518 -197.813238) (xy 170.04919 -197.808596) (xy 170.055794 -197.685914) (xy 170.076114 -197.290182)
			(xy 170.709082 -185.129932) (xy 171.746672 -165.195504) (xy 172.293534 -154.687524) (xy 172.813726 -144.693894)
			(xy 172.813728 -144.68284) (xy 172.805497 -144.662349) (xy 172.789458 -144.64717) (xy 172.779182 -144.643094)
			(xy 172.776134 -144.642078) (xy 172.774356 -144.64157) (xy 172.747352 -144.634156) (xy 172.695711 -144.6125)
			(xy 172.647789 -144.58353) (xy 172.604617 -144.547866) (xy 172.56712 -144.506276) (xy 172.536105 -144.459651)
			(xy 172.512237 -144.408994) (xy 172.49603 -144.355393) (xy 172.487831 -144.299999) (xy 172.487336 -144.272)
			(xy 172.487889 -144.242811) (xy 172.496772 -144.185113) (xy 172.514332 -144.129439) (xy 172.540158 -144.077085)
			(xy 172.573651 -144.02927) (xy 172.614029 -143.987109) (xy 172.660353 -143.951583) (xy 172.711543 -143.923519)
			(xy 172.766407 -143.903572) (xy 172.79493 -143.89735) (xy 172.795184 -143.89735) (xy 172.79874 -143.896588)
			(xy 172.806868 -143.893794) (xy 172.811522 -143.892076) (xy 172.820094 -143.887087) (xy 172.823886 -143.883888)
			(xy 172.827442 -143.880332) (xy 172.845476 -143.860774) (xy 172.84827 -143.857472) (xy 172.852475 -143.851686)
			(xy 172.857764 -143.838403) (xy 172.858684 -143.83131) (xy 172.859446 -143.815308) (xy 172.861732 -143.77162)
			(xy 172.861732 -143.769588) (xy 172.864018 -143.72971) (xy 172.864018 -143.729202) (xy 172.876464 -143.488664)
			(xy 172.880274 -143.417036) (xy 172.883322 -143.356076) (xy 172.883322 -143.355822) (xy 172.88383 -143.348202)
			(xy 172.882052 -143.34109) (xy 172.880274 -143.335248) (xy 172.876718 -143.327628) (xy 172.863002 -143.306546)
			(xy 172.859192 -143.300704) (xy 172.849032 -143.29156) (xy 172.843444 -143.288512) (xy 172.817584 -143.27418)
			(xy 172.770238 -143.238774) (xy 172.728916 -143.196492) (xy 172.694606 -143.148346) (xy 172.66813 -143.095485)
			(xy 172.650119 -143.039174) (xy 172.641004 -142.98076) (xy 172.640498 -142.9512) (xy 172.640498 -142.950438)
			(xy 172.640601 -142.938979) (xy 172.642001 -142.916104) (xy 172.643292 -142.904718) (xy 172.6438 -142.90167)
			(xy 172.6438 -142.901416) (xy 172.644562 -142.894558) (xy 172.645578 -142.889478) (xy 172.649057 -142.86979)
			(xy 172.659616 -142.831227) (xy 172.66666 -142.812516) (xy 172.678087 -142.78475) (xy 172.708391 -142.732918)
			(xy 172.746439 -142.686472) (xy 172.791293 -142.646559) (xy 172.816266 -142.62989) (xy 172.826172 -142.62354)
			(xy 172.841521 -142.614563) (xy 172.873578 -142.599174) (xy 172.89018 -142.592806) (xy 172.894752 -142.591028)
			(xy 172.903896 -142.58544) (xy 172.912538 -142.578751) (xy 172.92359 -142.559923) (xy 172.925232 -142.549118)
			(xy 172.927264 -142.512796) (xy 172.927518 -142.510256) (xy 172.927518 -142.510002) (xy 172.928788 -142.485618)
			(xy 172.929296 -142.473934) (xy 172.929296 -142.469362) (xy 172.929231 -142.465353) (xy 172.927962 -142.457437)
			(xy 172.926756 -142.453614) (xy 172.925505 -142.450246) (xy 172.922189 -142.443873) (xy 172.920152 -142.440914)
			(xy 172.903388 -142.418816) (xy 172.897038 -142.412466) (xy 172.8941 -142.409642) (xy 172.887462 -142.404916)
			(xy 172.88383 -142.403068) (xy 172.87621 -142.399512) (xy 172.871638 -142.398242) (xy 172.841957 -142.389091)
			(xy 172.78505 -142.364204) (xy 172.731808 -142.33222) (xy 172.683111 -142.293666) (xy 172.639765 -142.249181)
			(xy 172.602487 -142.1995) (xy 172.571894 -142.145446) (xy 172.548492 -142.087913) (xy 172.532667 -142.027851)
			(xy 172.524683 -141.966255) (xy 172.524166 -141.9352) (xy 172.524644 -141.904538) (xy 172.532421 -141.843708)
			(xy 172.547848 -141.784356) (xy 172.570677 -141.727439) (xy 172.600538 -141.673877) (xy 172.636951 -141.624533)
			(xy 172.679327 -141.580206) (xy 172.726982 -141.541609) (xy 172.779147 -141.509367) (xy 172.834979 -141.484)
			(xy 172.893577 -141.465918) (xy 172.923708 -141.46022) (xy 172.923962 -141.46022) (xy 172.927772 -141.459458)
			(xy 172.92828 -141.459458) (xy 172.932344 -141.458696) (xy 172.939456 -141.454886) (xy 172.9428 -141.452947)
			(xy 172.948924 -141.448231) (xy 172.951648 -141.445488) (xy 172.96003 -141.436598) (xy 172.960538 -141.43609)
			(xy 172.972476 -141.422882) (xy 172.975389 -141.41952) (xy 172.980108 -141.411979) (xy 172.981874 -141.407896)
			(xy 172.985176 -141.400022) (xy 172.985684 -141.390878) (xy 172.986446 -141.376146) (xy 172.986446 -141.374876)
			(xy 172.986954 -141.366748) (xy 172.987208 -141.3637) (xy 172.987387 -141.352586) (xy 172.97936 -141.331888)
			(xy 172.971714 -141.323822) (xy 172.965872 -141.318234) (xy 172.95622 -141.313408) (xy 172.955966 -141.313408)
			(xy 172.932233 -141.301357) (xy 172.888062 -141.271656) (xy 172.848451 -141.236101) (xy 172.814168 -141.195384)
			(xy 172.78588 -141.150296) (xy 172.764137 -141.101712) (xy 172.749361 -141.050576) (xy 172.74184 -140.997883)
			(xy 172.741336 -140.97127) (xy 172.741336 -140.97) (xy 172.74286 -140.934694) (xy 172.743114 -140.931392)
			(xy 172.743876 -140.925042) (xy 172.745177 -140.914804) (xy 172.748736 -140.894473) (xy 172.750988 -140.884402)
			(xy 172.761402 -140.847318) (xy 172.762164 -140.845032) (xy 172.764196 -140.839444) (xy 172.764196 -140.838936)
			(xy 172.773848 -140.811504) (xy 172.773848 -140.81125) (xy 172.77842 -140.801344) (xy 172.797978 -140.769848)
			(xy 172.816476 -140.741176) (xy 172.861965 -140.690328) (xy 172.888402 -140.668756) (xy 172.912055 -140.651028)
			(xy 172.963725 -140.622324) (xy 172.991272 -140.611606) (xy 172.991526 -140.611606) (xy 172.996606 -140.609574)
			(xy 173.004625 -140.605962) (xy 173.017754 -140.594279) (xy 173.026136 -140.578832) (xy 173.027848 -140.570204)
			(xy 173.028356 -140.56741) (xy 173.0375 -140.396214) (xy 173.05274 -140.10259) (xy 173.053248 -140.093446)
			(xy 173.048168 -140.076682) (xy 173.04258 -140.069316) (xy 173.04131 -140.067538) (xy 173.02607 -140.049758)
			(xy 173.025308 -140.048996) (xy 173.019466 -140.042138) (xy 172.990764 -140.026898) (xy 172.982636 -140.025374)
			(xy 172.955857 -140.020321) (xy 172.903985 -140.003623) (xy 172.855016 -139.979716) (xy 172.809946 -139.949085)
			(xy 172.769692 -139.912354) (xy 172.735073 -139.87027) (xy 172.706793 -139.823689) (xy 172.685427 -139.773559)
			(xy 172.67141 -139.720899) (xy 172.667676 -139.693904) (xy 172.666406 -139.681458) (xy 172.664882 -139.649454)
			(xy 172.664882 -139.648946) (xy 172.665401 -139.621168) (xy 172.673491 -139.566204) (xy 172.689463 -139.512994)
			(xy 172.712981 -139.462661) (xy 172.743546 -139.416269) (xy 172.761656 -139.3952) (xy 172.76191 -139.394946)
			(xy 172.768768 -139.387072) (xy 172.771054 -139.380722) (xy 172.772832 -139.37488) (xy 172.77384 -139.371153)
			(xy 172.774855 -139.363501) (xy 172.774864 -139.35964) (xy 172.773594 -139.345416) (xy 172.773594 -139.344908)
			(xy 172.769276 -139.285726) (xy 172.768514 -139.275566) (xy 172.758862 -139.256262) (xy 172.750734 -139.249404)
			(xy 172.729776 -139.231179) (xy 172.692841 -139.189703) (xy 172.662311 -139.143308) (xy 172.638832 -139.092976)
			(xy 172.622901 -139.039772) (xy 172.614854 -138.984819) (xy 172.614336 -138.95705) (xy 172.614796 -138.929796)
			(xy 172.622547 -138.875842) (xy 172.6379 -138.823541) (xy 172.66054 -138.773957) (xy 172.690007 -138.728101)
			(xy 172.725701 -138.686906) (xy 172.766896 -138.651211) (xy 172.812752 -138.621743) (xy 172.862335 -138.599102)
			(xy 172.914636 -138.583749) (xy 172.96859 -138.575996) (xy 172.995844 -138.575542) (xy 172.99813 -138.575542)
			(xy 173.029372 -138.576558) (xy 173.035214 -138.577066) (xy 173.038262 -138.57732) (xy 173.04766 -138.574272)
			(xy 173.052371 -138.572552) (xy 173.061066 -138.567561) (xy 173.064932 -138.564366) (xy 173.119796 -138.516614)
			(xy 173.12619 -138.510581) (xy 173.134761 -138.495248) (xy 173.13656 -138.486642) (xy 173.137068 -138.481054)
			(xy 173.155864 -138.122406) (xy 173.169072 -137.867898) (xy 173.177454 -137.703814) (xy 173.177591 -137.695222)
			(xy 173.172775 -137.678739) (xy 173.168056 -137.671556) (xy 173.16323 -137.664952) (xy 173.149768 -137.655554)
			(xy 173.141132 -137.653014) (xy 173.113374 -137.644208) (xy 173.060711 -137.619357) (xy 173.012437 -137.586791)
			(xy 172.969674 -137.547266) (xy 172.933414 -137.5017) (xy 172.904502 -137.451153) (xy 172.883607 -137.396799)
			(xy 172.871217 -137.339901) (xy 172.868844 -137.310876) (xy 172.868844 -137.309098) (xy 172.868258 -137.297739)
			(xy 172.86826 -137.274991) (xy 172.868844 -137.263632) (xy 172.871195 -137.234143) (xy 172.883831 -137.176354)
			(xy 172.89399 -137.14857) (xy 172.8978 -137.138664) (xy 172.897038 -137.117328) (xy 172.897038 -137.115042)
			(xy 172.898816 -137.101326) (xy 172.899578 -137.09904) (xy 172.900086 -137.096754) (xy 172.902867 -137.087578)
			(xy 172.91409 -137.072048) (xy 172.92193 -137.066528) (xy 172.922438 -137.066274) (xy 172.922946 -137.065766)
			(xy 172.924724 -137.06475) (xy 172.925486 -137.064242) (xy 172.92574 -137.064242) (xy 172.930058 -137.061702)
			(xy 172.948854 -137.04951) (xy 172.952918 -137.046208) (xy 172.953426 -137.0457) (xy 172.96257 -137.035286)
			(xy 172.963586 -137.03427) (xy 172.964094 -137.033762) (xy 172.964602 -137.033254) (xy 172.96638 -137.031476)
			(xy 172.991018 -137.00633) (xy 172.993304 -137.004298) (xy 172.997114 -137.000996) (xy 172.997368 -137.000742)
			(xy 173.015738 -136.985035) (xy 173.055738 -136.957902) (xy 173.077124 -136.94664) (xy 173.105064 -136.93394)
			(xy 173.114676 -136.930053) (xy 173.134244 -136.923189) (xy 173.14418 -136.920224) (xy 173.164754 -136.91489)
			(xy 173.16577 -136.914636) (xy 173.170342 -136.91362) (xy 173.17847 -136.909302) (xy 173.186852 -136.90473)
			(xy 173.198536 -136.891014) (xy 173.207934 -136.879838) (xy 173.208442 -136.87933) (xy 173.211236 -136.875774)
			(xy 173.214538 -136.871456) (xy 173.216673 -136.86783) (xy 173.219864 -136.860044) (xy 173.220888 -136.855962)
			(xy 173.22165 -136.851898) (xy 173.221904 -136.850374) (xy 173.221904 -136.85012) (xy 173.222158 -136.849104)
			(xy 173.226222 -136.770364) (xy 173.238414 -136.534906) (xy 173.244256 -136.422384) (xy 173.261782 -136.086088)
			(xy 173.287944 -135.584438) (xy 173.294802 -135.451342) (xy 173.31563 -135.041132) (xy 173.315671 -135.031293)
			(xy 173.309218 -135.012724) (xy 173.296277 -134.997926) (xy 173.28769 -134.993126) (xy 173.279308 -134.989062)
			(xy 173.274482 -134.987538) (xy 173.273466 -134.987284) (xy 173.273212 -134.987284) (xy 173.246905 -134.979341)
			(xy 173.196721 -134.956949) (xy 173.150266 -134.927594) (xy 173.108499 -134.891882) (xy 173.072283 -134.850552)
			(xy 173.042367 -134.804457) (xy 173.019367 -134.754549) (xy 173.00376 -134.701859) (xy 172.995868 -134.647476)
			(xy 172.995336 -134.62) (xy 172.995414 -134.607262) (xy 172.997068 -134.581841) (xy 172.998638 -134.5692)
			(xy 173.002643 -134.542761) (xy 173.017092 -134.491276) (xy 173.038589 -134.442313) (xy 173.066711 -134.396831)
			(xy 173.100908 -134.355721) (xy 173.140511 -134.319789) (xy 173.184742 -134.289738) (xy 173.232736 -134.266157)
			(xy 173.283552 -134.249508) (xy 173.309788 -134.244334) (xy 173.31817 -134.24281) (xy 173.33341 -134.234428)
			(xy 173.340785 -134.229951) (xy 173.352239 -134.217063) (xy 173.358778 -134.20111) (xy 173.359572 -134.192518)
			(xy 175.217836 -98.506788) (xy 176.988216 -64.48552) (xy 176.988216 -64.482472) (xy 176.981612 -62.6364)
			(xy 176.98085 -62.422024) (xy 176.979938 -62.412324) (xy 176.9718 -62.39464) (xy 176.95765 -62.381272)
			(xy 176.939533 -62.374151) (xy 176.929796 -62.373764) (xy 176.91608 -62.373764) (xy 176.904396 -62.380622)
			(xy 176.882806 -62.392306) (xy 176.881282 -62.393068) (xy 176.87925 -62.394084) (xy 176.864518 -62.400942)
			(xy 176.864264 -62.400942) (xy 176.85512 -62.404752) (xy 176.843243 -62.409531) (xy 176.818966 -62.417669)
			(xy 176.806606 -62.421008) (xy 176.802542 -62.422024) (xy 176.78072 -62.427036) (xy 176.736282 -62.432516)
			(xy 176.713896 -62.432946) (xy 176.709832 -62.432946) (xy 176.687127 -62.432576) (xy 176.642048 -62.427105)
			(xy 176.619916 -62.422024) (xy 176.616868 -62.421262) (xy 176.610518 -62.4205) (xy 176.599218 -62.419851)
			(xy 176.577854 -62.427233) (xy 176.56937 -62.434724) (xy 176.53381 -62.476126) (xy 176.533556 -62.476634)
			(xy 176.507902 -62.505844) (xy 176.503584 -62.51194) (xy 176.498882 -62.520337) (xy 176.495477 -62.539265)
			(xy 176.49698 -62.54877) (xy 176.499774 -62.558422) (xy 176.50079 -62.561216) (xy 176.50972 -62.584163)
			(xy 176.522271 -62.631779) (xy 176.52859 -62.680613) (xy 176.528984 -62.705234) (xy 176.528984 -62.705996)
			(xy 176.527714 -62.736222) (xy 176.527206 -62.740286) (xy 176.527206 -62.741302) (xy 176.524095 -62.769352)
			(xy 176.510664 -62.824167) (xy 176.489302 -62.876403) (xy 176.460477 -62.924922) (xy 176.424817 -62.968664)
			(xy 176.383101 -63.006675) (xy 176.33624 -63.038124) (xy 176.285257 -63.062324) (xy 176.231264 -63.078749)
			(xy 176.17544 -63.087038) (xy 176.147222 -63.087504) (xy 176.119968 -63.087042) (xy 176.066015 -63.079288)
			(xy 176.013715 -63.063934) (xy 175.964132 -63.041292) (xy 175.918277 -63.011825) (xy 175.877082 -62.976131)
			(xy 175.841386 -62.934938) (xy 175.811916 -62.889084) (xy 175.789273 -62.839502) (xy 175.773916 -62.787202)
			(xy 175.766159 -62.73325) (xy 175.765714 -62.705996) (xy 175.766195 -62.678826) (xy 175.773906 -62.625037)
			(xy 175.789172 -62.572886) (xy 175.811684 -62.523429) (xy 175.840986 -62.477666) (xy 175.876485 -62.436525)
			(xy 175.917463 -62.400838) (xy 175.96309 -62.371326) (xy 176.012443 -62.348587) (xy 176.064523 -62.333082)
			(xy 176.118277 -62.325124) (xy 176.145444 -62.324488) (xy 176.147984 -62.324488) (xy 176.169056 -62.324794)
			(xy 176.210937 -62.329501) (xy 176.23155 -62.333886) (xy 176.232058 -62.333886) (xy 176.239678 -62.335664)
			(xy 176.24298 -62.336426) (xy 176.24806 -62.336934) (xy 176.248568 -62.336934) (xy 176.257397 -62.337437)
			(xy 176.274539 -62.333145) (xy 176.282096 -62.328552) (xy 176.2887 -62.323218) (xy 176.3522 -62.249304)
			(xy 176.358074 -62.240504) (xy 176.362803 -62.219905) (xy 176.361344 -62.209426) (xy 176.35855 -62.199012)
			(xy 176.357534 -62.196218) (xy 176.348602 -62.173271) (xy 176.336046 -62.125656) (xy 176.329722 -62.076821)
			(xy 176.32934 -62.0522) (xy 176.32934 -62.051438) (xy 176.33061 -62.02045) (xy 176.331626 -62.012322)
			(xy 176.332134 -62.006988) (xy 176.336118 -61.977633) (xy 176.351991 -61.920562) (xy 176.376501 -61.866634)
			(xy 176.409057 -61.817145) (xy 176.448876 -61.773288) (xy 176.47158 -61.754258) (xy 176.493058 -61.737575)
			(xy 176.539822 -61.709811) (xy 176.590049 -61.688957) (xy 176.642725 -61.675433) (xy 176.6697 -61.671962)
			(xy 176.67097 -61.671962) (xy 176.676304 -61.6712) (xy 176.677066 -61.6712) (xy 176.679098 -61.670946)
			(xy 176.680622 -61.670946) (xy 176.684432 -61.670692) (xy 176.686464 -61.670692) (xy 176.68875 -61.670438)
			(xy 176.69256 -61.670438) (xy 176.69764 -61.670184) (xy 176.698656 -61.670184) (xy 176.702466 -61.66993)
			(xy 176.71161 -61.66993) (xy 176.744746 -61.670661) (xy 176.810014 -61.682154) (xy 176.841404 -61.69279)
			(xy 176.853342 -61.695584) (xy 176.862533 -61.696201) (xy 176.880365 -61.691636) (xy 176.88814 -61.686694)
			(xy 176.957736 -61.637418) (xy 176.96434 -61.631576) (xy 176.967388 -61.62802) (xy 176.97193 -61.62163)
			(xy 176.977221 -61.606883) (xy 176.977802 -61.599064) (xy 176.977548 -61.548518) (xy 176.97577 -60.998608)
			(xy 176.97577 -60.997084) (xy 176.975516 -60.99302) (xy 176.97577 -60.979558) (xy 176.977802 -60.845954)
			(xy 176.972976 -60.83808) (xy 176.957608 -60.812858) (xy 176.933999 -60.758723) (xy 176.919014 -60.701597)
			(xy 176.913011 -60.642843) (xy 176.916134 -60.583866) (xy 176.928308 -60.526075) (xy 176.949243 -60.470851)
			(xy 176.963324 -60.444888) (xy 176.977294 -60.422028) (xy 176.980596 -60.416948) (xy 176.982628 -60.410344)
			(xy 176.98466 -60.396374) (xy 177.010568 -58.728356) (xy 177.010548 -58.723955) (xy 177.009142 -58.715267)
			(xy 177.007774 -58.711084) (xy 177.00498 -58.702702) (xy 176.998884 -58.695336) (xy 176.982104 -58.674694)
			(xy 176.953824 -58.629637) (xy 176.932078 -58.581088) (xy 176.917289 -58.529989) (xy 176.909741 -58.477331)
			(xy 176.909222 -58.450734) (xy 176.909476 -58.444384) (xy 176.910369 -58.416598) (xy 176.9192 -58.361712)
			(xy 176.935889 -58.308684) (xy 176.960082 -58.258632) (xy 176.975262 -58.235342) (xy 176.981318 -58.226521)
			(xy 176.99428 -58.209493) (xy 177.00117 -58.201306) (xy 177.006758 -58.194702) (xy 177.01641 -58.170318)
			(xy 177.018012 -58.166045) (xy 177.019807 -58.157098) (xy 177.019966 -58.152538) (xy 177.061368 -55.495444)
			(xy 177.061368 -55.492904) (xy 177.013108 -54.262274) (xy 176.845722 -49.986946) (xy 176.845007 -49.977953)
			(xy 176.838119 -49.961293) (xy 176.83226 -49.954434) (xy 176.825402 -49.947576) (xy 176.750472 -49.906936)
			(xy 176.7459 -49.904904) (xy 176.74209 -49.902872) (xy 176.733765 -49.899196) (xy 176.715671 -49.897359)
			(xy 176.706784 -49.899316) (xy 176.693322 -49.903126) (xy 176.68748 -49.906428) (xy 176.665886 -49.918255)
			(xy 176.620304 -49.936866) (xy 176.572706 -49.949456) (xy 176.523883 -49.955814) (xy 176.499266 -49.956212)
			(xy 176.495456 -49.956212) (xy 176.457102 -49.953926) (xy 176.430628 -49.950553) (xy 176.378915 -49.937356)
			(xy 176.329547 -49.917082) (xy 176.283486 -49.890126) (xy 176.262284 -49.873916) (xy 176.257458 -49.870106)
			(xy 176.25187 -49.867566) (xy 176.246536 -49.864772) (xy 176.23536 -49.862232) (xy 176.208182 -49.862232)
			(xy 176.202742 -49.86209) (xy 176.192111 -49.859782) (xy 176.1871 -49.85766) (xy 176.173638 -49.851564)
			(xy 176.164975 -49.847938) (xy 176.14625 -49.846697) (xy 176.128345 -49.852318) (xy 176.120806 -49.857914)
			(xy 176.113694 -49.863502) (xy 176.109122 -49.867058) (xy 176.10836 -49.867566) (xy 176.087719 -49.884209)
			(xy 176.042708 -49.912232) (xy 175.99425 -49.933753) (xy 175.943279 -49.948356) (xy 175.890776 -49.955762)
			(xy 175.864266 -49.956212) (xy 175.85436 -49.956212) (xy 175.82564 -49.954968) (xy 175.769043 -49.944908)
			(xy 175.714601 -49.926455) (xy 175.663551 -49.90003) (xy 175.639984 -49.883568) (xy 175.631348 -49.877472)
			(xy 175.626268 -49.873154) (xy 175.618902 -49.868582) (xy 175.61687 -49.867566) (xy 175.611545 -49.865102)
			(xy 175.600129 -49.862403) (xy 175.594264 -49.862232) (xy 175.573182 -49.862232) (xy 175.567742 -49.86209)
			(xy 175.557111 -49.859782) (xy 175.5521 -49.85766) (xy 175.538638 -49.851564) (xy 175.529975 -49.847938)
			(xy 175.51125 -49.846697) (xy 175.493345 -49.852318) (xy 175.485806 -49.857914) (xy 175.478694 -49.863502)
			(xy 175.474122 -49.867058) (xy 175.47336 -49.867566) (xy 175.452719 -49.884209) (xy 175.407708 -49.912232)
			(xy 175.35925 -49.933753) (xy 175.308279 -49.948356) (xy 175.255776 -49.955762) (xy 175.229266 -49.956212)
			(xy 175.21936 -49.956212) (xy 175.19064 -49.954968) (xy 175.134043 -49.944908) (xy 175.079601 -49.926455)
			(xy 175.028551 -49.90003) (xy 175.004984 -49.883568) (xy 174.996348 -49.877472) (xy 174.991268 -49.873154)
			(xy 174.983902 -49.868582) (xy 174.98187 -49.867566) (xy 174.976545 -49.865102) (xy 174.965129 -49.862403)
			(xy 174.959264 -49.862232) (xy 174.938182 -49.862232) (xy 174.932742 -49.86209) (xy 174.922111 -49.859782)
			(xy 174.9171 -49.85766) (xy 174.903638 -49.851564) (xy 174.894975 -49.847938) (xy 174.87625 -49.846697)
			(xy 174.858345 -49.852318) (xy 174.850806 -49.857914) (xy 174.843694 -49.863502) (xy 174.839122 -49.867058)
			(xy 174.83836 -49.867566) (xy 174.817719 -49.884209) (xy 174.772708 -49.912232) (xy 174.72425 -49.933753)
			(xy 174.673279 -49.948356) (xy 174.620776 -49.955762) (xy 174.594266 -49.956212) (xy 174.594012 -49.956212)
			(xy 174.566758 -49.955749) (xy 174.512806 -49.947994) (xy 174.460506 -49.932639) (xy 174.410924 -49.909997)
			(xy 174.365068 -49.880529) (xy 174.323874 -49.844835) (xy 174.288179 -49.803641) (xy 174.258709 -49.757787)
			(xy 174.236066 -49.708206) (xy 174.220709 -49.655906) (xy 174.212951 -49.601954) (xy 174.212951 -49.547446)
			(xy 174.220709 -49.493494) (xy 174.236066 -49.441194) (xy 174.258709 -49.391613) (xy 174.288179 -49.345759)
			(xy 174.323874 -49.304565) (xy 174.365068 -49.268871) (xy 174.410924 -49.239403) (xy 174.460506 -49.216761)
			(xy 174.512806 -49.201406) (xy 174.566758 -49.193651) (xy 174.594012 -49.193196) (xy 174.594266 -49.193196)
			(xy 174.619882 -49.19361) (xy 174.670652 -49.200471) (xy 174.720045 -49.214073) (xy 174.76717 -49.234172)
			(xy 174.811176 -49.260404) (xy 174.831502 -49.276) (xy 174.836328 -49.27981) (xy 174.843694 -49.283112)
			(xy 174.848433 -49.284982) (xy 174.858413 -49.287029) (xy 174.863506 -49.287176) (xy 174.884842 -49.287176)
			(xy 174.890281 -49.28732) (xy 174.900913 -49.289628) (xy 174.905924 -49.291748) (xy 174.919386 -49.297844)
			(xy 174.928048 -49.301465) (xy 174.946769 -49.302698) (xy 174.964667 -49.297072) (xy 174.972218 -49.291494)
			(xy 174.97933 -49.285906) (xy 174.983902 -49.28235) (xy 174.984664 -49.281842) (xy 175.005305 -49.2652)
			(xy 175.050317 -49.237179) (xy 175.098775 -49.215661) (xy 175.149746 -49.20106) (xy 175.202248 -49.193658)
			(xy 175.228758 -49.193196) (xy 175.238664 -49.193196) (xy 175.269452 -49.194564) (xy 175.330008 -49.205998)
			(xy 175.387942 -49.227008) (xy 175.441749 -49.257049) (xy 175.466248 -49.275746) (xy 175.471328 -49.27981)
			(xy 175.479202 -49.283366) (xy 175.48383 -49.285139) (xy 175.493551 -49.287058) (xy 175.498506 -49.287176)
			(xy 175.519842 -49.287176) (xy 175.525281 -49.28732) (xy 175.535913 -49.289628) (xy 175.540924 -49.291748)
			(xy 175.554386 -49.297844) (xy 175.563048 -49.301465) (xy 175.581769 -49.302698) (xy 175.599667 -49.297072)
			(xy 175.607218 -49.291494) (xy 175.61433 -49.285906) (xy 175.618902 -49.28235) (xy 175.619664 -49.281842)
			(xy 175.640305 -49.2652) (xy 175.685317 -49.237179) (xy 175.733775 -49.215661) (xy 175.784746 -49.20106)
			(xy 175.837248 -49.193658) (xy 175.863758 -49.193196) (xy 175.873664 -49.193196) (xy 175.904452 -49.194564)
			(xy 175.965008 -49.205998) (xy 176.022942 -49.227008) (xy 176.076749 -49.257049) (xy 176.101248 -49.275746)
			(xy 176.106328 -49.27981) (xy 176.114202 -49.283366) (xy 176.11883 -49.285139) (xy 176.128551 -49.287058)
			(xy 176.133506 -49.287176) (xy 176.154842 -49.287176) (xy 176.160281 -49.28732) (xy 176.170913 -49.289628)
			(xy 176.175924 -49.291748) (xy 176.189386 -49.297844) (xy 176.198048 -49.301465) (xy 176.216769 -49.302698)
			(xy 176.234667 -49.297072) (xy 176.242218 -49.291494) (xy 176.24933 -49.285906) (xy 176.253902 -49.28235)
			(xy 176.254664 -49.281842) (xy 176.275305 -49.2652) (xy 176.320317 -49.237179) (xy 176.368775 -49.215661)
			(xy 176.419746 -49.20106) (xy 176.472248 -49.193658) (xy 176.498758 -49.193196) (xy 176.508156 -49.193196)
			(xy 176.526797 -49.193895) (xy 176.56382 -49.198479) (xy 176.58207 -49.20234) (xy 176.60874 -49.209198)
			(xy 176.616868 -49.211738) (xy 176.617884 -49.211992) (xy 176.618392 -49.212246) (xy 176.622456 -49.213516)
			(xy 176.648618 -49.223676) (xy 176.651158 -49.224946) (xy 176.652428 -49.225454) (xy 176.652936 -49.225454)
			(xy 176.66081 -49.229264) (xy 176.66589 -49.23155) (xy 176.679098 -49.234598) (xy 176.687723 -49.236218)
			(xy 176.705134 -49.23414) (xy 176.713134 -49.230534) (xy 176.716182 -49.22901) (xy 176.785016 -49.183798)
			(xy 176.793144 -49.177194) (xy 176.797462 -49.172876) (xy 176.802034 -49.167542) (xy 176.803558 -49.16551)
			(xy 176.807831 -49.158652) (xy 176.812222 -49.143111) (xy 176.812194 -49.13503) (xy 176.72304 -46.852586)
			(xy 176.72304 -46.8503) (xy 175.786542 -39.919656) (xy 175.78278 -39.890264) (xy 175.778332 -39.83117)
			(xy 175.777652 -39.801546) (xy 175.772318 -39.470076) (xy 175.769778 -39.4589) (xy 175.767238 -39.454074)
			(xy 175.747992 -39.414111) (xy 175.715852 -39.331432) (xy 175.691186 -39.246224) (xy 175.674189 -39.159162)
			(xy 175.664996 -39.070933) (xy 175.66386 -39.026592) (xy 175.657256 -38.598094) (xy 175.657256 -38.59657)
			(xy 175.65624 -38.551358) (xy 175.65624 -38.548564) (xy 175.65624 -38.515798) (xy 175.65659 -38.476006)
			(xy 175.662853 -38.396669) (xy 175.675421 -38.318084) (xy 175.684434 -38.279324) (xy 175.686974 -38.269418)
			(xy 175.68291 -38.243764) (xy 175.681132 -38.232842) (xy 175.671226 -38.172136) (xy 175.665161 -38.132665)
			(xy 175.658679 -38.053064) (xy 175.658272 -38.013132) (xy 175.658526 -37.992812) (xy 175.65878 -37.981636)
			(xy 175.658018 -37.977064) (xy 175.652554 -37.941234) (xy 175.646201 -37.869026) (xy 175.645318 -37.832792)
			(xy 175.645318 -37.831268) (xy 175.645064 -37.818568) (xy 175.637698 -37.337238) (xy 175.637698 -37.336984)
			(xy 175.637444 -37.322252) (xy 175.637444 -37.320728) (xy 175.63805 -37.274261) (xy 175.64684 -37.181742)
			(xy 175.664197 -37.090442) (xy 175.67656 -37.045646) (xy 175.678338 -37.039296) (xy 175.679862 -36.960556)
			(xy 175.67529 -36.950396) (xy 175.670972 -36.940236) (xy 175.66767 -36.932362) (xy 175.646588 -36.908232)
			(xy 175.63846 -36.902644) (xy 175.618648 -36.892738) (xy 175.613322 -36.890277) (xy 175.601906 -36.887584)
			(xy 175.596042 -36.887404) (xy 175.582072 -36.887404) (xy 175.576738 -36.888674) (xy 175.562283 -36.89163)
			(xy 175.53304 -36.895574) (xy 175.518318 -36.896548) (xy 175.514762 -36.896548) (xy 175.51273 -36.896802)
			(xy 175.508412 -36.896802) (xy 175.505618 -36.897056) (xy 175.493172 -36.897056) (xy 175.466063 -36.896364)
			(xy 175.412446 -36.888259) (xy 175.360517 -36.872643) (xy 175.311322 -36.84983) (xy 175.265854 -36.820281)
			(xy 175.225029 -36.78459) (xy 175.189669 -36.743478) (xy 175.160488 -36.697773) (xy 175.138073 -36.648396)
			(xy 175.122877 -36.596342) (xy 175.115205 -36.542661) (xy 175.114712 -36.515548) (xy 175.115194 -36.488307)
			(xy 175.122939 -36.434377) (xy 175.138277 -36.382098) (xy 175.160897 -36.332533) (xy 175.190339 -36.28669)
			(xy 175.226003 -36.245503) (xy 175.267164 -36.209808) (xy 175.312985 -36.180332) (xy 175.362534 -36.157676)
			(xy 175.414801 -36.142299) (xy 175.468725 -36.134514) (xy 175.495966 -36.13404) (xy 175.510698 -36.13404)
			(xy 175.515778 -36.133532) (xy 175.52316 -36.132421) (xy 175.536847 -36.12648) (xy 175.542702 -36.121848)
			(xy 175.546512 -36.118546) (xy 175.54702 -36.118038) (xy 175.595534 -36.074604) (xy 175.602392 -36.06673)
			(xy 175.608742 -36.056824) (xy 175.611282 -36.045902) (xy 175.612044 -36.039806) (xy 175.612044 -36.038536)
			(xy 175.61814 -35.988498) (xy 175.624658 -35.946034) (xy 175.644117 -35.862349) (xy 175.657002 -35.821366)
			(xy 175.67783 -35.763962) (xy 175.67783 -35.763454) (xy 175.680624 -35.75685) (xy 175.680624 -35.756596)
			(xy 175.683418 -35.749992) (xy 175.683418 -35.749738) (xy 175.684434 -35.747706) (xy 175.684942 -35.746182)
			(xy 175.690784 -35.73272) (xy 175.695864 -35.72129) (xy 175.698341 -35.714664) (xy 175.699887 -35.70061)
			(xy 175.698912 -35.693604) (xy 175.68926 -35.658298) (xy 175.68926 -35.65779) (xy 175.684434 -35.639756)
			(xy 175.677322 -35.61334) (xy 175.676052 -35.60826) (xy 175.672496 -35.595306) (xy 175.672496 -35.594798)
			(xy 175.661828 -35.556444) (xy 175.659034 -35.546284) (xy 175.650398 -35.535616) (xy 175.640238 -35.526726)
			(xy 175.620934 -35.514788) (xy 175.620172 -35.514534) (xy 175.591978 -35.49777) (xy 175.586102 -35.494624)
			(xy 175.573239 -35.491143) (xy 175.566578 -35.490912) (xy 175.555402 -35.490912) (xy 175.542448 -35.49269)
			(xy 175.504454 -35.501351) (xy 175.427464 -35.513439) (xy 175.349767 -35.519494) (xy 175.3108 -35.519868)
			(xy 175.306482 -35.519868) (xy 175.259809 -35.519126) (xy 175.166906 -35.510006) (xy 175.075261 -35.49224)
			(xy 174.985679 -35.465984) (xy 174.898944 -35.431468) (xy 174.815816 -35.388995) (xy 174.77613 -35.36442)
			(xy 174.774098 -35.364928) (xy 174.770034 -35.36569) (xy 174.753035 -35.368564) (xy 174.718693 -35.371615)
			(xy 174.701454 -35.371786) (xy 174.700946 -35.371786) (xy 174.673692 -35.371326) (xy 174.619737 -35.363574)
			(xy 174.567435 -35.348222) (xy 174.51785 -35.325582) (xy 174.471993 -35.296114) (xy 174.430797 -35.26042)
			(xy 174.3951 -35.219226) (xy 174.36563 -35.173371) (xy 174.342987 -35.123788) (xy 174.327631 -35.071487)
			(xy 174.319876 -35.017532) (xy 174.319438 -34.990278) (xy 174.319438 -34.987484) (xy 174.320007 -34.963282)
			(xy 174.326522 -34.91531) (xy 174.339063 -34.86855) (xy 174.347886 -34.846006) (xy 174.348394 -34.844482)
			(xy 174.350172 -34.840164) (xy 174.356776 -34.824162) (xy 174.358046 -34.818574) (xy 174.353474 -34.802826)
			(xy 174.340977 -34.758474) (xy 174.323265 -34.668039) (xy 174.313982 -34.576355) (xy 174.313088 -34.530284)
			(xy 174.313088 -34.519108) (xy 174.313664 -34.477575) (xy 174.320865 -34.394817) (xy 174.33492 -34.312944)
			(xy 174.355731 -34.232522) (xy 174.383154 -34.154109) (xy 174.399702 -34.11601) (xy 174.40275 -34.106358)
			(xy 174.406306 -34.091118) (xy 174.406306 -34.090102) (xy 174.40275 -34.074862) (xy 174.399702 -34.06521)
			(xy 174.383022 -34.026807) (xy 174.355412 -33.947757) (xy 174.334532 -33.866669) (xy 174.32053 -33.784115)
			(xy 174.313503 -33.700677) (xy 174.313088 -33.65881) (xy 174.313088 -33.658302) (xy 174.313359 -33.626014)
			(xy 174.317556 -33.561575) (xy 174.32147 -33.529524) (xy 174.32497 -33.504119) (xy 174.334246 -33.453675)
			(xy 174.340012 -33.428686) (xy 174.344029 -33.412172) (xy 174.35305 -33.379399) (xy 174.358046 -33.363154)
			(xy 174.356268 -33.35528) (xy 174.353982 -33.349692) (xy 174.344466 -33.328077) (xy 174.330242 -33.283041)
			(xy 174.321687 -33.236593) (xy 174.319946 -33.21304) (xy 174.319946 -33.208722) (xy 174.319438 -33.19018)
			(xy 174.319438 -33.18256) (xy 174.320432 -33.155664) (xy 174.32905 -33.102538) (xy 174.345049 -33.05115)
			(xy 174.368114 -33.002522) (xy 174.397785 -32.957618) (xy 174.433474 -32.917332) (xy 174.474471 -32.882462)
			(xy 174.519963 -32.853702) (xy 174.569047 -32.831622) (xy 174.620746 -32.816661) (xy 174.674035 -32.809115)
			(xy 174.700946 -32.808672) (xy 174.7012 -32.808672) (xy 174.715671 -32.808786) (xy 174.744531 -32.810948)
			(xy 174.758858 -32.81299) (xy 174.767676 -32.81398) (xy 174.785082 -32.810596) (xy 174.792894 -32.806386)
			(xy 174.831934 -32.783272) (xy 174.913438 -32.7434) (xy 174.998224 -32.711091) (xy 175.085593 -32.686612)
			(xy 175.174824 -32.670166) (xy 175.265179 -32.661888) (xy 175.310546 -32.661352) (xy 175.3108 -32.661352)
			(xy 175.35614 -32.661878) (xy 175.446444 -32.67013) (xy 175.535627 -32.68654) (xy 175.622954 -32.710972)
			(xy 175.707705 -32.743224) (xy 175.789181 -32.783031) (xy 175.828198 -32.806132) (xy 175.835923 -32.8104)
			(xy 175.853204 -32.813914) (xy 175.86198 -32.81299) (xy 175.876686 -32.81091) (xy 175.90631 -32.808746)
			(xy 175.921162 -32.808672) (xy 175.921924 -32.808672) (xy 175.951642 -32.80936) (xy 176.010331 -32.818796)
			(xy 176.038764 -32.827468) (xy 176.05248 -32.83204) (xy 176.06391 -32.831024) (xy 176.071791 -32.830011)
			(xy 176.086405 -32.823794) (xy 176.092612 -32.818832) (xy 176.11217 -32.804608) (xy 176.15535 -32.773112)
			(xy 176.159126 -32.769919) (xy 176.165516 -32.762373) (xy 176.16805 -32.758126) (xy 176.167542 -32.737552)
			(xy 176.167542 -32.737298) (xy 176.167288 -32.722566) (xy 176.167288 -32.720788) (xy 176.167542 -32.696912)
			(xy 176.169386 -32.647678) (xy 176.181589 -32.549908) (xy 176.203385 -32.45382) (xy 176.234561 -32.360353)
			(xy 176.254156 -32.31515) (xy 176.255934 -32.311086) (xy 176.260506 -32.29102) (xy 176.260506 -32.290004)
			(xy 176.25695 -32.274764) (xy 176.253902 -32.265112) (xy 176.237222 -32.226709) (xy 176.209612 -32.147659)
			(xy 176.188732 -32.066571) (xy 176.174729 -31.984017) (xy 176.167703 -31.900579) (xy 176.167288 -31.858712)
			(xy 176.168812 -31.804864) (xy 176.169828 -31.785052) (xy 176.16805 -31.782258) (xy 176.166272 -31.779972)
			(xy 176.162716 -31.775908) (xy 176.162208 -31.7754) (xy 176.160684 -31.773622) (xy 176.16043 -31.773368)
			(xy 176.14265 -31.753048) (xy 176.134014 -31.74619) (xy 176.12233 -31.739586) (xy 176.118266 -31.739078)
			(xy 176.115726 -31.738824) (xy 176.111662 -31.738316) (xy 176.111408 -31.738316) (xy 176.101248 -31.737046)
			(xy 176.093374 -31.736284) (xy 176.077626 -31.739332) (xy 176.06772 -31.74238) (xy 176.049407 -31.74972)
			(xy 176.011614 -31.761047) (xy 175.992282 -31.764986) (xy 175.992028 -31.764986) (xy 175.98771 -31.765748)
			(xy 175.979328 -31.767272) (xy 175.978566 -31.767272) (xy 175.975518 -31.76778) (xy 175.967136 -31.76905)
			(xy 175.965612 -31.76905) (xy 175.964342 -31.769304) (xy 175.963326 -31.769304) (xy 175.92929 -31.771844)
			(xy 175.919638 -31.771844) (xy 175.903363 -31.771661) (xy 175.870934 -31.76886) (xy 175.854868 -31.766256)
			(xy 175.844962 -31.764478) (xy 175.804977 -31.7892) (xy 175.721202 -31.831867) (xy 175.633785 -31.866465)
			(xy 175.543501 -31.892687) (xy 175.451151 -31.910299) (xy 175.357553 -31.919147) (xy 175.310546 -31.919672)
			(xy 175.264915 -31.919185) (xy 175.17403 -31.910893) (xy 175.084283 -31.894329) (xy 174.996427 -31.86963)
			(xy 174.911195 -31.837005) (xy 174.829303 -31.796726) (xy 174.7901 -31.773368) (xy 174.78447 -31.770548)
			(xy 174.772264 -31.767473) (xy 174.76597 -31.767272) (xy 174.759874 -31.767272) (xy 174.756318 -31.76778)
			(xy 174.755302 -31.768034) (xy 174.754032 -31.768034) (xy 174.736252 -31.77032) (xy 174.730918 -31.770828)
			(xy 174.729902 -31.770828) (xy 174.72787 -31.771082) (xy 174.726854 -31.771082) (xy 174.706788 -31.771844)
			(xy 174.700946 -31.771844) (xy 174.67369 -31.771384) (xy 174.619732 -31.763633) (xy 174.567427 -31.748281)
			(xy 174.517838 -31.725642) (xy 174.471977 -31.696176) (xy 174.430776 -31.660482) (xy 174.395074 -31.619289)
			(xy 174.365598 -31.573434) (xy 174.342948 -31.52385) (xy 174.327585 -31.471548) (xy 174.319822 -31.417592)
			(xy 174.319438 -31.390336) (xy 174.319438 -31.387542) (xy 174.320003 -31.363339) (xy 174.326511 -31.315365)
			(xy 174.339046 -31.268602) (xy 174.347886 -31.246064) (xy 174.348394 -31.24454) (xy 174.350172 -31.240222)
			(xy 174.356776 -31.22422) (xy 174.358046 -31.218632) (xy 174.353474 -31.202884) (xy 174.340744 -31.157586)
			(xy 174.322859 -31.065204) (xy 174.313748 -30.971548) (xy 174.313088 -30.9245) (xy 174.313088 -30.91561)
			(xy 174.313688 -30.878397) (xy 174.319747 -30.804211) (xy 174.331323 -30.730684) (xy 174.339504 -30.694376)
			(xy 174.35087 -30.648428) (xy 174.381147 -30.558741) (xy 174.399956 -30.515306) (xy 174.401734 -30.511242)
			(xy 174.406306 -30.491176) (xy 174.406306 -30.49016) (xy 174.401734 -30.470094) (xy 174.399956 -30.46603)
			(xy 174.383228 -30.42756) (xy 174.355537 -30.348367) (xy 174.334599 -30.267127) (xy 174.320561 -30.184415)
			(xy 174.313523 -30.100815) (xy 174.313088 -30.058868) (xy 174.313544 -30.015527) (xy 174.321049 -29.929172)
			(xy 174.328074 -29.886402) (xy 174.332232 -29.863598) (xy 174.342396 -29.818368) (xy 174.348394 -29.795978)
			(xy 174.3583 -29.76245) (xy 174.356522 -29.755084) (xy 174.344817 -29.729287) (xy 174.328297 -29.675101)
			(xy 174.319957 -29.61907) (xy 174.319438 -29.590746) (xy 174.319438 -29.590238) (xy 174.319899 -29.562985)
			(xy 174.327652 -29.509032) (xy 174.343005 -29.456732) (xy 174.365646 -29.40715) (xy 174.395113 -29.361296)
			(xy 174.430808 -29.320102) (xy 174.472002 -29.284409) (xy 174.517857 -29.254942) (xy 174.56744 -29.232302)
			(xy 174.61974 -29.21695) (xy 174.673693 -29.209198) (xy 174.700946 -29.20873) (xy 174.701708 -29.20873)
			(xy 174.719403 -29.208943) (xy 174.754639 -29.212253) (xy 174.772066 -29.215334) (xy 174.77613 -29.216096)
			(xy 174.776892 -29.21635) (xy 174.816833 -29.1917) (xy 174.900506 -29.149163) (xy 174.987804 -29.114674)
			(xy 175.077956 -29.088538) (xy 175.170164 -29.070985) (xy 175.263614 -29.062172) (xy 175.310546 -29.061664)
			(xy 175.35745 -29.062194) (xy 175.450845 -29.070983) (xy 175.543002 -29.0885) (xy 175.633109 -29.114588)
			(xy 175.720369 -29.149018) (xy 175.804013 -29.191486) (xy 175.843946 -29.216096) (xy 175.844962 -29.215842)
			(xy 175.848518 -29.215334) (xy 175.866197 -29.212222) (xy 175.901943 -29.208917) (xy 175.919892 -29.20873)
			(xy 175.920908 -29.20873) (xy 175.9463 -29.209148) (xy 175.996633 -29.215904) (xy 176.021238 -29.222192)
			(xy 176.023016 -29.2227) (xy 176.024286 -29.222954) (xy 176.028096 -29.22397) (xy 176.042066 -29.228542)
			(xy 176.042574 -29.228542) (xy 176.047908 -29.230574) (xy 176.060608 -29.231844) (xy 176.06645 -29.231082)
			(xy 176.077118 -29.228288) (xy 176.08931 -29.221684) (xy 176.152302 -29.17571) (xy 176.153064 -29.175202)
			(xy 176.15789 -29.171646) (xy 176.164494 -29.165296) (xy 176.16805 -29.16047) (xy 176.167542 -29.137864)
			(xy 176.167542 -29.13761) (xy 176.167288 -29.122624) (xy 176.167288 -29.120846) (xy 176.167542 -29.09697)
			(xy 176.169388 -29.047737) (xy 176.181595 -28.949968) (xy 176.203394 -28.853882) (xy 176.234574 -28.760417)
			(xy 176.254156 -28.715208) (xy 176.255934 -28.711144) (xy 176.260506 -28.691078) (xy 176.260506 -28.690062)
			(xy 176.255934 -28.669996) (xy 176.254156 -28.665932) (xy 176.237428 -28.627462) (xy 176.209737 -28.548269)
			(xy 176.188799 -28.467029) (xy 176.17476 -28.384317) (xy 176.167722 -28.300718) (xy 176.167288 -28.25877)
			(xy 176.167744 -28.215429) (xy 176.175249 -28.129074) (xy 176.182274 -28.086304) (xy 176.186437 -28.063564)
			(xy 176.196601 -28.018461) (xy 176.202594 -27.996134) (xy 176.202594 -27.995626) (xy 176.209706 -27.972004)
			(xy 176.209706 -27.971496) (xy 176.2125 -27.962352) (xy 176.210722 -27.954986) (xy 176.208436 -27.95016)
			(xy 176.198853 -27.928471) (xy 176.184519 -27.883272) (xy 176.17589 -27.836647) (xy 176.174146 -27.813)
			(xy 176.174146 -27.808682) (xy 176.173638 -27.79014) (xy 176.173638 -27.78252) (xy 176.174635 -27.755626)
			(xy 176.183257 -27.702504) (xy 176.19926 -27.651121) (xy 176.222327 -27.602497) (xy 176.251999 -27.557599)
			(xy 176.287688 -27.517317) (xy 176.328684 -27.482452) (xy 176.374174 -27.453695) (xy 176.423255 -27.431618)
			(xy 176.474951 -27.416659) (xy 176.528237 -27.409115) (xy 176.555146 -27.408632) (xy 176.572767 -27.408742)
			(xy 176.607874 -27.411796) (xy 176.62525 -27.414728) (xy 176.627282 -27.415236) (xy 176.6316 -27.415998)
			(xy 176.674526 -27.39009) (xy 176.675542 -27.389582) (xy 176.678844 -27.387804) (xy 176.69637 -27.377898)
			(xy 176.69764 -27.375104) (xy 176.698148 -27.37358) (xy 176.698656 -27.372564) (xy 176.719738 -27.295348)
			(xy 176.719484 -27.281632) (xy 176.717706 -27.275028) (xy 176.713388 -27.259534) (xy 176.71034 -27.2542)
			(xy 176.698646 -27.232664) (xy 176.680229 -27.187249) (xy 176.66777 -27.139852) (xy 176.661473 -27.091251)
			(xy 176.661064 -27.066748) (xy 176.661064 -27.057604) (xy 176.661318 -27.05354) (xy 176.661318 -27.052778)
			(xy 176.663604 -27.022552) (xy 176.666708 -26.998918) (xy 176.678054 -26.952619) (xy 176.695097 -26.908102)
			(xy 176.706022 -26.886916) (xy 176.718853 -26.8638) (xy 176.749924 -26.821025) (xy 176.786606 -26.782952)
			(xy 176.807114 -26.766266) (xy 176.809146 -26.764742) (xy 176.816258 -26.757884) (xy 176.829212 -26.742136)
			(xy 176.831752 -26.736802) (xy 176.834292 -26.725118) (xy 176.830228 -26.647394) (xy 176.82972 -26.634948)
			(xy 176.814734 -26.609294) (xy 176.80686 -26.59888) (xy 176.799494 -26.591514) (xy 176.791366 -26.584656)
			(xy 176.78908 -26.583132) (xy 176.767181 -26.567859) (xy 176.72747 -26.532172) (xy 176.693118 -26.4913)
			(xy 176.664797 -26.446041) (xy 176.643058 -26.397277) (xy 176.628326 -26.345959) (xy 176.620887 -26.293089)
			(xy 176.620424 -26.266394) (xy 176.62091 -26.239125) (xy 176.628672 -26.185141) (xy 176.644037 -26.132811)
			(xy 176.666694 -26.083201) (xy 176.69618 -26.03732) (xy 176.731895 -25.996103) (xy 176.773112 -25.960388)
			(xy 176.818993 -25.930902) (xy 176.868603 -25.908245) (xy 176.920933 -25.89288) (xy 176.974917 -25.885118)
			(xy 177.029455 -25.885118) (xy 177.083439 -25.89288) (xy 177.135769 -25.908245) (xy 177.185379 -25.930902)
			(xy 177.23126 -25.960388) (xy 177.272477 -25.996103) (xy 177.308192 -26.03732) (xy 177.337678 -26.083201)
			(xy 177.360335 -26.132811) (xy 177.3757 -26.185141) (xy 177.383462 -26.239125) (xy 177.383948 -26.266394)
			(xy 177.383411 -26.295751) (xy 177.374424 -26.353774) (xy 177.356661 -26.409737) (xy 177.330542 -26.462322)
			(xy 177.29668 -26.510288) (xy 177.255876 -26.552507) (xy 177.232818 -26.570686) (xy 177.229516 -26.573226)
			(xy 177.225706 -26.577036) (xy 177.21961 -26.58491) (xy 177.215881 -26.591021) (xy 177.211637 -26.604686)
			(xy 177.211228 -26.611834) (xy 177.215038 -26.69667) (xy 177.219864 -26.706068) (xy 177.22088 -26.708354)
			(xy 177.23358 -26.72969) (xy 177.237898 -26.734008) (xy 177.249074 -26.745438) (xy 177.255424 -26.749756)
			(xy 177.277282 -26.764969) (xy 177.316928 -26.800525) (xy 177.351239 -26.841252) (xy 177.379548 -26.886359)
			(xy 177.401303 -26.934967) (xy 177.41608 -26.98613) (xy 177.423593 -27.038852) (xy 177.42408 -27.065478)
			(xy 177.42408 -27.07005) (xy 177.423235 -27.100326) (xy 177.413151 -27.160045) (xy 177.404014 -27.188922)
			(xy 177.403252 -27.191208) (xy 177.400712 -27.199336) (xy 177.401728 -27.210512) (xy 177.404014 -27.221688)
			(xy 177.404776 -27.223466) (xy 177.419762 -27.254454) (xy 177.42027 -27.254962) (xy 177.428144 -27.27071)
			(xy 177.442622 -27.298904) (xy 177.4444 -27.30119) (xy 177.457354 -27.305254) (xy 177.463958 -27.307286)
			(xy 177.487824 -27.314949) (xy 177.534837 -27.332355) (xy 177.557938 -27.342084) (xy 177.559674 -27.342846)
			(xy 184.623456 -27.342846) (xy 184.623456 -26.479246) (xy 184.623946 -26.449262) (xy 184.631774 -26.389806)
			(xy 184.647295 -26.331881) (xy 184.670244 -26.276477) (xy 184.700228 -26.224543) (xy 184.736734 -26.176967)
			(xy 184.779139 -26.134562) (xy 184.826715 -26.098056) (xy 184.878649 -26.068072) (xy 184.934053 -26.045123)
			(xy 184.991978 -26.029602) (xy 185.051434 -26.021774) (xy 185.111402 -26.021774) (xy 185.170858 -26.029602)
			(xy 185.228783 -26.045123) (xy 185.284187 -26.068072) (xy 185.336121 -26.098056) (xy 185.383697 -26.134562)
			(xy 185.426102 -26.176967) (xy 185.462608 -26.224543) (xy 185.492592 -26.276477) (xy 185.515541 -26.331881)
			(xy 185.523312 -26.360882) (xy 187.189616 -26.360882) (xy 187.193687 -26.30526) (xy 187.205813 -26.250823)
			(xy 187.225736 -26.198732) (xy 187.253032 -26.150097) (xy 187.287118 -26.105954) (xy 187.327267 -26.067245)
			(xy 187.372625 -26.034794) (xy 187.422225 -26.009293) (xy 187.475009 -25.991286) (xy 187.529852 -25.981156)
			(xy 187.585586 -25.979119) (xy 187.641023 -25.985219) (xy 187.69498 -25.999325) (xy 187.746309 -26.021137)
			(xy 187.793915 -26.050191) (xy 187.836783 -26.085866) (xy 187.874 -26.127403) (xy 187.904773 -26.173916)
			(xy 187.928445 -26.224413) (xy 187.944513 -26.27782) (xy 187.950681 -26.319734) (xy 192.941954 -26.319734)
			(xy 192.946025 -26.264112) (xy 192.958151 -26.209675) (xy 192.978074 -26.157584) (xy 193.00537 -26.108949)
			(xy 193.039456 -26.064806) (xy 193.079605 -26.026097) (xy 193.124963 -25.993646) (xy 193.174563 -25.968145)
			(xy 193.227347 -25.950138) (xy 193.28219 -25.940008) (xy 193.337924 -25.937971) (xy 193.393361 -25.944071)
			(xy 193.447318 -25.958177) (xy 193.498647 -25.979989) (xy 193.546253 -26.009043) (xy 193.575918 -26.03373)
			(xy 199.3679 -26.03373) (xy 199.371971 -25.978108) (xy 199.384097 -25.923671) (xy 199.40402 -25.87158)
			(xy 199.431316 -25.822945) (xy 199.465402 -25.778802) (xy 199.505551 -25.740093) (xy 199.550909 -25.707642)
			(xy 199.600509 -25.682141) (xy 199.653293 -25.664134) (xy 199.708136 -25.654004) (xy 199.76387 -25.651967)
			(xy 199.819307 -25.658067) (xy 199.873264 -25.672173) (xy 199.924593 -25.693985) (xy 199.972199 -25.723039)
			(xy 200.015067 -25.758714) (xy 200.052284 -25.800251) (xy 200.083057 -25.846764) (xy 200.106729 -25.897261)
			(xy 200.122797 -25.950668) (xy 200.130917 -26.005844) (xy 200.131426 -26.03373) (xy 200.130917 -26.061616)
			(xy 200.122797 -26.116792) (xy 200.106729 -26.170199) (xy 200.083057 -26.220696) (xy 200.052284 -26.267209)
			(xy 200.015067 -26.308746) (xy 199.972199 -26.344421) (xy 199.924593 -26.373475) (xy 199.873264 -26.395287)
			(xy 199.819307 -26.409393) (xy 199.76387 -26.415493) (xy 199.708136 -26.413456) (xy 199.653293 -26.403326)
			(xy 199.600509 -26.385319) (xy 199.550909 -26.359818) (xy 199.505551 -26.327367) (xy 199.465402 -26.288658)
			(xy 199.431316 -26.244515) (xy 199.40402 -26.19588) (xy 199.384097 -26.143789) (xy 199.371971 -26.089352)
			(xy 199.3679 -26.03373) (xy 193.575918 -26.03373) (xy 193.589121 -26.044718) (xy 193.626338 -26.086255)
			(xy 193.657111 -26.132768) (xy 193.680783 -26.183265) (xy 193.696851 -26.236672) (xy 193.704971 -26.291848)
			(xy 193.70548 -26.319734) (xy 193.704971 -26.34762) (xy 193.696851 -26.402796) (xy 193.680783 -26.456203)
			(xy 193.657111 -26.5067) (xy 193.626338 -26.553213) (xy 193.589121 -26.59475) (xy 193.546253 -26.630425)
			(xy 193.498647 -26.659479) (xy 193.447318 -26.681291) (xy 193.393361 -26.695397) (xy 193.337924 -26.701497)
			(xy 193.28219 -26.69946) (xy 193.227347 -26.68933) (xy 193.174563 -26.671323) (xy 193.124963 -26.645822)
			(xy 193.079605 -26.613371) (xy 193.039456 -26.574662) (xy 193.00537 -26.530519) (xy 192.978074 -26.481884)
			(xy 192.958151 -26.429793) (xy 192.946025 -26.375356) (xy 192.941954 -26.319734) (xy 187.950681 -26.319734)
			(xy 187.952633 -26.332996) (xy 187.953142 -26.360882) (xy 187.952633 -26.388768) (xy 187.944513 -26.443944)
			(xy 187.928445 -26.497351) (xy 187.904773 -26.547848) (xy 187.874 -26.594361) (xy 187.836783 -26.635898)
			(xy 187.793915 -26.671573) (xy 187.746309 -26.700627) (xy 187.69498 -26.722439) (xy 187.641023 -26.736545)
			(xy 187.585586 -26.742645) (xy 187.529852 -26.740608) (xy 187.475009 -26.730478) (xy 187.422225 -26.712471)
			(xy 187.372625 -26.68697) (xy 187.327267 -26.654519) (xy 187.287118 -26.61581) (xy 187.253032 -26.571667)
			(xy 187.225736 -26.523032) (xy 187.205813 -26.470941) (xy 187.193687 -26.416504) (xy 187.189616 -26.360882)
			(xy 185.523312 -26.360882) (xy 185.531062 -26.389806) (xy 185.53889 -26.449262) (xy 185.53938 -26.479246)
			(xy 185.53938 -26.971244) (xy 188.951106 -26.971244) (xy 188.955177 -26.915622) (xy 188.967303 -26.861185)
			(xy 188.987226 -26.809094) (xy 189.014522 -26.760459) (xy 189.048608 -26.716316) (xy 189.088757 -26.677607)
			(xy 189.134115 -26.645156) (xy 189.183715 -26.619655) (xy 189.236499 -26.601648) (xy 189.291342 -26.591518)
			(xy 189.347076 -26.589481) (xy 189.402513 -26.595581) (xy 189.45647 -26.609687) (xy 189.507799 -26.631499)
			(xy 189.555405 -26.660553) (xy 189.598273 -26.696228) (xy 189.63549 -26.737765) (xy 189.666263 -26.784278)
			(xy 189.689935 -26.834775) (xy 189.706003 -26.888182) (xy 189.714123 -26.943358) (xy 189.714632 -26.971244)
			(xy 189.714123 -26.99913) (xy 189.706003 -27.054306) (xy 189.689935 -27.107713) (xy 189.666263 -27.15821)
			(xy 189.63549 -27.204723) (xy 189.598273 -27.24626) (xy 189.555405 -27.281935) (xy 189.507799 -27.310989)
			(xy 189.45647 -27.332801) (xy 189.402513 -27.346907) (xy 189.347076 -27.353007) (xy 189.291342 -27.35097)
			(xy 189.236499 -27.34084) (xy 189.183715 -27.322833) (xy 189.134115 -27.297332) (xy 189.088757 -27.264881)
			(xy 189.048608 -27.226172) (xy 189.014522 -27.182029) (xy 188.987226 -27.133394) (xy 188.967303 -27.081303)
			(xy 188.955177 -27.026866) (xy 188.951106 -26.971244) (xy 185.53938 -26.971244) (xy 185.53938 -27.342846)
			(xy 185.53889 -27.37283) (xy 185.531062 -27.432286) (xy 185.515541 -27.490211) (xy 185.492592 -27.545615)
			(xy 185.462608 -27.597549) (xy 185.426102 -27.645125) (xy 185.383697 -27.68753) (xy 185.336121 -27.724036)
			(xy 185.284187 -27.75402) (xy 185.228783 -27.776969) (xy 185.170858 -27.79249) (xy 185.111402 -27.800318)
			(xy 185.051434 -27.800318) (xy 184.991978 -27.79249) (xy 184.934053 -27.776969) (xy 184.878649 -27.75402)
			(xy 184.826715 -27.724036) (xy 184.779139 -27.68753) (xy 184.736734 -27.645125) (xy 184.700228 -27.597549)
			(xy 184.670244 -27.545615) (xy 184.647295 -27.490211) (xy 184.631774 -27.432286) (xy 184.623946 -27.37283)
			(xy 184.623456 -27.342846) (xy 177.559674 -27.342846) (xy 177.58886 -27.355653) (xy 177.648983 -27.386415)
			(xy 177.67808 -27.403552) (xy 177.685128 -27.407419) (xy 177.700783 -27.411036) (xy 177.708814 -27.410664)
			(xy 177.712624 -27.410156) (xy 177.714148 -27.410156) (xy 177.717196 -27.409648) (xy 177.718212 -27.409648)
			(xy 177.718974 -27.409394) (xy 177.72888 -27.408886) (xy 177.730404 -27.408886) (xy 177.738786 -27.408378)
			(xy 177.744882 -27.408378) (xy 177.748946 -27.408378) (xy 177.76825 -27.408886) (xy 177.777902 -27.409648)
			(xy 177.804909 -27.412184) (xy 177.857866 -27.423922) (xy 177.908628 -27.44304) (xy 177.956172 -27.469152)
			(xy 177.999539 -27.501733) (xy 178.037857 -27.540126) (xy 178.054508 -27.56154) (xy 178.05654 -27.56408)
			(xy 178.100935 -27.571476) (xy 178.188274 -27.59324) (xy 178.273296 -27.622783) (xy 178.355311 -27.659865)
			(xy 178.433652 -27.704185) (xy 178.507683 -27.755382) (xy 178.5768 -27.81304) (xy 178.60899 -27.844496)
			(xy 179.878966 -29.114242) (xy 186.947556 -29.114242) (xy 186.947556 -28.250642) (xy 186.948046 -28.220674)
			(xy 186.955869 -28.161252) (xy 186.971382 -28.103359) (xy 186.994318 -28.047986) (xy 187.024285 -27.99608)
			(xy 187.060772 -27.94853) (xy 187.103152 -27.90615) (xy 187.150702 -27.869663) (xy 187.202608 -27.839696)
			(xy 187.257981 -27.81676) (xy 187.315874 -27.801247) (xy 187.375296 -27.793424) (xy 187.435232 -27.793424)
			(xy 187.494654 -27.801247) (xy 187.552547 -27.81676) (xy 187.60792 -27.839696) (xy 187.659826 -27.869663)
			(xy 187.707376 -27.90615) (xy 187.749756 -27.94853) (xy 187.786243 -27.99608) (xy 187.81621 -28.047986)
			(xy 187.839146 -28.103359) (xy 187.854659 -28.161252) (xy 187.862482 -28.220674) (xy 187.862972 -28.250642)
			(xy 187.862972 -28.469082) (xy 191.852548 -28.469082) (xy 191.856619 -28.41346) (xy 191.868745 -28.359023)
			(xy 191.888668 -28.306932) (xy 191.915964 -28.258297) (xy 191.95005 -28.214154) (xy 191.990199 -28.175445)
			(xy 192.035557 -28.142994) (xy 192.085157 -28.117493) (xy 192.137941 -28.099486) (xy 192.192784 -28.089356)
			(xy 192.248518 -28.087319) (xy 192.303955 -28.093419) (xy 192.357912 -28.107525) (xy 192.409241 -28.129337)
			(xy 192.425297 -28.139136) (xy 196.497954 -28.139136) (xy 196.502025 -28.083514) (xy 196.514151 -28.029077)
			(xy 196.534074 -27.976986) (xy 196.56137 -27.928351) (xy 196.595456 -27.884208) (xy 196.635605 -27.845499)
			(xy 196.680963 -27.813048) (xy 196.730563 -27.787547) (xy 196.783347 -27.76954) (xy 196.83819 -27.75941)
			(xy 196.893924 -27.757373) (xy 196.949361 -27.763473) (xy 197.003318 -27.777579) (xy 197.054647 -27.799391)
			(xy 197.102253 -27.828445) (xy 197.145121 -27.86412) (xy 197.182338 -27.905657) (xy 197.213111 -27.95217)
			(xy 197.236783 -28.002667) (xy 197.252851 -28.056074) (xy 197.260971 -28.11125) (xy 197.26148 -28.139136)
			(xy 197.767954 -28.139136) (xy 197.772025 -28.083514) (xy 197.784151 -28.029077) (xy 197.804074 -27.976986)
			(xy 197.83137 -27.928351) (xy 197.865456 -27.884208) (xy 197.905605 -27.845499) (xy 197.950963 -27.813048)
			(xy 198.000563 -27.787547) (xy 198.053347 -27.76954) (xy 198.10819 -27.75941) (xy 198.163924 -27.757373)
			(xy 198.219361 -27.763473) (xy 198.273318 -27.777579) (xy 198.324647 -27.799391) (xy 198.372253 -27.828445)
			(xy 198.415121 -27.86412) (xy 198.452338 -27.905657) (xy 198.483111 -27.95217) (xy 198.506783 -28.002667)
			(xy 198.522851 -28.056074) (xy 198.530971 -28.11125) (xy 198.53148 -28.139136) (xy 198.530971 -28.167022)
			(xy 198.522851 -28.222198) (xy 198.506783 -28.275605) (xy 198.483111 -28.326102) (xy 198.452338 -28.372615)
			(xy 198.415121 -28.414152) (xy 198.372253 -28.449827) (xy 198.324647 -28.478881) (xy 198.273318 -28.500693)
			(xy 198.219361 -28.514799) (xy 198.163924 -28.520899) (xy 198.10819 -28.518862) (xy 198.053347 -28.508732)
			(xy 198.000563 -28.490725) (xy 197.950963 -28.465224) (xy 197.905605 -28.432773) (xy 197.865456 -28.394064)
			(xy 197.83137 -28.349921) (xy 197.804074 -28.301286) (xy 197.784151 -28.249195) (xy 197.772025 -28.194758)
			(xy 197.767954 -28.139136) (xy 197.26148 -28.139136) (xy 197.260971 -28.167022) (xy 197.252851 -28.222198)
			(xy 197.236783 -28.275605) (xy 197.213111 -28.326102) (xy 197.182338 -28.372615) (xy 197.145121 -28.414152)
			(xy 197.102253 -28.449827) (xy 197.054647 -28.478881) (xy 197.003318 -28.500693) (xy 196.949361 -28.514799)
			(xy 196.893924 -28.520899) (xy 196.83819 -28.518862) (xy 196.783347 -28.508732) (xy 196.730563 -28.490725)
			(xy 196.680963 -28.465224) (xy 196.635605 -28.432773) (xy 196.595456 -28.394064) (xy 196.56137 -28.349921)
			(xy 196.534074 -28.301286) (xy 196.514151 -28.249195) (xy 196.502025 -28.194758) (xy 196.497954 -28.139136)
			(xy 192.425297 -28.139136) (xy 192.456847 -28.158391) (xy 192.499715 -28.194066) (xy 192.536932 -28.235603)
			(xy 192.567705 -28.282116) (xy 192.591377 -28.332613) (xy 192.607445 -28.38602) (xy 192.615565 -28.441196)
			(xy 192.616074 -28.469082) (xy 192.615565 -28.496968) (xy 192.607445 -28.552144) (xy 192.591377 -28.605551)
			(xy 192.567705 -28.656048) (xy 192.536932 -28.702561) (xy 192.499715 -28.744098) (xy 192.456847 -28.779773)
			(xy 192.409241 -28.808827) (xy 192.357912 -28.830639) (xy 192.303955 -28.844745) (xy 192.248518 -28.850845)
			(xy 192.192784 -28.848808) (xy 192.137941 -28.838678) (xy 192.085157 -28.820671) (xy 192.035557 -28.79517)
			(xy 191.990199 -28.762719) (xy 191.95005 -28.72401) (xy 191.915964 -28.679867) (xy 191.888668 -28.631232)
			(xy 191.868745 -28.579141) (xy 191.856619 -28.524704) (xy 191.852548 -28.469082) (xy 187.862972 -28.469082)
			(xy 187.862972 -29.114242) (xy 187.862482 -29.14421) (xy 187.854659 -29.203632) (xy 187.839146 -29.261525)
			(xy 187.81621 -29.316898) (xy 187.786243 -29.368804) (xy 187.749756 -29.416354) (xy 187.707376 -29.458734)
			(xy 187.659826 -29.495221) (xy 187.60792 -29.525188) (xy 187.552547 -29.548124) (xy 187.494654 -29.563637)
			(xy 187.435232 -29.57146) (xy 187.375296 -29.57146) (xy 187.315874 -29.563637) (xy 187.257981 -29.548124)
			(xy 187.202608 -29.525188) (xy 187.150702 -29.495221) (xy 187.103152 -29.458734) (xy 187.060772 -29.416354)
			(xy 187.024285 -29.368804) (xy 186.994318 -29.316898) (xy 186.971382 -29.261525) (xy 186.955869 -29.203632)
			(xy 186.948046 -29.14421) (xy 186.947556 -29.114242) (xy 179.878966 -29.114242) (xy 180.01107 -29.246322)
			(xy 180.014118 -29.247846) (xy 180.017166 -29.24937) (xy 180.018182 -29.249878) (xy 180.044672 -29.263993)
			(xy 180.093237 -29.299263) (xy 180.135683 -29.3417) (xy 180.170963 -29.390257) (xy 180.18506 -29.416756)
			(xy 180.185568 -29.417772) (xy 180.187092 -29.42082) (xy 180.188616 -29.423868) (xy 180.307996 -29.543248)
			(xy 181.507892 -30.743398) (xy 181.532551 -30.768434) (xy 181.578693 -30.821443) (xy 181.600094 -30.849316)
			(xy 181.615243 -30.869694) (xy 181.643705 -30.911751) (xy 181.649193 -30.92069) (xy 189.589664 -30.92069)
			(xy 189.589664 -30.05709) (xy 189.590154 -30.027122) (xy 189.597977 -29.9677) (xy 189.61349 -29.909807)
			(xy 189.636426 -29.854434) (xy 189.666393 -29.802528) (xy 189.70288 -29.754978) (xy 189.74526 -29.712598)
			(xy 189.79281 -29.676111) (xy 189.844716 -29.646144) (xy 189.900089 -29.623208) (xy 189.957982 -29.607695)
			(xy 190.017404 -29.599872) (xy 190.07734 -29.599872) (xy 190.136762 -29.607695) (xy 190.194655 -29.623208)
			(xy 190.250028 -29.646144) (xy 190.301934 -29.676111) (xy 190.349484 -29.712598) (xy 190.391864 -29.754978)
			(xy 190.428351 -29.802528) (xy 190.458318 -29.854434) (xy 190.481254 -29.909807) (xy 190.496767 -29.9677)
			(xy 190.50459 -30.027122) (xy 190.50508 -30.05709) (xy 190.50508 -30.376876) (xy 194.988942 -30.376876)
			(xy 194.989499 -30.34796) (xy 194.998218 -30.29079) (xy 195.015467 -30.235592) (xy 195.040851 -30.183629)
			(xy 195.073789 -30.136095) (xy 195.113525 -30.094077) (xy 195.136008 -30.075886) (xy 195.144813 -30.068276)
			(xy 195.154997 -30.047378) (xy 195.155566 -30.035754) (xy 195.155566 -29.955998) (xy 195.155026 -29.944366)
			(xy 195.144839 -29.923456) (xy 195.136008 -29.915866) (xy 195.11351 -29.897692) (xy 195.073775 -29.855669)
			(xy 195.040838 -29.808131) (xy 195.015452 -29.756166) (xy 194.998199 -29.700965) (xy 194.989474 -29.643793)
			(xy 194.988942 -29.614876) (xy 194.989428 -29.587625) (xy 194.997184 -29.533677) (xy 195.012539 -29.481382)
			(xy 195.035181 -29.431805) (xy 195.064647 -29.385955) (xy 195.100338 -29.344764) (xy 195.141529 -29.309073)
			(xy 195.187379 -29.279607) (xy 195.236956 -29.256965) (xy 195.289251 -29.24161) (xy 195.343199 -29.233854)
			(xy 195.397701 -29.233854) (xy 195.451649 -29.24161) (xy 195.503944 -29.256965) (xy 195.553521 -29.279607)
			(xy 195.599371 -29.309073) (xy 195.640562 -29.344764) (xy 195.676253 -29.385955) (xy 195.705719 -29.431805)
			(xy 195.728361 -29.481382) (xy 195.743716 -29.533677) (xy 195.751472 -29.587625) (xy 195.751958 -29.614876)
			(xy 195.751438 -29.643793) (xy 195.742712 -29.700965) (xy 195.725455 -29.756164) (xy 195.700064 -29.808126)
			(xy 195.66712 -29.85566) (xy 195.627378 -29.897676) (xy 195.604892 -29.915866) (xy 195.596109 -29.923497)
			(xy 195.585912 -29.944379) (xy 195.585334 -29.955998) (xy 195.585334 -30.035754) (xy 195.585845 -30.04739)
			(xy 195.596053 -30.0683) (xy 195.604892 -30.075886) (xy 195.627367 -30.094087) (xy 195.667103 -30.136104)
			(xy 195.700043 -30.183637) (xy 195.725433 -30.235597) (xy 195.742691 -30.290792) (xy 195.751422 -30.347961)
			(xy 195.751958 -30.376876) (xy 198.029068 -30.376876) (xy 198.029615 -30.34796) (xy 198.038335 -30.290789)
			(xy 198.055585 -30.23559) (xy 198.080971 -30.183627) (xy 198.113911 -30.136093) (xy 198.15365 -30.094076)
			(xy 198.176134 -30.075886) (xy 198.184943 -30.068281) (xy 198.195124 -30.047378) (xy 198.195692 -30.035754)
			(xy 198.195692 -29.955998) (xy 198.195143 -29.944367) (xy 198.184961 -29.923457) (xy 198.176134 -29.915866)
			(xy 198.153641 -29.897686) (xy 198.113905 -29.855665) (xy 198.080966 -29.808128) (xy 198.055579 -29.756164)
			(xy 198.038325 -29.700964) (xy 198.0296 -29.643793) (xy 198.029068 -29.614876) (xy 198.029554 -29.587625)
			(xy 198.03731 -29.533677) (xy 198.052665 -29.481382) (xy 198.075307 -29.431805) (xy 198.104773 -29.385955)
			(xy 198.140464 -29.344764) (xy 198.181655 -29.309073) (xy 198.227505 -29.279607) (xy 198.277082 -29.256965)
			(xy 198.329377 -29.24161) (xy 198.383325 -29.233854) (xy 198.437827 -29.233854) (xy 198.491775 -29.24161)
			(xy 198.54407 -29.256965) (xy 198.593647 -29.279607) (xy 198.639497 -29.309073) (xy 198.680688 -29.344764)
			(xy 198.716379 -29.385955) (xy 198.745845 -29.431805) (xy 198.768487 -29.481382) (xy 198.783842 -29.533677)
			(xy 198.791598 -29.587625) (xy 198.792084 -29.614876) (xy 198.791554 -29.643793) (xy 198.782829 -29.700964)
			(xy 198.765573 -29.756162) (xy 198.740184 -29.808124) (xy 198.707242 -29.855658) (xy 198.667503 -29.897676)
			(xy 198.645018 -29.915866) (xy 198.636222 -29.923484) (xy 198.626036 -29.944377) (xy 198.62546 -29.955998)
			(xy 198.62546 -30.035754) (xy 198.625961 -30.047391) (xy 198.636175 -30.068302) (xy 198.645018 -30.075886)
			(xy 198.667499 -30.09408) (xy 198.707233 -30.1361) (xy 198.740172 -30.183634) (xy 198.765561 -30.235595)
			(xy 198.782818 -30.290792) (xy 198.791548 -30.34796) (xy 198.792084 -30.376876) (xy 198.791598 -30.404127)
			(xy 198.783842 -30.458075) (xy 198.768487 -30.51037) (xy 198.745845 -30.559947) (xy 198.716379 -30.605797)
			(xy 198.680688 -30.646988) (xy 198.639497 -30.682679) (xy 198.593647 -30.712145) (xy 198.54407 -30.734787)
			(xy 198.491775 -30.750142) (xy 198.437827 -30.757898) (xy 198.383325 -30.757898) (xy 198.329377 -30.750142)
			(xy 198.277082 -30.734787) (xy 198.227505 -30.712145) (xy 198.181655 -30.682679) (xy 198.140464 -30.646988)
			(xy 198.104773 -30.605797) (xy 198.075307 -30.559947) (xy 198.052665 -30.51037) (xy 198.03731 -30.458075)
			(xy 198.029554 -30.404127) (xy 198.029068 -30.376876) (xy 195.751958 -30.376876) (xy 195.751472 -30.404127)
			(xy 195.743716 -30.458075) (xy 195.728361 -30.51037) (xy 195.705719 -30.559947) (xy 195.676253 -30.605797)
			(xy 195.640562 -30.646988) (xy 195.599371 -30.682679) (xy 195.553521 -30.712145) (xy 195.503944 -30.734787)
			(xy 195.451649 -30.750142) (xy 195.397701 -30.757898) (xy 195.343199 -30.757898) (xy 195.289251 -30.750142)
			(xy 195.236956 -30.734787) (xy 195.187379 -30.712145) (xy 195.141529 -30.682679) (xy 195.100338 -30.646988)
			(xy 195.064647 -30.605797) (xy 195.035181 -30.559947) (xy 195.012539 -30.51037) (xy 194.997184 -30.458075)
			(xy 194.989428 -30.404127) (xy 194.988942 -30.376876) (xy 190.50508 -30.376876) (xy 190.50508 -30.92069)
			(xy 190.50459 -30.950658) (xy 190.496767 -31.01008) (xy 190.481254 -31.067973) (xy 190.458318 -31.123346)
			(xy 190.428351 -31.175252) (xy 190.391864 -31.222802) (xy 190.349484 -31.265182) (xy 190.301934 -31.301669)
			(xy 190.250028 -31.331636) (xy 190.194655 -31.354572) (xy 190.136762 -31.370085) (xy 190.07734 -31.377908)
			(xy 190.017404 -31.377908) (xy 189.957982 -31.370085) (xy 189.900089 -31.354572) (xy 189.844716 -31.331636)
			(xy 189.79281 -31.301669) (xy 189.74526 -31.265182) (xy 189.70288 -31.222802) (xy 189.666393 -31.175252)
			(xy 189.636426 -31.123346) (xy 189.61349 -31.067973) (xy 189.597977 -31.01008) (xy 189.590154 -30.950658)
			(xy 189.589664 -30.92069) (xy 181.649193 -30.92069) (xy 181.65699 -30.93339) (xy 181.658006 -30.935168)
			(xy 181.664102 -30.94355) (xy 181.677938 -30.958748) (xy 181.704488 -30.990128) (xy 181.717188 -31.006288)
			(xy 181.730291 -31.023208) (xy 181.755193 -31.058018) (xy 181.766972 -31.075884) (xy 181.783482 -31.1023)
			(xy 181.784498 -31.104332) (xy 181.786022 -31.106618) (xy 181.792118 -31.116778) (xy 181.800246 -31.130748)
			(xy 181.800246 -31.131002) (xy 181.806342 -31.142178) (xy 181.807358 -31.14421) (xy 181.819315 -31.166691)
			(xy 181.841169 -31.212689) (xy 181.851046 -31.236158) (xy 182.208932 -32.099504) (xy 182.463482 -32.714184)
			(xy 186.947556 -32.714184) (xy 186.947556 -31.850584) (xy 186.948046 -31.820616) (xy 186.955869 -31.761194)
			(xy 186.971382 -31.703301) (xy 186.994318 -31.647928) (xy 187.024285 -31.596022) (xy 187.060772 -31.548472)
			(xy 187.103152 -31.506092) (xy 187.150702 -31.469605) (xy 187.202608 -31.439638) (xy 187.257981 -31.416702)
			(xy 187.315874 -31.401189) (xy 187.375296 -31.393366) (xy 187.435232 -31.393366) (xy 187.494654 -31.401189)
			(xy 187.552547 -31.416702) (xy 187.60792 -31.439638) (xy 187.659826 -31.469605) (xy 187.707376 -31.506092)
			(xy 187.749756 -31.548472) (xy 187.76465 -31.567882) (xy 195.098668 -31.567882) (xy 195.102739 -31.51226)
			(xy 195.114865 -31.457823) (xy 195.134788 -31.405732) (xy 195.162084 -31.357097) (xy 195.19617 -31.312954)
			(xy 195.236319 -31.274245) (xy 195.281677 -31.241794) (xy 195.331277 -31.216293) (xy 195.384061 -31.198286)
			(xy 195.438904 -31.188156) (xy 195.494638 -31.186119) (xy 195.550075 -31.192219) (xy 195.604032 -31.206325)
			(xy 195.655361 -31.228137) (xy 195.702967 -31.257191) (xy 195.745835 -31.292866) (xy 195.783052 -31.334403)
			(xy 195.813825 -31.380916) (xy 195.837497 -31.431413) (xy 195.853565 -31.48482) (xy 195.861685 -31.539996)
			(xy 195.862194 -31.567882) (xy 195.861685 -31.595768) (xy 195.853565 -31.650944) (xy 195.837497 -31.704351)
			(xy 195.830505 -31.719266) (xy 196.385432 -31.719266) (xy 196.389503 -31.663644) (xy 196.401629 -31.609207)
			(xy 196.421552 -31.557116) (xy 196.448848 -31.508481) (xy 196.482934 -31.464338) (xy 196.523083 -31.425629)
			(xy 196.568441 -31.393178) (xy 196.618041 -31.367677) (xy 196.670825 -31.34967) (xy 196.725668 -31.33954)
			(xy 196.781402 -31.337503) (xy 196.836839 -31.343603) (xy 196.890796 -31.357709) (xy 196.942125 -31.379521)
			(xy 196.989731 -31.408575) (xy 197.032599 -31.44425) (xy 197.069816 -31.485787) (xy 197.100589 -31.5323)
			(xy 197.124261 -31.582797) (xy 197.140329 -31.636204) (xy 197.144479 -31.664402) (xy 197.66102 -31.664402)
			(xy 197.665091 -31.60878) (xy 197.677217 -31.554343) (xy 197.69714 -31.502252) (xy 197.724436 -31.453617)
			(xy 197.758522 -31.409474) (xy 197.798671 -31.370765) (xy 197.844029 -31.338314) (xy 197.893629 -31.312813)
			(xy 197.946413 -31.294806) (xy 198.001256 -31.284676) (xy 198.05699 -31.282639) (xy 198.112427 -31.288739)
			(xy 198.166384 -31.302845) (xy 198.217713 -31.324657) (xy 198.265319 -31.353711) (xy 198.308187 -31.389386)
			(xy 198.345404 -31.430923) (xy 198.376177 -31.477436) (xy 198.399849 -31.527933) (xy 198.415917 -31.58134)
			(xy 198.424037 -31.636516) (xy 198.424546 -31.664402) (xy 198.424037 -31.692288) (xy 198.415917 -31.747464)
			(xy 198.406977 -31.777178) (xy 198.926194 -31.777178) (xy 198.930265 -31.721556) (xy 198.942391 -31.667119)
			(xy 198.962314 -31.615028) (xy 198.98961 -31.566393) (xy 199.023696 -31.52225) (xy 199.063845 -31.483541)
			(xy 199.109203 -31.45109) (xy 199.158803 -31.425589) (xy 199.211587 -31.407582) (xy 199.26643 -31.397452)
			(xy 199.322164 -31.395415) (xy 199.377601 -31.401515) (xy 199.431558 -31.415621) (xy 199.482887 -31.437433)
			(xy 199.530493 -31.466487) (xy 199.573361 -31.502162) (xy 199.610578 -31.543699) (xy 199.641351 -31.590212)
			(xy 199.665023 -31.640709) (xy 199.681091 -31.694116) (xy 199.689211 -31.749292) (xy 199.68972 -31.777178)
			(xy 199.689211 -31.805064) (xy 199.681091 -31.86024) (xy 199.665023 -31.913647) (xy 199.641351 -31.964144)
			(xy 199.610578 -32.010657) (xy 199.573361 -32.052194) (xy 199.530493 -32.087869) (xy 199.482887 -32.116923)
			(xy 199.431558 -32.138735) (xy 199.377601 -32.152841) (xy 199.322164 -32.158941) (xy 199.26643 -32.156904)
			(xy 199.211587 -32.146774) (xy 199.158803 -32.128767) (xy 199.109203 -32.103266) (xy 199.063845 -32.070815)
			(xy 199.023696 -32.032106) (xy 198.98961 -31.987963) (xy 198.962314 -31.939328) (xy 198.942391 -31.887237)
			(xy 198.930265 -31.8328) (xy 198.926194 -31.777178) (xy 198.406977 -31.777178) (xy 198.399849 -31.800871)
			(xy 198.376177 -31.851368) (xy 198.345404 -31.897881) (xy 198.308187 -31.939418) (xy 198.265319 -31.975093)
			(xy 198.217713 -32.004147) (xy 198.166384 -32.025959) (xy 198.112427 -32.040065) (xy 198.05699 -32.046165)
			(xy 198.001256 -32.044128) (xy 197.946413 -32.033998) (xy 197.893629 -32.015991) (xy 197.844029 -31.99049)
			(xy 197.798671 -31.958039) (xy 197.758522 -31.91933) (xy 197.724436 -31.875187) (xy 197.69714 -31.826552)
			(xy 197.677217 -31.774461) (xy 197.665091 -31.720024) (xy 197.66102 -31.664402) (xy 197.144479 -31.664402)
			(xy 197.148449 -31.69138) (xy 197.148958 -31.719266) (xy 197.148449 -31.747152) (xy 197.140329 -31.802328)
			(xy 197.124261 -31.855735) (xy 197.100589 -31.906232) (xy 197.069816 -31.952745) (xy 197.032599 -31.994282)
			(xy 196.989731 -32.029957) (xy 196.942125 -32.059011) (xy 196.890796 -32.080823) (xy 196.836839 -32.094929)
			(xy 196.781402 -32.101029) (xy 196.725668 -32.098992) (xy 196.670825 -32.088862) (xy 196.618041 -32.070855)
			(xy 196.568441 -32.045354) (xy 196.523083 -32.012903) (xy 196.482934 -31.974194) (xy 196.448848 -31.930051)
			(xy 196.421552 -31.881416) (xy 196.401629 -31.829325) (xy 196.389503 -31.774888) (xy 196.385432 -31.719266)
			(xy 195.830505 -31.719266) (xy 195.813825 -31.754848) (xy 195.783052 -31.801361) (xy 195.745835 -31.842898)
			(xy 195.702967 -31.878573) (xy 195.655361 -31.907627) (xy 195.604032 -31.929439) (xy 195.550075 -31.943545)
			(xy 195.494638 -31.949645) (xy 195.438904 -31.947608) (xy 195.384061 -31.937478) (xy 195.331277 -31.919471)
			(xy 195.281677 -31.89397) (xy 195.236319 -31.861519) (xy 195.19617 -31.82281) (xy 195.162084 -31.778667)
			(xy 195.134788 -31.730032) (xy 195.114865 -31.677941) (xy 195.102739 -31.623504) (xy 195.098668 -31.567882)
			(xy 187.76465 -31.567882) (xy 187.786243 -31.596022) (xy 187.81621 -31.647928) (xy 187.839146 -31.703301)
			(xy 187.854659 -31.761194) (xy 187.862482 -31.820616) (xy 187.862972 -31.850584) (xy 187.862972 -32.714184)
			(xy 187.862482 -32.744152) (xy 187.854659 -32.803574) (xy 187.839146 -32.861467) (xy 187.81621 -32.91684)
			(xy 187.786243 -32.968746) (xy 187.749756 -33.016296) (xy 187.707376 -33.058676) (xy 187.659826 -33.095163)
			(xy 187.60792 -33.12513) (xy 187.552547 -33.148066) (xy 187.494654 -33.163579) (xy 187.435232 -33.171402)
			(xy 187.375296 -33.171402) (xy 187.315874 -33.163579) (xy 187.257981 -33.148066) (xy 187.202608 -33.12513)
			(xy 187.150702 -33.095163) (xy 187.103152 -33.058676) (xy 187.060772 -33.016296) (xy 187.024285 -32.968746)
			(xy 186.994318 -32.91684) (xy 186.971382 -32.861467) (xy 186.955869 -32.803574) (xy 186.948046 -32.744152)
			(xy 186.947556 -32.714184) (xy 182.463482 -32.714184) (xy 182.477156 -32.747204) (xy 182.509668 -32.825944)
			(xy 182.516526 -32.836612) (xy 182.534306 -32.856678) (xy 182.541418 -32.860742) (xy 182.565686 -32.875524)
			(xy 182.609955 -32.911146) (xy 182.648448 -32.952944) (xy 182.680312 -32.999991) (xy 182.704842 -33.051245)
			(xy 182.721493 -33.105572) (xy 182.729899 -33.161769) (xy 182.730394 -33.19018) (xy 182.730394 -33.197038)
			(xy 182.729657 -33.22194) (xy 182.722517 -33.271245) (xy 182.71617 -33.295336) (xy 182.71363 -33.304226)
			(xy 182.714138 -33.311846) (xy 182.714498 -33.316027) (xy 182.716413 -33.324196) (xy 182.717948 -33.328102)
			(xy 183.21205 -34.520886) (xy 189.589664 -34.520886) (xy 189.589664 -33.657286) (xy 189.590154 -33.627318)
			(xy 189.597977 -33.567896) (xy 189.61349 -33.510003) (xy 189.636426 -33.45463) (xy 189.666393 -33.402724)
			(xy 189.70288 -33.355174) (xy 189.74526 -33.312794) (xy 189.79281 -33.276307) (xy 189.844716 -33.24634)
			(xy 189.900089 -33.223404) (xy 189.957982 -33.207891) (xy 190.017404 -33.200068) (xy 190.07734 -33.200068)
			(xy 190.136762 -33.207891) (xy 190.194655 -33.223404) (xy 190.250028 -33.24634) (xy 190.301934 -33.276307)
			(xy 190.349484 -33.312794) (xy 190.391864 -33.355174) (xy 190.428351 -33.402724) (xy 190.458318 -33.45463)
			(xy 190.481254 -33.510003) (xy 190.496767 -33.567896) (xy 190.50459 -33.627318) (xy 190.50508 -33.657286)
			(xy 190.50508 -34.520886) (xy 190.50459 -34.550854) (xy 190.496767 -34.610276) (xy 190.481254 -34.668169)
			(xy 190.458318 -34.723542) (xy 190.428351 -34.775448) (xy 190.391864 -34.822998) (xy 190.349484 -34.865378)
			(xy 190.301934 -34.901865) (xy 190.250028 -34.931832) (xy 190.194655 -34.954768) (xy 190.136762 -34.970281)
			(xy 190.07734 -34.978104) (xy 190.017404 -34.978104) (xy 189.957982 -34.970281) (xy 189.900089 -34.954768)
			(xy 189.844716 -34.931832) (xy 189.79281 -34.901865) (xy 189.74526 -34.865378) (xy 189.70288 -34.822998)
			(xy 189.666393 -34.775448) (xy 189.636426 -34.723542) (xy 189.61349 -34.668169) (xy 189.597977 -34.610276)
			(xy 189.590154 -34.550854) (xy 189.589664 -34.520886) (xy 183.21205 -34.520886) (xy 183.520233 -35.264852)
			(xy 198.002396 -35.264852) (xy 198.006467 -35.20923) (xy 198.018593 -35.154793) (xy 198.038516 -35.102702)
			(xy 198.065812 -35.054067) (xy 198.099898 -35.009924) (xy 198.140047 -34.971215) (xy 198.185405 -34.938764)
			(xy 198.235005 -34.913263) (xy 198.287789 -34.895256) (xy 198.342632 -34.885126) (xy 198.398366 -34.883089)
			(xy 198.453803 -34.889189) (xy 198.50776 -34.903295) (xy 198.559089 -34.925107) (xy 198.606695 -34.954161)
			(xy 198.649563 -34.989836) (xy 198.68678 -35.031373) (xy 198.717553 -35.077886) (xy 198.741225 -35.128383)
			(xy 198.757293 -35.18179) (xy 198.765413 -35.236966) (xy 198.765922 -35.264852) (xy 198.765413 -35.292738)
			(xy 198.757293 -35.347914) (xy 198.741225 -35.401321) (xy 198.717553 -35.451818) (xy 198.68678 -35.498331)
			(xy 198.649563 -35.539868) (xy 198.606695 -35.575543) (xy 198.559089 -35.604597) (xy 198.50776 -35.626409)
			(xy 198.453803 -35.640515) (xy 198.398366 -35.646615) (xy 198.342632 -35.644578) (xy 198.287789 -35.634448)
			(xy 198.235005 -35.616441) (xy 198.185405 -35.59094) (xy 198.140047 -35.558489) (xy 198.099898 -35.51978)
			(xy 198.065812 -35.475637) (xy 198.038516 -35.427002) (xy 198.018593 -35.374911) (xy 198.006467 -35.320474)
			(xy 198.002396 -35.264852) (xy 183.520233 -35.264852) (xy 183.701944 -35.70351) (xy 183.773641 -35.876738)
			(xy 186.817252 -35.876738) (xy 186.821323 -35.821116) (xy 186.833449 -35.766679) (xy 186.853372 -35.714588)
			(xy 186.880668 -35.665953) (xy 186.914754 -35.62181) (xy 186.954903 -35.583101) (xy 187.000261 -35.55065)
			(xy 187.049861 -35.525149) (xy 187.102645 -35.507142) (xy 187.157488 -35.497012) (xy 187.213222 -35.494975)
			(xy 187.268659 -35.501075) (xy 187.322616 -35.515181) (xy 187.373945 -35.536993) (xy 187.421551 -35.566047)
			(xy 187.464419 -35.601722) (xy 187.501636 -35.643259) (xy 187.532409 -35.689772) (xy 187.556081 -35.740269)
			(xy 187.572149 -35.793676) (xy 187.580269 -35.848852) (xy 187.580778 -35.876738) (xy 190.888872 -35.876738)
			(xy 190.892943 -35.821116) (xy 190.905069 -35.766679) (xy 190.924992 -35.714588) (xy 190.952288 -35.665953)
			(xy 190.986374 -35.62181) (xy 191.026523 -35.583101) (xy 191.071881 -35.55065) (xy 191.121481 -35.525149)
			(xy 191.174265 -35.507142) (xy 191.229108 -35.497012) (xy 191.284842 -35.494975) (xy 191.340279 -35.501075)
			(xy 191.394236 -35.515181) (xy 191.445565 -35.536993) (xy 191.493171 -35.566047) (xy 191.536039 -35.601722)
			(xy 191.573256 -35.643259) (xy 191.604029 -35.689772) (xy 191.627701 -35.740269) (xy 191.643769 -35.793676)
			(xy 191.651889 -35.848852) (xy 191.652398 -35.876738) (xy 191.651889 -35.904624) (xy 191.643769 -35.9598)
			(xy 191.627701 -36.013207) (xy 191.604029 -36.063704) (xy 191.573256 -36.110217) (xy 191.536039 -36.151754)
			(xy 191.493171 -36.187429) (xy 191.445565 -36.216483) (xy 191.394236 -36.238295) (xy 191.340279 -36.252401)
			(xy 191.284842 -36.258501) (xy 191.229108 -36.256464) (xy 191.174265 -36.246334) (xy 191.121481 -36.228327)
			(xy 191.071881 -36.202826) (xy 191.026523 -36.170375) (xy 190.986374 -36.131666) (xy 190.952288 -36.087523)
			(xy 190.924992 -36.038888) (xy 190.905069 -35.986797) (xy 190.892943 -35.93236) (xy 190.888872 -35.876738)
			(xy 187.580778 -35.876738) (xy 187.580269 -35.904624) (xy 187.572149 -35.9598) (xy 187.556081 -36.013207)
			(xy 187.532409 -36.063704) (xy 187.501636 -36.110217) (xy 187.464419 -36.151754) (xy 187.421551 -36.187429)
			(xy 187.373945 -36.216483) (xy 187.322616 -36.238295) (xy 187.268659 -36.252401) (xy 187.213222 -36.258501)
			(xy 187.157488 -36.256464) (xy 187.102645 -36.246334) (xy 187.049861 -36.228327) (xy 187.000261 -36.202826)
			(xy 186.954903 -36.170375) (xy 186.914754 -36.131666) (xy 186.880668 -36.087523) (xy 186.853372 -36.038888)
			(xy 186.833449 -35.986797) (xy 186.821323 -35.93236) (xy 186.817252 -35.876738) (xy 183.773641 -35.876738)
			(xy 183.935116 -36.266882) (xy 183.969406 -36.349432) (xy 184.035885 -36.50996) (xy 188.71387 -36.50996)
			(xy 188.717941 -36.454338) (xy 188.730067 -36.399901) (xy 188.74999 -36.34781) (xy 188.777286 -36.299175)
			(xy 188.811372 -36.255032) (xy 188.851521 -36.216323) (xy 188.896879 -36.183872) (xy 188.946479 -36.158371)
			(xy 188.999263 -36.140364) (xy 189.054106 -36.130234) (xy 189.10984 -36.128197) (xy 189.165277 -36.134297)
			(xy 189.219234 -36.148403) (xy 189.270563 -36.170215) (xy 189.318169 -36.199269) (xy 189.361037 -36.234944)
			(xy 189.398254 -36.276481) (xy 189.429027 -36.322994) (xy 189.452699 -36.373491) (xy 189.468767 -36.426898)
			(xy 189.472692 -36.453572) (xy 192.02857 -36.453572) (xy 192.032641 -36.39795) (xy 192.044767 -36.343513)
			(xy 192.06469 -36.291422) (xy 192.091986 -36.242787) (xy 192.126072 -36.198644) (xy 192.166221 -36.159935)
			(xy 192.211579 -36.127484) (xy 192.261179 -36.101983) (xy 192.313963 -36.083976) (xy 192.368806 -36.073846)
			(xy 192.42454 -36.071809) (xy 192.479977 -36.077909) (xy 192.533934 -36.092015) (xy 192.585263 -36.113827)
			(xy 192.632869 -36.142881) (xy 192.675737 -36.178556) (xy 192.712954 -36.220093) (xy 192.743727 -36.266606)
			(xy 192.753263 -36.286948) (xy 199.300336 -36.286948) (xy 199.304407 -36.231326) (xy 199.316533 -36.176889)
			(xy 199.336456 -36.124798) (xy 199.363752 -36.076163) (xy 199.397838 -36.03202) (xy 199.437987 -35.993311)
			(xy 199.483345 -35.96086) (xy 199.532945 -35.935359) (xy 199.585729 -35.917352) (xy 199.640572 -35.907222)
			(xy 199.696306 -35.905185) (xy 199.751743 -35.911285) (xy 199.8057 -35.925391) (xy 199.857029 -35.947203)
			(xy 199.904635 -35.976257) (xy 199.947503 -36.011932) (xy 199.98472 -36.053469) (xy 200.015493 -36.099982)
			(xy 200.039165 -36.150479) (xy 200.055233 -36.203886) (xy 200.063353 -36.259062) (xy 200.063862 -36.286948)
			(xy 200.063353 -36.314834) (xy 200.055233 -36.37001) (xy 200.039165 -36.423417) (xy 200.015493 -36.473914)
			(xy 199.98472 -36.520427) (xy 199.947503 -36.561964) (xy 199.904635 -36.597639) (xy 199.857029 -36.626693)
			(xy 199.8057 -36.648505) (xy 199.751743 -36.662611) (xy 199.696306 -36.668711) (xy 199.640572 -36.666674)
			(xy 199.585729 -36.656544) (xy 199.532945 -36.638537) (xy 199.483345 -36.613036) (xy 199.437987 -36.580585)
			(xy 199.397838 -36.541876) (xy 199.363752 -36.497733) (xy 199.336456 -36.449098) (xy 199.316533 -36.397007)
			(xy 199.304407 -36.34257) (xy 199.300336 -36.286948) (xy 192.753263 -36.286948) (xy 192.767399 -36.317103)
			(xy 192.783467 -36.37051) (xy 192.791587 -36.425686) (xy 192.792096 -36.453572) (xy 192.791587 -36.481458)
			(xy 192.783467 -36.536634) (xy 192.767399 -36.590041) (xy 192.743727 -36.640538) (xy 192.712954 -36.687051)
			(xy 192.675737 -36.728588) (xy 192.632869 -36.764263) (xy 192.585263 -36.793317) (xy 192.533934 -36.815129)
			(xy 192.479977 -36.829235) (xy 192.42454 -36.835335) (xy 192.368806 -36.833298) (xy 192.313963 -36.823168)
			(xy 192.261179 -36.805161) (xy 192.211579 -36.77966) (xy 192.166221 -36.747209) (xy 192.126072 -36.7085)
			(xy 192.091986 -36.664357) (xy 192.06469 -36.615722) (xy 192.044767 -36.563631) (xy 192.032641 -36.509194)
			(xy 192.02857 -36.453572) (xy 189.472692 -36.453572) (xy 189.476887 -36.482074) (xy 189.477396 -36.50996)
			(xy 189.476887 -36.537846) (xy 189.468767 -36.593022) (xy 189.452699 -36.646429) (xy 189.429027 -36.696926)
			(xy 189.398254 -36.743439) (xy 189.361037 -36.784976) (xy 189.318169 -36.820651) (xy 189.270563 -36.849705)
			(xy 189.219234 -36.871517) (xy 189.165277 -36.885623) (xy 189.10984 -36.891723) (xy 189.054106 -36.889686)
			(xy 188.999263 -36.879556) (xy 188.946479 -36.861549) (xy 188.896879 -36.836048) (xy 188.851521 -36.803597)
			(xy 188.811372 -36.764888) (xy 188.777286 -36.720745) (xy 188.74999 -36.67211) (xy 188.730067 -36.620019)
			(xy 188.717941 -36.565582) (xy 188.71387 -36.50996) (xy 184.035885 -36.50996) (xy 184.131712 -36.741354)
			(xy 184.276238 -37.090604) (xy 184.290554 -37.125953) (xy 184.314332 -37.198424) (xy 184.323736 -37.235384)
			(xy 184.324244 -37.237924) (xy 184.324498 -37.23894) (xy 184.350406 -37.300916) (xy 184.371173 -37.351976)
			(xy 184.402611 -37.45763) (xy 184.406024 -37.47516) (xy 185.859164 -37.47516) (xy 185.863235 -37.419538)
			(xy 185.875361 -37.365101) (xy 185.895284 -37.31301) (xy 185.92258 -37.264375) (xy 185.956666 -37.220232)
			(xy 185.996815 -37.181523) (xy 186.042173 -37.149072) (xy 186.091773 -37.123571) (xy 186.144557 -37.105564)
			(xy 186.1994 -37.095434) (xy 186.255134 -37.093397) (xy 186.310571 -37.099497) (xy 186.364528 -37.113603)
			(xy 186.415857 -37.135415) (xy 186.463463 -37.164469) (xy 186.506331 -37.200144) (xy 186.543548 -37.241681)
			(xy 186.574321 -37.288194) (xy 186.597993 -37.338691) (xy 186.614061 -37.392098) (xy 186.622181 -37.447274)
			(xy 186.62269 -37.47516) (xy 186.622181 -37.503046) (xy 186.614061 -37.558222) (xy 186.597993 -37.611629)
			(xy 186.574321 -37.662126) (xy 186.574168 -37.662358) (xy 188.04839 -37.662358) (xy 188.052461 -37.606736)
			(xy 188.064587 -37.552299) (xy 188.08451 -37.500208) (xy 188.111806 -37.451573) (xy 188.145892 -37.40743)
			(xy 188.186041 -37.368721) (xy 188.231399 -37.33627) (xy 188.280999 -37.310769) (xy 188.333783 -37.292762)
			(xy 188.388626 -37.282632) (xy 188.44436 -37.280595) (xy 188.499797 -37.286695) (xy 188.553754 -37.300801)
			(xy 188.605083 -37.322613) (xy 188.652689 -37.351667) (xy 188.695557 -37.387342) (xy 188.732774 -37.428879)
			(xy 188.763547 -37.475392) (xy 188.787219 -37.525889) (xy 188.803287 -37.579296) (xy 188.811407 -37.634472)
			(xy 188.811916 -37.662358) (xy 188.811407 -37.690244) (xy 188.803287 -37.74542) (xy 188.794653 -37.774118)
			(xy 199.56475 -37.774118) (xy 199.568821 -37.718496) (xy 199.580947 -37.664059) (xy 199.60087 -37.611968)
			(xy 199.628166 -37.563333) (xy 199.662252 -37.51919) (xy 199.702401 -37.480481) (xy 199.747759 -37.44803)
			(xy 199.797359 -37.422529) (xy 199.850143 -37.404522) (xy 199.904986 -37.394392) (xy 199.96072 -37.392355)
			(xy 200.016157 -37.398455) (xy 200.070114 -37.412561) (xy 200.121443 -37.434373) (xy 200.169049 -37.463427)
			(xy 200.211917 -37.499102) (xy 200.249134 -37.540639) (xy 200.279907 -37.587152) (xy 200.303579 -37.637649)
			(xy 200.319647 -37.691056) (xy 200.327767 -37.746232) (xy 200.328276 -37.774118) (xy 200.327767 -37.802004)
			(xy 200.319647 -37.85718) (xy 200.303579 -37.910587) (xy 200.279907 -37.961084) (xy 200.249134 -38.007597)
			(xy 200.211917 -38.049134) (xy 200.169049 -38.084809) (xy 200.121443 -38.113863) (xy 200.070114 -38.135675)
			(xy 200.016157 -38.149781) (xy 199.96072 -38.155881) (xy 199.904986 -38.153844) (xy 199.850143 -38.143714)
			(xy 199.797359 -38.125707) (xy 199.747759 -38.100206) (xy 199.702401 -38.067755) (xy 199.662252 -38.029046)
			(xy 199.628166 -37.984903) (xy 199.60087 -37.936268) (xy 199.580947 -37.884177) (xy 199.568821 -37.82974)
			(xy 199.56475 -37.774118) (xy 188.794653 -37.774118) (xy 188.787219 -37.798827) (xy 188.763547 -37.849324)
			(xy 188.732774 -37.895837) (xy 188.695557 -37.937374) (xy 188.652689 -37.973049) (xy 188.605083 -38.002103)
			(xy 188.553754 -38.023915) (xy 188.499797 -38.038021) (xy 188.44436 -38.044121) (xy 188.388626 -38.042084)
			(xy 188.333783 -38.031954) (xy 188.280999 -38.013947) (xy 188.231399 -37.988446) (xy 188.186041 -37.955995)
			(xy 188.145892 -37.917286) (xy 188.111806 -37.873143) (xy 188.08451 -37.824508) (xy 188.064587 -37.772417)
			(xy 188.052461 -37.71798) (xy 188.04839 -37.662358) (xy 186.574168 -37.662358) (xy 186.543548 -37.708639)
			(xy 186.506331 -37.750176) (xy 186.463463 -37.785851) (xy 186.415857 -37.814905) (xy 186.364528 -37.836717)
			(xy 186.310571 -37.850823) (xy 186.255134 -37.856923) (xy 186.1994 -37.854886) (xy 186.144557 -37.844756)
			(xy 186.091773 -37.826749) (xy 186.042173 -37.801248) (xy 185.996815 -37.768797) (xy 185.956666 -37.730088)
			(xy 185.92258 -37.685945) (xy 185.895284 -37.63731) (xy 185.875361 -37.585219) (xy 185.863235 -37.530782)
			(xy 185.859164 -37.47516) (xy 184.406024 -37.47516) (xy 184.413144 -37.511736) (xy 184.420504 -37.555369)
			(xy 184.428389 -37.643511) (xy 184.428892 -37.687758) (xy 184.428892 -37.688266) (xy 184.428638 -37.704268)
			(xy 184.428638 -37.704522) (xy 184.411586 -38.729948) (xy 191.80102 -38.729948) (xy 191.80102 -38.675452)
			(xy 191.808775 -38.621512) (xy 191.824128 -38.569224) (xy 191.846766 -38.519653) (xy 191.876228 -38.473808)
			(xy 191.911914 -38.432623) (xy 191.953098 -38.396935) (xy 191.998942 -38.367472) (xy 192.048512 -38.344832)
			(xy 192.1008 -38.329478) (xy 192.15474 -38.321721) (xy 192.181988 -38.321234) (xy 192.210293 -38.321717)
			(xy 192.266282 -38.330068) (xy 192.320422 -38.346604) (xy 192.371523 -38.37096) (xy 192.418463 -38.402602)
			(xy 192.46021 -38.440834) (xy 192.495847 -38.484818) (xy 192.510664 -38.50894) (xy 192.518212 -38.521009)
			(xy 192.538841 -38.540613) (xy 192.564084 -38.553754) (xy 192.591975 -38.55941) (xy 192.620342 -38.557139)
			(xy 192.646979 -38.547119) (xy 192.669809 -38.53013) (xy 192.678812 -38.5191) (xy 192.696997 -38.496222)
			(xy 192.73916 -38.455758) (xy 192.786996 -38.422191) (xy 192.839388 -38.396304) (xy 192.895113 -38.378703)
			(xy 192.952869 -38.369797) (xy 192.982088 -38.36924) (xy 193.009345 -38.369606) (xy 193.063304 -38.377363)
			(xy 193.11561 -38.39272) (xy 193.165198 -38.415364) (xy 193.211058 -38.444836) (xy 193.252258 -38.480534)
			(xy 193.287957 -38.521732) (xy 193.31743 -38.567592) (xy 193.340076 -38.617179) (xy 193.355435 -38.669484)
			(xy 193.363193 -38.723443) (xy 193.363193 -38.777957) (xy 193.355435 -38.831916) (xy 193.340076 -38.884221)
			(xy 193.31743 -38.933808) (xy 193.287957 -38.979668) (xy 193.252258 -39.020866) (xy 193.211058 -39.056564)
			(xy 193.165198 -39.086036) (xy 193.11561 -39.10868) (xy 193.063304 -39.124037) (xy 193.009345 -39.131794)
			(xy 192.982088 -39.132256) (xy 192.953785 -39.131718) (xy 192.897798 -39.123377) (xy 192.843659 -39.106852)
			(xy 192.792558 -39.082505) (xy 192.745617 -39.050872) (xy 192.703869 -39.012646) (xy 192.66823 -38.968669)
			(xy 192.653412 -38.94455) (xy 192.645765 -38.93255) (xy 192.625156 -38.912952) (xy 192.599935 -38.89981)
			(xy 192.572064 -38.894147) (xy 192.543714 -38.896404) (xy 192.517091 -38.906405) (xy 192.494266 -38.923372)
			(xy 192.485264 -38.93439) (xy 192.467091 -38.957277) (xy 192.424925 -38.997741) (xy 192.377087 -39.031307)
			(xy 192.324693 -39.057193) (xy 192.268966 -39.074792) (xy 192.211208 -39.083695) (xy 192.181988 -39.08425)
			(xy 192.15474 -39.083679) (xy 192.1008 -39.075922) (xy 192.048512 -39.060568) (xy 191.998942 -39.037928)
			(xy 191.953098 -39.008465) (xy 191.911914 -38.972777) (xy 191.876228 -38.931592) (xy 191.846766 -38.885747)
			(xy 191.824128 -38.836176) (xy 191.808775 -38.783888) (xy 191.80102 -38.729948) (xy 184.411586 -38.729948)
			(xy 184.404 -39.186104) (xy 184.402642 -39.233452) (xy 184.392081 -39.327591) (xy 184.382918 -39.374064)
			(xy 184.335166 -39.60241) (xy 184.257683 -39.97198) (xy 193.9958 -39.97198) (xy 193.999871 -39.916358)
			(xy 194.011997 -39.861921) (xy 194.03192 -39.80983) (xy 194.059216 -39.761195) (xy 194.093302 -39.717052)
			(xy 194.133451 -39.678343) (xy 194.178809 -39.645892) (xy 194.228409 -39.620391) (xy 194.281193 -39.602384)
			(xy 194.336036 -39.592254) (xy 194.39177 -39.590217) (xy 194.447207 -39.596317) (xy 194.501164 -39.610423)
			(xy 194.552493 -39.632235) (xy 194.600099 -39.661289) (xy 194.642967 -39.696964) (xy 194.680184 -39.738501)
			(xy 194.710957 -39.785014) (xy 194.734629 -39.835511) (xy 194.750697 -39.888918) (xy 194.758817 -39.944094)
			(xy 194.759326 -39.97198) (xy 194.758817 -39.999866) (xy 194.750697 -40.055042) (xy 194.734629 -40.108449)
			(xy 194.710957 -40.158946) (xy 194.680184 -40.205459) (xy 194.642967 -40.246996) (xy 194.600099 -40.282671)
			(xy 194.552493 -40.311725) (xy 194.501164 -40.333537) (xy 194.447207 -40.347643) (xy 194.39177 -40.353743)
			(xy 194.336036 -40.351706) (xy 194.281193 -40.341576) (xy 194.228409 -40.323569) (xy 194.178809 -40.298068)
			(xy 194.133451 -40.265617) (xy 194.093302 -40.226908) (xy 194.059216 -40.182765) (xy 194.03192 -40.13413)
			(xy 194.011997 -40.082039) (xy 193.999871 -40.027602) (xy 193.9958 -39.97198) (xy 184.257683 -39.97198)
			(xy 184.251346 -40.002206) (xy 184.093612 -40.756078) (xy 184.091782 -40.767636) (xy 184.097606 -40.790273)
			(xy 184.104788 -40.799512) (xy 184.108598 -40.803576) (xy 184.172098 -40.862758) (xy 184.178736 -40.868509)
			(xy 184.194835 -40.875493) (xy 184.21235 -40.876583) (xy 184.220866 -40.874442) (xy 184.246367 -40.867674)
			(xy 184.298626 -40.860409) (xy 184.325006 -40.859964) (xy 184.353744 -40.860486) (xy 184.410571 -40.86911)
			(xy 184.46546 -40.886163) (xy 184.517169 -40.911259) (xy 184.564527 -40.943828) (xy 184.585864 -40.963088)
			(xy 184.586118 -40.963342) (xy 184.590098 -40.966818) (xy 184.599187 -40.972203) (xy 184.604152 -40.97401)
			(xy 184.608159 -40.975296) (xy 184.616455 -40.976705) (xy 184.620662 -40.976804) (xy 184.68975 -40.976804)
			(xy 184.69396 -40.976728) (xy 184.702263 -40.975331) (xy 184.70626 -40.97401) (xy 184.711218 -40.972186)
			(xy 184.720307 -40.966807) (xy 184.724294 -40.963342) (xy 184.724548 -40.963088) (xy 184.745876 -40.943819)
			(xy 184.793239 -40.911258) (xy 184.844951 -40.886169) (xy 184.899841 -40.869122) (xy 184.956668 -40.860501)
			(xy 184.985406 -40.859964) (xy 185.012659 -40.86045) (xy 185.06661 -40.868208) (xy 185.118908 -40.883565)
			(xy 185.168488 -40.906208) (xy 185.214341 -40.935677) (xy 185.255534 -40.971371) (xy 185.291227 -41.012564)
			(xy 185.320695 -41.058417) (xy 185.343337 -41.107998) (xy 185.358693 -41.160296) (xy 185.36645 -41.214247)
			(xy 185.36645 -41.268753) (xy 185.358693 -41.322704) (xy 185.343337 -41.375002) (xy 185.320695 -41.424583)
			(xy 185.291227 -41.470436) (xy 185.255534 -41.511629) (xy 185.214341 -41.547323) (xy 185.168488 -41.576792)
			(xy 185.118908 -41.599435) (xy 185.06661 -41.614792) (xy 185.012659 -41.62255) (xy 184.985406 -41.62298)
			(xy 184.956667 -41.622459) (xy 184.899839 -41.613837) (xy 184.844948 -41.596787) (xy 184.793236 -41.571695)
			(xy 184.745873 -41.539129) (xy 184.724548 -41.519856) (xy 184.724294 -41.519602) (xy 184.720312 -41.51613)
			(xy 184.711219 -41.510756) (xy 184.70626 -41.508934) (xy 184.702253 -41.507648) (xy 184.693957 -41.506239)
			(xy 184.68975 -41.50614) (xy 184.620662 -41.50614) (xy 184.616454 -41.506224) (xy 184.608156 -41.507635)
			(xy 184.604152 -41.508934) (xy 184.599192 -41.510754) (xy 184.590098 -41.516128) (xy 184.586118 -41.519602)
			(xy 184.585864 -41.519856) (xy 184.564536 -41.539124) (xy 184.517171 -41.571683) (xy 184.465459 -41.59677)
			(xy 184.41057 -41.613817) (xy 184.353744 -41.622439) (xy 184.325006 -41.62298) (xy 184.298738 -41.622541)
			(xy 184.2467 -41.615329) (xy 184.196144 -41.601041) (xy 184.148029 -41.579947) (xy 184.103266 -41.552447)
			(xy 184.08269 -41.536112) (xy 184.082182 -41.535604) (xy 184.081928 -41.535604) (xy 184.076825 -41.531664)
			(xy 184.065124 -41.52626) (xy 184.058814 -41.524936) (xy 184.052464 -41.52392) (xy 184.03951 -41.524936)
			(xy 183.951118 -41.555924) (xy 183.943055 -41.559146) (xy 183.929565 -41.570059) (xy 183.920486 -41.584846)
			(xy 183.918352 -41.593262) (xy 183.615076 -43.041062) (xy 183.559805 -43.305222) (xy 186.407298 -43.305222)
			(xy 186.407777 -43.277852) (xy 186.415592 -43.223674) (xy 186.431078 -43.171171) (xy 186.453917 -43.121424)
			(xy 186.483638 -43.075456) (xy 186.501278 -43.054524) (xy 186.501532 -43.05427) (xy 186.507099 -43.04717)
			(xy 186.513356 -43.030263) (xy 186.513724 -43.02125) (xy 186.513724 -42.954194) (xy 186.513364 -42.945178)
			(xy 186.507118 -42.928261) (xy 186.501532 -42.921174) (xy 186.501278 -42.921174) (xy 186.501278 -42.92092)
			(xy 186.483631 -42.899994) (xy 186.453921 -42.854019) (xy 186.431087 -42.80427) (xy 186.415598 -42.751768)
			(xy 186.407771 -42.697592) (xy 186.407298 -42.670222) (xy 186.407836 -42.641484) (xy 186.416455 -42.584657)
			(xy 186.433502 -42.529766) (xy 186.45859 -42.478054) (xy 186.491153 -42.430691) (xy 186.510422 -42.409364)
			(xy 186.517026 -42.402506) (xy 186.524138 -42.384472) (xy 186.524138 -42.295572) (xy 186.517026 -42.277538)
			(xy 186.510422 -42.27068) (xy 186.491173 -42.249334) (xy 186.458607 -42.201975) (xy 186.433515 -42.150266)
			(xy 186.416463 -42.095378) (xy 186.407838 -42.038554) (xy 186.407836 -41.981078) (xy 186.416456 -41.924253)
			(xy 186.433503 -41.869364) (xy 186.458591 -41.817653) (xy 186.491153 -41.770291) (xy 186.510422 -41.748964)
			(xy 186.517026 -41.742106) (xy 186.524138 -41.724072) (xy 186.524138 -41.635172) (xy 186.517026 -41.617138)
			(xy 186.510422 -41.61028) (xy 186.491159 -41.588946) (xy 186.458592 -41.541586) (xy 186.433499 -41.489876)
			(xy 186.416446 -41.434987) (xy 186.407821 -41.37816) (xy 186.407298 -41.349422) (xy 186.407784 -41.322171)
			(xy 186.41554 -41.268223) (xy 186.430895 -41.215928) (xy 186.453537 -41.166351) (xy 186.483003 -41.120501)
			(xy 186.518694 -41.07931) (xy 186.559885 -41.043619) (xy 186.605735 -41.014153) (xy 186.655312 -40.991511)
			(xy 186.707607 -40.976156) (xy 186.761555 -40.9684) (xy 186.816057 -40.9684) (xy 186.839178 -40.971724)
			(xy 194.694046 -40.971724) (xy 194.698117 -40.916102) (xy 194.710243 -40.861665) (xy 194.730166 -40.809574)
			(xy 194.757462 -40.760939) (xy 194.791548 -40.716796) (xy 194.831697 -40.678087) (xy 194.877055 -40.645636)
			(xy 194.926655 -40.620135) (xy 194.979439 -40.602128) (xy 195.034282 -40.591998) (xy 195.090016 -40.589961)
			(xy 195.145453 -40.596061) (xy 195.19941 -40.610167) (xy 195.250739 -40.631979) (xy 195.298345 -40.661033)
			(xy 195.341213 -40.696708) (xy 195.37843 -40.738245) (xy 195.409203 -40.784758) (xy 195.432875 -40.835255)
			(xy 195.448943 -40.888662) (xy 195.457063 -40.943838) (xy 195.457572 -40.971724) (xy 195.457063 -40.99961)
			(xy 195.448943 -41.054786) (xy 195.432875 -41.108193) (xy 195.409203 -41.15869) (xy 195.37843 -41.205203)
			(xy 195.341213 -41.24674) (xy 195.298345 -41.282415) (xy 195.250739 -41.311469) (xy 195.19941 -41.333281)
			(xy 195.145453 -41.347387) (xy 195.090016 -41.353487) (xy 195.034282 -41.35145) (xy 194.979439 -41.34132)
			(xy 194.926655 -41.323313) (xy 194.877055 -41.297812) (xy 194.831697 -41.265361) (xy 194.791548 -41.226652)
			(xy 194.757462 -41.182509) (xy 194.730166 -41.133874) (xy 194.710243 -41.081783) (xy 194.698117 -41.027346)
			(xy 194.694046 -40.971724) (xy 186.839178 -40.971724) (xy 186.870005 -40.976156) (xy 186.9223 -40.991511)
			(xy 186.971877 -41.014153) (xy 187.017727 -41.043619) (xy 187.058918 -41.07931) (xy 187.094609 -41.120501)
			(xy 187.124075 -41.166351) (xy 187.146717 -41.215928) (xy 187.162072 -41.268223) (xy 187.169828 -41.322171)
			(xy 187.170314 -41.349422) (xy 187.1698 -41.378161) (xy 187.161174 -41.434989) (xy 187.144122 -41.48988)
			(xy 187.119028 -41.541591) (xy 187.086461 -41.588953) (xy 187.06719 -41.61028) (xy 187.060586 -41.617138)
			(xy 187.053474 -41.635172) (xy 187.053474 -41.724072) (xy 187.060586 -41.742106) (xy 187.06719 -41.748964)
			(xy 187.086482 -41.770272) (xy 187.119045 -41.817638) (xy 187.144135 -41.869353) (xy 187.161183 -41.924247)
			(xy 187.169803 -41.981076) (xy 187.1698 -42.038556) (xy 187.161175 -42.095385) (xy 187.144123 -42.150277)
			(xy 187.119029 -42.20199) (xy 187.086462 -42.249353) (xy 187.06719 -42.27068) (xy 187.060586 -42.277538)
			(xy 187.053474 -42.295572) (xy 187.053474 -42.384472) (xy 187.060586 -42.402506) (xy 187.06719 -42.409364)
			(xy 187.086476 -42.430678) (xy 187.119039 -42.478044) (xy 187.144128 -42.529759) (xy 187.161175 -42.584653)
			(xy 187.169795 -42.641482) (xy 187.170314 -42.670222) (xy 187.169857 -42.697593) (xy 187.162037 -42.751772)
			(xy 187.146545 -42.804275) (xy 187.125991 -42.849038) (xy 188.992 -42.849038) (xy 188.996071 -42.793416)
			(xy 189.008197 -42.738979) (xy 189.02812 -42.686888) (xy 189.055416 -42.638253) (xy 189.089502 -42.59411)
			(xy 189.129651 -42.555401) (xy 189.175009 -42.52295) (xy 189.224609 -42.497449) (xy 189.277393 -42.479442)
			(xy 189.332236 -42.469312) (xy 189.38797 -42.467275) (xy 189.443407 -42.473375) (xy 189.497364 -42.487481)
			(xy 189.548693 -42.509293) (xy 189.596299 -42.538347) (xy 189.639167 -42.574022) (xy 189.676384 -42.615559)
			(xy 189.707157 -42.662072) (xy 189.730829 -42.712569) (xy 189.746897 -42.765976) (xy 189.755017 -42.821152)
			(xy 189.755378 -42.84091) (xy 195.033136 -42.84091) (xy 195.037207 -42.785288) (xy 195.049333 -42.730851)
			(xy 195.069256 -42.67876) (xy 195.096552 -42.630125) (xy 195.130638 -42.585982) (xy 195.170787 -42.547273)
			(xy 195.216145 -42.514822) (xy 195.265745 -42.489321) (xy 195.318529 -42.471314) (xy 195.373372 -42.461184)
			(xy 195.429106 -42.459147) (xy 195.484543 -42.465247) (xy 195.5385 -42.479353) (xy 195.589829 -42.501165)
			(xy 195.637435 -42.530219) (xy 195.680303 -42.565894) (xy 195.71752 -42.607431) (xy 195.748293 -42.653944)
			(xy 195.771965 -42.704441) (xy 195.788033 -42.757848) (xy 195.796153 -42.813024) (xy 195.796662 -42.84091)
			(xy 195.796153 -42.868796) (xy 195.788033 -42.923972) (xy 195.771965 -42.977379) (xy 195.748293 -43.027876)
			(xy 195.71752 -43.074389) (xy 195.680303 -43.115926) (xy 195.637435 -43.151601) (xy 195.589829 -43.180655)
			(xy 195.5385 -43.202467) (xy 195.484543 -43.216573) (xy 195.429106 -43.222673) (xy 195.373372 -43.220636)
			(xy 195.318529 -43.210506) (xy 195.265745 -43.192499) (xy 195.216145 -43.166998) (xy 195.170787 -43.134547)
			(xy 195.130638 -43.095838) (xy 195.096552 -43.051695) (xy 195.069256 -43.00306) (xy 195.049333 -42.950969)
			(xy 195.037207 -42.896532) (xy 195.033136 -42.84091) (xy 189.755378 -42.84091) (xy 189.755526 -42.849038)
			(xy 189.755017 -42.876924) (xy 189.746897 -42.9321) (xy 189.730829 -42.985507) (xy 189.707157 -43.036004)
			(xy 189.676384 -43.082517) (xy 189.639167 -43.124054) (xy 189.596299 -43.159729) (xy 189.548693 -43.188783)
			(xy 189.497364 -43.210595) (xy 189.443407 -43.224701) (xy 189.38797 -43.230801) (xy 189.332236 -43.228764)
			(xy 189.277393 -43.218634) (xy 189.224609 -43.200627) (xy 189.175009 -43.175126) (xy 189.129651 -43.142675)
			(xy 189.089502 -43.103966) (xy 189.055416 -43.059823) (xy 189.02812 -43.011188) (xy 189.008197 -42.959097)
			(xy 188.996071 -42.90466) (xy 188.992 -42.849038) (xy 187.125991 -42.849038) (xy 187.123702 -42.854022)
			(xy 187.093976 -42.899988) (xy 187.076334 -42.92092) (xy 187.07608 -42.921174) (xy 187.070496 -42.928262)
			(xy 187.064248 -42.945178) (xy 187.063888 -42.954194) (xy 187.063888 -43.02125) (xy 187.064271 -43.030264)
			(xy 187.070501 -43.047181) (xy 187.07608 -43.05427) (xy 187.076334 -43.05427) (xy 187.076334 -43.054524)
			(xy 187.093956 -43.07547) (xy 187.123669 -43.121439) (xy 187.146508 -43.171183) (xy 187.162003 -43.223681)
			(xy 187.169837 -43.277854) (xy 187.170314 -43.305222) (xy 187.169828 -43.332473) (xy 187.162072 -43.386421)
			(xy 187.146717 -43.438716) (xy 187.124075 -43.488293) (xy 187.094609 -43.534143) (xy 187.058918 -43.575334)
			(xy 187.017727 -43.611025) (xy 186.971877 -43.640491) (xy 186.9223 -43.663133) (xy 186.870005 -43.678488)
			(xy 186.816057 -43.686244) (xy 186.761555 -43.686244) (xy 186.707607 -43.678488) (xy 186.655312 -43.663133)
			(xy 186.605735 -43.640491) (xy 186.559885 -43.611025) (xy 186.518694 -43.575334) (xy 186.483003 -43.534143)
			(xy 186.453537 -43.488293) (xy 186.430895 -43.438716) (xy 186.41554 -43.386421) (xy 186.407784 -43.332473)
			(xy 186.407298 -43.305222) (xy 183.559805 -43.305222) (xy 183.469618 -43.73626) (xy 188.313058 -43.73626)
			(xy 188.317129 -43.680638) (xy 188.329255 -43.626201) (xy 188.349178 -43.57411) (xy 188.376474 -43.525475)
			(xy 188.41056 -43.481332) (xy 188.450709 -43.442623) (xy 188.496067 -43.410172) (xy 188.545667 -43.384671)
			(xy 188.598451 -43.366664) (xy 188.653294 -43.356534) (xy 188.709028 -43.354497) (xy 188.764465 -43.360597)
			(xy 188.818422 -43.374703) (xy 188.869751 -43.396515) (xy 188.917357 -43.425569) (xy 188.960225 -43.461244)
			(xy 188.997442 -43.502781) (xy 189.028215 -43.549294) (xy 189.051887 -43.599791) (xy 189.067955 -43.653198)
			(xy 189.076075 -43.708374) (xy 189.076584 -43.73626) (xy 189.076075 -43.764146) (xy 189.067955 -43.819322)
			(xy 189.056646 -43.85691) (xy 192.81978 -43.85691) (xy 192.823851 -43.801288) (xy 192.835977 -43.746851)
			(xy 192.8559 -43.69476) (xy 192.883196 -43.646125) (xy 192.917282 -43.601982) (xy 192.957431 -43.563273)
			(xy 193.002789 -43.530822) (xy 193.052389 -43.505321) (xy 193.105173 -43.487314) (xy 193.160016 -43.477184)
			(xy 193.21575 -43.475147) (xy 193.271187 -43.481247) (xy 193.325144 -43.495353) (xy 193.376473 -43.517165)
			(xy 193.424079 -43.546219) (xy 193.466947 -43.581894) (xy 193.504164 -43.623431) (xy 193.534937 -43.669944)
			(xy 193.558609 -43.720441) (xy 193.574677 -43.773848) (xy 193.582797 -43.829024) (xy 193.583306 -43.85691)
			(xy 193.582797 -43.884796) (xy 193.574677 -43.939972) (xy 193.558609 -43.993379) (xy 193.534937 -44.043876)
			(xy 193.504164 -44.090389) (xy 193.466947 -44.131926) (xy 193.424079 -44.167601) (xy 193.376473 -44.196655)
			(xy 193.325144 -44.218467) (xy 193.271187 -44.232573) (xy 193.21575 -44.238673) (xy 193.160016 -44.236636)
			(xy 193.105173 -44.226506) (xy 193.052389 -44.208499) (xy 193.002789 -44.182998) (xy 192.957431 -44.150547)
			(xy 192.917282 -44.111838) (xy 192.883196 -44.067695) (xy 192.8559 -44.01906) (xy 192.835977 -43.966969)
			(xy 192.823851 -43.912532) (xy 192.81978 -43.85691) (xy 189.056646 -43.85691) (xy 189.051887 -43.872729)
			(xy 189.028215 -43.923226) (xy 188.997442 -43.969739) (xy 188.960225 -44.011276) (xy 188.917357 -44.046951)
			(xy 188.869751 -44.076005) (xy 188.818422 -44.097817) (xy 188.764465 -44.111923) (xy 188.709028 -44.118023)
			(xy 188.653294 -44.115986) (xy 188.598451 -44.105856) (xy 188.545667 -44.087849) (xy 188.496067 -44.062348)
			(xy 188.450709 -44.029897) (xy 188.41056 -43.991188) (xy 188.376474 -43.947045) (xy 188.349178 -43.89841)
			(xy 188.329255 -43.846319) (xy 188.317129 -43.791882) (xy 188.313058 -43.73626) (xy 183.469618 -43.73626)
			(xy 183.455056 -43.805856) (xy 183.181087 -45.114464) (xy 188.165484 -45.114464) (xy 188.169555 -45.058842)
			(xy 188.181681 -45.004405) (xy 188.201604 -44.952314) (xy 188.2289 -44.903679) (xy 188.262986 -44.859536)
			(xy 188.303135 -44.820827) (xy 188.348493 -44.788376) (xy 188.398093 -44.762875) (xy 188.450877 -44.744868)
			(xy 188.50572 -44.734738) (xy 188.561454 -44.732701) (xy 188.616891 -44.738801) (xy 188.670848 -44.752907)
			(xy 188.722177 -44.774719) (xy 188.769783 -44.803773) (xy 188.812651 -44.839448) (xy 188.842633 -44.87291)
			(xy 195.033136 -44.87291) (xy 195.037207 -44.817288) (xy 195.049333 -44.762851) (xy 195.069256 -44.71076)
			(xy 195.096552 -44.662125) (xy 195.130638 -44.617982) (xy 195.170787 -44.579273) (xy 195.216145 -44.546822)
			(xy 195.265745 -44.521321) (xy 195.318529 -44.503314) (xy 195.373372 -44.493184) (xy 195.429106 -44.491147)
			(xy 195.484543 -44.497247) (xy 195.5385 -44.511353) (xy 195.589829 -44.533165) (xy 195.637435 -44.562219)
			(xy 195.680303 -44.597894) (xy 195.71752 -44.639431) (xy 195.748293 -44.685944) (xy 195.771965 -44.736441)
			(xy 195.788033 -44.789848) (xy 195.796153 -44.845024) (xy 195.796662 -44.87291) (xy 195.796153 -44.900796)
			(xy 195.788033 -44.955972) (xy 195.771965 -45.009379) (xy 195.748293 -45.059876) (xy 195.71752 -45.106389)
			(xy 195.680303 -45.147926) (xy 195.637435 -45.183601) (xy 195.589829 -45.212655) (xy 195.5385 -45.234467)
			(xy 195.484543 -45.248573) (xy 195.429106 -45.254673) (xy 195.373372 -45.252636) (xy 195.318529 -45.242506)
			(xy 195.265745 -45.224499) (xy 195.216145 -45.198998) (xy 195.170787 -45.166547) (xy 195.130638 -45.127838)
			(xy 195.096552 -45.083695) (xy 195.069256 -45.03506) (xy 195.049333 -44.982969) (xy 195.037207 -44.928532)
			(xy 195.033136 -44.87291) (xy 188.842633 -44.87291) (xy 188.849868 -44.880985) (xy 188.880641 -44.927498)
			(xy 188.904313 -44.977995) (xy 188.920381 -45.031402) (xy 188.928501 -45.086578) (xy 188.92901 -45.114464)
			(xy 188.928501 -45.14235) (xy 188.920381 -45.197526) (xy 188.904313 -45.250933) (xy 188.880641 -45.30143)
			(xy 188.849868 -45.347943) (xy 188.844226 -45.35424) (xy 192.803778 -45.35424) (xy 192.807849 -45.298618)
			(xy 192.819975 -45.244181) (xy 192.839898 -45.19209) (xy 192.867194 -45.143455) (xy 192.90128 -45.099312)
			(xy 192.941429 -45.060603) (xy 192.986787 -45.028152) (xy 193.036387 -45.002651) (xy 193.089171 -44.984644)
			(xy 193.144014 -44.974514) (xy 193.199748 -44.972477) (xy 193.255185 -44.978577) (xy 193.309142 -44.992683)
			(xy 193.360471 -45.014495) (xy 193.408077 -45.043549) (xy 193.450945 -45.079224) (xy 193.488162 -45.120761)
			(xy 193.518935 -45.167274) (xy 193.542607 -45.217771) (xy 193.558675 -45.271178) (xy 193.566795 -45.326354)
			(xy 193.567304 -45.35424) (xy 193.566795 -45.382126) (xy 193.558675 -45.437302) (xy 193.542607 -45.490709)
			(xy 193.518935 -45.541206) (xy 193.488162 -45.587719) (xy 193.450945 -45.629256) (xy 193.408077 -45.664931)
			(xy 193.360471 -45.693985) (xy 193.309142 -45.715797) (xy 193.255185 -45.729903) (xy 193.199748 -45.736003)
			(xy 193.144014 -45.733966) (xy 193.089171 -45.723836) (xy 193.036387 -45.705829) (xy 192.986787 -45.680328)
			(xy 192.941429 -45.647877) (xy 192.90128 -45.609168) (xy 192.867194 -45.565025) (xy 192.839898 -45.51639)
			(xy 192.819975 -45.464299) (xy 192.807849 -45.409862) (xy 192.803778 -45.35424) (xy 188.844226 -45.35424)
			(xy 188.812651 -45.38948) (xy 188.769783 -45.425155) (xy 188.722177 -45.454209) (xy 188.670848 -45.476021)
			(xy 188.616891 -45.490127) (xy 188.561454 -45.496227) (xy 188.50572 -45.49419) (xy 188.450877 -45.48406)
			(xy 188.398093 -45.466053) (xy 188.348493 -45.440552) (xy 188.303135 -45.408101) (xy 188.262986 -45.369392)
			(xy 188.2289 -45.325249) (xy 188.201604 -45.276614) (xy 188.181681 -45.224523) (xy 188.169555 -45.170086)
			(xy 188.165484 -45.114464) (xy 183.181087 -45.114464) (xy 182.978481 -46.082204) (xy 186.152536 -46.082204)
			(xy 186.152959 -46.054949) (xy 186.160717 -46.000995) (xy 186.176075 -45.948693) (xy 186.19872 -45.89911)
			(xy 186.228191 -45.853255) (xy 186.263889 -45.812061) (xy 186.305087 -45.776367) (xy 186.350945 -45.746901)
			(xy 186.400531 -45.724261) (xy 186.452834 -45.708908) (xy 186.506789 -45.701156) (xy 186.534044 -45.700696)
			(xy 186.560948 -45.701125) (xy 186.614219 -45.708703) (xy 186.665898 -45.723688) (xy 186.71496 -45.745783)
			(xy 186.760432 -45.774551) (xy 186.801413 -45.80942) (xy 186.837089 -45.8497) (xy 186.852306 -45.871892)
			(xy 186.859418 -45.882814) (xy 186.882278 -45.894752) (xy 186.994546 -45.89272) (xy 187.016898 -45.879766)
			(xy 187.023756 -45.86859) (xy 187.038653 -45.844972) (xy 187.074336 -45.802021) (xy 187.115899 -45.764729)
			(xy 187.162453 -45.733893) (xy 187.213004 -45.710172) (xy 187.266473 -45.694073) (xy 187.321718 -45.68594)
			(xy 187.349638 -45.685456) (xy 187.376632 -45.685895) (xy 187.430081 -45.693506) (xy 187.481925 -45.708572)
			(xy 187.531129 -45.730791) (xy 187.576712 -45.75972) (xy 187.597542 -45.776896) (xy 187.60567 -45.784008)
			(xy 187.626244 -45.790104) (xy 187.711588 -45.779182) (xy 187.722134 -45.777412) (xy 187.740416 -45.766355)
			(xy 187.746894 -45.757846) (xy 187.762258 -45.736623) (xy 187.797843 -45.69817) (xy 187.838358 -45.664951)
			(xy 187.88304 -45.637591) (xy 187.931046 -45.616607) (xy 187.981473 -45.602392) (xy 188.033372 -45.595214)
			(xy 188.059568 -45.594778) (xy 188.086821 -45.595267) (xy 188.140774 -45.60302) (xy 188.193074 -45.618373)
			(xy 188.242656 -45.641013) (xy 188.288511 -45.670479) (xy 188.329706 -45.706171) (xy 188.365402 -45.747363)
			(xy 188.394872 -45.793216) (xy 188.417516 -45.842796) (xy 188.432873 -45.895095) (xy 188.440631 -45.949047)
			(xy 188.440631 -46.003553) (xy 188.432873 -46.057505) (xy 188.417516 -46.109804) (xy 188.394872 -46.159384)
			(xy 188.365402 -46.205237) (xy 188.329706 -46.246429) (xy 188.288511 -46.282121) (xy 188.242656 -46.311587)
			(xy 188.193074 -46.334227) (xy 188.140774 -46.34958) (xy 188.086821 -46.357333) (xy 188.059568 -46.357794)
			(xy 188.032575 -46.35734) (xy 187.979127 -46.34973) (xy 187.927284 -46.334668) (xy 187.878079 -46.312453)
			(xy 187.832495 -46.283528) (xy 187.811664 -46.266354) (xy 187.803536 -46.259242) (xy 187.782962 -46.253146)
			(xy 187.697618 -46.264068) (xy 187.687078 -46.265859) (xy 187.668794 -46.276903) (xy 187.662312 -46.285404)
			(xy 187.644694 -46.309701) (xy 187.603102 -46.352962) (xy 187.579508 -46.37151) (xy 187.571634 -46.377352)
			(xy 187.56122 -46.394878) (xy 187.548012 -46.485302) (xy 187.552838 -46.504606) (xy 187.55868 -46.51248)
			(xy 187.55868 -46.512734) (xy 187.576184 -46.537478) (xy 187.603986 -46.591331) (xy 187.622922 -46.648903)
			(xy 187.630125 -46.693836) (xy 192.776348 -46.693836) (xy 192.776834 -46.666585) (xy 192.78459 -46.612637)
			(xy 192.799945 -46.560342) (xy 192.822587 -46.510765) (xy 192.852053 -46.464915) (xy 192.887744 -46.423724)
			(xy 192.928935 -46.388033) (xy 192.974785 -46.358567) (xy 193.024362 -46.335925) (xy 193.076657 -46.32057)
			(xy 193.130605 -46.312814) (xy 193.185107 -46.312814) (xy 193.239055 -46.32057) (xy 193.29135 -46.335925)
			(xy 193.340927 -46.358567) (xy 193.386777 -46.388033) (xy 193.427968 -46.423724) (xy 193.463659 -46.464915)
			(xy 193.493125 -46.510765) (xy 193.515767 -46.560342) (xy 193.531122 -46.612637) (xy 193.538878 -46.666585)
			(xy 193.539364 -46.693836) (xy 193.538896 -46.720264) (xy 193.531586 -46.772611) (xy 193.517111 -46.823446)
			(xy 193.49575 -46.871793) (xy 193.482214 -46.894496) (xy 193.48196 -46.89475) (xy 193.476623 -46.904768)
			(xy 193.474365 -46.927318) (xy 193.477642 -46.938184) (xy 193.503804 -47.01286) (xy 193.508165 -47.023388)
			(xy 193.524269 -47.039471) (xy 193.534792 -47.043848) (xy 193.535046 -47.043848) (xy 193.559555 -47.052918)
			(xy 193.606007 -47.07686) (xy 193.648759 -47.106916) (xy 193.687011 -47.142523) (xy 193.720048 -47.183016)
			(xy 193.747251 -47.227637) (xy 193.768113 -47.275552) (xy 193.782243 -47.325866) (xy 193.789377 -47.377636)
			(xy 193.789808 -47.403766) (xy 193.789322 -47.431017) (xy 193.787799 -47.441612) (xy 195.061838 -47.441612)
			(xy 195.065909 -47.38599) (xy 195.078035 -47.331553) (xy 195.097958 -47.279462) (xy 195.125254 -47.230827)
			(xy 195.15934 -47.186684) (xy 195.199489 -47.147975) (xy 195.244847 -47.115524) (xy 195.294447 -47.090023)
			(xy 195.347231 -47.072016) (xy 195.402074 -47.061886) (xy 195.457808 -47.059849) (xy 195.513245 -47.065949)
			(xy 195.567202 -47.080055) (xy 195.618531 -47.101867) (xy 195.666137 -47.130921) (xy 195.709005 -47.166596)
			(xy 195.746222 -47.208133) (xy 195.776995 -47.254646) (xy 195.800667 -47.305143) (xy 195.816735 -47.35855)
			(xy 195.824855 -47.413726) (xy 195.825364 -47.441612) (xy 195.824855 -47.469498) (xy 195.816735 -47.524674)
			(xy 195.800667 -47.578081) (xy 195.776995 -47.628578) (xy 195.746222 -47.675091) (xy 195.709005 -47.716628)
			(xy 195.666137 -47.752303) (xy 195.618531 -47.781357) (xy 195.567202 -47.803169) (xy 195.513245 -47.817275)
			(xy 195.457808 -47.823375) (xy 195.402074 -47.821338) (xy 195.347231 -47.811208) (xy 195.294447 -47.793201)
			(xy 195.244847 -47.7677) (xy 195.199489 -47.735249) (xy 195.15934 -47.69654) (xy 195.125254 -47.652397)
			(xy 195.097958 -47.603762) (xy 195.078035 -47.551671) (xy 195.065909 -47.497234) (xy 195.061838 -47.441612)
			(xy 193.787799 -47.441612) (xy 193.781566 -47.484965) (xy 193.766211 -47.53726) (xy 193.743569 -47.586837)
			(xy 193.714103 -47.632687) (xy 193.678412 -47.673878) (xy 193.637221 -47.709569) (xy 193.591371 -47.739035)
			(xy 193.541794 -47.761677) (xy 193.489499 -47.777032) (xy 193.435551 -47.784788) (xy 193.381049 -47.784788)
			(xy 193.327101 -47.777032) (xy 193.274806 -47.761677) (xy 193.225229 -47.739035) (xy 193.179379 -47.709569)
			(xy 193.138188 -47.673878) (xy 193.102497 -47.632687) (xy 193.073031 -47.586837) (xy 193.050389 -47.53726)
			(xy 193.035034 -47.484965) (xy 193.027278 -47.431017) (xy 193.026792 -47.403766) (xy 193.027267 -47.377339)
			(xy 193.034576 -47.324991) (xy 193.049049 -47.274156) (xy 193.070408 -47.225809) (xy 193.083942 -47.203106)
			(xy 193.084196 -47.202852) (xy 193.089531 -47.192834) (xy 193.091788 -47.170284) (xy 193.088514 -47.159418)
			(xy 193.062352 -47.084742) (xy 193.057965 -47.074228) (xy 193.041879 -47.058139) (xy 193.031364 -47.053754)
			(xy 193.03111 -47.053754) (xy 193.006593 -47.044708) (xy 192.960141 -47.02076) (xy 192.917391 -46.9907)
			(xy 192.87914 -46.955089) (xy 192.846105 -46.914594) (xy 192.818903 -46.86997) (xy 192.798042 -46.822053)
			(xy 192.783913 -46.771738) (xy 192.776779 -46.719966) (xy 192.776348 -46.693836) (xy 187.630125 -46.693836)
			(xy 187.632515 -46.708745) (xy 187.633102 -46.739048) (xy 187.632667 -46.766301) (xy 187.624904 -46.820251)
			(xy 187.609542 -46.872547) (xy 187.586895 -46.922124) (xy 187.557423 -46.967975) (xy 187.521726 -47.009165)
			(xy 187.480532 -47.044855) (xy 187.434677 -47.074321) (xy 187.385096 -47.096961) (xy 187.332798 -47.112315)
			(xy 187.278847 -47.120071) (xy 187.251594 -47.120556) (xy 187.225561 -47.120105) (xy 187.173978 -47.113018)
			(xy 187.123836 -47.098989) (xy 187.076065 -47.078279) (xy 187.03155 -47.051272) (xy 187.011056 -47.035212)
			(xy 187.003289 -47.029485) (xy 186.984886 -47.023735) (xy 186.975242 -47.024036) (xy 186.895486 -47.030386)
			(xy 186.877706 -47.039022) (xy 186.871356 -47.046388) (xy 186.85317 -47.066029) (xy 186.812263 -47.100551)
			(xy 186.766935 -47.129021) (xy 186.718075 -47.150879) (xy 186.66664 -47.165698) (xy 186.613639 -47.173186)
			(xy 186.586876 -47.173642) (xy 186.559626 -47.173145) (xy 186.50568 -47.165386) (xy 186.453388 -47.150029)
			(xy 186.403813 -47.127388) (xy 186.357964 -47.097922) (xy 186.316775 -47.062232) (xy 186.281084 -47.021044)
			(xy 186.251617 -46.975196) (xy 186.228974 -46.925622) (xy 186.213616 -46.87333) (xy 186.205856 -46.819384)
			(xy 186.205368 -46.792134) (xy 186.205901 -46.76336) (xy 186.214551 -46.706467) (xy 186.231646 -46.651517)
			(xy 186.256797 -46.599757) (xy 186.289435 -46.55236) (xy 186.308746 -46.531022) (xy 186.316112 -46.523148)
			(xy 186.323224 -46.503336) (xy 186.315858 -46.40707) (xy 186.305952 -46.388274) (xy 186.29757 -46.38167)
			(xy 186.275375 -46.363458) (xy 186.236168 -46.321518) (xy 186.203685 -46.27418) (xy 186.178659 -46.222509)
			(xy 186.161654 -46.167674) (xy 186.153054 -46.11091) (xy 186.152536 -46.082204) (xy 182.978481 -46.082204)
			(xy 182.97779 -46.085506) (xy 182.512566 -48.30699) (xy 192.653918 -48.30699) (xy 192.657989 -48.251368)
			(xy 192.670115 -48.196931) (xy 192.690038 -48.14484) (xy 192.717334 -48.096205) (xy 192.75142 -48.052062)
			(xy 192.791569 -48.013353) (xy 192.836927 -47.980902) (xy 192.886527 -47.955401) (xy 192.939311 -47.937394)
			(xy 192.994154 -47.927264) (xy 193.049888 -47.925227) (xy 193.105325 -47.931327) (xy 193.159282 -47.945433)
			(xy 193.210611 -47.967245) (xy 193.258217 -47.996299) (xy 193.301085 -48.031974) (xy 193.338302 -48.073511)
			(xy 193.369075 -48.120024) (xy 193.392747 -48.170521) (xy 193.408815 -48.223928) (xy 193.416935 -48.279104)
			(xy 193.417444 -48.30699) (xy 193.416935 -48.334876) (xy 193.408815 -48.390052) (xy 193.392747 -48.443459)
			(xy 193.369075 -48.493956) (xy 193.338302 -48.540469) (xy 193.301085 -48.582006) (xy 193.258217 -48.617681)
			(xy 193.210611 -48.646735) (xy 193.159282 -48.668547) (xy 193.105325 -48.682653) (xy 193.049888 -48.688753)
			(xy 192.994154 -48.686716) (xy 192.939311 -48.676586) (xy 192.886527 -48.658579) (xy 192.836927 -48.633078)
			(xy 192.791569 -48.600627) (xy 192.75142 -48.561918) (xy 192.717334 -48.517775) (xy 192.690038 -48.46914)
			(xy 192.670115 -48.417049) (xy 192.657989 -48.362612) (xy 192.653918 -48.30699) (xy 182.512566 -48.30699)
			(xy 182.41916 -48.753014) (xy 189.268352 -48.753014) (xy 189.272423 -48.697392) (xy 189.284549 -48.642955)
			(xy 189.304472 -48.590864) (xy 189.331768 -48.542229) (xy 189.365854 -48.498086) (xy 189.406003 -48.459377)
			(xy 189.451361 -48.426926) (xy 189.500961 -48.401425) (xy 189.553745 -48.383418) (xy 189.608588 -48.373288)
			(xy 189.664322 -48.371251) (xy 189.719759 -48.377351) (xy 189.773716 -48.391457) (xy 189.825045 -48.413269)
			(xy 189.872651 -48.442323) (xy 189.915519 -48.477998) (xy 189.952736 -48.519535) (xy 189.983509 -48.566048)
			(xy 190.007181 -48.616545) (xy 190.023249 -48.669952) (xy 190.031369 -48.725128) (xy 190.031878 -48.753014)
			(xy 190.031369 -48.7809) (xy 190.023249 -48.836076) (xy 190.020805 -48.8442) (xy 190.2874 -48.8442)
			(xy 190.291471 -48.788578) (xy 190.303597 -48.734141) (xy 190.32352 -48.68205) (xy 190.350816 -48.633415)
			(xy 190.384902 -48.589272) (xy 190.425051 -48.550563) (xy 190.470409 -48.518112) (xy 190.520009 -48.492611)
			(xy 190.572793 -48.474604) (xy 190.627636 -48.464474) (xy 190.68337 -48.462437) (xy 190.738807 -48.468537)
			(xy 190.792764 -48.482643) (xy 190.844093 -48.504455) (xy 190.891699 -48.533509) (xy 190.934567 -48.569184)
			(xy 190.971784 -48.610721) (xy 191.002557 -48.657234) (xy 191.026229 -48.707731) (xy 191.042297 -48.761138)
			(xy 191.050417 -48.816314) (xy 191.050926 -48.8442) (xy 191.050417 -48.872086) (xy 191.047419 -48.89246)
			(xy 191.314068 -48.89246) (xy 191.318139 -48.836838) (xy 191.330265 -48.782401) (xy 191.350188 -48.73031)
			(xy 191.377484 -48.681675) (xy 191.41157 -48.637532) (xy 191.451719 -48.598823) (xy 191.497077 -48.566372)
			(xy 191.546677 -48.540871) (xy 191.599461 -48.522864) (xy 191.654304 -48.512734) (xy 191.710038 -48.510697)
			(xy 191.765475 -48.516797) (xy 191.819432 -48.530903) (xy 191.870761 -48.552715) (xy 191.918367 -48.581769)
			(xy 191.961235 -48.617444) (xy 191.998452 -48.658981) (xy 192.029225 -48.705494) (xy 192.052897 -48.755991)
			(xy 192.068965 -48.809398) (xy 192.077085 -48.864574) (xy 192.077594 -48.89246) (xy 192.077085 -48.920346)
			(xy 192.074647 -48.93691) (xy 195.033136 -48.93691) (xy 195.037207 -48.881288) (xy 195.049333 -48.826851)
			(xy 195.069256 -48.77476) (xy 195.096552 -48.726125) (xy 195.130638 -48.681982) (xy 195.170787 -48.643273)
			(xy 195.216145 -48.610822) (xy 195.265745 -48.585321) (xy 195.318529 -48.567314) (xy 195.373372 -48.557184)
			(xy 195.429106 -48.555147) (xy 195.484543 -48.561247) (xy 195.5385 -48.575353) (xy 195.589829 -48.597165)
			(xy 195.637435 -48.626219) (xy 195.680303 -48.661894) (xy 195.71752 -48.703431) (xy 195.748293 -48.749944)
			(xy 195.771965 -48.800441) (xy 195.788033 -48.853848) (xy 195.796153 -48.909024) (xy 195.796662 -48.93691)
			(xy 195.796153 -48.964796) (xy 195.788033 -49.019972) (xy 195.771965 -49.073379) (xy 195.748293 -49.123876)
			(xy 195.71752 -49.170389) (xy 195.680303 -49.211926) (xy 195.637435 -49.247601) (xy 195.589829 -49.276655)
			(xy 195.5385 -49.298467) (xy 195.484543 -49.312573) (xy 195.429106 -49.318673) (xy 195.373372 -49.316636)
			(xy 195.318529 -49.306506) (xy 195.265745 -49.288499) (xy 195.216145 -49.262998) (xy 195.170787 -49.230547)
			(xy 195.130638 -49.191838) (xy 195.096552 -49.147695) (xy 195.069256 -49.09906) (xy 195.049333 -49.046969)
			(xy 195.037207 -48.992532) (xy 195.033136 -48.93691) (xy 192.074647 -48.93691) (xy 192.068965 -48.975522)
			(xy 192.052897 -49.028929) (xy 192.029225 -49.079426) (xy 191.998452 -49.125939) (xy 191.961235 -49.167476)
			(xy 191.918367 -49.203151) (xy 191.870761 -49.232205) (xy 191.819432 -49.254017) (xy 191.765475 -49.268123)
			(xy 191.710038 -49.274223) (xy 191.654304 -49.272186) (xy 191.599461 -49.262056) (xy 191.546677 -49.244049)
			(xy 191.497077 -49.218548) (xy 191.451719 -49.186097) (xy 191.41157 -49.147388) (xy 191.377484 -49.103245)
			(xy 191.350188 -49.05461) (xy 191.330265 -49.002519) (xy 191.318139 -48.948082) (xy 191.314068 -48.89246)
			(xy 191.047419 -48.89246) (xy 191.042297 -48.927262) (xy 191.026229 -48.980669) (xy 191.002557 -49.031166)
			(xy 190.971784 -49.077679) (xy 190.934567 -49.119216) (xy 190.891699 -49.154891) (xy 190.844093 -49.183945)
			(xy 190.792764 -49.205757) (xy 190.738807 -49.219863) (xy 190.68337 -49.225963) (xy 190.627636 -49.223926)
			(xy 190.572793 -49.213796) (xy 190.520009 -49.195789) (xy 190.470409 -49.170288) (xy 190.425051 -49.137837)
			(xy 190.384902 -49.099128) (xy 190.350816 -49.054985) (xy 190.32352 -49.00635) (xy 190.303597 -48.954259)
			(xy 190.291471 -48.899822) (xy 190.2874 -48.8442) (xy 190.020805 -48.8442) (xy 190.007181 -48.889483)
			(xy 189.983509 -48.93998) (xy 189.952736 -48.986493) (xy 189.915519 -49.02803) (xy 189.872651 -49.063705)
			(xy 189.825045 -49.092759) (xy 189.773716 -49.114571) (xy 189.719759 -49.128677) (xy 189.664322 -49.134777)
			(xy 189.608588 -49.13274) (xy 189.553745 -49.12261) (xy 189.500961 -49.104603) (xy 189.451361 -49.079102)
			(xy 189.406003 -49.046651) (xy 189.365854 -49.007942) (xy 189.331768 -48.963799) (xy 189.304472 -48.915164)
			(xy 189.284549 -48.863073) (xy 189.272423 -48.808636) (xy 189.268352 -48.753014) (xy 182.41916 -48.753014)
			(xy 182.380382 -48.93818) (xy 182.379366 -48.948086) (xy 182.37275 -49.601949) (xy 200.212982 -49.601949)
			(xy 200.212982 -49.547451) (xy 200.220737 -49.493507) (xy 200.23609 -49.441216) (xy 200.258728 -49.391642)
			(xy 200.28819 -49.345794) (xy 200.323877 -49.304605) (xy 200.365062 -49.268914) (xy 200.410907 -49.239447)
			(xy 200.460479 -49.216804) (xy 200.512768 -49.201446) (xy 200.566711 -49.193684) (xy 200.59396 -49.193196)
			(xy 200.621329 -49.193686) (xy 200.675507 -49.201499) (xy 200.72801 -49.216982) (xy 200.777757 -49.239818)
			(xy 200.823725 -49.269537) (xy 200.844658 -49.287176) (xy 200.844912 -49.28743) (xy 200.851988 -49.293031)
			(xy 200.868913 -49.299268) (xy 200.877932 -49.299622) (xy 200.944988 -49.299622) (xy 200.954004 -49.299254)
			(xy 200.97092 -49.293014) (xy 200.978008 -49.28743) (xy 200.978008 -49.287176) (xy 200.978262 -49.287176)
			(xy 200.999195 -49.269535) (xy 201.045163 -49.239811) (xy 201.094909 -49.216965) (xy 201.147411 -49.201469)
			(xy 201.201589 -49.19364) (xy 201.256331 -49.19364) (xy 201.310509 -49.201469) (xy 201.363011 -49.216965)
			(xy 201.412757 -49.239811) (xy 201.458725 -49.269535) (xy 201.479658 -49.287176) (xy 201.479912 -49.28743)
			(xy 201.486988 -49.293031) (xy 201.503913 -49.299268) (xy 201.512932 -49.299622) (xy 201.579988 -49.299622)
			(xy 201.589004 -49.299254) (xy 201.60592 -49.293014) (xy 201.613008 -49.28743) (xy 201.613008 -49.287176)
			(xy 201.613262 -49.287176) (xy 201.634195 -49.269535) (xy 201.680163 -49.239811) (xy 201.729909 -49.216965)
			(xy 201.782411 -49.201469) (xy 201.836589 -49.19364) (xy 201.891331 -49.19364) (xy 201.945509 -49.201469)
			(xy 201.998011 -49.216965) (xy 202.047757 -49.239811) (xy 202.093725 -49.269535) (xy 202.114658 -49.287176)
			(xy 202.114912 -49.28743) (xy 202.121988 -49.293031) (xy 202.138913 -49.299268) (xy 202.147932 -49.299622)
			(xy 202.214988 -49.299622) (xy 202.224004 -49.299254) (xy 202.24092 -49.293014) (xy 202.248008 -49.28743)
			(xy 202.248008 -49.287176) (xy 202.248262 -49.287176) (xy 202.269194 -49.269538) (xy 202.315168 -49.239826)
			(xy 202.364915 -49.216991) (xy 202.417415 -49.201499) (xy 202.471591 -49.193671) (xy 202.49896 -49.193196)
			(xy 202.526215 -49.193649) (xy 202.580171 -49.201401) (xy 202.632474 -49.216754) (xy 202.68206 -49.239394)
			(xy 202.727918 -49.268861) (xy 202.769116 -49.304555) (xy 202.804815 -49.34575) (xy 202.834287 -49.391605)
			(xy 202.856932 -49.441188) (xy 202.87229 -49.49349) (xy 202.880049 -49.547445) (xy 202.880049 -49.601955)
			(xy 202.87229 -49.65591) (xy 202.856932 -49.708212) (xy 202.834287 -49.757795) (xy 202.804815 -49.80365)
			(xy 202.769116 -49.844845) (xy 202.727918 -49.880539) (xy 202.68206 -49.910006) (xy 202.632474 -49.932646)
			(xy 202.580171 -49.947999) (xy 202.526215 -49.955751) (xy 202.49896 -49.956212) (xy 202.471591 -49.955708)
			(xy 202.417414 -49.947899) (xy 202.364911 -49.932418) (xy 202.315164 -49.909585) (xy 202.269195 -49.879869)
			(xy 202.248262 -49.862232) (xy 202.248008 -49.861978) (xy 202.240925 -49.856386) (xy 202.224005 -49.850143)
			(xy 202.214988 -49.849786) (xy 202.147932 -49.849786) (xy 202.138917 -49.850161) (xy 202.122 -49.856396)
			(xy 202.114912 -49.861978) (xy 202.114658 -49.862232) (xy 202.093725 -49.879873) (xy 202.047757 -49.909597)
			(xy 201.998011 -49.932443) (xy 201.945509 -49.947939) (xy 201.891331 -49.955768) (xy 201.836589 -49.955768)
			(xy 201.782411 -49.947939) (xy 201.729909 -49.932443) (xy 201.680163 -49.909597) (xy 201.634195 -49.879873)
			(xy 201.613262 -49.862232) (xy 201.613008 -49.861978) (xy 201.605925 -49.856386) (xy 201.589005 -49.850143)
			(xy 201.579988 -49.849786) (xy 201.512932 -49.849786) (xy 201.503917 -49.850161) (xy 201.487 -49.856396)
			(xy 201.479912 -49.861978) (xy 201.479912 -49.862232) (xy 201.479658 -49.862232) (xy 201.458725 -49.879873)
			(xy 201.412757 -49.909597) (xy 201.363011 -49.932443) (xy 201.310509 -49.947939) (xy 201.256331 -49.955768)
			(xy 201.201589 -49.955768) (xy 201.147411 -49.947939) (xy 201.094909 -49.932443) (xy 201.045163 -49.909597)
			(xy 200.999195 -49.879873) (xy 200.978262 -49.862232) (xy 200.978008 -49.861978) (xy 200.970925 -49.856386)
			(xy 200.954005 -49.850143) (xy 200.944988 -49.849786) (xy 200.877932 -49.849786) (xy 200.868917 -49.850161)
			(xy 200.852 -49.856396) (xy 200.844912 -49.861978) (xy 200.844912 -49.862232) (xy 200.844658 -49.862232)
			(xy 200.823719 -49.879862) (xy 200.777748 -49.909574) (xy 200.728002 -49.932412) (xy 200.675503 -49.947905)
			(xy 200.621329 -49.955736) (xy 200.59396 -49.956212) (xy 200.566711 -49.955716) (xy 200.512768 -49.947954)
			(xy 200.460479 -49.932596) (xy 200.410907 -49.909953) (xy 200.365062 -49.880486) (xy 200.323877 -49.844795)
			(xy 200.28819 -49.803606) (xy 200.258728 -49.757758) (xy 200.23609 -49.708184) (xy 200.220737 -49.655893)
			(xy 200.212982 -49.601949) (xy 182.37275 -49.601949) (xy 182.364044 -50.462434) (xy 190.92621 -50.462434)
			(xy 190.930281 -50.406812) (xy 190.942407 -50.352375) (xy 190.96233 -50.300284) (xy 190.989626 -50.251649)
			(xy 191.023712 -50.207506) (xy 191.063861 -50.168797) (xy 191.109219 -50.136346) (xy 191.158819 -50.110845)
			(xy 191.211603 -50.092838) (xy 191.266446 -50.082708) (xy 191.32218 -50.080671) (xy 191.377617 -50.086771)
			(xy 191.431574 -50.100877) (xy 191.482903 -50.122689) (xy 191.530509 -50.151743) (xy 191.573377 -50.187418)
			(xy 191.610594 -50.228955) (xy 191.641367 -50.275468) (xy 191.665039 -50.325965) (xy 191.681107 -50.379372)
			(xy 191.689227 -50.434548) (xy 191.689736 -50.462434) (xy 191.689227 -50.49032) (xy 191.681107 -50.545496)
			(xy 191.665039 -50.598903) (xy 191.641367 -50.6494) (xy 191.610594 -50.695913) (xy 191.573377 -50.73745)
			(xy 191.530509 -50.773125) (xy 191.482903 -50.802179) (xy 191.431574 -50.823991) (xy 191.377617 -50.838097)
			(xy 191.32218 -50.844197) (xy 191.266446 -50.84216) (xy 191.211603 -50.83203) (xy 191.158819 -50.814023)
			(xy 191.109219 -50.788522) (xy 191.063861 -50.756071) (xy 191.023712 -50.717362) (xy 190.989626 -50.673219)
			(xy 190.96233 -50.624584) (xy 190.942407 -50.572493) (xy 190.930281 -50.518056) (xy 190.92621 -50.462434)
			(xy 182.364044 -50.462434) (xy 182.361078 -50.75555) (xy 182.35842 -51.019456) (xy 192.849498 -51.019456)
			(xy 192.853569 -50.963834) (xy 192.865695 -50.909397) (xy 192.885618 -50.857306) (xy 192.912914 -50.808671)
			(xy 192.947 -50.764528) (xy 192.987149 -50.725819) (xy 193.032507 -50.693368) (xy 193.082107 -50.667867)
			(xy 193.134891 -50.64986) (xy 193.189734 -50.63973) (xy 193.245468 -50.637693) (xy 193.300905 -50.643793)
			(xy 193.354862 -50.657899) (xy 193.406191 -50.679711) (xy 193.453797 -50.708765) (xy 193.496665 -50.74444)
			(xy 193.533882 -50.785977) (xy 193.564655 -50.83249) (xy 193.588327 -50.882987) (xy 193.604395 -50.936394)
			(xy 193.612515 -50.99157) (xy 193.613024 -51.019456) (xy 193.612515 -51.047342) (xy 193.604395 -51.102518)
			(xy 193.588327 -51.155925) (xy 193.564655 -51.206422) (xy 193.539799 -51.243992) (xy 201.233024 -51.243992)
			(xy 201.23348 -51.216621) (xy 201.241299 -51.162442) (xy 201.25679 -51.109938) (xy 201.279634 -51.060191)
			(xy 201.309362 -51.014225) (xy 201.327004 -50.993294) (xy 201.327258 -50.99304) (xy 201.332841 -50.985951)
			(xy 201.339088 -50.969036) (xy 201.33945 -50.96002) (xy 201.33945 -50.892964) (xy 201.339121 -50.883944)
			(xy 201.332855 -50.867027) (xy 201.327258 -50.859944) (xy 201.327004 -50.859944) (xy 201.327004 -50.85969)
			(xy 201.309347 -50.838772) (xy 201.279638 -50.792795) (xy 201.256805 -50.743044) (xy 201.241318 -50.690541)
			(xy 201.233495 -50.636362) (xy 201.233024 -50.608992) (xy 201.233448 -50.581737) (xy 201.241207 -50.527784)
			(xy 201.256566 -50.475483) (xy 201.279211 -50.425901) (xy 201.308683 -50.380046) (xy 201.344381 -50.338853)
			(xy 201.385578 -50.303159) (xy 201.431436 -50.273692) (xy 201.481021 -50.251052) (xy 201.533323 -50.235698)
			(xy 201.587277 -50.227945) (xy 201.614532 -50.227484) (xy 201.643449 -50.228019) (xy 201.70062 -50.23674)
			(xy 201.75582 -50.253993) (xy 201.807783 -50.279381) (xy 201.855317 -50.312323) (xy 201.897333 -50.352064)
			(xy 201.915522 -50.37455) (xy 201.923121 -50.383366) (xy 201.944028 -50.393543) (xy 201.955654 -50.394108)
			(xy 202.03541 -50.394108) (xy 202.04704 -50.393557) (xy 202.06795 -50.383376) (xy 202.075542 -50.37455)
			(xy 202.093697 -50.352036) (xy 202.135725 -50.312305) (xy 202.183268 -50.279371) (xy 202.235237 -50.253988)
			(xy 202.29044 -50.236738) (xy 202.347614 -50.228016) (xy 202.376532 -50.227484) (xy 202.403784 -50.227948)
			(xy 202.457732 -50.235709) (xy 202.510026 -50.251067) (xy 202.559603 -50.273712) (xy 202.605453 -50.303181)
			(xy 202.646643 -50.338874) (xy 202.682334 -50.380066) (xy 202.7118 -50.425918) (xy 202.734441 -50.475496)
			(xy 202.749796 -50.527792) (xy 202.757554 -50.58174) (xy 202.75804 -50.608992) (xy 202.757586 -50.635307)
			(xy 202.750351 -50.687437) (xy 202.736031 -50.73808) (xy 202.714896 -50.78628) (xy 202.687347 -50.831123)
			(xy 202.653904 -50.871761) (xy 202.63485 -50.889916) (xy 202.627447 -50.897436) (xy 202.618922 -50.916717)
			(xy 202.61834 -50.927254) (xy 202.61834 -51.00193) (xy 202.618882 -51.012479) (xy 202.627407 -51.031775)
			(xy 202.63485 -51.039268) (xy 202.653941 -51.057388) (xy 202.687393 -51.098026) (xy 202.714946 -51.142874)
			(xy 202.736078 -51.191082) (xy 202.750388 -51.241735) (xy 202.757605 -51.293874) (xy 202.75804 -51.320192)
			(xy 202.757515 -51.347442) (xy 202.74976 -51.401386) (xy 202.734408 -51.453678) (xy 202.71177 -51.503253)
			(xy 202.682307 -51.549102) (xy 202.64662 -51.590292) (xy 202.605434 -51.625983) (xy 202.559589 -51.655451)
			(xy 202.510016 -51.678094) (xy 202.457725 -51.693452) (xy 202.403782 -51.701212) (xy 202.376532 -51.7017)
			(xy 202.348868 -51.701163) (xy 202.29412 -51.693168) (xy 202.241099 -51.677356) (xy 202.190915 -51.654057)
			(xy 202.144619 -51.623759) (xy 202.10318 -51.587098) (xy 202.067466 -51.544839) (xy 202.052428 -51.521614)
			(xy 202.045788 -51.511941) (xy 202.025929 -51.499496) (xy 202.014328 -51.497738) (xy 201.934318 -51.489864)
			(xy 201.92268 -51.489247) (xy 201.900843 -51.497316) (xy 201.892408 -51.505358) (xy 201.892154 -51.505612)
			(xy 201.87408 -51.5242) (xy 201.833746 -51.556777) (xy 201.78937 -51.583589) (xy 201.741771 -51.604141)
			(xy 201.691825 -51.618053) (xy 201.640455 -51.625069) (xy 201.614532 -51.6255) (xy 201.58728 -51.625015)
			(xy 201.533329 -51.617262) (xy 201.481031 -51.60191) (xy 201.431451 -51.57927) (xy 201.385597 -51.549805)
			(xy 201.344404 -51.514113) (xy 201.308709 -51.472922) (xy 201.279241 -51.427071) (xy 201.256599 -51.377491)
			(xy 201.241243 -51.325194) (xy 201.233487 -51.271244) (xy 201.233024 -51.243992) (xy 193.539799 -51.243992)
			(xy 193.533882 -51.252935) (xy 193.496665 -51.294472) (xy 193.453797 -51.330147) (xy 193.406191 -51.359201)
			(xy 193.354862 -51.381013) (xy 193.300905 -51.395119) (xy 193.245468 -51.401219) (xy 193.189734 -51.399182)
			(xy 193.134891 -51.389052) (xy 193.082107 -51.371045) (xy 193.032507 -51.345544) (xy 192.987149 -51.313093)
			(xy 192.947 -51.274384) (xy 192.912914 -51.230241) (xy 192.885618 -51.181606) (xy 192.865695 -51.129515)
			(xy 192.853569 -51.075078) (xy 192.849498 -51.019456) (xy 182.35842 -51.019456) (xy 182.348186 -52.035456)
			(xy 195.041264 -52.035456) (xy 195.045335 -51.979834) (xy 195.057461 -51.925397) (xy 195.077384 -51.873306)
			(xy 195.10468 -51.824671) (xy 195.138766 -51.780528) (xy 195.178915 -51.741819) (xy 195.224273 -51.709368)
			(xy 195.273873 -51.683867) (xy 195.326657 -51.66586) (xy 195.3815 -51.65573) (xy 195.437234 -51.653693)
			(xy 195.492671 -51.659793) (xy 195.546628 -51.673899) (xy 195.597957 -51.695711) (xy 195.645563 -51.724765)
			(xy 195.688431 -51.76044) (xy 195.725648 -51.801977) (xy 195.756421 -51.84849) (xy 195.780093 -51.898987)
			(xy 195.796161 -51.952394) (xy 195.804281 -52.00757) (xy 195.80479 -52.035456) (xy 195.804281 -52.063342)
			(xy 195.796161 -52.118518) (xy 195.780093 -52.171925) (xy 195.756421 -52.222422) (xy 195.725648 -52.268935)
			(xy 195.688431 -52.310472) (xy 195.645563 -52.346147) (xy 195.597957 -52.375201) (xy 195.546628 -52.397013)
			(xy 195.492671 -52.411119) (xy 195.437234 -52.417219) (xy 195.3815 -52.415182) (xy 195.326657 -52.405052)
			(xy 195.273873 -52.387045) (xy 195.224273 -52.361544) (xy 195.178915 -52.329093) (xy 195.138766 -52.290384)
			(xy 195.10468 -52.246241) (xy 195.077384 -52.197606) (xy 195.057461 -52.145515) (xy 195.045335 -52.091078)
			(xy 195.041264 -52.035456) (xy 182.348186 -52.035456) (xy 182.342028 -52.646834) (xy 182.343806 -52.650136)
			(xy 182.348632 -52.654708) (xy 182.351552 -52.657363) (xy 182.358058 -52.66183) (xy 182.361586 -52.663598)
			(xy 182.363872 -52.664614) (xy 182.381398 -52.668678) (xy 182.388868 -52.670716) (xy 182.402187 -52.678598)
			(xy 182.40756 -52.684172) (xy 182.414917 -52.693124) (xy 182.421412 -52.715344) (xy 182.420006 -52.726844)
			(xy 182.420006 -52.727352) (xy 182.419244 -52.7304) (xy 182.419244 -52.730654) (xy 182.418482 -52.733956)
			(xy 182.386732 -52.822856) (xy 182.386732 -52.831238) (xy 182.385795 -52.861106) (xy 182.37581 -52.920019)
			(xy 182.35682 -52.976675) (xy 182.343552 -53.00345) (xy 182.341774 -53.006752) (xy 182.34027 -53.010601)
			(xy 182.338362 -53.018641) (xy 182.337964 -53.022754) (xy 182.33517 -53.264308) (xy 182.33517 -53.274214)
			(xy 182.337964 -53.279548) (xy 182.352175 -53.307074) (xy 182.372468 -53.365601) (xy 182.383037 -53.426637)
			(xy 182.383938 -53.457602) (xy 182.383684 -53.47589) (xy 182.382922 -53.486812) (xy 182.38064 -53.514185)
			(xy 182.369202 -53.56791) (xy 182.350168 -53.619435) (xy 182.337456 -53.643784) (xy 182.334658 -53.649354)
			(xy 182.331581 -53.66143) (xy 182.33136 -53.66766) (xy 182.331106 -53.681884) (xy 182.329328 -53.859938)
			(xy 182.329374 -53.863608) (xy 182.330393 -53.870876) (xy 182.33136 -53.874416) (xy 182.336694 -53.893466)
			(xy 182.339996 -53.899054) (xy 182.352667 -53.921606) (xy 182.372619 -53.969332) (xy 182.386115 -54.019269)
			(xy 182.392922 -54.070548) (xy 182.393336 -54.096412) (xy 182.393336 -54.09692) (xy 182.392863 -54.123936)
			(xy 182.385406 -54.177452) (xy 182.370678 -54.229439) (xy 182.348957 -54.278914) (xy 182.33517 -54.302152)
			(xy 182.332376 -54.306724) (xy 182.326534 -54.325266) (xy 182.32557 -54.328807) (xy 182.32455 -54.336074)
			(xy 182.324502 -54.339744) (xy 182.32247 -54.516528) (xy 182.326026 -54.529736) (xy 182.329836 -54.535832)
			(xy 182.342662 -54.55809) (xy 182.36288 -54.605315) (xy 182.376578 -54.654826) (xy 182.38351 -54.705727)
			(xy 182.383938 -54.731412) (xy 182.382922 -54.761384) (xy 182.381144 -54.77637) (xy 182.379147 -54.791102)
			(xy 184.276492 -54.791102) (xy 184.276961 -54.763732) (xy 184.284779 -54.709553) (xy 184.300267 -54.65705)
			(xy 184.323108 -54.607303) (xy 184.352831 -54.561336) (xy 184.370472 -54.540404) (xy 184.370726 -54.54015)
			(xy 184.376301 -54.533055) (xy 184.382554 -54.516145) (xy 184.382918 -54.50713) (xy 184.382918 -54.440074)
			(xy 184.38257 -54.431056) (xy 184.376316 -54.41414) (xy 184.370726 -54.407054) (xy 184.370472 -54.407054)
			(xy 184.370472 -54.4068) (xy 184.352831 -54.385867) (xy 184.323103 -54.3399) (xy 184.300255 -54.290154)
			(xy 184.284757 -54.237652) (xy 184.276927 -54.183473) (xy 184.276927 -54.12873) (xy 184.284756 -54.074551)
			(xy 184.300254 -54.022049) (xy 184.323102 -53.972303) (xy 184.35283 -53.926336) (xy 184.370472 -53.905404)
			(xy 184.370726 -53.90515) (xy 184.376301 -53.898055) (xy 184.382554 -53.881145) (xy 184.382918 -53.87213)
			(xy 184.382918 -53.805074) (xy 184.38257 -53.796056) (xy 184.376316 -53.77914) (xy 184.370726 -53.772054)
			(xy 184.370472 -53.772054) (xy 184.370472 -53.7718) (xy 184.352831 -53.750867) (xy 184.323103 -53.7049)
			(xy 184.300255 -53.655154) (xy 184.284757 -53.602652) (xy 184.276927 -53.548473) (xy 184.276927 -53.49373)
			(xy 184.284756 -53.439551) (xy 184.300254 -53.387049) (xy 184.323102 -53.337303) (xy 184.35283 -53.291336)
			(xy 184.370472 -53.270404) (xy 184.370726 -53.27015) (xy 184.376301 -53.263055) (xy 184.382554 -53.246145)
			(xy 184.382918 -53.23713) (xy 184.382918 -53.170074) (xy 184.38257 -53.161056) (xy 184.376316 -53.14414)
			(xy 184.370726 -53.137054) (xy 184.370472 -53.137054) (xy 184.370472 -53.1368) (xy 184.352815 -53.115882)
			(xy 184.323107 -53.069905) (xy 184.300275 -53.020154) (xy 184.284788 -52.96765) (xy 184.276964 -52.913472)
			(xy 184.276492 -52.886102) (xy 184.276978 -52.858851) (xy 184.284734 -52.804903) (xy 184.300089 -52.752608)
			(xy 184.322731 -52.703031) (xy 184.352197 -52.657181) (xy 184.387888 -52.61599) (xy 184.429079 -52.580299)
			(xy 184.474929 -52.550833) (xy 184.524506 -52.528191) (xy 184.576801 -52.512836) (xy 184.630749 -52.50508)
			(xy 184.685251 -52.50508) (xy 184.739199 -52.512836) (xy 184.791494 -52.528191) (xy 184.830594 -52.546048)
			(xy 189.779696 -52.546048) (xy 189.779696 -52.491552) (xy 189.787451 -52.437611) (xy 189.802803 -52.385322)
			(xy 189.82544 -52.33575) (xy 189.854901 -52.289904) (xy 189.890586 -52.248717) (xy 189.931769 -52.213027)
			(xy 189.977612 -52.183561) (xy 190.027181 -52.160919) (xy 190.079468 -52.14556) (xy 190.133408 -52.137799)
			(xy 190.160656 -52.13731) (xy 190.188025 -52.137799) (xy 190.242204 -52.145611) (xy 190.294707 -52.161095)
			(xy 190.344454 -52.183931) (xy 190.390422 -52.213651) (xy 190.411354 -52.23129) (xy 190.411608 -52.231544)
			(xy 190.418684 -52.237145) (xy 190.435609 -52.243382) (xy 190.444628 -52.243736) (xy 190.511684 -52.243736)
			(xy 190.520699 -52.243363) (xy 190.537616 -52.237126) (xy 190.544704 -52.231544) (xy 190.544704 -52.23129)
			(xy 190.544958 -52.23129) (xy 190.565891 -52.213649) (xy 190.611859 -52.183925) (xy 190.661605 -52.161079)
			(xy 190.714107 -52.145583) (xy 190.768285 -52.137754) (xy 190.823027 -52.137754) (xy 190.877205 -52.145583)
			(xy 190.929707 -52.161079) (xy 190.979453 -52.183925) (xy 191.025421 -52.213649) (xy 191.046354 -52.23129)
			(xy 191.046608 -52.231544) (xy 191.053684 -52.237145) (xy 191.070609 -52.243382) (xy 191.079628 -52.243736)
			(xy 191.146684 -52.243736) (xy 191.155699 -52.243363) (xy 191.172616 -52.237126) (xy 191.179704 -52.231544)
			(xy 191.179704 -52.23129) (xy 191.179958 -52.23129) (xy 191.200894 -52.213656) (xy 191.246866 -52.183943)
			(xy 191.296612 -52.161107) (xy 191.349112 -52.145615) (xy 191.403287 -52.137785) (xy 191.430656 -52.13731)
			(xy 191.457912 -52.137734) (xy 191.511871 -52.145486) (xy 191.564176 -52.160839) (xy 191.613764 -52.18348)
			(xy 191.659625 -52.212948) (xy 191.700825 -52.248644) (xy 191.736525 -52.28984) (xy 191.765999 -52.335697)
			(xy 191.788645 -52.385283) (xy 191.804004 -52.437586) (xy 191.811763 -52.491544) (xy 191.811763 -52.546056)
			(xy 191.805818 -52.587398) (xy 192.85534 -52.587398) (xy 192.859411 -52.531776) (xy 192.871537 -52.477339)
			(xy 192.89146 -52.425248) (xy 192.918756 -52.376613) (xy 192.952842 -52.33247) (xy 192.992991 -52.293761)
			(xy 193.038349 -52.26131) (xy 193.087949 -52.235809) (xy 193.140733 -52.217802) (xy 193.195576 -52.207672)
			(xy 193.25131 -52.205635) (xy 193.306747 -52.211735) (xy 193.360704 -52.225841) (xy 193.412033 -52.247653)
			(xy 193.459639 -52.276707) (xy 193.502507 -52.312382) (xy 193.539724 -52.353919) (xy 193.570497 -52.400432)
			(xy 193.594169 -52.450929) (xy 193.610237 -52.504336) (xy 193.617833 -52.555948) (xy 200.683902 -52.555948)
			(xy 200.683902 -52.501452) (xy 200.691658 -52.447509) (xy 200.70701 -52.39522) (xy 200.729648 -52.345647)
			(xy 200.759111 -52.299801) (xy 200.794797 -52.258614) (xy 200.835982 -52.222925) (xy 200.881826 -52.19346)
			(xy 200.931397 -52.170819) (xy 200.983686 -52.155463) (xy 201.037628 -52.147704) (xy 201.064876 -52.147216)
			(xy 201.092246 -52.147692) (xy 201.146425 -52.155507) (xy 201.198928 -52.170994) (xy 201.248675 -52.193833)
			(xy 201.294642 -52.223556) (xy 201.315574 -52.241196) (xy 201.315828 -52.24145) (xy 201.322927 -52.247019)
			(xy 201.339834 -52.253275) (xy 201.348848 -52.253642) (xy 201.415904 -52.253642) (xy 201.424923 -52.253299)
			(xy 201.44184 -52.247043) (xy 201.448924 -52.24145) (xy 201.448924 -52.241196) (xy 201.449178 -52.241196)
			(xy 201.470107 -52.223553) (xy 201.516081 -52.193842) (xy 201.565829 -52.171007) (xy 201.61833 -52.155517)
			(xy 201.672507 -52.147689) (xy 201.699876 -52.147216) (xy 201.727132 -52.147629) (xy 201.781089 -52.155384)
			(xy 201.833393 -52.170739) (xy 201.882979 -52.193381) (xy 201.928838 -52.222851) (xy 201.970036 -52.258547)
			(xy 202.005735 -52.299743) (xy 202.035207 -52.3456) (xy 202.057853 -52.395185) (xy 202.073211 -52.447488)
			(xy 202.080969 -52.501444) (xy 202.080969 -52.555956) (xy 202.073211 -52.609912) (xy 202.057853 -52.662215)
			(xy 202.035207 -52.7118) (xy 202.005735 -52.757657) (xy 201.970036 -52.798853) (xy 201.928838 -52.834549)
			(xy 201.882979 -52.864019) (xy 201.833393 -52.886661) (xy 201.781089 -52.902016) (xy 201.727132 -52.909771)
			(xy 201.699876 -52.910232) (xy 201.672504 -52.909797) (xy 201.618323 -52.901974) (xy 201.565819 -52.886479)
			(xy 201.516073 -52.86363) (xy 201.470108 -52.833897) (xy 201.449178 -52.816252) (xy 201.448924 -52.815998)
			(xy 201.441835 -52.810415) (xy 201.42492 -52.804166) (xy 201.415904 -52.803806) (xy 201.348848 -52.803806)
			(xy 201.339833 -52.804185) (xy 201.322916 -52.810417) (xy 201.315828 -52.815998) (xy 201.315828 -52.816252)
			(xy 201.315574 -52.816252) (xy 201.294619 -52.833862) (xy 201.248653 -52.86358) (xy 201.198912 -52.886422)
			(xy 201.146416 -52.90192) (xy 201.092244 -52.909755) (xy 201.064876 -52.910232) (xy 201.037628 -52.909696)
			(xy 200.983686 -52.901937) (xy 200.931397 -52.886581) (xy 200.881826 -52.86394) (xy 200.835982 -52.834475)
			(xy 200.794797 -52.798786) (xy 200.759111 -52.757599) (xy 200.729648 -52.711753) (xy 200.70701 -52.66218)
			(xy 200.691658 -52.609891) (xy 200.683902 -52.555948) (xy 193.617833 -52.555948) (xy 193.618357 -52.559512)
			(xy 193.618866 -52.587398) (xy 193.618357 -52.615284) (xy 193.610237 -52.67046) (xy 193.594169 -52.723867)
			(xy 193.570497 -52.774364) (xy 193.539724 -52.820877) (xy 193.502507 -52.862414) (xy 193.459639 -52.898089)
			(xy 193.412033 -52.927143) (xy 193.360704 -52.948955) (xy 193.306747 -52.963061) (xy 193.25131 -52.969161)
			(xy 193.195576 -52.967124) (xy 193.140733 -52.956994) (xy 193.087949 -52.938987) (xy 193.038349 -52.913486)
			(xy 192.992991 -52.881035) (xy 192.952842 -52.842326) (xy 192.918756 -52.798183) (xy 192.89146 -52.749548)
			(xy 192.871537 -52.697457) (xy 192.859411 -52.64302) (xy 192.85534 -52.587398) (xy 191.805818 -52.587398)
			(xy 191.804004 -52.600014) (xy 191.788645 -52.652317) (xy 191.765999 -52.701903) (xy 191.736525 -52.74776)
			(xy 191.700825 -52.788956) (xy 191.659625 -52.824652) (xy 191.613764 -52.85412) (xy 191.564176 -52.876761)
			(xy 191.511871 -52.892114) (xy 191.457912 -52.899866) (xy 191.430656 -52.900326) (xy 191.403286 -52.899845)
			(xy 191.349107 -52.892034) (xy 191.296603 -52.876549) (xy 191.246856 -52.85371) (xy 191.200889 -52.823987)
			(xy 191.179958 -52.806346) (xy 191.179704 -52.806092) (xy 191.172621 -52.8005) (xy 191.155701 -52.794257)
			(xy 191.146684 -52.7939) (xy 191.079628 -52.7939) (xy 191.070612 -52.79427) (xy 191.053695 -52.800509)
			(xy 191.046608 -52.806092) (xy 191.046354 -52.806346) (xy 191.025421 -52.823987) (xy 190.979453 -52.853711)
			(xy 190.929707 -52.876557) (xy 190.877205 -52.892053) (xy 190.823027 -52.899882) (xy 190.768285 -52.899882)
			(xy 190.714107 -52.892053) (xy 190.661605 -52.876557) (xy 190.611859 -52.853711) (xy 190.565891 -52.823987)
			(xy 190.544958 -52.806346) (xy 190.544704 -52.806092) (xy 190.537621 -52.8005) (xy 190.520701 -52.794257)
			(xy 190.511684 -52.7939) (xy 190.444628 -52.7939) (xy 190.435612 -52.79427) (xy 190.418695 -52.800509)
			(xy 190.411608 -52.806092) (xy 190.411608 -52.806346) (xy 190.411354 -52.806346) (xy 190.390405 -52.823965)
			(xy 190.344438 -52.853682) (xy 190.294695 -52.876522) (xy 190.242197 -52.892018) (xy 190.188024 -52.89985)
			(xy 190.160656 -52.900326) (xy 190.133408 -52.899801) (xy 190.079468 -52.89204) (xy 190.027181 -52.876681)
			(xy 189.977612 -52.854039) (xy 189.931769 -52.824573) (xy 189.890586 -52.788883) (xy 189.854901 -52.747696)
			(xy 189.82544 -52.70185) (xy 189.802803 -52.652278) (xy 189.787451 -52.599989) (xy 189.779696 -52.546048)
			(xy 184.830594 -52.546048) (xy 184.841071 -52.550833) (xy 184.886921 -52.580299) (xy 184.928112 -52.61599)
			(xy 184.963803 -52.657181) (xy 184.993269 -52.703031) (xy 185.015911 -52.752608) (xy 185.031266 -52.804903)
			(xy 185.039022 -52.858851) (xy 185.039508 -52.886102) (xy 185.039041 -52.913472) (xy 185.031223 -52.967651)
			(xy 185.015734 -53.020154) (xy 184.992893 -53.069901) (xy 184.963169 -53.115868) (xy 184.945528 -53.1368)
			(xy 184.945274 -53.137054) (xy 184.939698 -53.144147) (xy 184.933446 -53.161059) (xy 184.933082 -53.170074)
			(xy 184.933082 -53.23713) (xy 184.933428 -53.246148) (xy 184.939684 -53.263065) (xy 184.945274 -53.27015)
			(xy 184.945528 -53.27015) (xy 184.945528 -53.270404) (xy 184.963173 -53.291334) (xy 184.992901 -53.337301)
			(xy 185.015749 -53.387048) (xy 185.031247 -53.439551) (xy 185.039076 -53.49373) (xy 185.039076 -53.548473)
			(xy 185.031246 -53.602652) (xy 185.015748 -53.655155) (xy 184.992899 -53.704901) (xy 184.963171 -53.750868)
			(xy 184.946598 -53.77053) (xy 185.31078 -53.77053) (xy 185.311289 -53.741612) (xy 185.320016 -53.684439)
			(xy 185.337274 -53.629239) (xy 185.362667 -53.577277) (xy 185.395613 -53.529743) (xy 185.435358 -53.487728)
			(xy 185.457846 -53.46954) (xy 185.466633 -53.461913) (xy 185.476826 -53.441027) (xy 185.477404 -53.429408)
			(xy 185.477404 -53.349652) (xy 185.476877 -53.338019) (xy 185.466679 -53.317109) (xy 185.457846 -53.30952)
			(xy 185.435361 -53.291331) (xy 185.395628 -53.249309) (xy 185.362691 -53.201774) (xy 185.337303 -53.149812)
			(xy 185.320047 -53.094615) (xy 185.311316 -53.037446) (xy 185.31078 -53.00853) (xy 185.311283 -52.981278)
			(xy 185.319036 -52.92733) (xy 185.334387 -52.875033) (xy 185.357026 -52.825454) (xy 185.386489 -52.779601)
			(xy 185.422179 -52.738409) (xy 185.463368 -52.702714) (xy 185.509217 -52.673246) (xy 185.558794 -52.650602)
			(xy 185.611088 -52.635245) (xy 185.665036 -52.627486) (xy 185.692288 -52.627022) (xy 185.718602 -52.62749)
			(xy 185.770731 -52.634724) (xy 185.821374 -52.649042) (xy 185.869573 -52.670175) (xy 185.914416 -52.697721)
			(xy 185.955056 -52.73116) (xy 185.973212 -52.750212) (xy 185.980726 -52.757623) (xy 186.000012 -52.766142)
			(xy 186.01055 -52.766722) (xy 186.085226 -52.766722) (xy 186.095772 -52.76616) (xy 186.115067 -52.757647)
			(xy 186.122564 -52.750212) (xy 186.140698 -52.731135) (xy 186.181332 -52.697679) (xy 186.226177 -52.670123)
			(xy 186.274382 -52.648988) (xy 186.325033 -52.634676) (xy 186.377171 -52.627457) (xy 186.403488 -52.627022)
			(xy 186.430742 -52.627467) (xy 186.484695 -52.635223) (xy 186.536995 -52.650579) (xy 186.586577 -52.673222)
			(xy 186.632432 -52.702692) (xy 186.673625 -52.738387) (xy 186.709319 -52.779583) (xy 186.738787 -52.825439)
			(xy 186.761428 -52.875022) (xy 186.776781 -52.927323) (xy 186.784535 -52.981276) (xy 186.784996 -53.00853)
			(xy 186.784509 -53.036196) (xy 186.782278 -53.051456) (xy 195.041264 -53.051456) (xy 195.045335 -52.995834)
			(xy 195.057461 -52.941397) (xy 195.077384 -52.889306) (xy 195.10468 -52.840671) (xy 195.138766 -52.796528)
			(xy 195.178915 -52.757819) (xy 195.224273 -52.725368) (xy 195.273873 -52.699867) (xy 195.326657 -52.68186)
			(xy 195.3815 -52.67173) (xy 195.437234 -52.669693) (xy 195.492671 -52.675793) (xy 195.546628 -52.689899)
			(xy 195.597957 -52.711711) (xy 195.645563 -52.740765) (xy 195.688431 -52.77644) (xy 195.725648 -52.817977)
			(xy 195.756421 -52.86449) (xy 195.780093 -52.914987) (xy 195.796161 -52.968394) (xy 195.804281 -53.02357)
			(xy 195.80479 -53.051456) (xy 195.804281 -53.079342) (xy 195.796161 -53.134518) (xy 195.780093 -53.187925)
			(xy 195.756421 -53.238422) (xy 195.725648 -53.284935) (xy 195.688431 -53.326472) (xy 195.645563 -53.362147)
			(xy 195.597957 -53.391201) (xy 195.546628 -53.413013) (xy 195.492671 -53.427119) (xy 195.437234 -53.433219)
			(xy 195.3815 -53.431182) (xy 195.326657 -53.421052) (xy 195.273873 -53.403045) (xy 195.224273 -53.377544)
			(xy 195.178915 -53.345093) (xy 195.138766 -53.306384) (xy 195.10468 -53.262241) (xy 195.077384 -53.213606)
			(xy 195.057461 -53.161515) (xy 195.045335 -53.107078) (xy 195.041264 -53.051456) (xy 186.782278 -53.051456)
			(xy 186.776505 -53.090946) (xy 186.760684 -53.143969) (xy 186.737377 -53.194153) (xy 186.707072 -53.240448)
			(xy 186.670403 -53.281886) (xy 186.628139 -53.317598) (xy 186.60491 -53.332634) (xy 186.595211 -53.339244)
			(xy 186.58278 -53.359125) (xy 186.581034 -53.370734) (xy 186.57316 -53.450744) (xy 186.572506 -53.462383)
			(xy 186.580601 -53.484222) (xy 186.588654 -53.492654) (xy 186.588908 -53.492908) (xy 186.607477 -53.511001)
			(xy 186.640056 -53.551331) (xy 186.666871 -53.595702) (xy 186.687425 -53.643298) (xy 186.701342 -53.69324)
			(xy 186.708362 -53.744608) (xy 186.708796 -53.77053) (xy 186.70835 -53.797783) (xy 186.700589 -53.851732)
			(xy 186.68523 -53.904029) (xy 186.662584 -53.953607) (xy 186.633114 -53.999457) (xy 186.597418 -54.040648)
			(xy 186.556224 -54.076339) (xy 186.51037 -54.105804) (xy 186.460789 -54.128444) (xy 186.408491 -54.143798)
			(xy 186.354541 -54.151553) (xy 186.327288 -54.152038) (xy 186.299917 -54.151594) (xy 186.245736 -54.143773)
			(xy 186.193232 -54.12828) (xy 186.143486 -54.105433) (xy 186.09752 -54.075702) (xy 186.07659 -54.058058)
			(xy 186.076336 -54.057804) (xy 186.069243 -54.052227) (xy 186.052331 -54.045974) (xy 186.043316 -54.045612)
			(xy 185.97626 -54.045612) (xy 185.967241 -54.045947) (xy 185.950324 -54.05221) (xy 185.94324 -54.057804)
			(xy 185.94324 -54.058058) (xy 185.942986 -54.058058) (xy 185.922027 -54.075664) (xy 185.876062 -54.105382)
			(xy 185.826322 -54.128225) (xy 185.773827 -54.143724) (xy 185.719655 -54.15156) (xy 185.692288 -54.152038)
			(xy 185.665038 -54.151533) (xy 185.611092 -54.143776) (xy 185.5588 -54.128421) (xy 185.509224 -54.105781)
			(xy 185.463376 -54.076316) (xy 185.422186 -54.040626) (xy 185.386495 -53.999439) (xy 185.357028 -53.953591)
			(xy 185.334385 -53.904017) (xy 185.319028 -53.851725) (xy 185.311268 -53.79778) (xy 185.31078 -53.77053)
			(xy 184.946598 -53.77053) (xy 184.945528 -53.7718) (xy 184.945274 -53.772054) (xy 184.939698 -53.779147)
			(xy 184.933446 -53.796059) (xy 184.933082 -53.805074) (xy 184.933082 -53.87213) (xy 184.933428 -53.881148)
			(xy 184.939684 -53.898065) (xy 184.945274 -53.90515) (xy 184.945528 -53.90515) (xy 184.945528 -53.905404)
			(xy 184.963173 -53.926334) (xy 184.992901 -53.972301) (xy 185.015749 -54.022048) (xy 185.031247 -54.074551)
			(xy 185.039076 -54.12873) (xy 185.039076 -54.183473) (xy 185.031246 -54.237652) (xy 185.015748 -54.290155)
			(xy 185.001954 -54.320186) (xy 187.230512 -54.320186) (xy 187.230967 -54.292815) (xy 187.238787 -54.238636)
			(xy 187.254279 -54.186132) (xy 187.277123 -54.136386) (xy 187.30685 -54.090419) (xy 187.324492 -54.069488)
			(xy 187.324746 -54.069234) (xy 187.33033 -54.062146) (xy 187.336577 -54.04523) (xy 187.336938 -54.036214)
			(xy 187.336938 -53.969158) (xy 187.336545 -53.960145) (xy 187.330322 -53.943228) (xy 187.324746 -53.936138)
			(xy 187.324492 -53.936138) (xy 187.324492 -53.935884) (xy 187.306878 -53.914932) (xy 187.277162 -53.868965)
			(xy 187.254322 -53.819222) (xy 187.238825 -53.766726) (xy 187.23099 -53.712554) (xy 187.230512 -53.685186)
			(xy 187.230998 -53.657935) (xy 187.238754 -53.603987) (xy 187.254109 -53.551692) (xy 187.276751 -53.502115)
			(xy 187.306217 -53.456265) (xy 187.341908 -53.415074) (xy 187.383099 -53.379383) (xy 187.428949 -53.349917)
			(xy 187.478526 -53.327275) (xy 187.530821 -53.31192) (xy 187.584769 -53.304164) (xy 187.639271 -53.304164)
			(xy 187.693219 -53.31192) (xy 187.745514 -53.327275) (xy 187.795091 -53.349917) (xy 187.840941 -53.379383)
			(xy 187.882132 -53.415074) (xy 187.917823 -53.456265) (xy 187.943716 -53.496555) (xy 200.233441 -53.496555)
			(xy 200.233441 -53.442045) (xy 200.241199 -53.388089) (xy 200.256557 -53.335786) (xy 200.279203 -53.286202)
			(xy 200.308676 -53.240345) (xy 200.344374 -53.19915) (xy 200.385573 -53.163455) (xy 200.431432 -53.133987)
			(xy 200.481018 -53.111346) (xy 200.533322 -53.095992) (xy 200.587279 -53.088239) (xy 200.614534 -53.087778)
			(xy 200.641906 -53.088205) (xy 200.696087 -53.096029) (xy 200.748592 -53.111527) (xy 200.798338 -53.134377)
			(xy 200.844302 -53.164112) (xy 200.865232 -53.181758) (xy 200.865486 -53.182012) (xy 200.872571 -53.1876)
			(xy 200.889489 -53.193846) (xy 200.898506 -53.194204) (xy 200.965562 -53.194204) (xy 200.974577 -53.193828)
			(xy 200.991494 -53.187594) (xy 200.998582 -53.182012) (xy 200.998582 -53.181758) (xy 200.998836 -53.181758)
			(xy 201.019776 -53.164129) (xy 201.065747 -53.134417) (xy 201.115493 -53.111579) (xy 201.167991 -53.096086)
			(xy 201.222165 -53.088254) (xy 201.249534 -53.087778) (xy 201.276783 -53.088295) (xy 201.330725 -53.096055)
			(xy 201.383013 -53.111412) (xy 201.432584 -53.134054) (xy 201.478429 -53.163521) (xy 201.519613 -53.199211)
			(xy 201.5553 -53.240398) (xy 201.584762 -53.286245) (xy 201.6074 -53.335819) (xy 201.622753 -53.388109)
			(xy 201.630508 -53.442051) (xy 201.630508 -53.496549) (xy 201.622753 -53.550491) (xy 201.6074 -53.602781)
			(xy 201.584762 -53.652355) (xy 201.5553 -53.698202) (xy 201.519613 -53.739389) (xy 201.478429 -53.775079)
			(xy 201.432584 -53.804546) (xy 201.383013 -53.827188) (xy 201.330725 -53.842545) (xy 201.276783 -53.850305)
			(xy 201.249534 -53.850794) (xy 201.222164 -53.850309) (xy 201.167986 -53.842496) (xy 201.115483 -53.827012)
			(xy 201.065736 -53.804174) (xy 201.019768 -53.774453) (xy 200.998836 -53.756814) (xy 200.998582 -53.75656)
			(xy 200.991508 -53.750955) (xy 200.974581 -53.74472) (xy 200.965562 -53.744368) (xy 200.898506 -53.744368)
			(xy 200.88949 -53.744735) (xy 200.872574 -53.750976) (xy 200.865486 -53.75656) (xy 200.865486 -53.756814)
			(xy 200.865232 -53.756814) (xy 200.8443 -53.774454) (xy 200.798327 -53.804165) (xy 200.74858 -53.827001)
			(xy 200.696079 -53.842492) (xy 200.641903 -53.85032) (xy 200.614534 -53.850794) (xy 200.587279 -53.850361)
			(xy 200.533322 -53.842608) (xy 200.481018 -53.827254) (xy 200.431432 -53.804613) (xy 200.385573 -53.775145)
			(xy 200.344374 -53.73945) (xy 200.308676 -53.698255) (xy 200.279203 -53.652398) (xy 200.256557 -53.602814)
			(xy 200.241199 -53.550511) (xy 200.233441 -53.496555) (xy 187.943716 -53.496555) (xy 187.947289 -53.502115)
			(xy 187.969931 -53.551692) (xy 187.985286 -53.603987) (xy 187.993042 -53.657935) (xy 187.993528 -53.685186)
			(xy 187.993071 -53.712557) (xy 187.985254 -53.766737) (xy 187.969764 -53.819241) (xy 187.946919 -53.868988)
			(xy 187.917191 -53.914953) (xy 187.899548 -53.935884) (xy 187.899294 -53.936138) (xy 187.893727 -53.943238)
			(xy 187.887469 -53.960144) (xy 187.887102 -53.969158) (xy 187.887102 -54.036214) (xy 187.887452 -54.045232)
			(xy 187.893704 -54.062148) (xy 187.899294 -54.069234) (xy 187.899548 -54.069234) (xy 187.899548 -54.069488)
			(xy 187.917187 -54.09042) (xy 187.946901 -54.136392) (xy 187.969737 -54.18614) (xy 187.985228 -54.238641)
			(xy 187.993055 -54.292817) (xy 187.993528 -54.320186) (xy 187.993042 -54.347437) (xy 187.985286 -54.401385)
			(xy 187.969931 -54.45368) (xy 187.947289 -54.503257) (xy 187.917823 -54.549107) (xy 187.882132 -54.590298)
			(xy 187.840941 -54.625989) (xy 187.795091 -54.655455) (xy 187.745514 -54.678097) (xy 187.693219 -54.693452)
			(xy 187.639271 -54.701208) (xy 187.584769 -54.701208) (xy 187.530821 -54.693452) (xy 187.478526 -54.678097)
			(xy 187.428949 -54.655455) (xy 187.383099 -54.625989) (xy 187.341908 -54.590298) (xy 187.306217 -54.549107)
			(xy 187.276751 -54.503257) (xy 187.254109 -54.45368) (xy 187.238754 -54.401385) (xy 187.230998 -54.347437)
			(xy 187.230512 -54.320186) (xy 185.001954 -54.320186) (xy 184.992899 -54.339901) (xy 184.963171 -54.385868)
			(xy 184.945528 -54.4068) (xy 184.945274 -54.407054) (xy 184.939698 -54.414147) (xy 184.933446 -54.431059)
			(xy 184.933082 -54.440074) (xy 184.933082 -54.50713) (xy 184.933428 -54.516148) (xy 184.939684 -54.533065)
			(xy 184.945274 -54.54015) (xy 184.945528 -54.54015) (xy 184.945528 -54.540404) (xy 184.963187 -54.56132)
			(xy 184.992895 -54.607298) (xy 185.015726 -54.657049) (xy 185.031213 -54.709553) (xy 185.039036 -54.763732)
			(xy 185.039153 -54.770528) (xy 188.171074 -54.770528) (xy 188.171538 -54.743158) (xy 188.179354 -54.688978)
			(xy 188.194842 -54.636474) (xy 188.217685 -54.586727) (xy 188.247411 -54.540761) (xy 188.265054 -54.51983)
			(xy 188.265308 -54.519576) (xy 188.270912 -54.512501) (xy 188.277148 -54.495575) (xy 188.2775 -54.486556)
			(xy 188.2775 -54.4195) (xy 188.277143 -54.410483) (xy 188.270895 -54.393566) (xy 188.265308 -54.38648)
			(xy 188.265054 -54.38648) (xy 188.265054 -54.386226) (xy 188.247422 -54.365288) (xy 188.217707 -54.319318)
			(xy 188.194869 -54.269572) (xy 188.179377 -54.217072) (xy 188.171548 -54.162897) (xy 188.171074 -54.135528)
			(xy 188.17156 -54.108277) (xy 188.179316 -54.054329) (xy 188.194671 -54.002034) (xy 188.217313 -53.952457)
			(xy 188.246779 -53.906607) (xy 188.28247 -53.865416) (xy 188.323661 -53.829725) (xy 188.369511 -53.800259)
			(xy 188.419088 -53.777617) (xy 188.471383 -53.762262) (xy 188.525331 -53.754506) (xy 188.579833 -53.754506)
			(xy 188.633781 -53.762262) (xy 188.686076 -53.777617) (xy 188.735653 -53.800259) (xy 188.781503 -53.829725)
			(xy 188.822694 -53.865416) (xy 188.858385 -53.906607) (xy 188.887851 -53.952457) (xy 188.892926 -53.96357)
			(xy 192.872104 -53.96357) (xy 192.876175 -53.907948) (xy 192.888301 -53.853511) (xy 192.908224 -53.80142)
			(xy 192.93552 -53.752785) (xy 192.969606 -53.708642) (xy 193.009755 -53.669933) (xy 193.055113 -53.637482)
			(xy 193.104713 -53.611981) (xy 193.157497 -53.593974) (xy 193.21234 -53.583844) (xy 193.268074 -53.581807)
			(xy 193.323511 -53.587907) (xy 193.377468 -53.602013) (xy 193.428797 -53.623825) (xy 193.476403 -53.652879)
			(xy 193.519271 -53.688554) (xy 193.556488 -53.730091) (xy 193.587261 -53.776604) (xy 193.610933 -53.827101)
			(xy 193.627001 -53.880508) (xy 193.635121 -53.935684) (xy 193.63563 -53.96357) (xy 193.635121 -53.991456)
			(xy 193.627001 -54.046632) (xy 193.610933 -54.100039) (xy 193.587261 -54.150536) (xy 193.556488 -54.197049)
			(xy 193.519271 -54.238586) (xy 193.476403 -54.274261) (xy 193.428797 -54.303315) (xy 193.377468 -54.325127)
			(xy 193.323511 -54.339233) (xy 193.268074 -54.345333) (xy 193.21234 -54.343296) (xy 193.157497 -54.333166)
			(xy 193.104713 -54.315159) (xy 193.055113 -54.289658) (xy 193.009755 -54.257207) (xy 192.969606 -54.218498)
			(xy 192.93552 -54.174355) (xy 192.908224 -54.12572) (xy 192.888301 -54.073629) (xy 192.876175 -54.019192)
			(xy 192.872104 -53.96357) (xy 188.892926 -53.96357) (xy 188.910493 -54.002034) (xy 188.925848 -54.054329)
			(xy 188.933604 -54.108277) (xy 188.93409 -54.135528) (xy 188.933643 -54.162899) (xy 188.925821 -54.217079)
			(xy 188.910327 -54.269582) (xy 188.887481 -54.319329) (xy 188.857753 -54.365295) (xy 188.84011 -54.386226)
			(xy 188.839856 -54.38648) (xy 188.834266 -54.393564) (xy 188.828023 -54.410483) (xy 188.827664 -54.4195)
			(xy 188.827664 -54.486556) (xy 188.82805 -54.49557) (xy 188.834278 -54.512487) (xy 188.839856 -54.519576)
			(xy 188.84011 -54.519576) (xy 188.84011 -54.51983) (xy 188.857731 -54.540776) (xy 188.887445 -54.586745)
			(xy 188.910285 -54.636489) (xy 188.92578 -54.688987) (xy 188.933613 -54.74316) (xy 188.93409 -54.770528)
			(xy 188.933604 -54.797779) (xy 188.925848 -54.851727) (xy 188.910493 -54.904022) (xy 188.887851 -54.953599)
			(xy 188.865065 -54.989055) (xy 198.001045 -54.989055) (xy 198.001045 -54.934545) (xy 198.008803 -54.88059)
			(xy 198.024161 -54.828289) (xy 198.046806 -54.778705) (xy 198.076277 -54.73285) (xy 198.111975 -54.691655)
			(xy 198.153172 -54.655961) (xy 198.19903 -54.626492) (xy 198.248615 -54.603851) (xy 198.300918 -54.588497)
			(xy 198.354873 -54.580743) (xy 198.382128 -54.580282) (xy 198.41022 -54.580755) (xy 198.465799 -54.588986)
			(xy 198.519568 -54.605281) (xy 198.570366 -54.629287) (xy 198.617092 -54.660485) (xy 198.658737 -54.6982)
			(xy 198.694398 -54.741616) (xy 198.70928 -54.765448) (xy 198.714614 -54.774338) (xy 198.731632 -54.78653)
			(xy 198.82485 -54.80685) (xy 198.845424 -54.802532) (xy 198.85406 -54.79669) (xy 198.878132 -54.780704)
			(xy 198.930061 -54.755358) (xy 198.985216 -54.738129) (xy 199.042338 -54.729409) (xy 199.07123 -54.728872)
			(xy 199.098481 -54.72935) (xy 199.152428 -54.73711) (xy 199.204722 -54.752468) (xy 199.254298 -54.775111)
			(xy 199.300147 -54.804579) (xy 199.341336 -54.840271) (xy 199.377027 -54.881461) (xy 199.406494 -54.927311)
			(xy 199.429136 -54.976888) (xy 199.444492 -55.029182) (xy 199.452251 -55.083129) (xy 199.452738 -55.11038)
			(xy 199.452275 -55.137751) (xy 199.444459 -55.19193) (xy 199.42897 -55.244434) (xy 199.406127 -55.294181)
			(xy 199.3764 -55.340147) (xy 199.358758 -55.361078) (xy 199.358504 -55.361332) (xy 199.35294 -55.368434)
			(xy 199.34668 -55.385339) (xy 199.346312 -55.394352) (xy 199.346312 -55.461408) (xy 199.346663 -55.470426)
			(xy 199.352914 -55.487343) (xy 199.358504 -55.494428) (xy 199.358758 -55.494428) (xy 199.358758 -55.494682)
			(xy 199.37638 -55.51563) (xy 199.406106 -55.561595) (xy 199.428954 -55.611339) (xy 199.444452 -55.663838)
			(xy 199.452283 -55.718015) (xy 199.452285 -55.772755) (xy 199.444459 -55.826932) (xy 199.428965 -55.879433)
			(xy 199.406121 -55.929179) (xy 199.376398 -55.975146) (xy 199.358758 -55.996078) (xy 199.358504 -55.996332)
			(xy 199.35294 -56.003434) (xy 199.34668 -56.020339) (xy 199.346312 -56.029352) (xy 199.346312 -56.096408)
			(xy 199.346663 -56.105426) (xy 199.352914 -56.122343) (xy 199.358504 -56.129428) (xy 199.358758 -56.129428)
			(xy 199.358758 -56.129682) (xy 199.376396 -56.150615) (xy 199.406109 -56.196587) (xy 199.428946 -56.246334)
			(xy 199.444437 -56.298835) (xy 199.452265 -56.353011) (xy 199.452738 -56.38038) (xy 199.452252 -56.407631)
			(xy 199.444496 -56.461579) (xy 199.429141 -56.513874) (xy 199.406499 -56.563451) (xy 199.377033 -56.609301)
			(xy 199.341342 -56.650492) (xy 199.300151 -56.686183) (xy 199.254301 -56.715649) (xy 199.204724 -56.738291)
			(xy 199.152429 -56.753646) (xy 199.098481 -56.761402) (xy 199.043979 -56.761402) (xy 198.990031 -56.753646)
			(xy 198.937736 -56.738291) (xy 198.888159 -56.715649) (xy 198.842309 -56.686183) (xy 198.801118 -56.650492)
			(xy 198.765427 -56.609301) (xy 198.735961 -56.563451) (xy 198.713319 -56.513874) (xy 198.697964 -56.461579)
			(xy 198.690208 -56.407631) (xy 198.689722 -56.38038) (xy 198.690171 -56.353009) (xy 198.697992 -56.298829)
			(xy 198.713485 -56.246326) (xy 198.736331 -56.196579) (xy 198.766059 -56.150613) (xy 198.783702 -56.129682)
			(xy 198.783956 -56.129428) (xy 198.789544 -56.122342) (xy 198.795788 -56.105425) (xy 198.796148 -56.096408)
			(xy 198.796148 -56.029352) (xy 198.795777 -56.020336) (xy 198.789541 -56.003419) (xy 198.783956 -55.996332)
			(xy 198.783702 -55.996332) (xy 198.783702 -55.996078) (xy 198.766043 -55.975161) (xy 198.736321 -55.92919)
			(xy 198.713478 -55.879441) (xy 198.697984 -55.826936) (xy 198.690158 -55.772756) (xy 198.69016 -55.718014)
			(xy 198.697991 -55.663834) (xy 198.713489 -55.611331) (xy 198.736335 -55.561584) (xy 198.766061 -55.515615)
			(xy 198.783702 -55.494682) (xy 198.783956 -55.494428) (xy 198.789544 -55.487342) (xy 198.795788 -55.470425)
			(xy 198.796148 -55.461408) (xy 198.796148 -55.394352) (xy 198.795777 -55.385336) (xy 198.789541 -55.368419)
			(xy 198.783956 -55.361332) (xy 198.783702 -55.360824) (xy 198.772759 -55.348089) (xy 198.752917 -55.320998)
			(xy 198.744078 -55.306722) (xy 198.738744 -55.297832) (xy 198.721726 -55.28564) (xy 198.628508 -55.26532)
			(xy 198.607934 -55.269638) (xy 198.599298 -55.27548) (xy 198.575235 -55.291481) (xy 198.523303 -55.316824)
			(xy 198.468145 -55.334049) (xy 198.411021 -55.342764) (xy 198.382128 -55.343298) (xy 198.354873 -55.342857)
			(xy 198.300918 -55.335103) (xy 198.248615 -55.319749) (xy 198.19903 -55.297108) (xy 198.153172 -55.267639)
			(xy 198.111975 -55.231945) (xy 198.076277 -55.19075) (xy 198.046806 -55.144895) (xy 198.024161 -55.095311)
			(xy 198.008803 -55.04301) (xy 198.001045 -54.989055) (xy 188.865065 -54.989055) (xy 188.858385 -54.999449)
			(xy 188.822694 -55.04064) (xy 188.781503 -55.076331) (xy 188.735653 -55.105797) (xy 188.686076 -55.128439)
			(xy 188.633781 -55.143794) (xy 188.579833 -55.15155) (xy 188.525331 -55.15155) (xy 188.471383 -55.143794)
			(xy 188.419088 -55.128439) (xy 188.369511 -55.105797) (xy 188.323661 -55.076331) (xy 188.28247 -55.04064)
			(xy 188.246779 -54.999449) (xy 188.217313 -54.953599) (xy 188.194671 -54.904022) (xy 188.179316 -54.851727)
			(xy 188.17156 -54.797779) (xy 188.171074 -54.770528) (xy 185.039153 -54.770528) (xy 185.039508 -54.791102)
			(xy 185.039022 -54.818353) (xy 185.031266 -54.872301) (xy 185.015911 -54.924596) (xy 184.993269 -54.974173)
			(xy 184.963803 -55.020023) (xy 184.928112 -55.061214) (xy 184.886921 -55.096905) (xy 184.841071 -55.126371)
			(xy 184.791494 -55.149013) (xy 184.739199 -55.164368) (xy 184.685251 -55.172124) (xy 184.630749 -55.172124)
			(xy 184.576801 -55.164368) (xy 184.524506 -55.149013) (xy 184.474929 -55.126371) (xy 184.429079 -55.096905)
			(xy 184.387888 -55.061214) (xy 184.352197 -55.020023) (xy 184.322731 -54.974173) (xy 184.300089 -54.924596)
			(xy 184.284734 -54.872301) (xy 184.276978 -54.818353) (xy 184.276492 -54.791102) (xy 182.379147 -54.791102)
			(xy 182.377692 -54.801842) (xy 182.364817 -54.851607) (xy 182.345368 -54.899188) (xy 182.332884 -54.921658)
			(xy 182.325772 -54.933596) (xy 182.320692 -54.94147) (xy 182.318152 -54.945788) (xy 182.317644 -54.993794)
			(xy 182.31014 -55.722266) (xy 193.934078 -55.722266) (xy 193.938149 -55.666644) (xy 193.950275 -55.612207)
			(xy 193.970198 -55.560116) (xy 193.997494 -55.511481) (xy 194.03158 -55.467338) (xy 194.071729 -55.428629)
			(xy 194.117087 -55.396178) (xy 194.166687 -55.370677) (xy 194.219471 -55.35267) (xy 194.274314 -55.34254)
			(xy 194.330048 -55.340503) (xy 194.385485 -55.346603) (xy 194.439442 -55.360709) (xy 194.490771 -55.382521)
			(xy 194.538377 -55.411575) (xy 194.549528 -55.420855) (xy 196.324645 -55.420855) (xy 196.324645 -55.366345)
			(xy 196.332403 -55.31239) (xy 196.347761 -55.260089) (xy 196.370406 -55.210505) (xy 196.399877 -55.16465)
			(xy 196.435575 -55.123455) (xy 196.476772 -55.087761) (xy 196.52263 -55.058292) (xy 196.572215 -55.035651)
			(xy 196.624518 -55.020297) (xy 196.678473 -55.012543) (xy 196.705728 -55.012082) (xy 196.732042 -55.012537)
			(xy 196.784171 -55.019775) (xy 196.834814 -55.034097) (xy 196.883013 -55.055232) (xy 196.927856 -55.08278)
			(xy 196.968495 -55.11622) (xy 196.986652 -55.135272) (xy 196.994156 -55.142695) (xy 197.013449 -55.151208)
			(xy 197.02399 -55.151782) (xy 197.098666 -55.151782) (xy 197.109216 -55.151253) (xy 197.128512 -55.142719)
			(xy 197.136004 -55.135272) (xy 197.154159 -55.116216) (xy 197.19479 -55.08276) (xy 197.23963 -55.055202)
			(xy 197.287831 -55.034064) (xy 197.338478 -55.019746) (xy 197.390612 -55.012521) (xy 197.416928 -55.012082)
			(xy 197.444177 -55.01259) (xy 197.49812 -55.02035) (xy 197.55041 -55.035707) (xy 197.599983 -55.058349)
			(xy 197.645828 -55.087815) (xy 197.687014 -55.123506) (xy 197.722702 -55.164694) (xy 197.752164 -55.210542)
			(xy 197.774803 -55.260116) (xy 197.790156 -55.312407) (xy 197.797912 -55.366351) (xy 197.797912 -55.420849)
			(xy 197.790156 -55.474793) (xy 197.774803 -55.527084) (xy 197.752164 -55.576658) (xy 197.722702 -55.622506)
			(xy 197.687014 -55.663694) (xy 197.645828 -55.699385) (xy 197.599983 -55.728851) (xy 197.55041 -55.751493)
			(xy 197.49812 -55.76685) (xy 197.444177 -55.77461) (xy 197.416928 -55.775098) (xy 197.390612 -55.774679)
			(xy 197.338482 -55.767435) (xy 197.287838 -55.753106) (xy 197.239639 -55.731964) (xy 197.194797 -55.70441)
			(xy 197.154159 -55.670963) (xy 197.136004 -55.651908) (xy 197.128482 -55.644507) (xy 197.109202 -55.635982)
			(xy 197.098666 -55.635398) (xy 197.02399 -55.635398) (xy 197.013438 -55.635909) (xy 196.994143 -55.644457)
			(xy 196.986652 -55.651908) (xy 196.968514 -55.670981) (xy 196.927881 -55.704437) (xy 196.883037 -55.731993)
			(xy 196.834832 -55.753128) (xy 196.784182 -55.767442) (xy 196.732045 -55.774662) (xy 196.705728 -55.775098)
			(xy 196.678473 -55.774657) (xy 196.624518 -55.766903) (xy 196.572215 -55.751549) (xy 196.52263 -55.728908)
			(xy 196.476772 -55.699439) (xy 196.435575 -55.663745) (xy 196.399877 -55.62255) (xy 196.370406 -55.576695)
			(xy 196.347761 -55.527111) (xy 196.332403 -55.47481) (xy 196.324645 -55.420855) (xy 194.549528 -55.420855)
			(xy 194.581245 -55.44725) (xy 194.618462 -55.488787) (xy 194.649235 -55.5353) (xy 194.672907 -55.585797)
			(xy 194.688975 -55.639204) (xy 194.697095 -55.69438) (xy 194.697604 -55.722266) (xy 194.697095 -55.750152)
			(xy 194.688975 -55.805328) (xy 194.672907 -55.858735) (xy 194.649235 -55.909232) (xy 194.618462 -55.955745)
			(xy 194.581245 -55.997282) (xy 194.538377 -56.032957) (xy 194.490771 -56.062011) (xy 194.439442 -56.083823)
			(xy 194.385485 -56.097929) (xy 194.330048 -56.104029) (xy 194.274314 -56.101992) (xy 194.219471 -56.091862)
			(xy 194.166687 -56.073855) (xy 194.117087 -56.048354) (xy 194.071729 -56.015903) (xy 194.03158 -55.977194)
			(xy 193.997494 -55.933051) (xy 193.970198 -55.884416) (xy 193.950275 -55.832325) (xy 193.938149 -55.777888)
			(xy 193.934078 -55.722266) (xy 182.31014 -55.722266) (xy 182.301388 -56.571896) (xy 182.301421 -56.576032)
			(xy 182.302698 -56.584203) (xy 182.303928 -56.588152) (xy 182.306214 -56.59501) (xy 182.309516 -56.599836)
			(xy 182.310024 -56.600344) (xy 182.327355 -56.625014) (xy 182.354853 -56.678665) (xy 182.373592 -56.735967)
			(xy 182.383107 -56.795499) (xy 182.383684 -56.825642) (xy 182.383684 -56.835802) (xy 182.38343 -56.844438)
			(xy 182.38343 -56.844946) (xy 182.381758 -56.870161) (xy 182.372581 -56.919855) (xy 182.365142 -56.944006)
			(xy 182.356252 -56.968898) (xy 182.355744 -56.969914) (xy 182.35549 -56.97093) (xy 182.354982 -56.971438)
			(xy 182.347441 -56.989235) (xy 182.34013 -57.002934) (xy 189.663578 -57.002934) (xy 189.664102 -56.974843)
			(xy 189.672324 -56.919268) (xy 189.68861 -56.8655) (xy 189.712608 -56.814702) (xy 189.743798 -56.767975)
			(xy 189.781506 -56.726329) (xy 189.824915 -56.690665) (xy 189.848744 -56.675782) (xy 189.857634 -56.670448)
			(xy 189.869826 -56.65343) (xy 189.890146 -56.560212) (xy 189.885828 -56.539638) (xy 189.879986 -56.531002)
			(xy 189.863983 -56.50694) (xy 189.838641 -56.455008) (xy 189.821417 -56.399849) (xy 189.812702 -56.342725)
			(xy 189.812168 -56.313832) (xy 189.812685 -56.286581) (xy 189.820437 -56.232633) (xy 189.835788 -56.180338)
			(xy 189.858425 -56.130759) (xy 189.887887 -56.084907) (xy 189.923575 -56.043715) (xy 189.964762 -56.008021)
			(xy 190.01061 -55.978552) (xy 190.060185 -55.955907) (xy 190.112478 -55.940549) (xy 190.166425 -55.932789)
			(xy 190.193676 -55.932324) (xy 190.221046 -55.932798) (xy 190.275225 -55.940613) (xy 190.327728 -55.9561)
			(xy 190.377475 -55.97894) (xy 190.423442 -56.008663) (xy 190.444374 -56.026304) (xy 190.444628 -56.026558)
			(xy 190.451726 -56.032127) (xy 190.468634 -56.038383) (xy 190.477648 -56.03875) (xy 190.544704 -56.03875)
			(xy 190.553722 -56.038406) (xy 190.57064 -56.03215) (xy 190.577724 -56.026558) (xy 190.577724 -56.026304)
			(xy 190.577978 -56.026304) (xy 190.598911 -56.008663) (xy 190.644879 -55.978939) (xy 190.694625 -55.956093)
			(xy 190.747127 -55.940597) (xy 190.801305 -55.932768) (xy 190.856047 -55.932768) (xy 190.910225 -55.940597)
			(xy 190.962727 -55.956093) (xy 191.012473 -55.978939) (xy 191.058441 -56.008663) (xy 191.079374 -56.026304)
			(xy 191.079628 -56.026558) (xy 191.086726 -56.032127) (xy 191.103634 -56.038383) (xy 191.112648 -56.03875)
			(xy 191.179704 -56.03875) (xy 191.188722 -56.038406) (xy 191.20564 -56.03215) (xy 191.212724 -56.026558)
			(xy 191.212724 -56.026304) (xy 191.212978 -56.026304) (xy 191.233908 -56.008662) (xy 191.279881 -55.978951)
			(xy 191.329629 -55.956115) (xy 191.382131 -55.940625) (xy 191.436307 -55.932797) (xy 191.463676 -55.932324)
			(xy 191.490932 -55.932721) (xy 191.54489 -55.940476) (xy 191.597196 -55.955831) (xy 191.646783 -55.978474)
			(xy 191.692643 -56.007944) (xy 191.733842 -56.043641) (xy 191.769541 -56.084838) (xy 191.799014 -56.130696)
			(xy 191.82166 -56.180282) (xy 191.837019 -56.232586) (xy 191.844777 -56.286544) (xy 191.844777 -56.297068)
			(xy 192.186558 -56.297068) (xy 192.190629 -56.241446) (xy 192.202755 -56.187009) (xy 192.222678 -56.134918)
			(xy 192.249974 -56.086283) (xy 192.28406 -56.04214) (xy 192.324209 -56.003431) (xy 192.369567 -55.97098)
			(xy 192.419167 -55.945479) (xy 192.471951 -55.927472) (xy 192.526794 -55.917342) (xy 192.582528 -55.915305)
			(xy 192.637965 -55.921405) (xy 192.691922 -55.935511) (xy 192.743251 -55.957323) (xy 192.790857 -55.986377)
			(xy 192.833725 -56.022052) (xy 192.870942 -56.063589) (xy 192.901715 -56.110102) (xy 192.925387 -56.160599)
			(xy 192.941455 -56.214006) (xy 192.949575 -56.269182) (xy 192.950084 -56.297068) (xy 192.949575 -56.324954)
			(xy 192.941455 -56.38013) (xy 192.925387 -56.433537) (xy 192.901715 -56.484034) (xy 192.870942 -56.530547)
			(xy 192.833725 -56.572084) (xy 192.790857 -56.607759) (xy 192.743251 -56.636813) (xy 192.691922 -56.658625)
			(xy 192.637965 -56.672731) (xy 192.582528 -56.678831) (xy 192.526794 -56.676794) (xy 192.471951 -56.666664)
			(xy 192.419167 -56.648657) (xy 192.369567 -56.623156) (xy 192.324209 -56.590705) (xy 192.28406 -56.551996)
			(xy 192.249974 -56.507853) (xy 192.222678 -56.459218) (xy 192.202755 -56.407127) (xy 192.190629 -56.35269)
			(xy 192.186558 -56.297068) (xy 191.844777 -56.297068) (xy 191.844777 -56.341056) (xy 191.837019 -56.395014)
			(xy 191.82166 -56.447318) (xy 191.799014 -56.496904) (xy 191.769541 -56.542762) (xy 191.733842 -56.583959)
			(xy 191.692643 -56.619656) (xy 191.646783 -56.649126) (xy 191.597196 -56.671769) (xy 191.54489 -56.687124)
			(xy 191.490932 -56.694879) (xy 191.463676 -56.69534) (xy 191.436305 -56.694903) (xy 191.382124 -56.68708)
			(xy 191.32962 -56.671585) (xy 191.279873 -56.648737) (xy 191.233908 -56.619005) (xy 191.212978 -56.60136)
			(xy 191.212724 -56.601106) (xy 191.205634 -56.595524) (xy 191.18872 -56.589274) (xy 191.179704 -56.588914)
			(xy 191.112648 -56.588914) (xy 191.103633 -56.589291) (xy 191.086716 -56.595524) (xy 191.079628 -56.601106)
			(xy 191.079628 -56.60136) (xy 191.079374 -56.60136) (xy 191.058441 -56.619001) (xy 191.012473 -56.648725)
			(xy 190.962727 -56.671571) (xy 190.910225 -56.687067) (xy 190.856047 -56.694896) (xy 190.801305 -56.694896)
			(xy 190.747127 -56.687067) (xy 190.694625 -56.671571) (xy 190.644879 -56.648725) (xy 190.598911 -56.619001)
			(xy 190.577978 -56.60136) (xy 190.577724 -56.601106) (xy 190.570634 -56.595524) (xy 190.55372 -56.589274)
			(xy 190.544704 -56.588914) (xy 190.477648 -56.588914) (xy 190.468633 -56.589291) (xy 190.451716 -56.595524)
			(xy 190.444628 -56.601106) (xy 190.44412 -56.60136) (xy 190.431388 -56.612307) (xy 190.404295 -56.632146)
			(xy 190.390018 -56.640984) (xy 190.381128 -56.646318) (xy 190.368936 -56.663336) (xy 190.348616 -56.756554)
			(xy 190.352934 -56.777128) (xy 190.358776 -56.785764) (xy 190.37476 -56.809838) (xy 190.400107 -56.861766)
			(xy 190.417337 -56.91692) (xy 190.426057 -56.974042) (xy 190.426594 -57.002934) (xy 190.426108 -57.030185)
			(xy 190.425826 -57.032144) (xy 193.585844 -57.032144) (xy 193.589915 -56.976522) (xy 193.602041 -56.922085)
			(xy 193.621964 -56.869994) (xy 193.64926 -56.821359) (xy 193.683346 -56.777216) (xy 193.723495 -56.738507)
			(xy 193.768853 -56.706056) (xy 193.818453 -56.680555) (xy 193.871237 -56.662548) (xy 193.92608 -56.652418)
			(xy 193.981814 -56.650381) (xy 194.037251 -56.656481) (xy 194.091208 -56.670587) (xy 194.142537 -56.692399)
			(xy 194.190143 -56.721453) (xy 194.233011 -56.757128) (xy 194.270228 -56.798665) (xy 194.301001 -56.845178)
			(xy 194.324673 -56.895675) (xy 194.340741 -56.949082) (xy 194.348861 -57.004258) (xy 194.34937 -57.032144)
			(xy 194.348861 -57.06003) (xy 194.340741 -57.115206) (xy 194.324673 -57.168613) (xy 194.301001 -57.21911)
			(xy 194.270228 -57.265623) (xy 194.233011 -57.30716) (xy 194.190143 -57.342835) (xy 194.142537 -57.371889)
			(xy 194.091208 -57.393701) (xy 194.037251 -57.407807) (xy 193.981814 -57.413907) (xy 193.92608 -57.41187)
			(xy 193.871237 -57.40174) (xy 193.818453 -57.383733) (xy 193.768853 -57.358232) (xy 193.723495 -57.325781)
			(xy 193.683346 -57.287072) (xy 193.64926 -57.242929) (xy 193.621964 -57.194294) (xy 193.602041 -57.142203)
			(xy 193.589915 -57.087766) (xy 193.585844 -57.032144) (xy 190.425826 -57.032144) (xy 190.418352 -57.084133)
			(xy 190.402997 -57.136428) (xy 190.380355 -57.186005) (xy 190.350889 -57.231855) (xy 190.315198 -57.273046)
			(xy 190.274007 -57.308737) (xy 190.228157 -57.338203) (xy 190.17858 -57.360845) (xy 190.126285 -57.3762)
			(xy 190.072337 -57.383956) (xy 190.017835 -57.383956) (xy 189.963887 -57.3762) (xy 189.911592 -57.360845)
			(xy 189.862015 -57.338203) (xy 189.816165 -57.308737) (xy 189.774974 -57.273046) (xy 189.739283 -57.231855)
			(xy 189.709817 -57.186005) (xy 189.687175 -57.136428) (xy 189.67182 -57.084133) (xy 189.664064 -57.030185)
			(xy 189.663578 -57.002934) (xy 182.34013 -57.002934) (xy 182.329242 -57.023335) (xy 182.31866 -57.03951)
			(xy 182.31358 -57.046876) (xy 182.306976 -57.05602) (xy 182.306722 -57.056274) (xy 182.302385 -57.062346)
			(xy 182.297085 -57.076286) (xy 182.296308 -57.083706) (xy 182.295038 -57.198768) (xy 182.295099 -57.203041)
			(xy 182.296507 -57.211469) (xy 182.297832 -57.215532) (xy 182.300118 -57.222644) (xy 182.305452 -57.229502)
			(xy 182.30977 -57.235598) (xy 182.310024 -57.235852) (xy 182.311548 -57.237884) (xy 182.322978 -57.25414)
			(xy 182.33009 -57.266078) (xy 182.340611 -57.28431) (xy 182.358047 -57.322625) (xy 182.364888 -57.342532)
			(xy 182.368952 -57.354978) (xy 182.370222 -57.359042) (xy 182.37327 -57.371742) (xy 182.37835 -57.396888)
			(xy 182.380848 -57.412708) (xy 182.383519 -57.444627) (xy 182.383684 -57.460642) (xy 182.383684 -57.47131)
			(xy 182.383044 -57.48528) (xy 198.705976 -57.48528) (xy 198.710047 -57.429658) (xy 198.722173 -57.375221)
			(xy 198.742096 -57.32313) (xy 198.769392 -57.274495) (xy 198.803478 -57.230352) (xy 198.843627 -57.191643)
			(xy 198.888985 -57.159192) (xy 198.938585 -57.133691) (xy 198.991369 -57.115684) (xy 199.046212 -57.105554)
			(xy 199.101946 -57.103517) (xy 199.157383 -57.109617) (xy 199.21134 -57.123723) (xy 199.262669 -57.145535)
			(xy 199.310275 -57.174589) (xy 199.353143 -57.210264) (xy 199.39036 -57.251801) (xy 199.421133 -57.298314)
			(xy 199.444805 -57.348811) (xy 199.460873 -57.402218) (xy 199.468993 -57.457394) (xy 199.469502 -57.48528)
			(xy 199.468993 -57.513166) (xy 199.460873 -57.568342) (xy 199.444805 -57.621749) (xy 199.421133 -57.672246)
			(xy 199.39036 -57.718759) (xy 199.353143 -57.760296) (xy 199.310275 -57.795971) (xy 199.262669 -57.825025)
			(xy 199.21134 -57.846837) (xy 199.157383 -57.860943) (xy 199.101946 -57.867043) (xy 199.046212 -57.865006)
			(xy 198.991369 -57.854876) (xy 198.938585 -57.836869) (xy 198.888985 -57.811368) (xy 198.843627 -57.778917)
			(xy 198.803478 -57.740208) (xy 198.769392 -57.696065) (xy 198.742096 -57.64743) (xy 198.722173 -57.595339)
			(xy 198.710047 -57.540902) (xy 198.705976 -57.48528) (xy 182.383044 -57.48528) (xy 182.382281 -57.501947)
			(xy 182.370903 -57.562207) (xy 182.35002 -57.619868) (xy 182.32017 -57.673438) (xy 182.301642 -57.697878)
			(xy 182.299102 -57.70118) (xy 182.292244 -57.714134) (xy 182.289958 -57.724294) (xy 182.289704 -57.738518)
			(xy 182.289704 -57.755536) (xy 182.28945 -57.756044) (xy 182.28945 -57.757314) (xy 182.288942 -57.825894)
			(xy 182.289173 -57.833897) (xy 182.293954 -57.849168) (xy 182.29834 -57.855866) (xy 182.300118 -57.858152)
			(xy 182.317848 -57.881159) (xy 182.346861 -57.931475) (xy 182.367903 -57.985612) (xy 182.380485 -58.042315)
			(xy 182.382922 -58.071258) (xy 182.383684 -58.09234) (xy 182.383684 -58.095388) (xy 182.383349 -58.120772)
			(xy 182.376784 -58.171112) (xy 182.363609 -58.220138) (xy 182.35422 -58.243724) (xy 182.35422 -58.243978)
			(xy 182.35295 -58.246518) (xy 182.344304 -58.265978) (xy 182.323302 -58.303023) (xy 182.31104 -58.320432)
			(xy 182.304944 -58.328814) (xy 182.300372 -58.334656) (xy 182.296054 -58.341514) (xy 182.295038 -58.343546)
			(xy 182.292576 -58.348871) (xy 182.289882 -58.360288) (xy 182.289704 -58.366152) (xy 182.289704 -58.387488)
			(xy 182.289551 -58.392723) (xy 182.287381 -58.402966) (xy 182.285386 -58.407808) (xy 182.285132 -58.40857)
			(xy 182.282846 -58.414412) (xy 182.282338 -58.452766) (xy 182.282422 -58.457442) (xy 182.284085 -58.466644)
			(xy 182.28564 -58.471054) (xy 182.288434 -58.478674) (xy 182.294276 -58.485786) (xy 182.313296 -58.509285)
			(xy 182.344429 -58.561103) (xy 182.366989 -58.617188) (xy 182.380408 -58.676132) (xy 182.380675 -58.679334)
			(xy 190.095378 -58.679334) (xy 190.095808 -58.653019) (xy 190.103052 -58.600889) (xy 190.117379 -58.550246)
			(xy 190.138518 -58.502047) (xy 190.16607 -58.457205) (xy 190.199514 -58.416566) (xy 190.218568 -58.39841)
			(xy 190.225963 -58.390882) (xy 190.234492 -58.371607) (xy 190.235078 -58.361072) (xy 190.235078 -58.286396)
			(xy 190.234571 -58.275844) (xy 190.226021 -58.256548) (xy 190.218568 -58.249058) (xy 190.199493 -58.230922)
			(xy 190.166039 -58.190287) (xy 190.138483 -58.145443) (xy 190.117348 -58.097238) (xy 190.103035 -58.046588)
			(xy 190.095814 -57.994451) (xy 190.095378 -57.968134) (xy 190.095864 -57.940883) (xy 190.10362 -57.886935)
			(xy 190.118975 -57.83464) (xy 190.141617 -57.785063) (xy 190.171083 -57.739213) (xy 190.206774 -57.698022)
			(xy 190.247965 -57.662331) (xy 190.293815 -57.632865) (xy 190.343392 -57.610223) (xy 190.395687 -57.594868)
			(xy 190.449635 -57.587112) (xy 190.504137 -57.587112) (xy 190.558085 -57.594868) (xy 190.61038 -57.610223)
			(xy 190.659957 -57.632865) (xy 190.705807 -57.662331) (xy 190.746998 -57.698022) (xy 190.782689 -57.739213)
			(xy 190.812155 -57.785063) (xy 190.834797 -57.83464) (xy 190.850152 -57.886935) (xy 190.857908 -57.940883)
			(xy 190.858394 -57.968134) (xy 190.857951 -57.994449) (xy 190.850712 -58.046578) (xy 190.842367 -58.076084)
			(xy 199.45807 -58.076084) (xy 199.462141 -58.020462) (xy 199.474267 -57.966025) (xy 199.49419 -57.913934)
			(xy 199.521486 -57.865299) (xy 199.555572 -57.821156) (xy 199.595721 -57.782447) (xy 199.641079 -57.749996)
			(xy 199.690679 -57.724495) (xy 199.743463 -57.706488) (xy 199.798306 -57.696358) (xy 199.85404 -57.694321)
			(xy 199.909477 -57.700421) (xy 199.963434 -57.714527) (xy 200.014763 -57.736339) (xy 200.062369 -57.765393)
			(xy 200.105237 -57.801068) (xy 200.142454 -57.842605) (xy 200.15879 -57.867296) (xy 201.743054 -57.867296)
			(xy 201.747125 -57.811674) (xy 201.759251 -57.757237) (xy 201.779174 -57.705146) (xy 201.80647 -57.656511)
			(xy 201.840556 -57.612368) (xy 201.880705 -57.573659) (xy 201.926063 -57.541208) (xy 201.975663 -57.515707)
			(xy 202.028447 -57.4977) (xy 202.08329 -57.48757) (xy 202.139024 -57.485533) (xy 202.194461 -57.491633)
			(xy 202.248418 -57.505739) (xy 202.299747 -57.527551) (xy 202.347353 -57.556605) (xy 202.390221 -57.59228)
			(xy 202.427438 -57.633817) (xy 202.458211 -57.68033) (xy 202.481883 -57.730827) (xy 202.497951 -57.784234)
			(xy 202.506071 -57.83941) (xy 202.50658 -57.867296) (xy 202.506071 -57.895182) (xy 202.497951 -57.950358)
			(xy 202.481883 -58.003765) (xy 202.458211 -58.054262) (xy 202.427438 -58.100775) (xy 202.390221 -58.142312)
			(xy 202.347353 -58.177987) (xy 202.299747 -58.207041) (xy 202.248418 -58.228853) (xy 202.194461 -58.242959)
			(xy 202.139024 -58.249059) (xy 202.08329 -58.247022) (xy 202.028447 -58.236892) (xy 201.975663 -58.218885)
			(xy 201.926063 -58.193384) (xy 201.880705 -58.160933) (xy 201.840556 -58.122224) (xy 201.80647 -58.078081)
			(xy 201.779174 -58.029446) (xy 201.759251 -57.977355) (xy 201.747125 -57.922918) (xy 201.743054 -57.867296)
			(xy 200.15879 -57.867296) (xy 200.173227 -57.889118) (xy 200.196899 -57.939615) (xy 200.212967 -57.993022)
			(xy 200.221087 -58.048198) (xy 200.221596 -58.076084) (xy 200.221087 -58.10397) (xy 200.212967 -58.159146)
			(xy 200.196899 -58.212553) (xy 200.173227 -58.26305) (xy 200.142454 -58.309563) (xy 200.105237 -58.3511)
			(xy 200.062369 -58.386775) (xy 200.014763 -58.415829) (xy 199.963434 -58.437641) (xy 199.909477 -58.451747)
			(xy 199.85404 -58.457847) (xy 199.798306 -58.45581) (xy 199.743463 -58.44568) (xy 199.690679 -58.427673)
			(xy 199.641079 -58.402172) (xy 199.595721 -58.369721) (xy 199.555572 -58.331012) (xy 199.521486 -58.286869)
			(xy 199.49419 -58.238234) (xy 199.474267 -58.186143) (xy 199.462141 -58.131706) (xy 199.45807 -58.076084)
			(xy 190.842367 -58.076084) (xy 190.836388 -58.097222) (xy 190.815251 -58.145421) (xy 190.7877 -58.190264)
			(xy 190.754257 -58.230902) (xy 190.735204 -58.249058) (xy 190.72782 -58.256594) (xy 190.719285 -58.275863)
			(xy 190.718694 -58.286396) (xy 190.718694 -58.361072) (xy 190.719227 -58.371621) (xy 190.72776 -58.390916)
			(xy 190.735204 -58.39841) (xy 190.754258 -58.416567) (xy 190.787715 -58.457196) (xy 190.815274 -58.502036)
			(xy 190.836413 -58.550237) (xy 190.839519 -58.561224) (xy 200.662284 -58.561224) (xy 200.666355 -58.505602)
			(xy 200.678481 -58.451165) (xy 200.698404 -58.399074) (xy 200.7257 -58.350439) (xy 200.759786 -58.306296)
			(xy 200.799935 -58.267587) (xy 200.845293 -58.235136) (xy 200.894893 -58.209635) (xy 200.947677 -58.191628)
			(xy 201.00252 -58.181498) (xy 201.058254 -58.179461) (xy 201.113691 -58.185561) (xy 201.167648 -58.199667)
			(xy 201.218977 -58.221479) (xy 201.266583 -58.250533) (xy 201.309451 -58.286208) (xy 201.346668 -58.327745)
			(xy 201.377441 -58.374258) (xy 201.401113 -58.424755) (xy 201.417181 -58.478162) (xy 201.425301 -58.533338)
			(xy 201.42581 -58.561224) (xy 201.425301 -58.58911) (xy 201.417181 -58.644286) (xy 201.401113 -58.697693)
			(xy 201.377441 -58.74819) (xy 201.346668 -58.794703) (xy 201.309451 -58.83624) (xy 201.266583 -58.871915)
			(xy 201.218977 -58.900969) (xy 201.167648 -58.922781) (xy 201.113691 -58.936887) (xy 201.058254 -58.942987)
			(xy 201.00252 -58.94095) (xy 200.947677 -58.93082) (xy 200.894893 -58.912813) (xy 200.845293 -58.887312)
			(xy 200.799935 -58.854861) (xy 200.759786 -58.816152) (xy 200.7257 -58.772009) (xy 200.698404 -58.723374)
			(xy 200.678481 -58.671283) (xy 200.666355 -58.616846) (xy 200.662284 -58.561224) (xy 190.839519 -58.561224)
			(xy 190.850731 -58.600884) (xy 190.857955 -58.653018) (xy 190.858394 -58.679334) (xy 190.857908 -58.706585)
			(xy 190.850152 -58.760533) (xy 190.834797 -58.812828) (xy 190.812155 -58.862405) (xy 190.782689 -58.908255)
			(xy 190.746998 -58.949446) (xy 190.705807 -58.985137) (xy 190.659957 -59.014603) (xy 190.61038 -59.037245)
			(xy 190.558085 -59.0526) (xy 190.504137 -59.060356) (xy 190.449635 -59.060356) (xy 190.395687 -59.0526)
			(xy 190.343392 -59.037245) (xy 190.293815 -59.014603) (xy 190.247965 -58.985137) (xy 190.206774 -58.949446)
			(xy 190.171083 -58.908255) (xy 190.141617 -58.862405) (xy 190.118975 -58.812828) (xy 190.10362 -58.760533)
			(xy 190.095864 -58.706585) (xy 190.095378 -58.679334) (xy 182.380675 -58.679334) (xy 182.382922 -58.706258)
			(xy 182.384144 -58.730492) (xy 182.381169 -58.778925) (xy 182.372061 -58.826587) (xy 182.364888 -58.849768)
			(xy 182.356539 -58.87416) (xy 182.334197 -58.920623) (xy 182.305815 -58.963661) (xy 182.289196 -58.983372)
			(xy 182.283862 -58.989468) (xy 182.2831 -58.99023) (xy 182.280052 -58.998612) (xy 182.278549 -59.002839)
			(xy 182.276889 -59.011654) (xy 182.27675 -59.016138) (xy 182.275132 -59.174634) (xy 199.193148 -59.174634)
			(xy 199.197219 -59.119012) (xy 199.209345 -59.064575) (xy 199.229268 -59.012484) (xy 199.256564 -58.963849)
			(xy 199.29065 -58.919706) (xy 199.330799 -58.880997) (xy 199.376157 -58.848546) (xy 199.425757 -58.823045)
			(xy 199.478541 -58.805038) (xy 199.533384 -58.794908) (xy 199.589118 -58.792871) (xy 199.644555 -58.798971)
			(xy 199.698512 -58.813077) (xy 199.749841 -58.834889) (xy 199.797447 -58.863943) (xy 199.840315 -58.899618)
			(xy 199.877532 -58.941155) (xy 199.908305 -58.987668) (xy 199.931977 -59.038165) (xy 199.948045 -59.091572)
			(xy 199.956165 -59.146748) (xy 199.956674 -59.174634) (xy 199.956165 -59.20252) (xy 199.948045 -59.257696)
			(xy 199.931977 -59.311103) (xy 199.908305 -59.3616) (xy 199.877532 -59.408113) (xy 199.840315 -59.44965)
			(xy 199.797447 -59.485325) (xy 199.749841 -59.514379) (xy 199.698512 -59.536191) (xy 199.644555 -59.550297)
			(xy 199.589118 -59.556397) (xy 199.533384 -59.55436) (xy 199.478541 -59.54423) (xy 199.425757 -59.526223)
			(xy 199.376157 -59.500722) (xy 199.330799 -59.468271) (xy 199.29065 -59.429562) (xy 199.256564 -59.385419)
			(xy 199.229268 -59.336784) (xy 199.209345 -59.284693) (xy 199.197219 -59.230256) (xy 199.193148 -59.174634)
			(xy 182.275132 -59.174634) (xy 182.266511 -60.019254) (xy 190.235761 -60.019254) (xy 190.235761 -59.964746)
			(xy 190.243519 -59.910792) (xy 190.258877 -59.858492) (xy 190.281522 -59.80891) (xy 190.310993 -59.763056)
			(xy 190.346691 -59.721863) (xy 190.387888 -59.686169) (xy 190.433745 -59.656703) (xy 190.483329 -59.634063)
			(xy 190.535631 -59.618711) (xy 190.589586 -59.610959) (xy 190.61684 -59.610498) (xy 190.644209 -59.611)
			(xy 190.698386 -59.618809) (xy 190.750889 -59.63429) (xy 190.800637 -59.657124) (xy 190.846605 -59.68684)
			(xy 190.867538 -59.704478) (xy 190.867792 -59.704732) (xy 190.874874 -59.710325) (xy 190.891794 -59.716567)
			(xy 190.900812 -59.716924) (xy 190.967868 -59.716924) (xy 190.976883 -59.716546) (xy 190.9938 -59.710313)
			(xy 191.000888 -59.704732) (xy 191.000888 -59.704478) (xy 191.001142 -59.704478) (xy 191.022075 -59.686837)
			(xy 191.068043 -59.657113) (xy 191.117789 -59.634267) (xy 191.170291 -59.618771) (xy 191.224469 -59.610942)
			(xy 191.279211 -59.610942) (xy 191.333389 -59.618771) (xy 191.385891 -59.634267) (xy 191.435637 -59.657113)
			(xy 191.481605 -59.686837) (xy 191.502538 -59.704478) (xy 191.502792 -59.704732) (xy 191.509874 -59.710325)
			(xy 191.526794 -59.716567) (xy 191.535812 -59.716924) (xy 191.602868 -59.716924) (xy 191.611883 -59.716546)
			(xy 191.6288 -59.710313) (xy 191.635888 -59.704732) (xy 191.635888 -59.704478) (xy 191.636142 -59.704478)
			(xy 191.657082 -59.686849) (xy 191.703053 -59.657137) (xy 191.752799 -59.634299) (xy 191.805297 -59.618805)
			(xy 191.859471 -59.610974) (xy 191.88684 -59.610498) (xy 191.91409 -59.610975) (xy 191.968034 -59.618736)
			(xy 192.020325 -59.634095) (xy 192.069898 -59.656738) (xy 192.115744 -59.686206) (xy 192.15693 -59.721898)
			(xy 192.192618 -59.763088) (xy 192.222081 -59.808937) (xy 192.244719 -59.858513) (xy 192.260073 -59.910805)
			(xy 192.267828 -59.96475) (xy 192.267828 -60.01925) (xy 192.260073 -60.073195) (xy 192.244719 -60.125487)
			(xy 192.222081 -60.175063) (xy 192.192618 -60.220912) (xy 192.15693 -60.262102) (xy 192.115744 -60.297794)
			(xy 192.069898 -60.327262) (xy 192.020325 -60.349905) (xy 191.968034 -60.365264) (xy 191.91409 -60.373025)
			(xy 191.88684 -60.373514) (xy 191.859471 -60.373021) (xy 191.805293 -60.365209) (xy 191.75279 -60.349726)
			(xy 191.703043 -60.326891) (xy 191.657075 -60.297172) (xy 191.636142 -60.279534) (xy 191.635888 -60.27928)
			(xy 191.628811 -60.27368) (xy 191.611887 -60.267442) (xy 191.602868 -60.267088) (xy 191.535812 -60.267088)
			(xy 191.526796 -60.267453) (xy 191.509879 -60.273695) (xy 191.502792 -60.27928) (xy 191.502538 -60.279534)
			(xy 191.481605 -60.297175) (xy 191.435637 -60.326899) (xy 191.385891 -60.349745) (xy 191.333389 -60.365241)
			(xy 191.279211 -60.37307) (xy 191.224469 -60.37307) (xy 191.170291 -60.365241) (xy 191.117789 -60.349745)
			(xy 191.068043 -60.326899) (xy 191.022075 -60.297175) (xy 191.001142 -60.279534) (xy 191.000888 -60.27928)
			(xy 190.993811 -60.27368) (xy 190.976887 -60.267442) (xy 190.967868 -60.267088) (xy 190.900812 -60.267088)
			(xy 190.891796 -60.267453) (xy 190.874879 -60.273695) (xy 190.867792 -60.27928) (xy 190.867792 -60.279534)
			(xy 190.867538 -60.279534) (xy 190.846607 -60.297174) (xy 190.800633 -60.326885) (xy 190.750885 -60.34972)
			(xy 190.698385 -60.365211) (xy 190.644209 -60.373039) (xy 190.61684 -60.373514) (xy 190.589586 -60.373041)
			(xy 190.535631 -60.365289) (xy 190.483329 -60.349937) (xy 190.433745 -60.327297) (xy 190.387888 -60.297831)
			(xy 190.346691 -60.262137) (xy 190.310993 -60.220944) (xy 190.281522 -60.17509) (xy 190.258877 -60.125508)
			(xy 190.243519 -60.073208) (xy 190.235761 -60.019254) (xy 182.266511 -60.019254) (xy 182.260243 -60.633356)
			(xy 201.896978 -60.633356) (xy 201.901049 -60.577734) (xy 201.913175 -60.523297) (xy 201.933098 -60.471206)
			(xy 201.960394 -60.422571) (xy 201.99448 -60.378428) (xy 202.034629 -60.339719) (xy 202.079987 -60.307268)
			(xy 202.129587 -60.281767) (xy 202.182371 -60.26376) (xy 202.237214 -60.25363) (xy 202.292948 -60.251593)
			(xy 202.348385 -60.257693) (xy 202.402342 -60.271799) (xy 202.453671 -60.293611) (xy 202.501277 -60.322665)
			(xy 202.544145 -60.35834) (xy 202.581362 -60.399877) (xy 202.612135 -60.44639) (xy 202.635807 -60.496887)
			(xy 202.651875 -60.550294) (xy 202.659995 -60.60547) (xy 202.660504 -60.633356) (xy 202.659995 -60.661242)
			(xy 202.651875 -60.716418) (xy 202.635807 -60.769825) (xy 202.612135 -60.820322) (xy 202.581362 -60.866835)
			(xy 202.544145 -60.908372) (xy 202.501277 -60.944047) (xy 202.453671 -60.973101) (xy 202.402342 -60.994913)
			(xy 202.348385 -61.009019) (xy 202.292948 -61.015119) (xy 202.237214 -61.013082) (xy 202.182371 -61.002952)
			(xy 202.129587 -60.984945) (xy 202.079987 -60.959444) (xy 202.034629 -60.926993) (xy 201.99448 -60.888284)
			(xy 201.960394 -60.844141) (xy 201.933098 -60.795506) (xy 201.913175 -60.743415) (xy 201.901049 -60.688978)
			(xy 201.896978 -60.633356) (xy 182.260243 -60.633356) (xy 182.251521 -61.487812) (xy 200.404474 -61.487812)
			(xy 200.408545 -61.43219) (xy 200.420671 -61.377753) (xy 200.440594 -61.325662) (xy 200.46789 -61.277027)
			(xy 200.501976 -61.232884) (xy 200.542125 -61.194175) (xy 200.587483 -61.161724) (xy 200.637083 -61.136223)
			(xy 200.689867 -61.118216) (xy 200.74471 -61.108086) (xy 200.800444 -61.106049) (xy 200.855881 -61.112149)
			(xy 200.909838 -61.126255) (xy 200.961167 -61.148067) (xy 201.008773 -61.177121) (xy 201.051641 -61.212796)
			(xy 201.088858 -61.254333) (xy 201.119631 -61.300846) (xy 201.143303 -61.351343) (xy 201.159371 -61.40475)
			(xy 201.167491 -61.459926) (xy 201.168 -61.487812) (xy 201.167491 -61.515698) (xy 201.159371 -61.570874)
			(xy 201.143303 -61.624281) (xy 201.119631 -61.674778) (xy 201.088858 -61.721291) (xy 201.051641 -61.762828)
			(xy 201.008773 -61.798503) (xy 200.961167 -61.827557) (xy 200.909838 -61.849369) (xy 200.855881 -61.863475)
			(xy 200.800444 -61.869575) (xy 200.74471 -61.867538) (xy 200.689867 -61.857408) (xy 200.637083 -61.839401)
			(xy 200.587483 -61.8139) (xy 200.542125 -61.781449) (xy 200.501976 -61.74274) (xy 200.46789 -61.698597)
			(xy 200.440594 -61.649962) (xy 200.420671 -61.597871) (xy 200.408545 -61.543434) (xy 200.404474 -61.487812)
			(xy 182.251521 -61.487812) (xy 182.245058 -62.121034) (xy 198.342248 -62.121034) (xy 198.346319 -62.065412)
			(xy 198.358445 -62.010975) (xy 198.378368 -61.958884) (xy 198.405664 -61.910249) (xy 198.43975 -61.866106)
			(xy 198.479899 -61.827397) (xy 198.525257 -61.794946) (xy 198.574857 -61.769445) (xy 198.627641 -61.751438)
			(xy 198.682484 -61.741308) (xy 198.738218 -61.739271) (xy 198.793655 -61.745371) (xy 198.847612 -61.759477)
			(xy 198.898941 -61.781289) (xy 198.946547 -61.810343) (xy 198.989415 -61.846018) (xy 199.026632 -61.887555)
			(xy 199.057405 -61.934068) (xy 199.081077 -61.984565) (xy 199.097145 -62.037972) (xy 199.105265 -62.093148)
			(xy 199.105774 -62.121034) (xy 199.105265 -62.14892) (xy 199.097145 -62.204096) (xy 199.081077 -62.257503)
			(xy 199.057405 -62.308) (xy 199.026632 -62.354513) (xy 198.989415 -62.39605) (xy 198.946547 -62.431725)
			(xy 198.898941 -62.460779) (xy 198.847612 -62.482591) (xy 198.793655 -62.496697) (xy 198.738218 -62.502797)
			(xy 198.682484 -62.50076) (xy 198.627641 -62.49063) (xy 198.574857 -62.472623) (xy 198.525257 -62.447122)
			(xy 198.479899 -62.414671) (xy 198.43975 -62.375962) (xy 198.405664 -62.331819) (xy 198.378368 -62.283184)
			(xy 198.358445 -62.231093) (xy 198.346319 -62.176656) (xy 198.342248 -62.121034) (xy 182.245058 -62.121034)
			(xy 182.233907 -63.213548) (xy 190.220888 -63.213548) (xy 190.220888 -63.159052) (xy 190.228643 -63.105109)
			(xy 190.243996 -63.05282) (xy 190.266633 -63.003247) (xy 190.296094 -62.9574) (xy 190.33178 -62.916212)
			(xy 190.372963 -62.880522) (xy 190.418807 -62.851055) (xy 190.468377 -62.828412) (xy 190.520664 -62.813053)
			(xy 190.574606 -62.805291) (xy 190.601854 -62.804802) (xy 190.629223 -62.805295) (xy 190.683401 -62.813106)
			(xy 190.735904 -62.828589) (xy 190.785651 -62.851425) (xy 190.831619 -62.881143) (xy 190.852552 -62.898782)
			(xy 190.852806 -62.899036) (xy 190.859884 -62.904635) (xy 190.876807 -62.910873) (xy 190.885826 -62.911228)
			(xy 190.952882 -62.911228) (xy 190.961897 -62.910856) (xy 190.978814 -62.904618) (xy 190.985902 -62.899036)
			(xy 190.985902 -62.898782) (xy 190.986156 -62.898782) (xy 191.007089 -62.881141) (xy 191.053057 -62.851417)
			(xy 191.102803 -62.828571) (xy 191.155305 -62.813075) (xy 191.209483 -62.805246) (xy 191.264225 -62.805246)
			(xy 191.318403 -62.813075) (xy 191.370905 -62.828571) (xy 191.420651 -62.851417) (xy 191.466619 -62.881141)
			(xy 191.487552 -62.898782) (xy 191.487806 -62.899036) (xy 191.494884 -62.904635) (xy 191.511807 -62.910873)
			(xy 191.520826 -62.911228) (xy 191.587882 -62.911228) (xy 191.596897 -62.910856) (xy 191.613814 -62.904618)
			(xy 191.620902 -62.899036) (xy 191.620902 -62.898782) (xy 191.621156 -62.898782) (xy 191.642092 -62.881147)
			(xy 191.688064 -62.851435) (xy 191.73781 -62.828599) (xy 191.79031 -62.813107) (xy 191.844485 -62.805277)
			(xy 191.871854 -62.804802) (xy 191.89911 -62.805242) (xy 191.953067 -62.812994) (xy 192.005372 -62.828346)
			(xy 192.054959 -62.850987) (xy 192.100819 -62.880454) (xy 192.142019 -62.916149) (xy 192.177718 -62.957344)
			(xy 192.207191 -63.0032) (xy 192.229838 -63.052785) (xy 192.23966 -63.086234) (xy 195.487542 -63.086234)
			(xy 195.491613 -63.030612) (xy 195.503739 -62.976175) (xy 195.523662 -62.924084) (xy 195.550958 -62.875449)
			(xy 195.585044 -62.831306) (xy 195.625193 -62.792597) (xy 195.670551 -62.760146) (xy 195.720151 -62.734645)
			(xy 195.772935 -62.716638) (xy 195.827778 -62.706508) (xy 195.883512 -62.704471) (xy 195.938949 -62.710571)
			(xy 195.992906 -62.724677) (xy 196.044235 -62.746489) (xy 196.091841 -62.775543) (xy 196.134709 -62.811218)
			(xy 196.171926 -62.852755) (xy 196.202699 -62.899268) (xy 196.226371 -62.949765) (xy 196.242439 -63.003172)
			(xy 196.250559 -63.058348) (xy 196.251068 -63.086234) (xy 196.250559 -63.11412) (xy 196.242439 -63.169296)
			(xy 196.226371 -63.222703) (xy 196.202699 -63.2732) (xy 196.202546 -63.273432) (xy 197.676768 -63.273432)
			(xy 197.680839 -63.21781) (xy 197.692965 -63.163373) (xy 197.712888 -63.111282) (xy 197.740184 -63.062647)
			(xy 197.77427 -63.018504) (xy 197.814419 -62.979795) (xy 197.859777 -62.947344) (xy 197.909377 -62.921843)
			(xy 197.962161 -62.903836) (xy 198.017004 -62.893706) (xy 198.072738 -62.891669) (xy 198.128175 -62.897769)
			(xy 198.182132 -62.911875) (xy 198.233461 -62.933687) (xy 198.281067 -62.962741) (xy 198.323935 -62.998416)
			(xy 198.361152 -63.039953) (xy 198.391925 -63.086466) (xy 198.415597 -63.136963) (xy 198.431665 -63.19037)
			(xy 198.439785 -63.245546) (xy 198.440294 -63.273432) (xy 198.439785 -63.301318) (xy 198.431665 -63.356494)
			(xy 198.415597 -63.409901) (xy 198.391925 -63.460398) (xy 198.361152 -63.506911) (xy 198.323935 -63.548448)
			(xy 198.281067 -63.584123) (xy 198.233461 -63.613177) (xy 198.182132 -63.634989) (xy 198.128175 -63.649095)
			(xy 198.072738 -63.655195) (xy 198.017004 -63.653158) (xy 197.962161 -63.643028) (xy 197.909377 -63.625021)
			(xy 197.859777 -63.59952) (xy 197.814419 -63.567069) (xy 197.77427 -63.52836) (xy 197.740184 -63.484217)
			(xy 197.712888 -63.435582) (xy 197.692965 -63.383491) (xy 197.680839 -63.329054) (xy 197.676768 -63.273432)
			(xy 196.202546 -63.273432) (xy 196.171926 -63.319713) (xy 196.134709 -63.36125) (xy 196.091841 -63.396925)
			(xy 196.044235 -63.425979) (xy 195.992906 -63.447791) (xy 195.938949 -63.461897) (xy 195.883512 -63.467997)
			(xy 195.827778 -63.46596) (xy 195.772935 -63.45583) (xy 195.720151 -63.437823) (xy 195.670551 -63.412322)
			(xy 195.625193 -63.379871) (xy 195.585044 -63.341162) (xy 195.550958 -63.297019) (xy 195.523662 -63.248384)
			(xy 195.503739 -63.196293) (xy 195.491613 -63.141856) (xy 195.487542 -63.086234) (xy 192.23966 -63.086234)
			(xy 192.245197 -63.105088) (xy 192.252955 -63.159044) (xy 192.252955 -63.213556) (xy 192.245197 -63.267512)
			(xy 192.229838 -63.319815) (xy 192.207191 -63.3694) (xy 192.177718 -63.415256) (xy 192.142019 -63.456451)
			(xy 192.100819 -63.492146) (xy 192.054959 -63.521613) (xy 192.005372 -63.544254) (xy 191.953067 -63.559606)
			(xy 191.89911 -63.567358) (xy 191.871854 -63.567818) (xy 191.844484 -63.56734) (xy 191.790305 -63.559528)
			(xy 191.737801 -63.544043) (xy 191.688054 -63.521203) (xy 191.642087 -63.491479) (xy 191.621156 -63.473838)
			(xy 191.620902 -63.473584) (xy 191.61382 -63.46799) (xy 191.5969 -63.461748) (xy 191.587882 -63.461392)
			(xy 191.520826 -63.461392) (xy 191.511811 -63.461763) (xy 191.494894 -63.468001) (xy 191.487806 -63.473584)
			(xy 191.487552 -63.473838) (xy 191.466619 -63.491479) (xy 191.420651 -63.521203) (xy 191.370905 -63.544049)
			(xy 191.318403 -63.559545) (xy 191.264225 -63.567374) (xy 191.209483 -63.567374) (xy 191.155305 -63.559545)
			(xy 191.102803 -63.544049) (xy 191.053057 -63.521203) (xy 191.007089 -63.491479) (xy 190.986156 -63.473838)
			(xy 190.985902 -63.473584) (xy 190.97882 -63.46799) (xy 190.9619 -63.461748) (xy 190.952882 -63.461392)
			(xy 190.885826 -63.461392) (xy 190.876811 -63.461763) (xy 190.859894 -63.468001) (xy 190.852806 -63.473584)
			(xy 190.852806 -63.473838) (xy 190.852552 -63.473838) (xy 190.831616 -63.491472) (xy 190.785644 -63.521184)
			(xy 190.735897 -63.54402) (xy 190.683398 -63.559513) (xy 190.629223 -63.567343) (xy 190.601854 -63.567818)
			(xy 190.574606 -63.567309) (xy 190.520664 -63.559547) (xy 190.468377 -63.544188) (xy 190.418807 -63.521545)
			(xy 190.372963 -63.492078) (xy 190.33178 -63.456388) (xy 190.296094 -63.4152) (xy 190.266633 -63.369353)
			(xy 190.243996 -63.31978) (xy 190.228643 -63.267491) (xy 190.220888 -63.213548) (xy 182.233907 -63.213548)
			(xy 182.221632 -64.416178) (xy 182.220108 -64.558418) (xy 182.220108 -65.100962) (xy 188.23254 -65.100962)
			(xy 188.236611 -65.04534) (xy 188.248737 -64.990903) (xy 188.26866 -64.938812) (xy 188.295956 -64.890177)
			(xy 188.330042 -64.846034) (xy 188.370191 -64.807325) (xy 188.415549 -64.774874) (xy 188.465149 -64.749373)
			(xy 188.517933 -64.731366) (xy 188.572776 -64.721236) (xy 188.62851 -64.719199) (xy 188.683947 -64.725299)
			(xy 188.737904 -64.739405) (xy 188.789233 -64.761217) (xy 188.836839 -64.790271) (xy 188.879707 -64.825946)
			(xy 188.916924 -64.867483) (xy 188.947697 -64.913996) (xy 188.971369 -64.964493) (xy 188.987437 -65.0179)
			(xy 188.995557 -65.073076) (xy 188.996066 -65.100962) (xy 188.995644 -65.124076) (xy 200.20737 -65.124076)
			(xy 200.211441 -65.068454) (xy 200.223567 -65.014017) (xy 200.24349 -64.961926) (xy 200.270786 -64.913291)
			(xy 200.304872 -64.869148) (xy 200.345021 -64.830439) (xy 200.390379 -64.797988) (xy 200.439979 -64.772487)
			(xy 200.492763 -64.75448) (xy 200.547606 -64.74435) (xy 200.60334 -64.742313) (xy 200.658777 -64.748413)
			(xy 200.712734 -64.762519) (xy 200.764063 -64.784331) (xy 200.811669 -64.813385) (xy 200.854537 -64.84906)
			(xy 200.891754 -64.890597) (xy 200.922527 -64.93711) (xy 200.946199 -64.987607) (xy 200.962267 -65.041014)
			(xy 200.970387 -65.09619) (xy 200.970896 -65.124076) (xy 200.970387 -65.151962) (xy 200.962267 -65.207138)
			(xy 200.946199 -65.260545) (xy 200.922527 -65.311042) (xy 200.891754 -65.357555) (xy 200.854537 -65.399092)
			(xy 200.811669 -65.434767) (xy 200.764063 -65.463821) (xy 200.712734 -65.485633) (xy 200.658777 -65.499739)
			(xy 200.60334 -65.505839) (xy 200.547606 -65.503802) (xy 200.492763 -65.493672) (xy 200.439979 -65.475665)
			(xy 200.390379 -65.450164) (xy 200.345021 -65.417713) (xy 200.304872 -65.379004) (xy 200.270786 -65.334861)
			(xy 200.24349 -65.286226) (xy 200.223567 -65.234135) (xy 200.211441 -65.179698) (xy 200.20737 -65.124076)
			(xy 188.995644 -65.124076) (xy 188.995557 -65.128848) (xy 188.987437 -65.184024) (xy 188.971369 -65.237431)
			(xy 188.947697 -65.287928) (xy 188.916924 -65.334441) (xy 188.879707 -65.375978) (xy 188.836839 -65.411653)
			(xy 188.789233 -65.440707) (xy 188.737904 -65.462519) (xy 188.683947 -65.476625) (xy 188.62851 -65.482725)
			(xy 188.572776 -65.480688) (xy 188.517933 -65.470558) (xy 188.465149 -65.452551) (xy 188.415549 -65.42705)
			(xy 188.370191 -65.394599) (xy 188.330042 -65.35589) (xy 188.295956 -65.311747) (xy 188.26866 -65.263112)
			(xy 188.248737 -65.211021) (xy 188.236611 -65.156584) (xy 188.23254 -65.100962) (xy 182.220108 -65.100962)
			(xy 182.220108 -65.75552) (xy 182.446674 -65.75552) (xy 182.450745 -65.699898) (xy 182.462871 -65.645461)
			(xy 182.482794 -65.59337) (xy 182.51009 -65.544735) (xy 182.544176 -65.500592) (xy 182.584325 -65.461883)
			(xy 182.629683 -65.429432) (xy 182.679283 -65.403931) (xy 182.732067 -65.385924) (xy 182.78691 -65.375794)
			(xy 182.842644 -65.373757) (xy 182.898081 -65.379857) (xy 182.952038 -65.393963) (xy 183.003367 -65.415775)
			(xy 183.050973 -65.444829) (xy 183.093841 -65.480504) (xy 183.131058 -65.522041) (xy 183.161831 -65.568554)
			(xy 183.185503 -65.619051) (xy 183.201571 -65.672458) (xy 183.209691 -65.727634) (xy 183.2102 -65.75552)
			(xy 183.209691 -65.783406) (xy 183.201571 -65.838582) (xy 183.185503 -65.891989) (xy 183.161831 -65.942486)
			(xy 183.131058 -65.988999) (xy 183.093841 -66.030536) (xy 183.050973 -66.066211) (xy 183.003367 -66.095265)
			(xy 182.952038 -66.117077) (xy 182.898081 -66.131183) (xy 182.842644 -66.137283) (xy 182.78691 -66.135246)
			(xy 182.732067 -66.125116) (xy 182.679283 -66.107109) (xy 182.629683 -66.081608) (xy 182.584325 -66.049157)
			(xy 182.544176 -66.010448) (xy 182.51009 -65.966305) (xy 182.482794 -65.91767) (xy 182.462871 -65.865579)
			(xy 182.450745 -65.811142) (xy 182.446674 -65.75552) (xy 182.220108 -65.75552) (xy 182.220108 -67.128953)
			(xy 182.466675 -67.128953) (xy 182.466675 -67.074447) (xy 182.474433 -67.020495) (xy 182.48979 -66.968196)
			(xy 182.512435 -66.918616) (xy 182.541905 -66.872763) (xy 182.577601 -66.831572) (xy 182.618797 -66.79588)
			(xy 182.664653 -66.766415) (xy 182.714236 -66.743776) (xy 182.766536 -66.728424) (xy 182.820489 -66.720672)
			(xy 182.847742 -66.720212) (xy 182.875111 -66.720709) (xy 182.929289 -66.728519) (xy 182.981792 -66.744001)
			(xy 183.031539 -66.766836) (xy 183.077507 -66.796554) (xy 183.09844 -66.814192) (xy 183.098694 -66.814446)
			(xy 183.105774 -66.820042) (xy 183.122696 -66.826282) (xy 183.131714 -66.826638) (xy 183.19877 -66.826638)
			(xy 183.207784 -66.826258) (xy 183.224701 -66.820026) (xy 183.23179 -66.814446) (xy 183.23179 -66.814192)
			(xy 183.232044 -66.814192) (xy 183.252985 -66.796564) (xy 183.298956 -66.766851) (xy 183.348701 -66.744013)
			(xy 183.401199 -66.728519) (xy 183.455373 -66.720688) (xy 183.482742 -66.720212) (xy 183.509993 -66.720661)
			(xy 183.563939 -66.728422) (xy 183.616231 -66.743782) (xy 183.665806 -66.766427) (xy 183.711653 -66.795896)
			(xy 183.752841 -66.831589) (xy 183.788529 -66.87278) (xy 183.817993 -66.918631) (xy 183.840633 -66.968208)
			(xy 183.855986 -67.020502) (xy 183.863742 -67.074449) (xy 183.863742 -67.128951) (xy 183.855986 -67.182898)
			(xy 183.840633 -67.235192) (xy 183.817993 -67.284769) (xy 183.788529 -67.33062) (xy 183.752841 -67.371811)
			(xy 183.711653 -67.407504) (xy 183.665806 -67.436973) (xy 183.616231 -67.459618) (xy 183.563939 -67.474978)
			(xy 183.509993 -67.482739) (xy 183.482742 -67.483228) (xy 183.455372 -67.482755) (xy 183.401192 -67.474941)
			(xy 183.348689 -67.459455) (xy 183.298942 -67.436614) (xy 183.252975 -67.40689) (xy 183.232044 -67.389248)
			(xy 183.23179 -67.388994) (xy 183.224711 -67.383396) (xy 183.207788 -67.377157) (xy 183.19877 -67.376802)
			(xy 183.131714 -67.376802) (xy 183.122698 -67.377165) (xy 183.105781 -67.383408) (xy 183.098694 -67.388994)
			(xy 183.098694 -67.389248) (xy 183.09844 -67.389248) (xy 183.077497 -67.406874) (xy 183.031528 -67.436589)
			(xy 182.981783 -67.459429) (xy 182.929285 -67.474923) (xy 182.875111 -67.482753) (xy 182.847742 -67.483228)
			(xy 182.820489 -67.482728) (xy 182.766536 -67.474976) (xy 182.714236 -67.459624) (xy 182.664653 -67.436985)
			(xy 182.618797 -67.40752) (xy 182.577601 -67.371828) (xy 182.541905 -67.330637) (xy 182.512435 -67.284784)
			(xy 182.48979 -67.235204) (xy 182.474433 -67.182905) (xy 182.466675 -67.128953) (xy 182.220108 -67.128953)
			(xy 182.220108 -67.488054) (xy 186.879228 -67.488054) (xy 186.883299 -67.432432) (xy 186.895425 -67.377995)
			(xy 186.915348 -67.325904) (xy 186.942644 -67.277269) (xy 186.97673 -67.233126) (xy 187.016879 -67.194417)
			(xy 187.062237 -67.161966) (xy 187.111837 -67.136465) (xy 187.164621 -67.118458) (xy 187.219464 -67.108328)
			(xy 187.275198 -67.106291) (xy 187.330635 -67.112391) (xy 187.384592 -67.126497) (xy 187.435921 -67.148309)
			(xy 187.483527 -67.177363) (xy 187.526395 -67.213038) (xy 187.563612 -67.254575) (xy 187.594385 -67.301088)
			(xy 187.618057 -67.351585) (xy 187.634125 -67.404992) (xy 187.642245 -67.460168) (xy 187.642754 -67.488054)
			(xy 187.642245 -67.51594) (xy 187.63906 -67.537584) (xy 188.171326 -67.537584) (xy 188.175397 -67.481962)
			(xy 188.187523 -67.427525) (xy 188.207446 -67.375434) (xy 188.234742 -67.326799) (xy 188.268828 -67.282656)
			(xy 188.308977 -67.243947) (xy 188.354335 -67.211496) (xy 188.403935 -67.185995) (xy 188.456719 -67.167988)
			(xy 188.511562 -67.157858) (xy 188.567296 -67.155821) (xy 188.622733 -67.161921) (xy 188.67669 -67.176027)
			(xy 188.728019 -67.197839) (xy 188.775625 -67.226893) (xy 188.818493 -67.262568) (xy 188.85571 -67.304105)
			(xy 188.886483 -67.350618) (xy 188.910155 -67.401115) (xy 188.926223 -67.454522) (xy 188.934343 -67.509698)
			(xy 188.934852 -67.537584) (xy 188.934343 -67.56547) (xy 188.930298 -67.592956) (xy 189.44539 -67.592956)
			(xy 189.449461 -67.537334) (xy 189.461587 -67.482897) (xy 189.48151 -67.430806) (xy 189.508806 -67.382171)
			(xy 189.542892 -67.338028) (xy 189.583041 -67.299319) (xy 189.628399 -67.266868) (xy 189.677999 -67.241367)
			(xy 189.730783 -67.22336) (xy 189.785626 -67.21323) (xy 189.84136 -67.211193) (xy 189.896797 -67.217293)
			(xy 189.950754 -67.231399) (xy 190.002083 -67.253211) (xy 190.049689 -67.282265) (xy 190.092557 -67.31794)
			(xy 190.129774 -67.359477) (xy 190.160547 -67.40599) (xy 190.184219 -67.456487) (xy 190.200287 -67.509894)
			(xy 190.208404 -67.565052) (xy 192.546693 -67.565052) (xy 192.546693 -67.510548) (xy 192.55445 -67.4566)
			(xy 192.569806 -67.404305) (xy 192.592449 -67.354728) (xy 192.621917 -67.308877) (xy 192.657611 -67.267688)
			(xy 192.698803 -67.231998) (xy 192.744656 -67.202534) (xy 192.794235 -67.179895) (xy 192.846531 -67.164544)
			(xy 192.90048 -67.156791) (xy 192.927732 -67.15633) (xy 192.955103 -67.15677) (xy 193.009284 -67.164593)
			(xy 193.061787 -67.180088) (xy 193.111534 -67.202935) (xy 193.157499 -67.232666) (xy 193.17843 -67.25031)
			(xy 193.178684 -67.250564) (xy 193.185765 -67.256158) (xy 193.202686 -67.262398) (xy 193.211704 -67.262756)
			(xy 193.27876 -67.262756) (xy 193.287776 -67.262389) (xy 193.304694 -67.25615) (xy 193.31178 -67.250564)
			(xy 193.31178 -67.25031) (xy 193.312034 -67.25031) (xy 193.332981 -67.23269) (xy 193.37895 -67.202975)
			(xy 193.428693 -67.180135) (xy 193.481191 -67.16464) (xy 193.535364 -67.156807) (xy 193.562732 -67.15633)
			(xy 193.589984 -67.156742) (xy 193.643934 -67.164503) (xy 193.69623 -67.179862) (xy 193.745808 -67.202508)
			(xy 193.791659 -67.231978) (xy 193.83285 -67.267673) (xy 193.868541 -67.308866) (xy 193.898008 -67.35472)
			(xy 193.920649 -67.4043) (xy 193.936004 -67.456597) (xy 193.94376 -67.510547) (xy 193.94376 -67.565053)
			(xy 193.936004 -67.619003) (xy 193.920649 -67.6713) (xy 193.898008 -67.72088) (xy 193.868541 -67.766734)
			(xy 193.83285 -67.807927) (xy 193.791659 -67.843622) (xy 193.745808 -67.873092) (xy 193.69623 -67.895738)
			(xy 193.643934 -67.911097) (xy 193.589984 -67.918858) (xy 193.562732 -67.919346) (xy 193.535362 -67.918874)
			(xy 193.481182 -67.91106) (xy 193.428679 -67.895573) (xy 193.378932 -67.872732) (xy 193.332965 -67.843007)
			(xy 193.312034 -67.825366) (xy 193.31178 -67.825112) (xy 193.304702 -67.819512) (xy 193.287779 -67.813273)
			(xy 193.27876 -67.81292) (xy 193.211704 -67.81292) (xy 193.202687 -67.813274) (xy 193.18577 -67.819523)
			(xy 193.178684 -67.825112) (xy 193.178684 -67.825366) (xy 193.17843 -67.825366) (xy 193.157493 -67.842999)
			(xy 193.111522 -67.872713) (xy 193.061776 -67.895551) (xy 193.009276 -67.911043) (xy 192.955101 -67.918872)
			(xy 192.927732 -67.919346) (xy 192.90048 -67.918809) (xy 192.846531 -67.911056) (xy 192.794235 -67.895705)
			(xy 192.744656 -67.873066) (xy 192.698803 -67.843602) (xy 192.657611 -67.807912) (xy 192.621917 -67.766723)
			(xy 192.592449 -67.720872) (xy 192.569806 -67.671295) (xy 192.55445 -67.619) (xy 192.546693 -67.565052)
			(xy 190.208404 -67.565052) (xy 190.208407 -67.56507) (xy 190.208916 -67.592956) (xy 190.208407 -67.620842)
			(xy 190.200287 -67.676018) (xy 190.184219 -67.729425) (xy 190.160547 -67.779922) (xy 190.129774 -67.826435)
			(xy 190.092557 -67.867972) (xy 190.049689 -67.903647) (xy 190.002083 -67.932701) (xy 189.950754 -67.954513)
			(xy 189.896797 -67.968619) (xy 189.84136 -67.974719) (xy 189.785626 -67.972682) (xy 189.730783 -67.962552)
			(xy 189.677999 -67.944545) (xy 189.628399 -67.919044) (xy 189.583041 -67.886593) (xy 189.542892 -67.847884)
			(xy 189.508806 -67.803741) (xy 189.48151 -67.755106) (xy 189.461587 -67.703015) (xy 189.449461 -67.648578)
			(xy 189.44539 -67.592956) (xy 188.930298 -67.592956) (xy 188.926223 -67.620646) (xy 188.910155 -67.674053)
			(xy 188.886483 -67.72455) (xy 188.85571 -67.771063) (xy 188.818493 -67.8126) (xy 188.775625 -67.848275)
			(xy 188.728019 -67.877329) (xy 188.67669 -67.899141) (xy 188.622733 -67.913247) (xy 188.567296 -67.919347)
			(xy 188.511562 -67.91731) (xy 188.456719 -67.90718) (xy 188.403935 -67.889173) (xy 188.354335 -67.863672)
			(xy 188.308977 -67.831221) (xy 188.268828 -67.792512) (xy 188.234742 -67.748369) (xy 188.207446 -67.699734)
			(xy 188.187523 -67.647643) (xy 188.175397 -67.593206) (xy 188.171326 -67.537584) (xy 187.63906 -67.537584)
			(xy 187.634125 -67.571116) (xy 187.618057 -67.624523) (xy 187.594385 -67.67502) (xy 187.563612 -67.721533)
			(xy 187.526395 -67.76307) (xy 187.483527 -67.798745) (xy 187.435921 -67.827799) (xy 187.384592 -67.849611)
			(xy 187.330635 -67.863717) (xy 187.275198 -67.869817) (xy 187.219464 -67.86778) (xy 187.164621 -67.85765)
			(xy 187.111837 -67.839643) (xy 187.062237 -67.814142) (xy 187.016879 -67.781691) (xy 186.97673 -67.742982)
			(xy 186.942644 -67.698839) (xy 186.915348 -67.650204) (xy 186.895425 -67.598113) (xy 186.883299 -67.543676)
			(xy 186.879228 -67.488054) (xy 182.220108 -67.488054) (xy 182.220108 -68.36791) (xy 182.218584 -68.419218)
			(xy 182.209873 -68.586604) (xy 184.72531 -68.586604) (xy 184.725776 -68.559234) (xy 184.733593 -68.505055)
			(xy 184.749082 -68.452551) (xy 184.771924 -68.402804) (xy 184.801649 -68.356838) (xy 184.81929 -68.335906)
			(xy 184.819544 -68.335652) (xy 184.82512 -68.328559) (xy 184.831372 -68.311647) (xy 184.831736 -68.302632)
			(xy 184.831736 -68.235576) (xy 184.831383 -68.226559) (xy 184.825132 -68.209642) (xy 184.819544 -68.202556)
			(xy 184.81929 -68.202556) (xy 184.81929 -68.202302) (xy 184.801637 -68.181381) (xy 184.771927 -68.135405)
			(xy 184.749094 -68.085655) (xy 184.733607 -68.033152) (xy 184.725782 -67.978974) (xy 184.72531 -67.951604)
			(xy 184.725759 -67.92435) (xy 184.733516 -67.870398) (xy 184.748872 -67.818099) (xy 184.771516 -67.768518)
			(xy 184.800985 -67.722664) (xy 184.83668 -67.68147) (xy 184.877875 -67.645777) (xy 184.92373 -67.616309)
			(xy 184.973312 -67.593668) (xy 185.025612 -67.578313) (xy 185.079564 -67.570558) (xy 185.106818 -67.570096)
			(xy 185.133132 -67.570553) (xy 185.185261 -67.57779) (xy 185.235904 -67.592111) (xy 185.284103 -67.613246)
			(xy 185.328946 -67.640794) (xy 185.369586 -67.674234) (xy 185.387742 -67.693286) (xy 185.395248 -67.700706)
			(xy 185.41454 -67.70922) (xy 185.42508 -67.709796) (xy 185.499756 -67.709796) (xy 185.510305 -67.709258)
			(xy 185.5296 -67.700729) (xy 185.537094 -67.693286) (xy 185.555257 -67.674238) (xy 185.595885 -67.64078)
			(xy 185.640724 -67.613221) (xy 185.688923 -67.592081) (xy 185.739569 -67.577762) (xy 185.791702 -67.570536)
			(xy 185.818018 -67.570096) (xy 185.845389 -67.570552) (xy 185.899568 -67.578373) (xy 185.952071 -67.593864)
			(xy 186.001818 -67.616708) (xy 186.047784 -67.646434) (xy 186.068716 -67.664076) (xy 186.06897 -67.66433)
			(xy 186.076059 -67.669913) (xy 186.092974 -67.676161) (xy 186.10199 -67.676522) (xy 186.169046 -67.676522)
			(xy 186.17806 -67.676135) (xy 186.194977 -67.669908) (xy 186.202066 -67.66433) (xy 186.202066 -67.664076)
			(xy 186.20232 -67.664076) (xy 186.223268 -67.646457) (xy 186.269237 -67.616743) (xy 186.31898 -67.593904)
			(xy 186.371477 -67.578408) (xy 186.42565 -67.570573) (xy 186.453018 -67.570096) (xy 186.48027 -67.570561)
			(xy 186.534219 -67.57832) (xy 186.586514 -67.593678) (xy 186.636091 -67.616321) (xy 186.681942 -67.64579)
			(xy 186.723132 -67.681483) (xy 186.758823 -67.722676) (xy 186.788289 -67.768528) (xy 186.81093 -67.818107)
			(xy 186.826285 -67.870403) (xy 186.834041 -67.924352) (xy 186.834526 -67.951604) (xy 186.83408 -67.978975)
			(xy 186.82626 -68.033156) (xy 186.810767 -68.08566) (xy 186.787921 -68.135406) (xy 186.75819 -68.181372)
			(xy 186.740546 -68.202302) (xy 186.740292 -68.202556) (xy 186.734717 -68.20965) (xy 186.728464 -68.226561)
			(xy 186.7281 -68.235576) (xy 186.7281 -68.302632) (xy 186.728442 -68.31165) (xy 186.7347 -68.328567)
			(xy 186.740292 -68.335652) (xy 186.740546 -68.335652) (xy 186.740546 -68.335906) (xy 186.758193 -68.356832)
			(xy 186.787905 -68.402806) (xy 186.810741 -68.452555) (xy 186.82623 -68.505057) (xy 186.834054 -68.559234)
			(xy 186.834526 -68.586604) (xy 186.834026 -68.613855) (xy 186.826269 -68.667801) (xy 186.810915 -68.720094)
			(xy 186.794275 -68.75653) (xy 190.270384 -68.75653) (xy 190.270847 -68.729159) (xy 190.278663 -68.674979)
			(xy 190.294151 -68.622475) (xy 190.316994 -68.572729) (xy 190.346721 -68.526763) (xy 190.364364 -68.505832)
			(xy 190.364618 -68.505578) (xy 190.370222 -68.498503) (xy 190.376458 -68.481577) (xy 190.37681 -68.472558)
			(xy 190.37681 -68.405502) (xy 190.37645 -68.396486) (xy 190.370204 -68.379569) (xy 190.364618 -68.372482)
			(xy 190.364364 -68.372482) (xy 190.364364 -68.372228) (xy 190.346719 -68.351301) (xy 190.317009 -68.305326)
			(xy 190.294175 -68.255577) (xy 190.278685 -68.203076) (xy 190.270858 -68.148899) (xy 190.270384 -68.12153)
			(xy 190.270883 -68.094278) (xy 190.278636 -68.040329) (xy 190.293988 -67.988032) (xy 190.316626 -67.938453)
			(xy 190.34609 -67.8926) (xy 190.38178 -67.851407) (xy 190.422969 -67.815713) (xy 190.468819 -67.786244)
			(xy 190.518397 -67.763601) (xy 190.570692 -67.748244) (xy 190.62464 -67.740486) (xy 190.651892 -67.740022)
			(xy 190.679262 -67.740487) (xy 190.733442 -67.748305) (xy 190.785945 -67.763794) (xy 190.835692 -67.786636)
			(xy 190.881658 -67.81636) (xy 190.90259 -67.834002) (xy 190.902844 -67.834256) (xy 190.909938 -67.839832)
			(xy 190.926849 -67.846084) (xy 190.935864 -67.846448) (xy 191.00292 -67.846448) (xy 191.011939 -67.846112)
			(xy 191.028857 -67.839851) (xy 191.03594 -67.834256) (xy 191.03594 -67.834002) (xy 191.036194 -67.834002)
			(xy 191.057118 -67.816353) (xy 191.103093 -67.786642) (xy 191.152842 -67.763808) (xy 191.205345 -67.74832)
			(xy 191.259522 -67.740494) (xy 191.286892 -67.740022) (xy 191.313206 -67.740488) (xy 191.365335 -67.747722)
			(xy 191.415978 -67.762041) (xy 191.464177 -67.783174) (xy 191.509021 -67.81072) (xy 191.54966 -67.84416)
			(xy 191.567816 -67.863212) (xy 191.575328 -67.870625) (xy 191.594615 -67.879142) (xy 191.605154 -67.879722)
			(xy 191.67983 -67.879722) (xy 191.690376 -67.879162) (xy 191.709671 -67.870648) (xy 191.717168 -67.863212)
			(xy 191.7353 -67.844133) (xy 191.775934 -67.810677) (xy 191.82078 -67.783121) (xy 191.868985 -67.761987)
			(xy 191.919637 -67.747675) (xy 191.971774 -67.740457) (xy 191.998092 -67.740022) (xy 192.025346 -67.740463)
			(xy 192.079299 -67.74822) (xy 192.131599 -67.763576) (xy 192.181182 -67.78622) (xy 192.227036 -67.81569)
			(xy 192.26823 -67.851386) (xy 192.303923 -67.892582) (xy 192.333391 -67.938438) (xy 192.356032 -67.988021)
			(xy 192.371385 -68.040322) (xy 192.379139 -68.094276) (xy 192.3796 -68.12153) (xy 192.379152 -68.148901)
			(xy 192.371329 -68.203081) (xy 192.355836 -68.255584) (xy 192.332991 -68.305331) (xy 192.303263 -68.351297)
			(xy 192.28562 -68.372228) (xy 192.285366 -68.372482) (xy 192.279777 -68.379567) (xy 192.273533 -68.396485)
			(xy 192.273174 -68.405502) (xy 192.273174 -68.472558) (xy 192.273557 -68.481572) (xy 192.279787 -68.498489)
			(xy 192.285366 -68.505578) (xy 192.28562 -68.505578) (xy 192.28562 -68.505832) (xy 192.303244 -68.526776)
			(xy 192.332957 -68.572746) (xy 192.355796 -68.622491) (xy 192.371291 -68.674988) (xy 192.379123 -68.729162)
			(xy 192.3796 -68.75653) (xy 192.37915 -68.783782) (xy 192.371389 -68.837732) (xy 192.35603 -68.890028)
			(xy 192.333385 -68.939606) (xy 192.303915 -68.985456) (xy 192.268219 -69.026646) (xy 192.227026 -69.062337)
			(xy 192.181172 -69.091803) (xy 192.131592 -69.114443) (xy 192.079295 -69.129797) (xy 192.025344 -69.137553)
			(xy 191.998092 -69.138038) (xy 191.971777 -69.137596) (xy 191.919647 -69.130358) (xy 191.869003 -69.116036)
			(xy 191.820803 -69.094899) (xy 191.77596 -69.067347) (xy 191.735323 -69.033903) (xy 191.717168 -69.014848)
			(xy 191.709654 -69.007437) (xy 191.690368 -68.998917) (xy 191.67983 -68.998338) (xy 191.605154 -68.998338)
			(xy 191.594605 -68.998872) (xy 191.575308 -69.007402) (xy 191.567816 -69.014848) (xy 191.549655 -69.033898)
			(xy 191.509025 -69.067354) (xy 191.464186 -69.094912) (xy 191.415986 -69.116051) (xy 191.36534 -69.13037)
			(xy 191.313208 -69.137598) (xy 191.286892 -69.138038) (xy 191.259521 -69.137592) (xy 191.20534 -69.129771)
			(xy 191.152836 -69.114279) (xy 191.10309 -69.091432) (xy 191.057124 -69.061702) (xy 191.036194 -69.044058)
			(xy 191.03594 -69.043804) (xy 191.028846 -69.038228) (xy 191.011935 -69.031975) (xy 191.00292 -69.031612)
			(xy 190.935864 -69.031612) (xy 190.926845 -69.031949) (xy 190.909928 -69.03821) (xy 190.902844 -69.043804)
			(xy 190.902844 -69.044058) (xy 190.90259 -69.044058) (xy 190.881667 -69.061709) (xy 190.835692 -69.09142)
			(xy 190.785943 -69.114255) (xy 190.73344 -69.129743) (xy 190.679262 -69.137567) (xy 190.651892 -69.138038)
			(xy 190.624642 -69.13753) (xy 190.570697 -69.129773) (xy 190.518404 -69.114418) (xy 190.468829 -69.091778)
			(xy 190.42298 -69.062314) (xy 190.381791 -69.026625) (xy 190.346099 -68.985438) (xy 190.316632 -68.939591)
			(xy 190.293989 -68.890017) (xy 190.278632 -68.837725) (xy 190.270872 -68.78378) (xy 190.270384 -68.75653)
			(xy 186.794275 -68.75653) (xy 186.788274 -68.76967) (xy 186.758809 -68.81552) (xy 186.723119 -68.856709)
			(xy 186.681931 -68.892401) (xy 186.636083 -68.921868) (xy 186.586507 -68.94451) (xy 186.534215 -68.959866)
			(xy 186.480269 -68.967625) (xy 186.453018 -68.968112) (xy 186.425648 -68.967632) (xy 186.37147 -68.959817)
			(xy 186.318967 -68.944331) (xy 186.26922 -68.921493) (xy 186.223252 -68.891772) (xy 186.20232 -68.874132)
			(xy 186.202066 -68.873878) (xy 186.194966 -68.86831) (xy 186.17806 -68.862053) (xy 186.169046 -68.861686)
			(xy 186.10199 -68.861686) (xy 186.092973 -68.862041) (xy 186.076056 -68.868291) (xy 186.06897 -68.873878)
			(xy 186.06897 -68.874132) (xy 186.068716 -68.874132) (xy 186.047793 -68.891782) (xy 186.001817 -68.921491)
			(xy 185.952067 -68.944324) (xy 185.899565 -68.959813) (xy 185.845388 -68.967639) (xy 185.818018 -68.968112)
			(xy 185.791705 -68.967629) (xy 185.739577 -68.960397) (xy 185.688935 -68.94608) (xy 185.640736 -68.924951)
			(xy 185.595892 -68.897408) (xy 185.555251 -68.863972) (xy 185.537094 -68.844922) (xy 185.529574 -68.837519)
			(xy 185.510293 -68.828995) (xy 185.499756 -68.828412) (xy 185.42508 -68.828412) (xy 185.414533 -68.828967)
			(xy 185.395237 -68.837484) (xy 185.387742 -68.844922) (xy 185.369612 -68.864003) (xy 185.328976 -68.897457)
			(xy 185.28413 -68.925012) (xy 185.235925 -68.946146) (xy 185.185273 -68.960458) (xy 185.133136 -68.967677)
			(xy 185.106818 -68.968112) (xy 185.079566 -68.967628) (xy 185.025616 -68.959874) (xy 184.973319 -68.94452)
			(xy 184.923739 -68.92188) (xy 184.877886 -68.892414) (xy 184.836693 -68.856723) (xy 184.800999 -68.815532)
			(xy 184.771531 -68.769681) (xy 184.748888 -68.720102) (xy 184.733531 -68.667806) (xy 184.725774 -68.613856)
			(xy 184.72531 -68.586604) (xy 182.209873 -68.586604) (xy 182.055342 -71.555864) (xy 187.294518 -71.555864)
			(xy 187.298589 -71.500242) (xy 187.310715 -71.445805) (xy 187.330638 -71.393714) (xy 187.357934 -71.345079)
			(xy 187.39202 -71.300936) (xy 187.432169 -71.262227) (xy 187.477527 -71.229776) (xy 187.527127 -71.204275)
			(xy 187.579911 -71.186268) (xy 187.634754 -71.176138) (xy 187.690488 -71.174101) (xy 187.745925 -71.180201)
			(xy 187.799882 -71.194307) (xy 187.851211 -71.216119) (xy 187.898817 -71.245173) (xy 187.941685 -71.280848)
			(xy 187.978902 -71.322385) (xy 188.009675 -71.368898) (xy 188.033347 -71.419395) (xy 188.049415 -71.472802)
			(xy 188.057535 -71.527978) (xy 188.058044 -71.555864) (xy 188.057535 -71.58375) (xy 188.051696 -71.623428)
			(xy 188.803532 -71.623428) (xy 188.807603 -71.567806) (xy 188.819729 -71.513369) (xy 188.839652 -71.461278)
			(xy 188.866948 -71.412643) (xy 188.901034 -71.3685) (xy 188.941183 -71.329791) (xy 188.986541 -71.29734)
			(xy 189.036141 -71.271839) (xy 189.088925 -71.253832) (xy 189.143768 -71.243702) (xy 189.199502 -71.241665)
			(xy 189.254939 -71.247765) (xy 189.308896 -71.261871) (xy 189.360225 -71.283683) (xy 189.407831 -71.312737)
			(xy 189.450699 -71.348412) (xy 189.487916 -71.389949) (xy 189.518689 -71.436462) (xy 189.542361 -71.486959)
			(xy 189.558429 -71.540366) (xy 189.566549 -71.595542) (xy 189.567058 -71.623428) (xy 189.566549 -71.651314)
			(xy 189.558429 -71.70649) (xy 189.542361 -71.759897) (xy 189.518689 -71.810394) (xy 189.487916 -71.856907)
			(xy 189.450699 -71.898444) (xy 189.407831 -71.934119) (xy 189.360225 -71.963173) (xy 189.308896 -71.984985)
			(xy 189.254939 -71.999091) (xy 189.199502 -72.005191) (xy 189.143768 -72.003154) (xy 189.088925 -71.993024)
			(xy 189.036141 -71.975017) (xy 188.986541 -71.949516) (xy 188.941183 -71.917065) (xy 188.901034 -71.878356)
			(xy 188.866948 -71.834213) (xy 188.839652 -71.785578) (xy 188.819729 -71.733487) (xy 188.807603 -71.67905)
			(xy 188.803532 -71.623428) (xy 188.051696 -71.623428) (xy 188.049415 -71.638926) (xy 188.033347 -71.692333)
			(xy 188.009675 -71.74283) (xy 187.978902 -71.789343) (xy 187.941685 -71.83088) (xy 187.898817 -71.866555)
			(xy 187.851211 -71.895609) (xy 187.799882 -71.917421) (xy 187.745925 -71.931527) (xy 187.690488 -71.937627)
			(xy 187.634754 -71.93559) (xy 187.579911 -71.92546) (xy 187.527127 -71.907453) (xy 187.477527 -71.881952)
			(xy 187.432169 -71.849501) (xy 187.39202 -71.810792) (xy 187.357934 -71.766649) (xy 187.330638 -71.718014)
			(xy 187.310715 -71.665923) (xy 187.298589 -71.611486) (xy 187.294518 -71.555864) (xy 182.055342 -71.555864)
			(xy 181.743954 -77.539088) (xy 182.075834 -77.539088) (xy 182.079905 -77.483466) (xy 182.092031 -77.429029)
			(xy 182.111954 -77.376938) (xy 182.13925 -77.328303) (xy 182.173336 -77.28416) (xy 182.213485 -77.245451)
			(xy 182.258843 -77.213) (xy 182.308443 -77.187499) (xy 182.361227 -77.169492) (xy 182.41607 -77.159362)
			(xy 182.471804 -77.157325) (xy 182.527241 -77.163425) (xy 182.581198 -77.177531) (xy 182.632527 -77.199343)
			(xy 182.644005 -77.206348) (xy 198.783954 -77.206348) (xy 198.788025 -77.150726) (xy 198.800151 -77.096289)
			(xy 198.820074 -77.044198) (xy 198.84737 -76.995563) (xy 198.881456 -76.95142) (xy 198.921605 -76.912711)
			(xy 198.966963 -76.88026) (xy 199.016563 -76.854759) (xy 199.069347 -76.836752) (xy 199.12419 -76.826622)
			(xy 199.179924 -76.824585) (xy 199.235361 -76.830685) (xy 199.289318 -76.844791) (xy 199.340647 -76.866603)
			(xy 199.388253 -76.895657) (xy 199.431121 -76.931332) (xy 199.468338 -76.972869) (xy 199.499111 -77.019382)
			(xy 199.522783 -77.069879) (xy 199.538851 -77.123286) (xy 199.546971 -77.178462) (xy 199.54748 -77.206348)
			(xy 199.546971 -77.234234) (xy 199.538851 -77.28941) (xy 199.522783 -77.342817) (xy 199.499111 -77.393314)
			(xy 199.468338 -77.439827) (xy 199.431121 -77.481364) (xy 199.388253 -77.517039) (xy 199.340647 -77.546093)
			(xy 199.289318 -77.567905) (xy 199.235361 -77.582011) (xy 199.179924 -77.588111) (xy 199.12419 -77.586074)
			(xy 199.069347 -77.575944) (xy 199.016563 -77.557937) (xy 198.966963 -77.532436) (xy 198.921605 -77.499985)
			(xy 198.881456 -77.461276) (xy 198.84737 -77.417133) (xy 198.820074 -77.368498) (xy 198.800151 -77.316407)
			(xy 198.788025 -77.26197) (xy 198.783954 -77.206348) (xy 182.644005 -77.206348) (xy 182.680133 -77.228397)
			(xy 182.723001 -77.264072) (xy 182.760218 -77.305609) (xy 182.790991 -77.352122) (xy 182.814663 -77.402619)
			(xy 182.830731 -77.456026) (xy 182.838851 -77.511202) (xy 182.83936 -77.539088) (xy 182.838851 -77.566974)
			(xy 182.830731 -77.62215) (xy 182.814663 -77.675557) (xy 182.790991 -77.726054) (xy 182.760218 -77.772567)
			(xy 182.723001 -77.814104) (xy 182.680133 -77.849779) (xy 182.632527 -77.878833) (xy 182.581198 -77.900645)
			(xy 182.527241 -77.914751) (xy 182.471804 -77.920851) (xy 182.41607 -77.918814) (xy 182.361227 -77.908684)
			(xy 182.308443 -77.890677) (xy 182.258843 -77.865176) (xy 182.213485 -77.832725) (xy 182.173336 -77.794016)
			(xy 182.13925 -77.749873) (xy 182.111954 -77.701238) (xy 182.092031 -77.649147) (xy 182.079905 -77.59471)
			(xy 182.075834 -77.539088) (xy 181.743954 -77.539088) (xy 181.658453 -79.18196) (xy 195.691506 -79.18196)
			(xy 195.691992 -79.154709) (xy 195.699748 -79.100761) (xy 195.715103 -79.048466) (xy 195.737745 -78.998889)
			(xy 195.767211 -78.953039) (xy 195.802902 -78.911848) (xy 195.844093 -78.876157) (xy 195.889943 -78.846691)
			(xy 195.93952 -78.824049) (xy 195.991815 -78.808694) (xy 196.045763 -78.800938) (xy 196.100265 -78.800938)
			(xy 196.154213 -78.808694) (xy 196.206508 -78.824049) (xy 196.256085 -78.846691) (xy 196.301935 -78.876157)
			(xy 196.343126 -78.911848) (xy 196.378817 -78.953039) (xy 196.408283 -78.998889) (xy 196.430925 -79.048466)
			(xy 196.44628 -79.100761) (xy 196.454036 -79.154709) (xy 196.454522 -79.18196) (xy 196.453958 -79.210843)
			(xy 196.445242 -79.267948) (xy 196.428018 -79.323087) (xy 196.402681 -79.375) (xy 196.369808 -79.422501)
			(xy 196.33015 -79.464504) (xy 196.30771 -79.482696) (xy 196.296786 -79.491858) (xy 196.280033 -79.51491)
			(xy 196.270293 -79.541691) (xy 196.268324 -79.57012) (xy 196.274279 -79.597987) (xy 196.287695 -79.623129)
			(xy 196.307529 -79.64359) (xy 196.319648 -79.651098) (xy 196.344249 -79.665763) (xy 196.389122 -79.701351)
			(xy 196.42817 -79.743248) (xy 196.460515 -79.790512) (xy 196.48543 -79.84208) (xy 196.502355 -79.896794)
			(xy 196.510909 -79.953424) (xy 196.511418 -79.98206) (xy 196.510932 -80.009311) (xy 196.503176 -80.063259)
			(xy 196.487821 -80.115554) (xy 196.465179 -80.165131) (xy 196.435713 -80.210981) (xy 196.400022 -80.252172)
			(xy 196.358831 -80.287863) (xy 196.312981 -80.317329) (xy 196.263404 -80.339971) (xy 196.211109 -80.355326)
			(xy 196.157161 -80.363082) (xy 196.102659 -80.363082) (xy 196.048711 -80.355326) (xy 195.996416 -80.339971)
			(xy 195.946839 -80.317329) (xy 195.900989 -80.287863) (xy 195.859798 -80.252172) (xy 195.824107 -80.210981)
			(xy 195.794641 -80.165131) (xy 195.771999 -80.115554) (xy 195.756644 -80.063259) (xy 195.748888 -80.009311)
			(xy 195.748402 -79.98206) (xy 195.7489 -79.953174) (xy 195.757628 -79.896066) (xy 195.774865 -79.840925)
			(xy 195.800215 -79.789012) (xy 195.8331 -79.741513) (xy 195.872768 -79.699514) (xy 195.895214 -79.681324)
			(xy 195.906112 -79.672135) (xy 195.922862 -79.649089) (xy 195.9326 -79.622315) (xy 195.934571 -79.593893)
			(xy 195.928622 -79.566031) (xy 195.915215 -79.540893) (xy 195.89539 -79.520431) (xy 195.883276 -79.512922)
			(xy 195.858667 -79.498271) (xy 195.813797 -79.462678) (xy 195.774752 -79.420778) (xy 195.74241 -79.373511)
			(xy 195.717496 -79.321941) (xy 195.700572 -79.267226) (xy 195.692016 -79.210596) (xy 195.691506 -79.18196)
			(xy 181.658453 -79.18196) (xy 181.596998 -80.362806) (xy 187.844936 -80.362806) (xy 187.849007 -80.307184)
			(xy 187.861133 -80.252747) (xy 187.881056 -80.200656) (xy 187.908352 -80.152021) (xy 187.942438 -80.107878)
			(xy 187.982587 -80.069169) (xy 188.027945 -80.036718) (xy 188.077545 -80.011217) (xy 188.130329 -79.99321)
			(xy 188.185172 -79.98308) (xy 188.240906 -79.981043) (xy 188.296343 -79.987143) (xy 188.3503 -80.001249)
			(xy 188.401629 -80.023061) (xy 188.449235 -80.052115) (xy 188.492103 -80.08779) (xy 188.52932 -80.129327)
			(xy 188.560093 -80.17584) (xy 188.583765 -80.226337) (xy 188.599833 -80.279744) (xy 188.607953 -80.33492)
			(xy 188.608462 -80.362806) (xy 188.607953 -80.390692) (xy 188.599833 -80.445868) (xy 188.583765 -80.499275)
			(xy 188.560093 -80.549772) (xy 188.52932 -80.596285) (xy 188.492103 -80.637822) (xy 188.449235 -80.673497)
			(xy 188.401629 -80.702551) (xy 188.3503 -80.724363) (xy 188.296343 -80.738469) (xy 188.240906 -80.744569)
			(xy 188.185172 -80.742532) (xy 188.130329 -80.732402) (xy 188.077545 -80.714395) (xy 188.027945 -80.688894)
			(xy 187.982587 -80.656443) (xy 187.942438 -80.617734) (xy 187.908352 -80.573591) (xy 187.881056 -80.524956)
			(xy 187.861133 -80.472865) (xy 187.849007 -80.418428) (xy 187.844936 -80.362806) (xy 181.596998 -80.362806)
			(xy 181.48954 -82.427572) (xy 195.032628 -82.427572) (xy 195.036699 -82.37195) (xy 195.048825 -82.317513)
			(xy 195.068748 -82.265422) (xy 195.096044 -82.216787) (xy 195.13013 -82.172644) (xy 195.170279 -82.133935)
			(xy 195.215637 -82.101484) (xy 195.265237 -82.075983) (xy 195.318021 -82.057976) (xy 195.372864 -82.047846)
			(xy 195.428598 -82.045809) (xy 195.484035 -82.051909) (xy 195.537992 -82.066015) (xy 195.589321 -82.087827)
			(xy 195.636927 -82.116881) (xy 195.679795 -82.152556) (xy 195.717012 -82.194093) (xy 195.747785 -82.240606)
			(xy 195.771457 -82.291103) (xy 195.787525 -82.34451) (xy 195.795645 -82.399686) (xy 195.796154 -82.427572)
			(xy 195.795645 -82.455458) (xy 195.787525 -82.510634) (xy 195.771457 -82.564041) (xy 195.747785 -82.614538)
			(xy 195.717012 -82.661051) (xy 195.679795 -82.702588) (xy 195.636927 -82.738263) (xy 195.589321 -82.767317)
			(xy 195.537992 -82.789129) (xy 195.484035 -82.803235) (xy 195.428598 -82.809335) (xy 195.372864 -82.807298)
			(xy 195.318021 -82.797168) (xy 195.265237 -82.779161) (xy 195.215637 -82.75366) (xy 195.170279 -82.721209)
			(xy 195.13013 -82.6825) (xy 195.096044 -82.638357) (xy 195.068748 -82.589722) (xy 195.048825 -82.537631)
			(xy 195.036699 -82.483194) (xy 195.032628 -82.427572) (xy 181.48954 -82.427572) (xy 181.434232 -83.490308)
			(xy 181.432087 -83.532218) (xy 192.411348 -83.532218) (xy 192.415419 -83.476596) (xy 192.427545 -83.422159)
			(xy 192.447468 -83.370068) (xy 192.474764 -83.321433) (xy 192.50885 -83.27729) (xy 192.548999 -83.238581)
			(xy 192.594357 -83.20613) (xy 192.643957 -83.180629) (xy 192.696741 -83.162622) (xy 192.751584 -83.152492)
			(xy 192.807318 -83.150455) (xy 192.862755 -83.156555) (xy 192.916712 -83.170661) (xy 192.968041 -83.192473)
			(xy 193.015647 -83.221527) (xy 193.058515 -83.257202) (xy 193.095732 -83.298739) (xy 193.126505 -83.345252)
			(xy 193.150177 -83.395749) (xy 193.166245 -83.449156) (xy 193.174365 -83.504332) (xy 193.174874 -83.532218)
			(xy 193.174365 -83.560104) (xy 193.166245 -83.61528) (xy 193.150177 -83.668687) (xy 193.126505 -83.719184)
			(xy 193.095732 -83.765697) (xy 193.058515 -83.807234) (xy 193.015647 -83.842909) (xy 192.968041 -83.871963)
			(xy 192.916712 -83.893775) (xy 192.862755 -83.907881) (xy 192.807318 -83.913981) (xy 192.751584 -83.911944)
			(xy 192.696741 -83.901814) (xy 192.643957 -83.883807) (xy 192.594357 -83.858306) (xy 192.548999 -83.825855)
			(xy 192.50885 -83.787146) (xy 192.474764 -83.743003) (xy 192.447468 -83.694368) (xy 192.427545 -83.642277)
			(xy 192.415419 -83.58784) (xy 192.411348 -83.532218) (xy 181.432087 -83.532218) (xy 181.428136 -83.609434)
			(xy 181.417214 -83.820762) (xy 181.394608 -84.254594) (xy 181.38307 -84.476336) (xy 195.74713 -84.476336)
			(xy 195.751201 -84.420714) (xy 195.763327 -84.366277) (xy 195.78325 -84.314186) (xy 195.810546 -84.265551)
			(xy 195.844632 -84.221408) (xy 195.884781 -84.182699) (xy 195.930139 -84.150248) (xy 195.979739 -84.124747)
			(xy 196.032523 -84.10674) (xy 196.087366 -84.09661) (xy 196.1431 -84.094573) (xy 196.198537 -84.100673)
			(xy 196.252494 -84.114779) (xy 196.303823 -84.136591) (xy 196.351429 -84.165645) (xy 196.394297 -84.20132)
			(xy 196.431514 -84.242857) (xy 196.462287 -84.28937) (xy 196.485959 -84.339867) (xy 196.502027 -84.393274)
			(xy 196.510147 -84.44845) (xy 196.510656 -84.476336) (xy 196.510147 -84.504222) (xy 196.502027 -84.559398)
			(xy 196.485959 -84.612805) (xy 196.462287 -84.663302) (xy 196.431514 -84.709815) (xy 196.394297 -84.751352)
			(xy 196.351429 -84.787027) (xy 196.303823 -84.816081) (xy 196.252494 -84.837893) (xy 196.198537 -84.851999)
			(xy 196.1431 -84.858099) (xy 196.087366 -84.856062) (xy 196.032523 -84.845932) (xy 195.979739 -84.827925)
			(xy 195.930139 -84.802424) (xy 195.884781 -84.769973) (xy 195.844632 -84.731264) (xy 195.810546 -84.687121)
			(xy 195.78325 -84.638486) (xy 195.763327 -84.586395) (xy 195.751201 -84.531958) (xy 195.74713 -84.476336)
			(xy 181.38307 -84.476336) (xy 181.337712 -85.348064) (xy 181.313328 -85.81517) (xy 181.290874 -86.247986)
			(xy 191.338452 -86.247986) (xy 191.342523 -86.192364) (xy 191.354649 -86.137927) (xy 191.374572 -86.085836)
			(xy 191.401868 -86.037201) (xy 191.435954 -85.993058) (xy 191.476103 -85.954349) (xy 191.521461 -85.921898)
			(xy 191.571061 -85.896397) (xy 191.623845 -85.87839) (xy 191.678688 -85.86826) (xy 191.734422 -85.866223)
			(xy 191.789859 -85.872323) (xy 191.843816 -85.886429) (xy 191.895145 -85.908241) (xy 191.942751 -85.937295)
			(xy 191.985619 -85.97297) (xy 192.022836 -86.014507) (xy 192.053609 -86.06102) (xy 192.077281 -86.111517)
			(xy 192.093349 -86.164924) (xy 192.101469 -86.2201) (xy 192.101978 -86.247986) (xy 192.101469 -86.275872)
			(xy 192.093349 -86.331048) (xy 192.077281 -86.384455) (xy 192.053609 -86.434952) (xy 192.022836 -86.481465)
			(xy 191.985619 -86.523002) (xy 191.942751 -86.558677) (xy 191.895145 -86.587731) (xy 191.843816 -86.609543)
			(xy 191.789859 -86.623649) (xy 191.734422 -86.629749) (xy 191.678688 -86.627712) (xy 191.623845 -86.617582)
			(xy 191.571061 -86.599575) (xy 191.521461 -86.574074) (xy 191.476103 -86.541623) (xy 191.435954 -86.502914)
			(xy 191.401868 -86.458771) (xy 191.374572 -86.410136) (xy 191.354649 -86.358045) (xy 191.342523 -86.303608)
			(xy 191.338452 -86.247986) (xy 181.290874 -86.247986) (xy 181.180474 -88.375998) (xy 195.924168 -88.375998)
			(xy 195.928239 -88.320376) (xy 195.940365 -88.265939) (xy 195.960288 -88.213848) (xy 195.987584 -88.165213)
			(xy 196.02167 -88.12107) (xy 196.061819 -88.082361) (xy 196.107177 -88.04991) (xy 196.156777 -88.024409)
			(xy 196.209561 -88.006402) (xy 196.264404 -87.996272) (xy 196.320138 -87.994235) (xy 196.375575 -88.000335)
			(xy 196.429532 -88.014441) (xy 196.480861 -88.036253) (xy 196.528467 -88.065307) (xy 196.571335 -88.100982)
			(xy 196.608552 -88.142519) (xy 196.639325 -88.189032) (xy 196.662997 -88.239529) (xy 196.679065 -88.292936)
			(xy 196.687185 -88.348112) (xy 196.687694 -88.375998) (xy 196.687185 -88.403884) (xy 196.679065 -88.45906)
			(xy 196.662997 -88.512467) (xy 196.639325 -88.562964) (xy 196.608552 -88.609477) (xy 196.571335 -88.651014)
			(xy 196.528467 -88.686689) (xy 196.480861 -88.715743) (xy 196.429532 -88.737555) (xy 196.375575 -88.751661)
			(xy 196.320138 -88.757761) (xy 196.264404 -88.755724) (xy 196.209561 -88.745594) (xy 196.156777 -88.727587)
			(xy 196.107177 -88.702086) (xy 196.061819 -88.669635) (xy 196.02167 -88.630926) (xy 195.987584 -88.586783)
			(xy 195.960288 -88.538148) (xy 195.940365 -88.486057) (xy 195.928239 -88.43162) (xy 195.924168 -88.375998)
			(xy 181.180474 -88.375998) (xy 181.101093 -89.906094) (xy 192.562478 -89.906094) (xy 192.566549 -89.850472)
			(xy 192.578675 -89.796035) (xy 192.598598 -89.743944) (xy 192.625894 -89.695309) (xy 192.65998 -89.651166)
			(xy 192.700129 -89.612457) (xy 192.745487 -89.580006) (xy 192.795087 -89.554505) (xy 192.847871 -89.536498)
			(xy 192.902714 -89.526368) (xy 192.958448 -89.524331) (xy 193.013885 -89.530431) (xy 193.067842 -89.544537)
			(xy 193.119171 -89.566349) (xy 193.166777 -89.595403) (xy 193.209645 -89.631078) (xy 193.246862 -89.672615)
			(xy 193.277635 -89.719128) (xy 193.301307 -89.769625) (xy 193.317375 -89.823032) (xy 193.325495 -89.878208)
			(xy 193.326004 -89.906094) (xy 193.325495 -89.93398) (xy 193.317375 -89.989156) (xy 193.301307 -90.042563)
			(xy 193.277635 -90.09306) (xy 193.246862 -90.139573) (xy 193.209645 -90.18111) (xy 193.166777 -90.216785)
			(xy 193.119171 -90.245839) (xy 193.067842 -90.267651) (xy 193.013885 -90.281757) (xy 192.958448 -90.287857)
			(xy 192.902714 -90.28582) (xy 192.847871 -90.27569) (xy 192.795087 -90.257683) (xy 192.745487 -90.232182)
			(xy 192.700129 -90.199731) (xy 192.65998 -90.161022) (xy 192.625894 -90.116879) (xy 192.598598 -90.068244)
			(xy 192.578675 -90.016153) (xy 192.566549 -89.961716) (xy 192.562478 -89.906094) (xy 181.101093 -89.906094)
			(xy 181.091078 -90.099134) (xy 181.091078 -90.099642) (xy 181.09057 -90.108532) (xy 181.092856 -90.116406)
			(xy 181.094341 -90.120854) (xy 181.09868 -90.129165) (xy 181.101492 -90.132916) (xy 181.106826 -90.140028)
			(xy 181.121558 -90.14968) (xy 181.130702 -90.151712) (xy 181.162267 -90.159431) (xy 181.223124 -90.182214)
			(xy 181.280367 -90.212967) (xy 181.33296 -90.251132) (xy 181.379947 -90.296018) (xy 181.420478 -90.34681)
			(xy 181.453817 -90.402588) (xy 181.479358 -90.462339) (xy 181.496641 -90.52498) (xy 181.505349 -90.589375)
			(xy 181.50586 -90.621866) (xy 181.505379 -90.65293) (xy 181.497403 -90.714543) (xy 181.48158 -90.774621)
			(xy 181.458171 -90.832169) (xy 181.427563 -90.886233) (xy 181.390265 -90.935918) (xy 181.346894 -90.980401)
			(xy 181.298169 -91.018945) (xy 181.244896 -91.05091) (xy 181.187959 -91.075768) (xy 181.128301 -91.093107)
			(xy 181.097682 -91.09837) (xy 181.095904 -91.098624) (xy 181.09227 -91.099372) (xy 181.085257 -91.101799)
			(xy 181.081934 -91.10345) (xy 181.074314 -91.107514) (xy 181.066186 -91.115896) (xy 181.065678 -91.116404)
			(xy 181.053232 -91.129612) (xy 181.052724 -91.13012) (xy 181.048152 -91.1352) (xy 181.047644 -91.135708)
			(xy 181.042652 -91.141843) (xy 181.036322 -91.156327) (xy 181.035198 -91.164156) (xy 180.99405 -91.952064)
			(xy 180.97246 -92.363798) (xy 180.824052 -95.214948) (xy 187.739796 -95.214948) (xy 187.743748 -95.123155)
			(xy 187.755578 -95.032041) (xy 187.775195 -94.942281) (xy 187.802457 -94.85454) (xy 187.83716 -94.769468)
			(xy 187.879048 -94.687693) (xy 187.927811 -94.609822) (xy 187.983087 -94.536432) (xy 188.044468 -94.468065)
			(xy 188.111499 -94.405227) (xy 188.183683 -94.348385) (xy 188.260487 -94.297958) (xy 188.341341 -94.25432)
			(xy 188.425647 -94.217794) (xy 188.512781 -94.188651) (xy 188.602098 -94.167106) (xy 188.692936 -94.15332)
			(xy 188.784623 -94.147393) (xy 188.87648 -94.14937) (xy 188.967828 -94.159236) (xy 189.057988 -94.176918)
			(xy 189.146296 -94.202285) (xy 189.232095 -94.23515) (xy 189.314752 -94.275269) (xy 189.393654 -94.322345)
			(xy 189.468217 -94.376029) (xy 189.537889 -94.435925) (xy 189.602154 -94.501588) (xy 189.660537 -94.572532)
			(xy 189.712604 -94.648233) (xy 189.757972 -94.72813) (xy 189.796303 -94.81163) (xy 189.827314 -94.898117)
			(xy 189.850775 -94.98695) (xy 189.866514 -95.07747) (xy 189.874412 -95.169009) (xy 189.874906 -95.214948)
			(xy 189.874412 -95.260887) (xy 189.866514 -95.352426) (xy 189.850775 -95.442946) (xy 189.827314 -95.531779)
			(xy 189.796303 -95.618266) (xy 189.757972 -95.701766) (xy 189.712604 -95.781663) (xy 189.660537 -95.857364)
			(xy 189.602154 -95.928308) (xy 189.54212 -95.989648) (xy 191.663826 -95.989648) (xy 191.667897 -95.934026)
			(xy 191.680023 -95.879589) (xy 191.699946 -95.827498) (xy 191.727242 -95.778863) (xy 191.761328 -95.73472)
			(xy 191.801477 -95.696011) (xy 191.846835 -95.66356) (xy 191.896435 -95.638059) (xy 191.949219 -95.620052)
			(xy 192.004062 -95.609922) (xy 192.059796 -95.607885) (xy 192.115233 -95.613985) (xy 192.16919 -95.628091)
			(xy 192.220519 -95.649903) (xy 192.268125 -95.678957) (xy 192.310993 -95.714632) (xy 192.34821 -95.756169)
			(xy 192.378983 -95.802682) (xy 192.402655 -95.853179) (xy 192.418723 -95.906586) (xy 192.426843 -95.961762)
			(xy 192.427352 -95.989648) (xy 194.269358 -95.989648) (xy 194.273429 -95.934026) (xy 194.285555 -95.879589)
			(xy 194.305478 -95.827498) (xy 194.332774 -95.778863) (xy 194.36686 -95.73472) (xy 194.407009 -95.696011)
			(xy 194.452367 -95.66356) (xy 194.501967 -95.638059) (xy 194.554751 -95.620052) (xy 194.609594 -95.609922)
			(xy 194.665328 -95.607885) (xy 194.720765 -95.613985) (xy 194.774722 -95.628091) (xy 194.826051 -95.649903)
			(xy 194.873657 -95.678957) (xy 194.916525 -95.714632) (xy 194.953742 -95.756169) (xy 194.984515 -95.802682)
			(xy 195.008187 -95.853179) (xy 195.024255 -95.906586) (xy 195.032375 -95.961762) (xy 195.032884 -95.989648)
			(xy 195.032375 -96.017534) (xy 195.024255 -96.07271) (xy 195.008187 -96.126117) (xy 194.984515 -96.176614)
			(xy 194.953742 -96.223127) (xy 194.916525 -96.264664) (xy 194.873657 -96.300339) (xy 194.826051 -96.329393)
			(xy 194.774722 -96.351205) (xy 194.720765 -96.365311) (xy 194.665328 -96.371411) (xy 194.609594 -96.369374)
			(xy 194.554751 -96.359244) (xy 194.501967 -96.341237) (xy 194.452367 -96.315736) (xy 194.407009 -96.283285)
			(xy 194.36686 -96.244576) (xy 194.332774 -96.200433) (xy 194.305478 -96.151798) (xy 194.285555 -96.099707)
			(xy 194.273429 -96.04527) (xy 194.269358 -95.989648) (xy 192.427352 -95.989648) (xy 192.426843 -96.017534)
			(xy 192.418723 -96.07271) (xy 192.402655 -96.126117) (xy 192.378983 -96.176614) (xy 192.34821 -96.223127)
			(xy 192.310993 -96.264664) (xy 192.268125 -96.300339) (xy 192.220519 -96.329393) (xy 192.16919 -96.351205)
			(xy 192.115233 -96.365311) (xy 192.059796 -96.371411) (xy 192.004062 -96.369374) (xy 191.949219 -96.359244)
			(xy 191.896435 -96.341237) (xy 191.846835 -96.315736) (xy 191.801477 -96.283285) (xy 191.761328 -96.244576)
			(xy 191.727242 -96.200433) (xy 191.699946 -96.151798) (xy 191.680023 -96.099707) (xy 191.667897 -96.04527)
			(xy 191.663826 -95.989648) (xy 189.54212 -95.989648) (xy 189.537889 -95.993971) (xy 189.468217 -96.053867)
			(xy 189.393654 -96.107551) (xy 189.314752 -96.154627) (xy 189.232095 -96.194746) (xy 189.146296 -96.227611)
			(xy 189.057988 -96.252978) (xy 188.967828 -96.27066) (xy 188.87648 -96.280526) (xy 188.784623 -96.282503)
			(xy 188.692936 -96.276576) (xy 188.602098 -96.26279) (xy 188.512781 -96.241245) (xy 188.425647 -96.212102)
			(xy 188.341341 -96.175576) (xy 188.260487 -96.131938) (xy 188.183683 -96.081511) (xy 188.111499 -96.024669)
			(xy 188.044468 -95.961831) (xy 187.983087 -95.893464) (xy 187.927811 -95.820074) (xy 187.879048 -95.742203)
			(xy 187.83716 -95.660428) (xy 187.802457 -95.575356) (xy 187.775195 -95.487615) (xy 187.755578 -95.397855)
			(xy 187.743748 -95.306741) (xy 187.739796 -95.214948) (xy 180.824052 -95.214948) (xy 180.760656 -96.432878)
			(xy 183.362598 -96.432878) (xy 183.366669 -96.377256) (xy 183.378795 -96.322819) (xy 183.398718 -96.270728)
			(xy 183.426014 -96.222093) (xy 183.4601 -96.17795) (xy 183.500249 -96.139241) (xy 183.545607 -96.10679)
			(xy 183.595207 -96.081289) (xy 183.647991 -96.063282) (xy 183.702834 -96.053152) (xy 183.758568 -96.051115)
			(xy 183.814005 -96.057215) (xy 183.867962 -96.071321) (xy 183.919291 -96.093133) (xy 183.966897 -96.122187)
			(xy 184.009765 -96.157862) (xy 184.046982 -96.199399) (xy 184.077755 -96.245912) (xy 184.101427 -96.296409)
			(xy 184.117495 -96.349816) (xy 184.125615 -96.404992) (xy 184.126124 -96.432878) (xy 184.125615 -96.460764)
			(xy 184.117495 -96.51594) (xy 184.101427 -96.569347) (xy 184.077755 -96.619844) (xy 184.046982 -96.666357)
			(xy 184.009765 -96.707894) (xy 183.966897 -96.743569) (xy 183.919291 -96.772623) (xy 183.867962 -96.794435)
			(xy 183.83634 -96.802702) (xy 185.421776 -96.802702) (xy 185.425847 -96.74708) (xy 185.437973 -96.692643)
			(xy 185.457896 -96.640552) (xy 185.485192 -96.591917) (xy 185.519278 -96.547774) (xy 185.559427 -96.509065)
			(xy 185.604785 -96.476614) (xy 185.654385 -96.451113) (xy 185.707169 -96.433106) (xy 185.762012 -96.422976)
			(xy 185.817746 -96.420939) (xy 185.873183 -96.427039) (xy 185.92714 -96.441145) (xy 185.978469 -96.462957)
			(xy 186.026075 -96.492011) (xy 186.068943 -96.527686) (xy 186.10616 -96.569223) (xy 186.136933 -96.615736)
			(xy 186.160605 -96.666233) (xy 186.176673 -96.71964) (xy 186.184793 -96.774816) (xy 186.185302 -96.802702)
			(xy 186.184793 -96.830588) (xy 186.176673 -96.885764) (xy 186.160605 -96.939171) (xy 186.136933 -96.989668)
			(xy 186.10616 -97.036181) (xy 186.102794 -97.039938) (xy 190.825372 -97.039938) (xy 190.829443 -96.984316)
			(xy 190.841569 -96.929879) (xy 190.861492 -96.877788) (xy 190.888788 -96.829153) (xy 190.922874 -96.78501)
			(xy 190.963023 -96.746301) (xy 191.008381 -96.71385) (xy 191.057981 -96.688349) (xy 191.110765 -96.670342)
			(xy 191.165608 -96.660212) (xy 191.221342 -96.658175) (xy 191.276779 -96.664275) (xy 191.330736 -96.678381)
			(xy 191.382065 -96.700193) (xy 191.429671 -96.729247) (xy 191.472539 -96.764922) (xy 191.509756 -96.806459)
			(xy 191.540529 -96.852972) (xy 191.564201 -96.903469) (xy 191.580269 -96.956876) (xy 191.587447 -97.005648)
			(xy 194.269358 -97.005648) (xy 194.273429 -96.950026) (xy 194.285555 -96.895589) (xy 194.305478 -96.843498)
			(xy 194.332774 -96.794863) (xy 194.36686 -96.75072) (xy 194.407009 -96.712011) (xy 194.452367 -96.67956)
			(xy 194.501967 -96.654059) (xy 194.554751 -96.636052) (xy 194.609594 -96.625922) (xy 194.665328 -96.623885)
			(xy 194.720765 -96.629985) (xy 194.774722 -96.644091) (xy 194.826051 -96.665903) (xy 194.873657 -96.694957)
			(xy 194.916525 -96.730632) (xy 194.953742 -96.772169) (xy 194.984515 -96.818682) (xy 195.008187 -96.869179)
			(xy 195.024255 -96.922586) (xy 195.032375 -96.977762) (xy 195.032884 -97.005648) (xy 195.032375 -97.033534)
			(xy 195.024255 -97.08871) (xy 195.008187 -97.142117) (xy 194.984515 -97.192614) (xy 194.953742 -97.239127)
			(xy 194.916525 -97.280664) (xy 194.873657 -97.316339) (xy 194.826051 -97.345393) (xy 194.774722 -97.367205)
			(xy 194.720765 -97.381311) (xy 194.665328 -97.387411) (xy 194.609594 -97.385374) (xy 194.554751 -97.375244)
			(xy 194.501967 -97.357237) (xy 194.452367 -97.331736) (xy 194.407009 -97.299285) (xy 194.36686 -97.260576)
			(xy 194.332774 -97.216433) (xy 194.305478 -97.167798) (xy 194.285555 -97.115707) (xy 194.273429 -97.06127)
			(xy 194.269358 -97.005648) (xy 191.587447 -97.005648) (xy 191.588389 -97.012052) (xy 191.588898 -97.039938)
			(xy 191.588389 -97.067824) (xy 191.580269 -97.123) (xy 191.564201 -97.176407) (xy 191.540529 -97.226904)
			(xy 191.509756 -97.273417) (xy 191.472539 -97.314954) (xy 191.429671 -97.350629) (xy 191.382065 -97.379683)
			(xy 191.330736 -97.401495) (xy 191.276779 -97.415601) (xy 191.221342 -97.421701) (xy 191.165608 -97.419664)
			(xy 191.110765 -97.409534) (xy 191.057981 -97.391527) (xy 191.008381 -97.366026) (xy 190.963023 -97.333575)
			(xy 190.922874 -97.294866) (xy 190.888788 -97.250723) (xy 190.861492 -97.202088) (xy 190.841569 -97.149997)
			(xy 190.829443 -97.09556) (xy 190.825372 -97.039938) (xy 186.102794 -97.039938) (xy 186.068943 -97.077718)
			(xy 186.026075 -97.113393) (xy 185.978469 -97.142447) (xy 185.92714 -97.164259) (xy 185.873183 -97.178365)
			(xy 185.817746 -97.184465) (xy 185.762012 -97.182428) (xy 185.707169 -97.172298) (xy 185.654385 -97.154291)
			(xy 185.604785 -97.12879) (xy 185.559427 -97.096339) (xy 185.519278 -97.05763) (xy 185.485192 -97.013487)
			(xy 185.457896 -96.964852) (xy 185.437973 -96.912761) (xy 185.425847 -96.858324) (xy 185.421776 -96.802702)
			(xy 183.83634 -96.802702) (xy 183.814005 -96.808541) (xy 183.758568 -96.814641) (xy 183.702834 -96.812604)
			(xy 183.647991 -96.802474) (xy 183.595207 -96.784467) (xy 183.545607 -96.758966) (xy 183.500249 -96.726515)
			(xy 183.4601 -96.687806) (xy 183.426014 -96.643663) (xy 183.398718 -96.595028) (xy 183.378795 -96.542937)
			(xy 183.366669 -96.4885) (xy 183.362598 -96.432878) (xy 180.760656 -96.432878) (xy 180.696626 -97.663)
			(xy 182.980582 -97.663) (xy 182.984653 -97.607378) (xy 182.996779 -97.552941) (xy 183.016702 -97.50085)
			(xy 183.043998 -97.452215) (xy 183.078084 -97.408072) (xy 183.118233 -97.369363) (xy 183.163591 -97.336912)
			(xy 183.213191 -97.311411) (xy 183.265975 -97.293404) (xy 183.320818 -97.283274) (xy 183.376552 -97.281237)
			(xy 183.431989 -97.287337) (xy 183.485946 -97.301443) (xy 183.537275 -97.323255) (xy 183.584881 -97.352309)
			(xy 183.627749 -97.387984) (xy 183.664966 -97.429521) (xy 183.695739 -97.476034) (xy 183.719411 -97.526531)
			(xy 183.735479 -97.579938) (xy 183.743599 -97.635114) (xy 183.743691 -97.64014) (xy 190.017906 -97.64014)
			(xy 190.021977 -97.584518) (xy 190.034103 -97.530081) (xy 190.054026 -97.47799) (xy 190.081322 -97.429355)
			(xy 190.115408 -97.385212) (xy 190.155557 -97.346503) (xy 190.200915 -97.314052) (xy 190.250515 -97.288551)
			(xy 190.303299 -97.270544) (xy 190.358142 -97.260414) (xy 190.413876 -97.258377) (xy 190.469313 -97.264477)
			(xy 190.52327 -97.278583) (xy 190.574599 -97.300395) (xy 190.622205 -97.329449) (xy 190.665073 -97.365124)
			(xy 190.70229 -97.406661) (xy 190.733063 -97.453174) (xy 190.756735 -97.503671) (xy 190.772803 -97.557078)
			(xy 190.780923 -97.612254) (xy 190.781432 -97.64014) (xy 190.780923 -97.668026) (xy 190.772803 -97.723202)
			(xy 190.756735 -97.776609) (xy 190.733063 -97.827106) (xy 190.70229 -97.873619) (xy 190.665073 -97.915156)
			(xy 190.622205 -97.950831) (xy 190.574599 -97.979885) (xy 190.52327 -98.001697) (xy 190.469313 -98.015803)
			(xy 190.413876 -98.021903) (xy 190.358142 -98.019866) (xy 190.303299 -98.009736) (xy 190.250515 -97.991729)
			(xy 190.200915 -97.966228) (xy 190.155557 -97.933777) (xy 190.115408 -97.895068) (xy 190.081322 -97.850925)
			(xy 190.054026 -97.80229) (xy 190.034103 -97.750199) (xy 190.021977 -97.695762) (xy 190.017906 -97.64014)
			(xy 183.743691 -97.64014) (xy 183.744108 -97.663) (xy 183.743599 -97.690886) (xy 183.735479 -97.746062)
			(xy 183.719411 -97.799469) (xy 183.695739 -97.849966) (xy 183.664966 -97.896479) (xy 183.627749 -97.938016)
			(xy 183.584881 -97.973691) (xy 183.537275 -98.002745) (xy 183.485946 -98.024557) (xy 183.431989 -98.038663)
			(xy 183.376552 -98.044763) (xy 183.320818 -98.042726) (xy 183.265975 -98.032596) (xy 183.213191 -98.014589)
			(xy 183.163591 -97.989088) (xy 183.118233 -97.956637) (xy 183.078084 -97.917928) (xy 183.043998 -97.873785)
			(xy 183.016702 -97.82515) (xy 182.996779 -97.773059) (xy 182.984653 -97.718622) (xy 182.980582 -97.663)
			(xy 180.696626 -97.663) (xy 180.670184 -98.171) (xy 191.663826 -98.171) (xy 191.667897 -98.115378)
			(xy 191.680023 -98.060941) (xy 191.699946 -98.00885) (xy 191.727242 -97.960215) (xy 191.761328 -97.916072)
			(xy 191.801477 -97.877363) (xy 191.846835 -97.844912) (xy 191.896435 -97.819411) (xy 191.949219 -97.801404)
			(xy 192.004062 -97.791274) (xy 192.059796 -97.789237) (xy 192.115233 -97.795337) (xy 192.16919 -97.809443)
			(xy 192.220519 -97.831255) (xy 192.268125 -97.860309) (xy 192.310993 -97.895984) (xy 192.34821 -97.937521)
			(xy 192.378983 -97.984034) (xy 192.402655 -98.034531) (xy 192.418723 -98.087938) (xy 192.426843 -98.143114)
			(xy 192.427352 -98.171) (xy 192.426843 -98.198886) (xy 192.418723 -98.254062) (xy 192.402655 -98.307469)
			(xy 192.378983 -98.357966) (xy 192.34821 -98.404479) (xy 192.310993 -98.446016) (xy 192.268125 -98.481691)
			(xy 192.220519 -98.510745) (xy 192.16919 -98.532557) (xy 192.115233 -98.546663) (xy 192.059796 -98.552763)
			(xy 192.004062 -98.550726) (xy 191.949219 -98.540596) (xy 191.896435 -98.522589) (xy 191.846835 -98.497088)
			(xy 191.801477 -98.464637) (xy 191.761328 -98.425928) (xy 191.727242 -98.381785) (xy 191.699946 -98.33315)
			(xy 191.680023 -98.281059) (xy 191.667897 -98.226622) (xy 191.663826 -98.171) (xy 180.670184 -98.171)
			(xy 180.604131 -99.439984) (xy 183.371742 -99.439984) (xy 183.375813 -99.384362) (xy 183.387939 -99.329925)
			(xy 183.407862 -99.277834) (xy 183.435158 -99.229199) (xy 183.469244 -99.185056) (xy 183.509393 -99.146347)
			(xy 183.554751 -99.113896) (xy 183.604351 -99.088395) (xy 183.657135 -99.070388) (xy 183.711978 -99.060258)
			(xy 183.767712 -99.058221) (xy 183.823149 -99.064321) (xy 183.877106 -99.078427) (xy 183.928435 -99.100239)
			(xy 183.976041 -99.129293) (xy 184.018909 -99.164968) (xy 184.056126 -99.206505) (xy 184.086899 -99.253018)
			(xy 184.110571 -99.303515) (xy 184.126639 -99.356922) (xy 184.134759 -99.412098) (xy 184.135268 -99.439984)
			(xy 191.409826 -99.439984) (xy 191.413897 -99.384362) (xy 191.426023 -99.329925) (xy 191.445946 -99.277834)
			(xy 191.473242 -99.229199) (xy 191.507328 -99.185056) (xy 191.547477 -99.146347) (xy 191.592835 -99.113896)
			(xy 191.642435 -99.088395) (xy 191.695219 -99.070388) (xy 191.750062 -99.060258) (xy 191.805796 -99.058221)
			(xy 191.861233 -99.064321) (xy 191.91519 -99.078427) (xy 191.966519 -99.100239) (xy 192.014125 -99.129293)
			(xy 192.056993 -99.164968) (xy 192.09421 -99.206505) (xy 192.124983 -99.253018) (xy 192.148655 -99.303515)
			(xy 192.164723 -99.356922) (xy 192.172843 -99.412098) (xy 192.173352 -99.439984) (xy 192.172843 -99.46787)
			(xy 192.164723 -99.523046) (xy 192.148655 -99.576453) (xy 192.124983 -99.62695) (xy 192.09421 -99.673463)
			(xy 192.056993 -99.715) (xy 192.014125 -99.750675) (xy 191.966519 -99.779729) (xy 191.91519 -99.801541)
			(xy 191.861233 -99.815647) (xy 191.805796 -99.821747) (xy 191.750062 -99.81971) (xy 191.695219 -99.80958)
			(xy 191.642435 -99.791573) (xy 191.592835 -99.766072) (xy 191.547477 -99.733621) (xy 191.507328 -99.694912)
			(xy 191.473242 -99.650769) (xy 191.445946 -99.602134) (xy 191.426023 -99.550043) (xy 191.413897 -99.495606)
			(xy 191.409826 -99.439984) (xy 184.135268 -99.439984) (xy 184.134759 -99.46787) (xy 184.126639 -99.523046)
			(xy 184.110571 -99.576453) (xy 184.086899 -99.62695) (xy 184.056126 -99.673463) (xy 184.018909 -99.715)
			(xy 183.976041 -99.750675) (xy 183.928435 -99.779729) (xy 183.877106 -99.801541) (xy 183.823149 -99.815647)
			(xy 183.767712 -99.821747) (xy 183.711978 -99.81971) (xy 183.657135 -99.80958) (xy 183.604351 -99.791573)
			(xy 183.554751 -99.766072) (xy 183.509393 -99.733621) (xy 183.469244 -99.694912) (xy 183.435158 -99.650769)
			(xy 183.407862 -99.602134) (xy 183.387939 -99.550043) (xy 183.375813 -99.495606) (xy 183.371742 -99.439984)
			(xy 180.604131 -99.439984) (xy 180.575877 -99.982782) (xy 186.221876 -99.982782) (xy 186.225947 -99.92716)
			(xy 186.238073 -99.872723) (xy 186.257996 -99.820632) (xy 186.285292 -99.771997) (xy 186.319378 -99.727854)
			(xy 186.359527 -99.689145) (xy 186.404885 -99.656694) (xy 186.454485 -99.631193) (xy 186.507269 -99.613186)
			(xy 186.562112 -99.603056) (xy 186.617846 -99.601019) (xy 186.673283 -99.607119) (xy 186.72724 -99.621225)
			(xy 186.778569 -99.643037) (xy 186.826175 -99.672091) (xy 186.869043 -99.707766) (xy 186.90626 -99.749303)
			(xy 186.937033 -99.795816) (xy 186.960705 -99.846313) (xy 186.976773 -99.89972) (xy 186.984893 -99.954896)
			(xy 186.985402 -99.982782) (xy 186.984893 -100.010668) (xy 186.980586 -100.039932) (xy 189.976758 -100.039932)
			(xy 189.980829 -99.98431) (xy 189.992955 -99.929873) (xy 190.012878 -99.877782) (xy 190.040174 -99.829147)
			(xy 190.07426 -99.785004) (xy 190.114409 -99.746295) (xy 190.159767 -99.713844) (xy 190.209367 -99.688343)
			(xy 190.262151 -99.670336) (xy 190.316994 -99.660206) (xy 190.372728 -99.658169) (xy 190.428165 -99.664269)
			(xy 190.482122 -99.678375) (xy 190.533451 -99.700187) (xy 190.581057 -99.729241) (xy 190.623925 -99.764916)
			(xy 190.661142 -99.806453) (xy 190.691915 -99.852966) (xy 190.715587 -99.903463) (xy 190.731655 -99.95687)
			(xy 190.739775 -100.012046) (xy 190.740284 -100.039932) (xy 190.739775 -100.067818) (xy 190.731655 -100.122994)
			(xy 190.715587 -100.176401) (xy 190.691915 -100.226898) (xy 190.661142 -100.273411) (xy 190.623925 -100.314948)
			(xy 190.581057 -100.350623) (xy 190.533451 -100.379677) (xy 190.482122 -100.401489) (xy 190.428165 -100.415595)
			(xy 190.372728 -100.421695) (xy 190.316994 -100.419658) (xy 190.262151 -100.409528) (xy 190.209367 -100.391521)
			(xy 190.159767 -100.36602) (xy 190.114409 -100.333569) (xy 190.07426 -100.29486) (xy 190.040174 -100.250717)
			(xy 190.012878 -100.202082) (xy 189.992955 -100.149991) (xy 189.980829 -100.095554) (xy 189.976758 -100.039932)
			(xy 186.980586 -100.039932) (xy 186.976773 -100.065844) (xy 186.960705 -100.119251) (xy 186.937033 -100.169748)
			(xy 186.90626 -100.216261) (xy 186.869043 -100.257798) (xy 186.826175 -100.293473) (xy 186.778569 -100.322527)
			(xy 186.72724 -100.344339) (xy 186.673283 -100.358445) (xy 186.617846 -100.364545) (xy 186.562112 -100.362508)
			(xy 186.507269 -100.352378) (xy 186.454485 -100.334371) (xy 186.404885 -100.30887) (xy 186.359527 -100.276419)
			(xy 186.319378 -100.23771) (xy 186.285292 -100.193567) (xy 186.257996 -100.144932) (xy 186.238073 -100.092841)
			(xy 186.225947 -100.038404) (xy 186.221876 -99.982782) (xy 180.575877 -99.982782) (xy 180.510432 -101.240082)
			(xy 183.371742 -101.240082) (xy 183.375813 -101.18446) (xy 183.387939 -101.130023) (xy 183.407862 -101.077932)
			(xy 183.435158 -101.029297) (xy 183.469244 -100.985154) (xy 183.509393 -100.946445) (xy 183.554751 -100.913994)
			(xy 183.604351 -100.888493) (xy 183.657135 -100.870486) (xy 183.711978 -100.860356) (xy 183.767712 -100.858319)
			(xy 183.823149 -100.864419) (xy 183.877106 -100.878525) (xy 183.928435 -100.900337) (xy 183.976041 -100.929391)
			(xy 184.018909 -100.965066) (xy 184.056126 -101.006603) (xy 184.086899 -101.053116) (xy 184.110571 -101.103613)
			(xy 184.126639 -101.15702) (xy 184.134759 -101.212196) (xy 184.135268 -101.240082) (xy 190.393826 -101.240082)
			(xy 190.397897 -101.18446) (xy 190.410023 -101.130023) (xy 190.429946 -101.077932) (xy 190.457242 -101.029297)
			(xy 190.491328 -100.985154) (xy 190.531477 -100.946445) (xy 190.576835 -100.913994) (xy 190.626435 -100.888493)
			(xy 190.679219 -100.870486) (xy 190.734062 -100.860356) (xy 190.789796 -100.858319) (xy 190.845233 -100.864419)
			(xy 190.89919 -100.878525) (xy 190.950519 -100.900337) (xy 190.998125 -100.929391) (xy 191.040993 -100.965066)
			(xy 191.07821 -101.006603) (xy 191.108983 -101.053116) (xy 191.116733 -101.069648) (xy 191.686178 -101.069648)
			(xy 191.690249 -101.014026) (xy 191.702375 -100.959589) (xy 191.722298 -100.907498) (xy 191.749594 -100.858863)
			(xy 191.78368 -100.81472) (xy 191.823829 -100.776011) (xy 191.869187 -100.74356) (xy 191.918787 -100.718059)
			(xy 191.971571 -100.700052) (xy 192.026414 -100.689922) (xy 192.082148 -100.687885) (xy 192.137585 -100.693985)
			(xy 192.191542 -100.708091) (xy 192.242871 -100.729903) (xy 192.290477 -100.758957) (xy 192.333345 -100.794632)
			(xy 192.370562 -100.836169) (xy 192.401335 -100.882682) (xy 192.425007 -100.933179) (xy 192.441075 -100.986586)
			(xy 192.449195 -101.041762) (xy 192.449704 -101.069648) (xy 192.449195 -101.097534) (xy 192.441075 -101.15271)
			(xy 192.425007 -101.206117) (xy 192.401335 -101.256614) (xy 192.370562 -101.303127) (xy 192.333345 -101.344664)
			(xy 192.290477 -101.380339) (xy 192.242871 -101.409393) (xy 192.191542 -101.431205) (xy 192.137585 -101.445311)
			(xy 192.082148 -101.451411) (xy 192.026414 -101.449374) (xy 191.971571 -101.439244) (xy 191.918787 -101.421237)
			(xy 191.869187 -101.395736) (xy 191.823829 -101.363285) (xy 191.78368 -101.324576) (xy 191.749594 -101.280433)
			(xy 191.722298 -101.231798) (xy 191.702375 -101.179707) (xy 191.690249 -101.12527) (xy 191.686178 -101.069648)
			(xy 191.116733 -101.069648) (xy 191.132655 -101.103613) (xy 191.148723 -101.15702) (xy 191.156843 -101.212196)
			(xy 191.157352 -101.240082) (xy 191.156843 -101.267968) (xy 191.148723 -101.323144) (xy 191.132655 -101.376551)
			(xy 191.108983 -101.427048) (xy 191.07821 -101.473561) (xy 191.040993 -101.515098) (xy 190.998125 -101.550773)
			(xy 190.950519 -101.579827) (xy 190.89919 -101.601639) (xy 190.845233 -101.615745) (xy 190.789796 -101.621845)
			(xy 190.734062 -101.619808) (xy 190.679219 -101.609678) (xy 190.626435 -101.591671) (xy 190.576835 -101.56617)
			(xy 190.531477 -101.533719) (xy 190.491328 -101.49501) (xy 190.457242 -101.450867) (xy 190.429946 -101.402232)
			(xy 190.410023 -101.350141) (xy 190.397897 -101.295704) (xy 190.393826 -101.240082) (xy 184.135268 -101.240082)
			(xy 184.134759 -101.267968) (xy 184.126639 -101.323144) (xy 184.110571 -101.376551) (xy 184.086899 -101.427048)
			(xy 184.056126 -101.473561) (xy 184.018909 -101.515098) (xy 183.976041 -101.550773) (xy 183.928435 -101.579827)
			(xy 183.877106 -101.601639) (xy 183.823149 -101.615745) (xy 183.767712 -101.621845) (xy 183.711978 -101.619808)
			(xy 183.657135 -101.609678) (xy 183.604351 -101.591671) (xy 183.554751 -101.56617) (xy 183.509393 -101.533719)
			(xy 183.469244 -101.49501) (xy 183.435158 -101.450867) (xy 183.407862 -101.402232) (xy 183.387939 -101.350141)
			(xy 183.375813 -101.295704) (xy 183.371742 -101.240082) (xy 180.510432 -101.240082) (xy 180.434397 -102.700836)
			(xy 181.842662 -102.700836) (xy 181.846733 -102.645214) (xy 181.858859 -102.590777) (xy 181.878782 -102.538686)
			(xy 181.906078 -102.490051) (xy 181.940164 -102.445908) (xy 181.980313 -102.407199) (xy 182.025671 -102.374748)
			(xy 182.075271 -102.349247) (xy 182.128055 -102.33124) (xy 182.182898 -102.32111) (xy 182.238632 -102.319073)
			(xy 182.294069 -102.325173) (xy 182.348026 -102.339279) (xy 182.399355 -102.361091) (xy 182.446961 -102.390145)
			(xy 182.489829 -102.42582) (xy 182.527046 -102.467357) (xy 182.541365 -102.489) (xy 190.901826 -102.489)
			(xy 190.905897 -102.433378) (xy 190.918023 -102.378941) (xy 190.937946 -102.32685) (xy 190.965242 -102.278215)
			(xy 190.999328 -102.234072) (xy 191.039477 -102.195363) (xy 191.084835 -102.162912) (xy 191.134435 -102.137411)
			(xy 191.187219 -102.119404) (xy 191.242062 -102.109274) (xy 191.297796 -102.107237) (xy 191.353233 -102.113337)
			(xy 191.40719 -102.127443) (xy 191.458519 -102.149255) (xy 191.506125 -102.178309) (xy 191.548993 -102.213984)
			(xy 191.58621 -102.255521) (xy 191.616983 -102.302034) (xy 191.640655 -102.352531) (xy 191.656723 -102.405938)
			(xy 191.664843 -102.461114) (xy 191.665352 -102.489) (xy 191.664843 -102.516886) (xy 191.656723 -102.572062)
			(xy 191.640655 -102.625469) (xy 191.616983 -102.675966) (xy 191.58621 -102.722479) (xy 191.548993 -102.764016)
			(xy 191.506125 -102.799691) (xy 191.458519 -102.828745) (xy 191.40719 -102.850557) (xy 191.353233 -102.864663)
			(xy 191.297796 -102.870763) (xy 191.242062 -102.868726) (xy 191.187219 -102.858596) (xy 191.134435 -102.840589)
			(xy 191.084835 -102.815088) (xy 191.039477 -102.782637) (xy 190.999328 -102.743928) (xy 190.965242 -102.699785)
			(xy 190.937946 -102.65115) (xy 190.918023 -102.599059) (xy 190.905897 -102.544622) (xy 190.901826 -102.489)
			(xy 182.541365 -102.489) (xy 182.557819 -102.51387) (xy 182.581491 -102.564367) (xy 182.597559 -102.617774)
			(xy 182.605679 -102.67295) (xy 182.606188 -102.700836) (xy 182.605679 -102.728722) (xy 182.597559 -102.783898)
			(xy 182.581491 -102.837305) (xy 182.557819 -102.887802) (xy 182.527046 -102.934315) (xy 182.489829 -102.975852)
			(xy 182.446961 -103.011527) (xy 182.399355 -103.040581) (xy 182.348026 -103.062393) (xy 182.294069 -103.076499)
			(xy 182.238632 -103.082599) (xy 182.182898 -103.080562) (xy 182.128055 -103.070432) (xy 182.075271 -103.052425)
			(xy 182.025671 -103.026924) (xy 181.980313 -102.994473) (xy 181.940164 -102.955764) (xy 181.906078 -102.911621)
			(xy 181.878782 -102.862986) (xy 181.858859 -102.810895) (xy 181.846733 -102.756458) (xy 181.842662 -102.700836)
			(xy 180.434397 -102.700836) (xy 180.372707 -103.886) (xy 191.409826 -103.886) (xy 191.413897 -103.830378)
			(xy 191.426023 -103.775941) (xy 191.445946 -103.72385) (xy 191.473242 -103.675215) (xy 191.507328 -103.631072)
			(xy 191.547477 -103.592363) (xy 191.592835 -103.559912) (xy 191.642435 -103.534411) (xy 191.695219 -103.516404)
			(xy 191.750062 -103.506274) (xy 191.805796 -103.504237) (xy 191.861233 -103.510337) (xy 191.91519 -103.524443)
			(xy 191.966519 -103.546255) (xy 192.014125 -103.575309) (xy 192.056993 -103.610984) (xy 192.09421 -103.652521)
			(xy 192.124983 -103.699034) (xy 192.148655 -103.749531) (xy 192.164723 -103.802938) (xy 192.172843 -103.858114)
			(xy 192.173352 -103.886) (xy 192.172843 -103.913886) (xy 192.164723 -103.969062) (xy 192.148655 -104.022469)
			(xy 192.124983 -104.072966) (xy 192.09421 -104.119479) (xy 192.056993 -104.161016) (xy 192.014125 -104.196691)
			(xy 191.966519 -104.225745) (xy 191.91519 -104.247557) (xy 191.861233 -104.261663) (xy 191.805796 -104.267763)
			(xy 191.750062 -104.265726) (xy 191.695219 -104.255596) (xy 191.642435 -104.237589) (xy 191.592835 -104.212088)
			(xy 191.547477 -104.179637) (xy 191.507328 -104.140928) (xy 191.473242 -104.096785) (xy 191.445946 -104.04815)
			(xy 191.426023 -103.996059) (xy 191.413897 -103.941622) (xy 191.409826 -103.886) (xy 180.372707 -103.886)
			(xy 180.346741 -104.384856) (xy 181.762652 -104.384856) (xy 181.766723 -104.329234) (xy 181.778849 -104.274797)
			(xy 181.798772 -104.222706) (xy 181.826068 -104.174071) (xy 181.860154 -104.129928) (xy 181.900303 -104.091219)
			(xy 181.945661 -104.058768) (xy 181.995261 -104.033267) (xy 182.048045 -104.01526) (xy 182.102888 -104.00513)
			(xy 182.158622 -104.003093) (xy 182.214059 -104.009193) (xy 182.268016 -104.023299) (xy 182.319345 -104.045111)
			(xy 182.366951 -104.074165) (xy 182.409819 -104.10984) (xy 182.447036 -104.151377) (xy 182.477809 -104.19789)
			(xy 182.501481 -104.248387) (xy 182.517549 -104.301794) (xy 182.525669 -104.35697) (xy 182.526178 -104.384856)
			(xy 182.525669 -104.412742) (xy 182.517549 -104.467918) (xy 182.501481 -104.521325) (xy 182.477809 -104.571822)
			(xy 182.447036 -104.618335) (xy 182.409819 -104.659872) (xy 182.366951 -104.695547) (xy 182.319345 -104.724601)
			(xy 182.268016 -104.746413) (xy 182.214059 -104.760519) (xy 182.158622 -104.766619) (xy 182.102888 -104.764582)
			(xy 182.048045 -104.754452) (xy 181.995261 -104.736445) (xy 181.945661 -104.710944) (xy 181.900303 -104.678493)
			(xy 181.860154 -104.639784) (xy 181.826068 -104.595641) (xy 181.798772 -104.547006) (xy 181.778849 -104.494915)
			(xy 181.766723 -104.440478) (xy 181.762652 -104.384856) (xy 180.346741 -104.384856) (xy 179.985023 -111.334042)
			(xy 180.363874 -111.334042) (xy 180.367945 -111.27842) (xy 180.380071 -111.223983) (xy 180.399994 -111.171892)
			(xy 180.42729 -111.123257) (xy 180.461376 -111.079114) (xy 180.501525 -111.040405) (xy 180.546883 -111.007954)
			(xy 180.596483 -110.982453) (xy 180.649267 -110.964446) (xy 180.70411 -110.954316) (xy 180.759844 -110.952279)
			(xy 180.815281 -110.958379) (xy 180.869238 -110.972485) (xy 180.920567 -110.994297) (xy 180.968173 -111.023351)
			(xy 181.011041 -111.059026) (xy 181.048258 -111.100563) (xy 181.079031 -111.147076) (xy 181.102703 -111.197573)
			(xy 181.118771 -111.25098) (xy 181.126891 -111.306156) (xy 181.1274 -111.334042) (xy 181.126891 -111.361928)
			(xy 181.118771 -111.417104) (xy 181.102703 -111.470511) (xy 181.079031 -111.521008) (xy 181.048258 -111.567521)
			(xy 181.011041 -111.609058) (xy 180.968173 -111.644733) (xy 180.920567 -111.673787) (xy 180.869238 -111.695599)
			(xy 180.815281 -111.709705) (xy 180.759844 -111.715805) (xy 180.70411 -111.713768) (xy 180.649267 -111.703638)
			(xy 180.596483 -111.685631) (xy 180.546883 -111.66013) (xy 180.501525 -111.627679) (xy 180.461376 -111.58897)
			(xy 180.42729 -111.544827) (xy 180.399994 -111.496192) (xy 180.380071 -111.444101) (xy 180.367945 -111.389664)
			(xy 180.363874 -111.334042) (xy 179.985023 -111.334042) (xy 179.952142 -111.96574) (xy 179.952142 -111.980726)
			(xy 190.001398 -111.980726) (xy 190.001938 -111.951988) (xy 190.010557 -111.895161) (xy 190.027603 -111.840271)
			(xy 190.052691 -111.788559) (xy 190.085253 -111.741195) (xy 190.104522 -111.719868) (xy 190.111126 -111.71301)
			(xy 190.118238 -111.694976) (xy 190.118238 -111.606076) (xy 190.111126 -111.588042) (xy 190.104522 -111.581184)
			(xy 190.085277 -111.559835) (xy 190.052711 -111.512476) (xy 190.027618 -111.460768) (xy 190.010566 -111.405881)
			(xy 190.001941 -111.349056) (xy 190.001939 -111.291581) (xy 190.010558 -111.234756) (xy 190.027604 -111.179867)
			(xy 190.052692 -111.128157) (xy 190.085253 -111.080795) (xy 190.104522 -111.059468) (xy 190.111126 -111.05261)
			(xy 190.118238 -111.034576) (xy 190.118238 -110.945676) (xy 190.111126 -110.927642) (xy 190.104522 -110.920784)
			(xy 190.085277 -110.899435) (xy 190.052711 -110.852076) (xy 190.027618 -110.800368) (xy 190.010566 -110.745481)
			(xy 190.001941 -110.688656) (xy 190.001939 -110.631181) (xy 190.010558 -110.574356) (xy 190.027604 -110.519467)
			(xy 190.052692 -110.467757) (xy 190.085253 -110.420395) (xy 190.104522 -110.399068) (xy 190.111126 -110.39221)
			(xy 190.118238 -110.374176) (xy 190.118238 -110.285276) (xy 190.111126 -110.267242) (xy 190.104522 -110.260384)
			(xy 190.085277 -110.239035) (xy 190.052711 -110.191676) (xy 190.027618 -110.139968) (xy 190.010566 -110.085081)
			(xy 190.001941 -110.028256) (xy 190.001939 -109.970781) (xy 190.010558 -109.913956) (xy 190.027604 -109.859067)
			(xy 190.052692 -109.807357) (xy 190.085253 -109.759995) (xy 190.104522 -109.738668) (xy 190.111126 -109.73181)
			(xy 190.118238 -109.713776) (xy 190.118238 -109.624876) (xy 190.111126 -109.606842) (xy 190.104522 -109.599984)
			(xy 190.085261 -109.578649) (xy 190.052694 -109.531289) (xy 190.0276 -109.479579) (xy 190.010547 -109.42469)
			(xy 190.001921 -109.367864) (xy 190.001398 -109.339126) (xy 190.00188 -109.311874) (xy 190.009633 -109.257923)
			(xy 190.024986 -109.205625) (xy 190.047626 -109.156045) (xy 190.077092 -109.110191) (xy 190.112784 -109.068998)
			(xy 190.153975 -109.033304) (xy 190.199827 -109.003836) (xy 190.249406 -108.981193) (xy 190.301703 -108.965837)
			(xy 190.355654 -108.958081) (xy 190.382906 -108.957618) (xy 190.40922 -108.958076) (xy 190.46135 -108.965312)
			(xy 190.511993 -108.979632) (xy 190.560192 -109.000767) (xy 190.605035 -109.028315) (xy 190.645674 -109.061755)
			(xy 190.66383 -109.080808) (xy 190.671338 -109.088226) (xy 190.690628 -109.09674) (xy 190.701168 -109.097318)
			(xy 190.775844 -109.097318) (xy 190.786391 -109.096767) (xy 190.805686 -109.088247) (xy 190.813182 -109.080808)
			(xy 190.831355 -109.06177) (xy 190.871981 -109.028311) (xy 190.916817 -109.000749) (xy 190.965015 -108.979608)
			(xy 191.015659 -108.965287) (xy 191.067791 -108.958058) (xy 191.094106 -108.957618) (xy 191.12136 -108.95805)
			(xy 191.175314 -108.965808) (xy 191.227614 -108.981166) (xy 191.277195 -109.003811) (xy 191.32305 -109.033283)
			(xy 191.364243 -109.06898) (xy 191.399937 -109.110176) (xy 191.429404 -109.156033) (xy 191.452045 -109.205616)
			(xy 191.467399 -109.257918) (xy 191.475152 -109.311872) (xy 191.475614 -109.339126) (xy 191.475102 -109.367865)
			(xy 191.466476 -109.424693) (xy 191.449423 -109.479584) (xy 191.424329 -109.531295) (xy 191.391762 -109.578657)
			(xy 191.37249 -109.599984) (xy 191.365886 -109.606842) (xy 191.358774 -109.624876) (xy 191.358774 -109.713776)
			(xy 191.365886 -109.73181) (xy 191.37249 -109.738668) (xy 191.391786 -109.759973) (xy 191.424349 -109.807339)
			(xy 191.449438 -109.859055) (xy 191.466486 -109.913949) (xy 191.475106 -109.970779) (xy 191.475103 -110.028259)
			(xy 191.466477 -110.085088) (xy 191.449424 -110.13998) (xy 191.42433 -110.191693) (xy 191.391762 -110.239057)
			(xy 191.37249 -110.260384) (xy 191.365886 -110.267242) (xy 191.358774 -110.285276) (xy 191.358774 -110.374176)
			(xy 191.365886 -110.39221) (xy 191.37249 -110.399068) (xy 191.391786 -110.420373) (xy 191.424349 -110.467739)
			(xy 191.449438 -110.519455) (xy 191.466486 -110.574349) (xy 191.475106 -110.631179) (xy 191.475103 -110.688659)
			(xy 191.466477 -110.745488) (xy 191.449424 -110.80038) (xy 191.42433 -110.852093) (xy 191.391762 -110.899457)
			(xy 191.37249 -110.920784) (xy 191.365886 -110.927642) (xy 191.358774 -110.945676) (xy 191.358774 -111.034576)
			(xy 191.365886 -111.05261) (xy 191.37249 -111.059468) (xy 191.391786 -111.080773) (xy 191.424349 -111.128139)
			(xy 191.449438 -111.179855) (xy 191.466486 -111.234749) (xy 191.475106 -111.291579) (xy 191.475103 -111.349059)
			(xy 191.466477 -111.405888) (xy 191.449424 -111.46078) (xy 191.42433 -111.512493) (xy 191.391762 -111.559857)
			(xy 191.37249 -111.581184) (xy 191.365886 -111.588042) (xy 191.358774 -111.606076) (xy 191.358774 -111.694976)
			(xy 191.365886 -111.71301) (xy 191.37249 -111.719868) (xy 191.391778 -111.74118) (xy 191.424341 -111.788547)
			(xy 191.449429 -111.840262) (xy 191.466476 -111.895156) (xy 191.475095 -111.951986) (xy 191.475614 -111.980726)
			(xy 191.475146 -112.007978) (xy 191.467387 -112.061926) (xy 191.452028 -112.11422) (xy 191.429385 -112.163797)
			(xy 191.399916 -112.209647) (xy 191.364223 -112.250837) (xy 191.323031 -112.286528) (xy 191.27718 -112.315994)
			(xy 191.227602 -112.338635) (xy 191.175306 -112.353991) (xy 191.121358 -112.361748) (xy 191.094106 -112.362234)
			(xy 191.067793 -112.361752) (xy 191.015665 -112.354518) (xy 190.965023 -112.340201) (xy 190.916824 -112.319072)
			(xy 190.87198 -112.291529) (xy 190.83134 -112.258094) (xy 190.813182 -112.239044) (xy 190.805663 -112.231639)
			(xy 190.786381 -112.223115) (xy 190.775844 -112.222534) (xy 190.701168 -112.222534) (xy 190.69062 -112.223076)
			(xy 190.671323 -112.231601) (xy 190.66383 -112.239044) (xy 190.645661 -112.258086) (xy 190.605034 -112.291543)
			(xy 190.560196 -112.319103) (xy 190.511998 -112.340243) (xy 190.461353 -112.354564) (xy 190.409221 -112.361793)
			(xy 190.382906 -112.362234) (xy 190.355656 -112.361717) (xy 190.301711 -112.353962) (xy 190.249418 -112.338609)
			(xy 190.199843 -112.31597) (xy 190.153994 -112.286507) (xy 190.112804 -112.250819) (xy 190.077112 -112.209632)
			(xy 190.047645 -112.163785) (xy 190.025003 -112.114212) (xy 190.009645 -112.06192) (xy 190.001886 -112.007976)
			(xy 190.001398 -111.980726) (xy 179.952142 -111.980726) (xy 179.952142 -112.09782) (xy 179.954174 -112.104678)
			(xy 179.954682 -112.10671) (xy 179.956153 -112.111588) (xy 179.960767 -112.120669) (xy 179.963826 -112.124744)
			(xy 179.970176 -112.132618) (xy 179.99456 -112.145826) (xy 179.994814 -112.14608) (xy 180.01488 -112.158018)
			(xy 180.020214 -112.16132) (xy 180.025802 -112.164622) (xy 180.041804 -112.174782) (xy 180.045616 -112.176909)
			(xy 180.053791 -112.179966) (xy 180.05806 -112.180878) (xy 180.058568 -112.180878) (xy 180.067712 -112.181894)
			(xy 180.07711 -112.181894) (xy 180.090826 -112.179608) (xy 180.101748 -112.175798) (xy 180.10378 -112.174782)
			(xy 180.108098 -112.172242) (xy 180.108352 -112.172242) (xy 180.11013 -112.171226) (xy 180.118258 -112.167162)
			(xy 180.144224 -112.155247) (xy 180.198813 -112.138401) (xy 180.255302 -112.129872) (xy 180.283866 -112.129316)
			(xy 180.487066 -112.129316) (xy 180.497929 -112.129891) (xy 180.51768 -112.138957) (xy 180.531966 -112.155335)
			(xy 180.538266 -112.176134) (xy 180.537358 -112.186974) (xy 180.536342 -112.194594) (xy 180.53812 -112.206532)
			(xy 180.543962 -112.220756) (xy 180.543962 -112.22101) (xy 180.545232 -112.224312) (xy 180.548788 -112.232694)
			(xy 180.55082 -112.23752) (xy 180.557678 -112.244632) (xy 180.577852 -112.266131) (xy 180.611999 -112.31419)
			(xy 180.638346 -112.366929) (xy 180.656266 -112.423094) (xy 180.665332 -112.481347) (xy 180.665408 -112.485424)
			(xy 182.750966 -112.485424) (xy 182.755037 -112.429802) (xy 182.767163 -112.375365) (xy 182.787086 -112.323274)
			(xy 182.814382 -112.274639) (xy 182.848468 -112.230496) (xy 182.888617 -112.191787) (xy 182.933975 -112.159336)
			(xy 182.983575 -112.133835) (xy 183.036359 -112.115828) (xy 183.091202 -112.105698) (xy 183.146936 -112.103661)
			(xy 183.202373 -112.109761) (xy 183.25633 -112.123867) (xy 183.307659 -112.145679) (xy 183.355265 -112.174733)
			(xy 183.398133 -112.210408) (xy 183.43535 -112.251945) (xy 183.466123 -112.298458) (xy 183.489795 -112.348955)
			(xy 183.505863 -112.402362) (xy 183.508742 -112.421924) (xy 185.554872 -112.421924) (xy 185.558943 -112.366302)
			(xy 185.571069 -112.311865) (xy 185.590992 -112.259774) (xy 185.618288 -112.211139) (xy 185.652374 -112.166996)
			(xy 185.692523 -112.128287) (xy 185.737881 -112.095836) (xy 185.787481 -112.070335) (xy 185.840265 -112.052328)
			(xy 185.895108 -112.042198) (xy 185.950842 -112.040161) (xy 186.006279 -112.046261) (xy 186.060236 -112.060367)
			(xy 186.111565 -112.082179) (xy 186.159171 -112.111233) (xy 186.202039 -112.146908) (xy 186.239256 -112.188445)
			(xy 186.270029 -112.234958) (xy 186.293701 -112.285455) (xy 186.309769 -112.338862) (xy 186.317889 -112.394038)
			(xy 186.318398 -112.421924) (xy 186.317889 -112.44981) (xy 186.309769 -112.504986) (xy 186.293701 -112.558393)
			(xy 186.270029 -112.60889) (xy 186.239256 -112.655403) (xy 186.202039 -112.69694) (xy 186.159171 -112.732615)
			(xy 186.111565 -112.761669) (xy 186.060236 -112.783481) (xy 186.006279 -112.797587) (xy 185.950842 -112.803687)
			(xy 185.895108 -112.80165) (xy 185.840265 -112.79152) (xy 185.787481 -112.773513) (xy 185.737881 -112.748012)
			(xy 185.692523 -112.715561) (xy 185.652374 -112.676852) (xy 185.618288 -112.632709) (xy 185.590992 -112.584074)
			(xy 185.571069 -112.531983) (xy 185.558943 -112.477546) (xy 185.554872 -112.421924) (xy 183.508742 -112.421924)
			(xy 183.513983 -112.457538) (xy 183.514492 -112.485424) (xy 183.513983 -112.51331) (xy 183.505863 -112.568486)
			(xy 183.489795 -112.621893) (xy 183.466123 -112.67239) (xy 183.43535 -112.718903) (xy 183.398133 -112.76044)
			(xy 183.355265 -112.796115) (xy 183.307659 -112.825169) (xy 183.25633 -112.846981) (xy 183.202373 -112.861087)
			(xy 183.146936 -112.867187) (xy 183.091202 -112.86515) (xy 183.036359 -112.85502) (xy 182.983575 -112.837013)
			(xy 182.933975 -112.811512) (xy 182.888617 -112.779061) (xy 182.848468 -112.740352) (xy 182.814382 -112.696209)
			(xy 182.787086 -112.647574) (xy 182.767163 -112.595483) (xy 182.755037 -112.541046) (xy 182.750966 -112.485424)
			(xy 180.665408 -112.485424) (xy 180.665882 -112.510824) (xy 180.665383 -112.538563) (xy 180.657347 -112.593457)
			(xy 180.641449 -112.646609) (xy 180.618023 -112.696899) (xy 180.587564 -112.743268) (xy 180.550712 -112.784739)
			(xy 180.508244 -112.820438) (xy 180.461055 -112.849612) (xy 180.41014 -112.871646) (xy 180.356571 -112.886078)
			(xy 180.329078 -112.889792) (xy 180.307742 -112.892332) (xy 180.302662 -112.892586) (xy 180.28412 -112.892586)
			(xy 180.255531 -112.892057) (xy 180.198998 -112.883491) (xy 180.144374 -112.866592) (xy 180.09288 -112.841739)
			(xy 180.068982 -112.826038) (xy 180.062632 -112.82172) (xy 180.04663 -112.81664) (xy 180.046122 -112.81664)
			(xy 180.043074 -112.815116) (xy 180.030882 -112.814862) (xy 180.024899 -112.814905) (xy 180.013216 -112.81747)
			(xy 180.007768 -112.819942) (xy 179.98694 -112.830102) (xy 179.986432 -112.830102) (xy 179.928012 -112.859312)
			(xy 179.92217 -112.865154) (xy 179.921154 -112.86617) (xy 179.91328 -112.873028) (xy 179.908962 -112.881918)
			(xy 179.906807 -112.886601) (xy 179.904251 -112.896587) (xy 179.903882 -112.90173) (xy 179.88566 -113.251742)
			(xy 180.406038 -113.251742) (xy 180.410109 -113.19612) (xy 180.422235 -113.141683) (xy 180.442158 -113.089592)
			(xy 180.469454 -113.040957) (xy 180.50354 -112.996814) (xy 180.543689 -112.958105) (xy 180.589047 -112.925654)
			(xy 180.638647 -112.900153) (xy 180.691431 -112.882146) (xy 180.746274 -112.872016) (xy 180.802008 -112.869979)
			(xy 180.857445 -112.876079) (xy 180.911402 -112.890185) (xy 180.962731 -112.911997) (xy 181.010337 -112.941051)
			(xy 181.053205 -112.976726) (xy 181.090422 -113.018263) (xy 181.121195 -113.064776) (xy 181.144867 -113.115273)
			(xy 181.160935 -113.16868) (xy 181.169055 -113.223856) (xy 181.169564 -113.251742) (xy 181.169055 -113.279628)
			(xy 181.160935 -113.334804) (xy 181.144867 -113.388211) (xy 181.122872 -113.43513) (xy 183.03062 -113.43513)
			(xy 183.034691 -113.379508) (xy 183.046817 -113.325071) (xy 183.06674 -113.27298) (xy 183.094036 -113.224345)
			(xy 183.128122 -113.180202) (xy 183.168271 -113.141493) (xy 183.213629 -113.109042) (xy 183.263229 -113.083541)
			(xy 183.316013 -113.065534) (xy 183.370856 -113.055404) (xy 183.42659 -113.053367) (xy 183.482027 -113.059467)
			(xy 183.535984 -113.073573) (xy 183.587313 -113.095385) (xy 183.634919 -113.124439) (xy 183.677787 -113.160114)
			(xy 183.715004 -113.201651) (xy 183.745777 -113.248164) (xy 183.769449 -113.298661) (xy 183.785517 -113.352068)
			(xy 183.793637 -113.407244) (xy 183.794146 -113.43513) (xy 183.794095 -113.437924) (xy 185.53379 -113.437924)
			(xy 185.537861 -113.382302) (xy 185.549987 -113.327865) (xy 185.56991 -113.275774) (xy 185.597206 -113.227139)
			(xy 185.631292 -113.182996) (xy 185.671441 -113.144287) (xy 185.716799 -113.111836) (xy 185.766399 -113.086335)
			(xy 185.819183 -113.068328) (xy 185.874026 -113.058198) (xy 185.92976 -113.056161) (xy 185.985197 -113.062261)
			(xy 186.039154 -113.076367) (xy 186.090483 -113.098179) (xy 186.138089 -113.127233) (xy 186.180957 -113.162908)
			(xy 186.218174 -113.204445) (xy 186.248947 -113.250958) (xy 186.272619 -113.301455) (xy 186.288687 -113.354862)
			(xy 186.296807 -113.410038) (xy 186.297316 -113.437924) (xy 186.296807 -113.46581) (xy 186.288687 -113.520986)
			(xy 186.272619 -113.574393) (xy 186.248947 -113.62489) (xy 186.218174 -113.671403) (xy 186.180957 -113.71294)
			(xy 186.138089 -113.748615) (xy 186.090483 -113.777669) (xy 186.039154 -113.799481) (xy 185.985197 -113.813587)
			(xy 185.92976 -113.819687) (xy 185.874026 -113.81765) (xy 185.819183 -113.80752) (xy 185.766399 -113.789513)
			(xy 185.716799 -113.764012) (xy 185.671441 -113.731561) (xy 185.631292 -113.692852) (xy 185.597206 -113.648709)
			(xy 185.56991 -113.600074) (xy 185.549987 -113.547983) (xy 185.537861 -113.493546) (xy 185.53379 -113.437924)
			(xy 183.794095 -113.437924) (xy 183.793637 -113.463016) (xy 183.785517 -113.518192) (xy 183.769449 -113.571599)
			(xy 183.745777 -113.622096) (xy 183.715004 -113.668609) (xy 183.677787 -113.710146) (xy 183.634919 -113.745821)
			(xy 183.587313 -113.774875) (xy 183.535984 -113.796687) (xy 183.482027 -113.810793) (xy 183.42659 -113.816893)
			(xy 183.370856 -113.814856) (xy 183.316013 -113.804726) (xy 183.263229 -113.786719) (xy 183.213629 -113.761218)
			(xy 183.168271 -113.728767) (xy 183.128122 -113.690058) (xy 183.094036 -113.645915) (xy 183.06674 -113.59728)
			(xy 183.046817 -113.545189) (xy 183.034691 -113.490752) (xy 183.03062 -113.43513) (xy 181.122872 -113.43513)
			(xy 181.121195 -113.438708) (xy 181.090422 -113.485221) (xy 181.053205 -113.526758) (xy 181.010337 -113.562433)
			(xy 180.962731 -113.591487) (xy 180.911402 -113.613299) (xy 180.857445 -113.627405) (xy 180.802008 -113.633505)
			(xy 180.746274 -113.631468) (xy 180.691431 -113.621338) (xy 180.638647 -113.603331) (xy 180.589047 -113.57783)
			(xy 180.543689 -113.545379) (xy 180.50354 -113.50667) (xy 180.469454 -113.462527) (xy 180.442158 -113.413892)
			(xy 180.422235 -113.361801) (xy 180.410109 -113.307364) (xy 180.406038 -113.251742) (xy 179.88566 -113.251742)
			(xy 179.816435 -114.581432) (xy 182.39943 -114.581432) (xy 182.403501 -114.52581) (xy 182.415627 -114.471373)
			(xy 182.43555 -114.419282) (xy 182.462846 -114.370647) (xy 182.496932 -114.326504) (xy 182.537081 -114.287795)
			(xy 182.582439 -114.255344) (xy 182.632039 -114.229843) (xy 182.684823 -114.211836) (xy 182.739666 -114.201706)
			(xy 182.7954 -114.199669) (xy 182.850837 -114.205769) (xy 182.904794 -114.219875) (xy 182.956123 -114.241687)
			(xy 183.003729 -114.270741) (xy 183.026984 -114.290094) (xy 186.460128 -114.290094) (xy 186.464199 -114.234472)
			(xy 186.476325 -114.180035) (xy 186.496248 -114.127944) (xy 186.523544 -114.079309) (xy 186.55763 -114.035166)
			(xy 186.597779 -113.996457) (xy 186.643137 -113.964006) (xy 186.692737 -113.938505) (xy 186.745521 -113.920498)
			(xy 186.800364 -113.910368) (xy 186.856098 -113.908331) (xy 186.911535 -113.914431) (xy 186.965492 -113.928537)
			(xy 187.016821 -113.950349) (xy 187.064427 -113.979403) (xy 187.107295 -114.015078) (xy 187.144512 -114.056615)
			(xy 187.175285 -114.103128) (xy 187.198957 -114.153625) (xy 187.215025 -114.207032) (xy 187.223145 -114.262208)
			(xy 187.223654 -114.290094) (xy 187.223145 -114.31798) (xy 187.215025 -114.373156) (xy 187.198957 -114.426563)
			(xy 187.175285 -114.47706) (xy 187.144512 -114.523573) (xy 187.107295 -114.56511) (xy 187.064427 -114.600785)
			(xy 187.016821 -114.629839) (xy 186.965492 -114.651651) (xy 186.911535 -114.665757) (xy 186.856098 -114.671857)
			(xy 186.800364 -114.66982) (xy 186.745521 -114.65969) (xy 186.692737 -114.641683) (xy 186.643137 -114.616182)
			(xy 186.597779 -114.583731) (xy 186.55763 -114.545022) (xy 186.523544 -114.500879) (xy 186.496248 -114.452244)
			(xy 186.476325 -114.400153) (xy 186.464199 -114.345716) (xy 186.460128 -114.290094) (xy 183.026984 -114.290094)
			(xy 183.046597 -114.306416) (xy 183.083814 -114.347953) (xy 183.114587 -114.394466) (xy 183.138259 -114.444963)
			(xy 183.154327 -114.49837) (xy 183.162447 -114.553546) (xy 183.162956 -114.581432) (xy 183.162447 -114.609318)
			(xy 183.154327 -114.664494) (xy 183.138259 -114.717901) (xy 183.114587 -114.768398) (xy 183.083814 -114.814911)
			(xy 183.046597 -114.856448) (xy 183.003729 -114.892123) (xy 182.956123 -114.921177) (xy 182.904794 -114.942989)
			(xy 182.850837 -114.957095) (xy 182.7954 -114.963195) (xy 182.739666 -114.961158) (xy 182.684823 -114.951028)
			(xy 182.632039 -114.933021) (xy 182.582439 -114.90752) (xy 182.537081 -114.875069) (xy 182.496932 -114.83636)
			(xy 182.462846 -114.792217) (xy 182.43555 -114.743582) (xy 182.415627 -114.691491) (xy 182.403501 -114.637054)
			(xy 182.39943 -114.581432) (xy 179.816435 -114.581432) (xy 179.786788 -115.1509) (xy 179.779777 -115.285774)
			(xy 183.03062 -115.285774) (xy 183.034691 -115.230152) (xy 183.046817 -115.175715) (xy 183.06674 -115.123624)
			(xy 183.094036 -115.074989) (xy 183.128122 -115.030846) (xy 183.168271 -114.992137) (xy 183.213629 -114.959686)
			(xy 183.263229 -114.934185) (xy 183.316013 -114.916178) (xy 183.370856 -114.906048) (xy 183.42659 -114.904011)
			(xy 183.482027 -114.910111) (xy 183.535984 -114.924217) (xy 183.587313 -114.946029) (xy 183.634919 -114.975083)
			(xy 183.677787 -115.010758) (xy 183.715004 -115.052295) (xy 183.745777 -115.098808) (xy 183.769449 -115.149305)
			(xy 183.785517 -115.202712) (xy 183.793637 -115.257888) (xy 183.794146 -115.285774) (xy 183.793637 -115.31366)
			(xy 183.786676 -115.360958) (xy 190.218314 -115.360958) (xy 190.218811 -115.333589) (xy 190.226621 -115.279411)
			(xy 190.242102 -115.226908) (xy 190.264937 -115.177161) (xy 190.294656 -115.131193) (xy 190.312294 -115.11026)
			(xy 190.312548 -115.110006) (xy 190.318144 -115.102926) (xy 190.324384 -115.086004) (xy 190.32474 -115.076986)
			(xy 190.32474 -115.00993) (xy 190.324382 -115.000913) (xy 190.318136 -114.983995) (xy 190.312548 -114.97691)
			(xy 190.312294 -114.97691) (xy 190.312294 -114.976656) (xy 190.294667 -114.955714) (xy 190.264953 -114.909744)
			(xy 190.242115 -114.859999) (xy 190.226621 -114.807501) (xy 190.21879 -114.753326) (xy 190.218314 -114.725958)
			(xy 190.218739 -114.698705) (xy 190.226502 -114.644754) (xy 190.241863 -114.592456) (xy 190.264511 -114.542878)
			(xy 190.293984 -114.497026) (xy 190.329681 -114.455836) (xy 190.370878 -114.420145) (xy 190.416734 -114.39068)
			(xy 190.466316 -114.368041) (xy 190.518616 -114.352688) (xy 190.572569 -114.344934) (xy 190.599822 -114.34445)
			(xy 190.627193 -114.344891) (xy 190.681374 -114.352713) (xy 190.733878 -114.368207) (xy 190.783624 -114.391055)
			(xy 190.82959 -114.420786) (xy 190.85052 -114.43843) (xy 190.850774 -114.438684) (xy 190.857865 -114.444264)
			(xy 190.874778 -114.450515) (xy 190.883794 -114.450876) (xy 190.95085 -114.450876) (xy 190.959865 -114.4505)
			(xy 190.976782 -114.444266) (xy 190.98387 -114.438684) (xy 190.98387 -114.43843) (xy 190.984124 -114.43843)
			(xy 191.005078 -114.420818) (xy 191.051044 -114.391101) (xy 191.100786 -114.368259) (xy 191.153282 -114.352762)
			(xy 191.207454 -114.344927) (xy 191.234822 -114.34445) (xy 191.262072 -114.344957) (xy 191.316017 -114.352716)
			(xy 191.368308 -114.368071) (xy 191.417883 -114.390712) (xy 191.463731 -114.420177) (xy 191.50492 -114.455866)
			(xy 191.540611 -114.497053) (xy 191.570078 -114.542899) (xy 191.592722 -114.592473) (xy 191.60808 -114.644764)
			(xy 191.615841 -114.698708) (xy 191.61633 -114.725958) (xy 191.615856 -114.753328) (xy 191.608043 -114.807508)
			(xy 191.592557 -114.860011) (xy 191.569716 -114.909758) (xy 191.539992 -114.955725) (xy 191.52235 -114.976656)
			(xy 191.522096 -114.97691) (xy 191.516499 -114.983989) (xy 191.510259 -115.000912) (xy 191.509904 -115.00993)
			(xy 191.509904 -115.076986) (xy 191.510267 -115.086002) (xy 191.51651 -115.102919) (xy 191.522096 -115.110006)
			(xy 191.52235 -115.110006) (xy 191.52235 -115.11026) (xy 191.539976 -115.131203) (xy 191.569692 -115.177172)
			(xy 191.592531 -115.226917) (xy 191.608025 -115.279415) (xy 191.615855 -115.333589) (xy 191.61633 -115.360958)
			(xy 191.615806 -115.388209) (xy 191.608055 -115.442156) (xy 191.592705 -115.494452) (xy 191.570069 -115.54403)
			(xy 191.540608 -115.589883) (xy 191.50492 -115.631075) (xy 191.463734 -115.666769) (xy 191.417887 -115.696239)
			(xy 191.368312 -115.718883) (xy 191.316019 -115.734241) (xy 191.262073 -115.742001) (xy 191.234822 -115.742466)
			(xy 191.207452 -115.741995) (xy 191.153273 -115.73418) (xy 191.100769 -115.718692) (xy 191.051022 -115.695851)
			(xy 191.005056 -115.666127) (xy 190.984124 -115.648486) (xy 190.98387 -115.648232) (xy 190.976773 -115.642661)
			(xy 190.959864 -115.636407) (xy 190.95085 -115.63604) (xy 190.883794 -115.63604) (xy 190.874776 -115.636385)
			(xy 190.857858 -115.64264) (xy 190.850774 -115.648232) (xy 190.850774 -115.648486) (xy 190.85052 -115.648486)
			(xy 190.829589 -115.666127) (xy 190.783616 -115.695839) (xy 190.733869 -115.718675) (xy 190.681367 -115.734165)
			(xy 190.627191 -115.741993) (xy 190.599822 -115.742466) (xy 190.572568 -115.742024) (xy 190.518614 -115.734269)
			(xy 190.466313 -115.718914) (xy 190.41673 -115.696271) (xy 190.370875 -115.666801) (xy 190.329681 -115.631105)
			(xy 190.293987 -115.589909) (xy 190.26452 -115.544052) (xy 190.241879 -115.494468) (xy 190.226527 -115.442167)
			(xy 190.218774 -115.388212) (xy 190.218314 -115.360958) (xy 183.786676 -115.360958) (xy 183.785517 -115.368836)
			(xy 183.769449 -115.422243) (xy 183.745777 -115.47274) (xy 183.715004 -115.519253) (xy 183.677787 -115.56079)
			(xy 183.634919 -115.596465) (xy 183.587313 -115.625519) (xy 183.535984 -115.647331) (xy 183.482027 -115.661437)
			(xy 183.42659 -115.667537) (xy 183.370856 -115.6655) (xy 183.316013 -115.65537) (xy 183.263229 -115.637363)
			(xy 183.213629 -115.611862) (xy 183.168271 -115.579411) (xy 183.128122 -115.540702) (xy 183.094036 -115.496559)
			(xy 183.06674 -115.447924) (xy 183.046817 -115.395833) (xy 183.034691 -115.341396) (xy 183.03062 -115.285774)
			(xy 179.779777 -115.285774) (xy 179.747374 -115.90909) (xy 180.121304 -115.90909) (xy 180.125375 -115.853468)
			(xy 180.137501 -115.799031) (xy 180.157424 -115.74694) (xy 180.18472 -115.698305) (xy 180.218806 -115.654162)
			(xy 180.258955 -115.615453) (xy 180.304313 -115.583002) (xy 180.353913 -115.557501) (xy 180.406697 -115.539494)
			(xy 180.46154 -115.529364) (xy 180.517274 -115.527327) (xy 180.572711 -115.533427) (xy 180.626668 -115.547533)
			(xy 180.677997 -115.569345) (xy 180.725603 -115.598399) (xy 180.768471 -115.634074) (xy 180.805688 -115.675611)
			(xy 180.836461 -115.722124) (xy 180.860133 -115.772621) (xy 180.876201 -115.826028) (xy 180.884321 -115.881204)
			(xy 180.88483 -115.90909) (xy 180.884321 -115.936976) (xy 180.876201 -115.992152) (xy 180.860133 -116.045559)
			(xy 180.836461 -116.096056) (xy 180.805688 -116.142569) (xy 180.768471 -116.184106) (xy 180.725603 -116.219781)
			(xy 180.677997 -116.248835) (xy 180.626668 -116.270647) (xy 180.572711 -116.284753) (xy 180.517274 -116.290853)
			(xy 180.46154 -116.288816) (xy 180.406697 -116.278686) (xy 180.353913 -116.260679) (xy 180.304313 -116.235178)
			(xy 180.258955 -116.202727) (xy 180.218806 -116.164018) (xy 180.18472 -116.119875) (xy 180.157424 -116.07124)
			(xy 180.137501 -116.019149) (xy 180.125375 -115.964712) (xy 180.121304 -115.90909) (xy 179.747374 -115.90909)
			(xy 179.719382 -116.44757) (xy 182.256936 -116.44757) (xy 182.261007 -116.391948) (xy 182.273133 -116.337511)
			(xy 182.293056 -116.28542) (xy 182.320352 -116.236785) (xy 182.354438 -116.192642) (xy 182.394587 -116.153933)
			(xy 182.439945 -116.121482) (xy 182.489545 -116.095981) (xy 182.542329 -116.077974) (xy 182.597172 -116.067844)
			(xy 182.652906 -116.065807) (xy 182.708343 -116.071907) (xy 182.7623 -116.086013) (xy 182.813629 -116.107825)
			(xy 182.861235 -116.136879) (xy 182.904103 -116.172554) (xy 182.94132 -116.214091) (xy 182.972093 -116.260604)
			(xy 182.995765 -116.311101) (xy 183.011833 -116.364508) (xy 183.019953 -116.419684) (xy 183.020462 -116.44757)
			(xy 183.019953 -116.475456) (xy 183.019683 -116.477288) (xy 187.404246 -116.477288) (xy 187.408317 -116.421666)
			(xy 187.420443 -116.367229) (xy 187.440366 -116.315138) (xy 187.467662 -116.266503) (xy 187.501748 -116.22236)
			(xy 187.541897 -116.183651) (xy 187.587255 -116.1512) (xy 187.636855 -116.125699) (xy 187.689639 -116.107692)
			(xy 187.744482 -116.097562) (xy 187.800216 -116.095525) (xy 187.855653 -116.101625) (xy 187.90961 -116.115731)
			(xy 187.960939 -116.137543) (xy 188.008545 -116.166597) (xy 188.051413 -116.202272) (xy 188.08863 -116.243809)
			(xy 188.119403 -116.290322) (xy 188.143075 -116.340819) (xy 188.159143 -116.394226) (xy 188.167263 -116.449402)
			(xy 188.167772 -116.477288) (xy 188.167263 -116.505174) (xy 188.159143 -116.56035) (xy 188.143075 -116.613757)
			(xy 188.119403 -116.664254) (xy 188.08863 -116.710767) (xy 188.051413 -116.752304) (xy 188.008545 -116.787979)
			(xy 187.960939 -116.817033) (xy 187.90961 -116.838845) (xy 187.855653 -116.852951) (xy 187.800216 -116.859051)
			(xy 187.744482 -116.857014) (xy 187.689639 -116.846884) (xy 187.636855 -116.828877) (xy 187.587255 -116.803376)
			(xy 187.541897 -116.770925) (xy 187.501748 -116.732216) (xy 187.467662 -116.688073) (xy 187.440366 -116.639438)
			(xy 187.420443 -116.587347) (xy 187.408317 -116.53291) (xy 187.404246 -116.477288) (xy 183.019683 -116.477288)
			(xy 183.011833 -116.530632) (xy 182.995765 -116.584039) (xy 182.972093 -116.634536) (xy 182.94132 -116.681049)
			(xy 182.904103 -116.722586) (xy 182.861235 -116.758261) (xy 182.813629 -116.787315) (xy 182.7623 -116.809127)
			(xy 182.708343 -116.823233) (xy 182.652906 -116.829333) (xy 182.597172 -116.827296) (xy 182.542329 -116.817166)
			(xy 182.489545 -116.799159) (xy 182.439945 -116.773658) (xy 182.394587 -116.741207) (xy 182.354438 -116.702498)
			(xy 182.320352 -116.658355) (xy 182.293056 -116.60972) (xy 182.273133 -116.557629) (xy 182.261007 -116.503192)
			(xy 182.256936 -116.44757) (xy 179.719382 -116.44757) (xy 179.653046 -117.723666) (xy 185.789568 -117.723666)
			(xy 185.793639 -117.668044) (xy 185.805765 -117.613607) (xy 185.825688 -117.561516) (xy 185.852984 -117.512881)
			(xy 185.88707 -117.468738) (xy 185.927219 -117.430029) (xy 185.972577 -117.397578) (xy 186.022177 -117.372077)
			(xy 186.074961 -117.35407) (xy 186.129804 -117.34394) (xy 186.185538 -117.341903) (xy 186.240975 -117.348003)
			(xy 186.294932 -117.362109) (xy 186.346261 -117.383921) (xy 186.393867 -117.412975) (xy 186.436735 -117.44865)
			(xy 186.473952 -117.490187) (xy 186.504725 -117.5367) (xy 186.528397 -117.587197) (xy 186.544465 -117.640604)
			(xy 186.552585 -117.69578) (xy 186.553094 -117.723666) (xy 186.552585 -117.751552) (xy 186.55153 -117.758718)
			(xy 190.574676 -117.758718) (xy 190.574676 -116.895118) (xy 190.575166 -116.865134) (xy 190.582994 -116.805678)
			(xy 190.598515 -116.747753) (xy 190.621464 -116.692349) (xy 190.651448 -116.640415) (xy 190.687954 -116.592839)
			(xy 190.730359 -116.550434) (xy 190.777935 -116.513928) (xy 190.829869 -116.483944) (xy 190.885273 -116.460995)
			(xy 190.943198 -116.445474) (xy 191.002654 -116.437646) (xy 191.062622 -116.437646) (xy 191.122078 -116.445474)
			(xy 191.180003 -116.460995) (xy 191.235407 -116.483944) (xy 191.287341 -116.513928) (xy 191.334917 -116.550434)
			(xy 191.377322 -116.592839) (xy 191.413828 -116.640415) (xy 191.443812 -116.692349) (xy 191.466761 -116.747753)
			(xy 191.482282 -116.805678) (xy 191.49011 -116.865134) (xy 191.4906 -116.895118) (xy 191.4906 -117.758718)
			(xy 191.49011 -117.788702) (xy 191.482282 -117.848158) (xy 191.466761 -117.906083) (xy 191.443812 -117.961487)
			(xy 191.413828 -118.013421) (xy 191.377322 -118.060997) (xy 191.334917 -118.103402) (xy 191.287341 -118.139908)
			(xy 191.235407 -118.169892) (xy 191.180003 -118.192841) (xy 191.122078 -118.208362) (xy 191.062622 -118.21619)
			(xy 191.002654 -118.21619) (xy 190.943198 -118.208362) (xy 190.885273 -118.192841) (xy 190.829869 -118.169892)
			(xy 190.777935 -118.139908) (xy 190.730359 -118.103402) (xy 190.687954 -118.060997) (xy 190.651448 -118.013421)
			(xy 190.621464 -117.961487) (xy 190.598515 -117.906083) (xy 190.582994 -117.848158) (xy 190.575166 -117.788702)
			(xy 190.574676 -117.758718) (xy 186.55153 -117.758718) (xy 186.544465 -117.806728) (xy 186.528397 -117.860135)
			(xy 186.504725 -117.910632) (xy 186.473952 -117.957145) (xy 186.436735 -117.998682) (xy 186.393867 -118.034357)
			(xy 186.346261 -118.063411) (xy 186.294932 -118.085223) (xy 186.240975 -118.099329) (xy 186.185538 -118.105429)
			(xy 186.129804 -118.103392) (xy 186.074961 -118.093262) (xy 186.022177 -118.075255) (xy 185.972577 -118.049754)
			(xy 185.927219 -118.017303) (xy 185.88707 -117.978594) (xy 185.852984 -117.934451) (xy 185.825688 -117.885816)
			(xy 185.805765 -117.833725) (xy 185.793639 -117.779288) (xy 185.789568 -117.723666) (xy 179.653046 -117.723666)
			(xy 179.63769 -118.019068) (xy 179.637182 -118.028466) (xy 179.642262 -118.043706) (xy 179.646072 -118.053104)
			(xy 179.64785 -118.057676) (xy 179.657248 -118.072154) (xy 179.660296 -118.075456) (xy 179.67862 -118.096472)
			(xy 179.709617 -118.142818) (xy 179.733555 -118.193174) (xy 179.749929 -118.246472) (xy 179.758391 -118.301582)
			(xy 179.759102 -118.329456) (xy 179.759102 -118.33225) (xy 179.758597 -118.36005) (xy 179.750523 -118.41506)
			(xy 179.734554 -118.468317) (xy 179.711027 -118.518693) (xy 179.68044 -118.565123) (xy 179.643441 -118.606624)
			(xy 179.62245 -118.624858) (xy 179.622196 -118.624858) (xy 179.616608 -118.629684) (xy 179.613814 -118.63197)
			(xy 179.609242 -118.64086) (xy 179.607398 -118.644656) (xy 179.604839 -118.652697) (xy 179.604162 -118.656862)
			(xy 179.556796 -119.567198) (xy 182.69966 -119.567198) (xy 182.69966 -118.703598) (xy 182.70015 -118.67363)
			(xy 182.707973 -118.614208) (xy 182.723486 -118.556315) (xy 182.746422 -118.500942) (xy 182.776389 -118.449036)
			(xy 182.812876 -118.401486) (xy 182.855256 -118.359106) (xy 182.902806 -118.322619) (xy 182.954712 -118.292652)
			(xy 183.010085 -118.269716) (xy 183.067978 -118.254203) (xy 183.1274 -118.24638) (xy 183.187336 -118.24638)
			(xy 183.246758 -118.254203) (xy 183.304651 -118.269716) (xy 183.360024 -118.292652) (xy 183.41193 -118.322619)
			(xy 183.45948 -118.359106) (xy 183.50186 -118.401486) (xy 183.538347 -118.449036) (xy 183.568314 -118.500942)
			(xy 183.59125 -118.556315) (xy 183.606763 -118.614208) (xy 183.614586 -118.67363) (xy 183.615076 -118.703598)
			(xy 183.615076 -118.711218) (xy 185.909202 -118.711218) (xy 185.913273 -118.655596) (xy 185.925399 -118.601159)
			(xy 185.945322 -118.549068) (xy 185.972618 -118.500433) (xy 186.006704 -118.45629) (xy 186.046853 -118.417581)
			(xy 186.092211 -118.38513) (xy 186.141811 -118.359629) (xy 186.194595 -118.341622) (xy 186.249438 -118.331492)
			(xy 186.305172 -118.329455) (xy 186.360609 -118.335555) (xy 186.414566 -118.349661) (xy 186.465895 -118.371473)
			(xy 186.513501 -118.400527) (xy 186.556369 -118.436202) (xy 186.593586 -118.477739) (xy 186.624359 -118.524252)
			(xy 186.648031 -118.574749) (xy 186.664099 -118.628156) (xy 186.672219 -118.683332) (xy 186.672728 -118.711218)
			(xy 186.672219 -118.739104) (xy 186.664099 -118.79428) (xy 186.648031 -118.847687) (xy 186.624359 -118.898184)
			(xy 186.593586 -118.944697) (xy 186.556369 -118.986234) (xy 186.513501 -119.021909) (xy 186.465895 -119.050963)
			(xy 186.414566 -119.072775) (xy 186.360609 -119.086881) (xy 186.305172 -119.092981) (xy 186.249438 -119.090944)
			(xy 186.194595 -119.080814) (xy 186.141811 -119.062807) (xy 186.092211 -119.037306) (xy 186.046853 -119.004855)
			(xy 186.006704 -118.966146) (xy 185.972618 -118.922003) (xy 185.945322 -118.873368) (xy 185.925399 -118.821277)
			(xy 185.913273 -118.76684) (xy 185.909202 -118.711218) (xy 183.615076 -118.711218) (xy 183.615076 -119.567198)
			(xy 183.614586 -119.597166) (xy 183.606763 -119.656588) (xy 183.59125 -119.714481) (xy 183.568314 -119.769854)
			(xy 183.538347 -119.82176) (xy 183.50186 -119.86931) (xy 183.45948 -119.91169) (xy 183.41193 -119.948177)
			(xy 183.360024 -119.978144) (xy 183.304651 -120.00108) (xy 183.246758 -120.016593) (xy 183.187336 -120.024416)
			(xy 183.1274 -120.024416) (xy 183.067978 -120.016593) (xy 183.010085 -120.00108) (xy 182.954712 -119.978144)
			(xy 182.902806 -119.948177) (xy 182.855256 -119.91169) (xy 182.812876 -119.86931) (xy 182.776389 -119.82176)
			(xy 182.746422 -119.769854) (xy 182.723486 -119.714481) (xy 182.707973 -119.656588) (xy 182.70015 -119.597166)
			(xy 182.69966 -119.567198) (xy 179.556796 -119.567198) (xy 179.509166 -120.482614) (xy 179.463073 -121.367296)
			(xy 180.84546 -121.367296) (xy 180.84546 -120.503696) (xy 180.84595 -120.473728) (xy 180.853773 -120.414306)
			(xy 180.869286 -120.356413) (xy 180.892222 -120.30104) (xy 180.922189 -120.249134) (xy 180.958676 -120.201584)
			(xy 181.001056 -120.159204) (xy 181.048606 -120.122717) (xy 181.100512 -120.09275) (xy 181.155885 -120.069814)
			(xy 181.213778 -120.054301) (xy 181.2732 -120.046478) (xy 181.333136 -120.046478) (xy 181.392558 -120.054301)
			(xy 181.450451 -120.069814) (xy 181.505824 -120.09275) (xy 181.55773 -120.122717) (xy 181.60528 -120.159204)
			(xy 181.64766 -120.201584) (xy 181.684147 -120.249134) (xy 181.714114 -120.30104) (xy 181.73705 -120.356413)
			(xy 181.752563 -120.414306) (xy 181.760386 -120.473728) (xy 181.760876 -120.503696) (xy 181.760876 -121.367296)
			(xy 181.760386 -121.397264) (xy 181.752563 -121.456686) (xy 181.73705 -121.514579) (xy 181.714114 -121.569952)
			(xy 181.684147 -121.621858) (xy 181.64766 -121.669408) (xy 181.60528 -121.711788) (xy 181.55773 -121.748275)
			(xy 181.505824 -121.778242) (xy 181.450451 -121.801178) (xy 181.392558 -121.816691) (xy 181.333136 -121.824514)
			(xy 181.2732 -121.824514) (xy 181.213778 -121.816691) (xy 181.155885 -121.801178) (xy 181.100512 -121.778242)
			(xy 181.048606 -121.748275) (xy 181.001056 -121.711788) (xy 180.958676 -121.669408) (xy 180.922189 -121.621858)
			(xy 180.892222 -121.569952) (xy 180.869286 -121.514579) (xy 180.853773 -121.456686) (xy 180.84595 -121.397264)
			(xy 180.84546 -121.367296) (xy 179.463073 -121.367296) (xy 179.3693 -123.16714) (xy 182.69966 -123.16714)
			(xy 182.69966 -122.30354) (xy 182.70015 -122.273572) (xy 182.707973 -122.21415) (xy 182.723486 -122.156257)
			(xy 182.746422 -122.100884) (xy 182.776389 -122.048978) (xy 182.812876 -122.001428) (xy 182.855256 -121.959048)
			(xy 182.902806 -121.922561) (xy 182.954712 -121.892594) (xy 183.010085 -121.869658) (xy 183.067978 -121.854145)
			(xy 183.1274 -121.846322) (xy 183.187336 -121.846322) (xy 183.246758 -121.854145) (xy 183.304651 -121.869658)
			(xy 183.360024 -121.892594) (xy 183.41193 -121.922561) (xy 183.45948 -121.959048) (xy 183.50186 -122.001428)
			(xy 183.538347 -122.048978) (xy 183.568314 -122.100884) (xy 183.59125 -122.156257) (xy 183.606763 -122.21415)
			(xy 183.614586 -122.273572) (xy 183.615076 -122.30354) (xy 183.615076 -123.16714) (xy 183.614586 -123.197108)
			(xy 183.606763 -123.25653) (xy 183.59125 -123.314423) (xy 183.568314 -123.369796) (xy 183.538347 -123.421702)
			(xy 183.50186 -123.469252) (xy 183.45948 -123.511632) (xy 183.41193 -123.548119) (xy 183.360024 -123.578086)
			(xy 183.304651 -123.601022) (xy 183.246758 -123.616535) (xy 183.187336 -123.624358) (xy 183.1274 -123.624358)
			(xy 183.067978 -123.616535) (xy 183.010085 -123.601022) (xy 182.954712 -123.578086) (xy 182.902806 -123.548119)
			(xy 182.855256 -123.511632) (xy 182.812876 -123.469252) (xy 182.776389 -123.421702) (xy 182.746422 -123.369796)
			(xy 182.723486 -123.314423) (xy 182.707973 -123.25653) (xy 182.70015 -123.197108) (xy 182.69966 -123.16714)
			(xy 179.3693 -123.16714) (xy 179.35829 -123.378468) (xy 179.275596 -124.967238) (xy 180.84546 -124.967238)
			(xy 180.84546 -124.103638) (xy 180.84595 -124.07367) (xy 180.853773 -124.014248) (xy 180.869286 -123.956355)
			(xy 180.892222 -123.900982) (xy 180.922189 -123.849076) (xy 180.958676 -123.801526) (xy 181.001056 -123.759146)
			(xy 181.048606 -123.722659) (xy 181.100512 -123.692692) (xy 181.155885 -123.669756) (xy 181.213778 -123.654243)
			(xy 181.2732 -123.64642) (xy 181.333136 -123.64642) (xy 181.392558 -123.654243) (xy 181.450451 -123.669756)
			(xy 181.505824 -123.692692) (xy 181.55773 -123.722659) (xy 181.60528 -123.759146) (xy 181.64766 -123.801526)
			(xy 181.684147 -123.849076) (xy 181.714114 -123.900982) (xy 181.73705 -123.956355) (xy 181.752563 -124.014248)
			(xy 181.760386 -124.07367) (xy 181.760876 -124.103638) (xy 181.760876 -124.967238) (xy 181.760386 -124.997206)
			(xy 181.752563 -125.056628) (xy 181.73705 -125.114521) (xy 181.714114 -125.169894) (xy 181.684147 -125.2218)
			(xy 181.64766 -125.26935) (xy 181.60528 -125.31173) (xy 181.55773 -125.348217) (xy 181.505824 -125.378184)
			(xy 181.450451 -125.40112) (xy 181.392558 -125.416633) (xy 181.333136 -125.424456) (xy 181.2732 -125.424456)
			(xy 181.213778 -125.416633) (xy 181.155885 -125.40112) (xy 181.100512 -125.378184) (xy 181.048606 -125.348217)
			(xy 181.001056 -125.31173) (xy 180.958676 -125.26935) (xy 180.922189 -125.2218) (xy 180.892222 -125.169894)
			(xy 180.869286 -125.114521) (xy 180.853773 -125.056628) (xy 180.84595 -124.997206) (xy 180.84546 -124.967238)
			(xy 179.275596 -124.967238) (xy 179.107246 -128.201674) (xy 183.60593 -128.201674) (xy 183.610001 -128.146052)
			(xy 183.622127 -128.091615) (xy 183.64205 -128.039524) (xy 183.669346 -127.990889) (xy 183.703432 -127.946746)
			(xy 183.743581 -127.908037) (xy 183.788939 -127.875586) (xy 183.838539 -127.850085) (xy 183.891323 -127.832078)
			(xy 183.946166 -127.821948) (xy 184.0019 -127.819911) (xy 184.057337 -127.826011) (xy 184.111294 -127.840117)
			(xy 184.162623 -127.861929) (xy 184.210229 -127.890983) (xy 184.253097 -127.926658) (xy 184.290314 -127.968195)
			(xy 184.321087 -128.014708) (xy 184.344759 -128.065205) (xy 184.360827 -128.118612) (xy 184.368947 -128.173788)
			(xy 184.369456 -128.201674) (xy 184.368947 -128.22956) (xy 184.360827 -128.284736) (xy 184.344759 -128.338143)
			(xy 184.321087 -128.38864) (xy 184.290314 -128.435153) (xy 184.253097 -128.47669) (xy 184.210229 -128.512365)
			(xy 184.162623 -128.541419) (xy 184.111294 -128.563231) (xy 184.057337 -128.577337) (xy 184.0019 -128.583437)
			(xy 183.946166 -128.5814) (xy 183.891323 -128.57127) (xy 183.838539 -128.553263) (xy 183.788939 -128.527762)
			(xy 183.743581 -128.495311) (xy 183.703432 -128.456602) (xy 183.669346 -128.412459) (xy 183.64205 -128.363824)
			(xy 183.622127 -128.311733) (xy 183.610001 -128.257296) (xy 183.60593 -128.201674) (xy 179.107246 -128.201674)
			(xy 178.97319 -130.777234) (xy 182.69966 -130.777234) (xy 182.69966 -129.913634) (xy 182.70015 -129.883666)
			(xy 182.707973 -129.824244) (xy 182.723486 -129.766351) (xy 182.746422 -129.710978) (xy 182.776389 -129.659072)
			(xy 182.812876 -129.611522) (xy 182.855256 -129.569142) (xy 182.902806 -129.532655) (xy 182.954712 -129.502688)
			(xy 183.010085 -129.479752) (xy 183.067978 -129.464239) (xy 183.1274 -129.456416) (xy 183.187336 -129.456416)
			(xy 183.246758 -129.464239) (xy 183.304651 -129.479752) (xy 183.360024 -129.502688) (xy 183.41193 -129.532655)
			(xy 183.45948 -129.569142) (xy 183.50186 -129.611522) (xy 183.538347 -129.659072) (xy 183.568314 -129.710978)
			(xy 183.59125 -129.766351) (xy 183.606763 -129.824244) (xy 183.614586 -129.883666) (xy 183.615076 -129.913634)
			(xy 183.615076 -130.777234) (xy 183.614586 -130.807202) (xy 183.606763 -130.866624) (xy 183.59125 -130.924517)
			(xy 183.568314 -130.97989) (xy 183.538347 -131.031796) (xy 183.50186 -131.079346) (xy 183.45948 -131.121726)
			(xy 183.41193 -131.158213) (xy 183.360024 -131.18818) (xy 183.304651 -131.211116) (xy 183.246758 -131.226629)
			(xy 183.187336 -131.234452) (xy 183.1274 -131.234452) (xy 183.067978 -131.226629) (xy 183.010085 -131.211116)
			(xy 182.954712 -131.18818) (xy 182.902806 -131.158213) (xy 182.855256 -131.121726) (xy 182.812876 -131.079346)
			(xy 182.776389 -131.031796) (xy 182.746422 -130.97989) (xy 182.723486 -130.924517) (xy 182.707973 -130.866624)
			(xy 182.70015 -130.807202) (xy 182.69966 -130.777234) (xy 178.97319 -130.777234) (xy 178.879496 -132.577332)
			(xy 180.84546 -132.577332) (xy 180.84546 -131.713732) (xy 180.84595 -131.683764) (xy 180.853773 -131.624342)
			(xy 180.869286 -131.566449) (xy 180.892222 -131.511076) (xy 180.922189 -131.45917) (xy 180.958676 -131.41162)
			(xy 181.001056 -131.36924) (xy 181.048606 -131.332753) (xy 181.100512 -131.302786) (xy 181.155885 -131.27985)
			(xy 181.213778 -131.264337) (xy 181.2732 -131.256514) (xy 181.333136 -131.256514) (xy 181.392558 -131.264337)
			(xy 181.450451 -131.27985) (xy 181.505824 -131.302786) (xy 181.55773 -131.332753) (xy 181.60528 -131.36924)
			(xy 181.64766 -131.41162) (xy 181.684147 -131.45917) (xy 181.714114 -131.511076) (xy 181.73705 -131.566449)
			(xy 181.752563 -131.624342) (xy 181.760386 -131.683764) (xy 181.760876 -131.713732) (xy 181.760876 -132.577332)
			(xy 181.760386 -132.6073) (xy 181.752563 -132.666722) (xy 181.73705 -132.724615) (xy 181.714114 -132.779988)
			(xy 181.684147 -132.831894) (xy 181.64766 -132.879444) (xy 181.60528 -132.921824) (xy 181.55773 -132.958311)
			(xy 181.505824 -132.988278) (xy 181.450451 -133.011214) (xy 181.392558 -133.026727) (xy 181.333136 -133.03455)
			(xy 181.2732 -133.03455) (xy 181.213778 -133.026727) (xy 181.155885 -133.011214) (xy 181.100512 -132.988278)
			(xy 181.048606 -132.958311) (xy 181.001056 -132.921824) (xy 180.958676 -132.879444) (xy 180.922189 -132.831894)
			(xy 180.892222 -132.779988) (xy 180.869286 -132.724615) (xy 180.853773 -132.666722) (xy 180.84595 -132.6073)
			(xy 180.84546 -132.577332) (xy 178.879496 -132.577332) (xy 178.785816 -134.377176) (xy 182.69966 -134.377176)
			(xy 182.69966 -133.513576) (xy 182.70015 -133.483608) (xy 182.707973 -133.424186) (xy 182.723486 -133.366293)
			(xy 182.746422 -133.31092) (xy 182.776389 -133.259014) (xy 182.812876 -133.211464) (xy 182.855256 -133.169084)
			(xy 182.902806 -133.132597) (xy 182.954712 -133.10263) (xy 183.010085 -133.079694) (xy 183.067978 -133.064181)
			(xy 183.1274 -133.056358) (xy 183.187336 -133.056358) (xy 183.246758 -133.064181) (xy 183.304651 -133.079694)
			(xy 183.360024 -133.10263) (xy 183.41193 -133.132597) (xy 183.45948 -133.169084) (xy 183.50186 -133.211464)
			(xy 183.538347 -133.259014) (xy 183.568314 -133.31092) (xy 183.59125 -133.366293) (xy 183.606763 -133.424186)
			(xy 183.614586 -133.483608) (xy 183.615076 -133.513576) (xy 183.615076 -134.377176) (xy 183.614586 -134.407144)
			(xy 183.606763 -134.466566) (xy 183.59125 -134.524459) (xy 183.568314 -134.579832) (xy 183.538347 -134.631738)
			(xy 183.50186 -134.679288) (xy 183.45948 -134.721668) (xy 183.41193 -134.758155) (xy 183.360024 -134.788122)
			(xy 183.304651 -134.811058) (xy 183.246758 -134.826571) (xy 183.187336 -134.834394) (xy 183.1274 -134.834394)
			(xy 183.067978 -134.826571) (xy 183.010085 -134.811058) (xy 182.954712 -134.788122) (xy 182.902806 -134.758155)
			(xy 182.855256 -134.721668) (xy 182.812876 -134.679288) (xy 182.776389 -134.631738) (xy 182.746422 -134.579832)
			(xy 182.723486 -134.524459) (xy 182.707973 -134.466566) (xy 182.70015 -134.407144) (xy 182.69966 -134.377176)
			(xy 178.785816 -134.377176) (xy 178.692122 -136.177274) (xy 180.84546 -136.177274) (xy 180.84546 -135.313674)
			(xy 180.84595 -135.283706) (xy 180.853773 -135.224284) (xy 180.869286 -135.166391) (xy 180.892222 -135.111018)
			(xy 180.922189 -135.059112) (xy 180.958676 -135.011562) (xy 181.001056 -134.969182) (xy 181.048606 -134.932695)
			(xy 181.100512 -134.902728) (xy 181.155885 -134.879792) (xy 181.213778 -134.864279) (xy 181.2732 -134.856456)
			(xy 181.333136 -134.856456) (xy 181.392558 -134.864279) (xy 181.450451 -134.879792) (xy 181.505824 -134.902728)
			(xy 181.55773 -134.932695) (xy 181.60528 -134.969182) (xy 181.64766 -135.011562) (xy 181.684147 -135.059112)
			(xy 181.714114 -135.111018) (xy 181.73705 -135.166391) (xy 181.752563 -135.224284) (xy 181.760386 -135.283706)
			(xy 181.760876 -135.313674) (xy 181.760876 -136.177274) (xy 181.760386 -136.207242) (xy 181.752563 -136.266664)
			(xy 181.73705 -136.324557) (xy 181.714114 -136.37993) (xy 181.684147 -136.431836) (xy 181.64766 -136.479386)
			(xy 181.60528 -136.521766) (xy 181.55773 -136.558253) (xy 181.505824 -136.58822) (xy 181.450451 -136.611156)
			(xy 181.392558 -136.626669) (xy 181.333136 -136.634492) (xy 181.2732 -136.634492) (xy 181.213778 -136.626669)
			(xy 181.155885 -136.611156) (xy 181.100512 -136.58822) (xy 181.048606 -136.558253) (xy 181.001056 -136.521766)
			(xy 180.958676 -136.479386) (xy 180.922189 -136.431836) (xy 180.892222 -136.37993) (xy 180.869286 -136.324557)
			(xy 180.853773 -136.266664) (xy 180.84595 -136.207242) (xy 180.84546 -136.177274) (xy 178.692122 -136.177274)
			(xy 178.69154 -136.18845) (xy 178.687222 -136.27354) (xy 178.679348 -136.426194) (xy 178.66106 -136.777222)
			(xy 178.652932 -136.931908) (xy 178.651916 -136.951974) (xy 178.627786 -137.415524) (xy 178.627024 -137.430002)
			(xy 178.626886 -137.43913) (xy 178.632327 -137.456541) (xy 178.643558 -137.470915) (xy 178.651154 -137.475976)
			(xy 178.674699 -137.490959) (xy 178.718149 -137.525985) (xy 178.756794 -137.566249) (xy 178.790007 -137.611099)
			(xy 178.81725 -137.659808) (xy 178.83808 -137.711584) (xy 178.85216 -137.765588) (xy 178.859261 -137.820943)
			(xy 178.859688 -137.848848) (xy 178.859203 -137.878761) (xy 178.851058 -137.93803) (xy 178.834913 -137.995636)
			(xy 178.811068 -138.050505) (xy 178.77997 -138.101613) (xy 178.742197 -138.148007) (xy 178.698455 -138.188821)
			(xy 178.64956 -138.223294) (xy 178.623214 -138.237468) (xy 178.617372 -138.240516) (xy 178.602132 -138.2522)
			(xy 178.593676 -138.259377) (xy 178.583406 -138.279007) (xy 178.58232 -138.290046) (xy 178.581812 -138.300714)
			(xy 178.575462 -138.421364) (xy 178.575462 -138.421872) (xy 178.5747 -138.437112) (xy 178.573938 -138.45032)
			(xy 178.57343 -138.464544) (xy 178.573684 -138.472926) (xy 178.573938 -138.47572) (xy 178.575462 -138.48461)
			(xy 178.576478 -138.488928) (xy 178.59375 -138.518392) (xy 178.598322 -138.52398) (xy 178.602894 -138.528552)
			(xy 178.610006 -138.532616) (xy 178.63475 -138.547291) (xy 178.679926 -138.582907) (xy 178.719257 -138.624888)
			(xy 178.751857 -138.672287) (xy 178.776989 -138.724034) (xy 178.794087 -138.778962) (xy 178.802764 -138.835831)
			(xy 178.8033 -138.864594) (xy 178.8033 -138.864848) (xy 180.329584 -138.864848) (xy 180.333655 -138.809226)
			(xy 180.345781 -138.754789) (xy 180.365704 -138.702698) (xy 180.393 -138.654063) (xy 180.427086 -138.60992)
			(xy 180.467235 -138.571211) (xy 180.512593 -138.53876) (xy 180.562193 -138.513259) (xy 180.614977 -138.495252)
			(xy 180.66982 -138.485122) (xy 180.725554 -138.483085) (xy 180.780991 -138.489185) (xy 180.834948 -138.503291)
			(xy 180.886277 -138.525103) (xy 180.933883 -138.554157) (xy 180.976751 -138.589832) (xy 181.013968 -138.631369)
			(xy 181.044741 -138.677882) (xy 181.068413 -138.728379) (xy 181.084481 -138.781786) (xy 181.092601 -138.836962)
			(xy 181.09311 -138.864848) (xy 181.092601 -138.892734) (xy 181.084481 -138.94791) (xy 181.068413 -139.001317)
			(xy 181.044741 -139.051814) (xy 181.013968 -139.098327) (xy 180.976751 -139.139864) (xy 180.933883 -139.175539)
			(xy 180.886277 -139.204593) (xy 180.834948 -139.226405) (xy 180.780991 -139.240511) (xy 180.725554 -139.246611)
			(xy 180.66982 -139.244574) (xy 180.614977 -139.234444) (xy 180.562193 -139.216437) (xy 180.512593 -139.190936)
			(xy 180.467235 -139.158485) (xy 180.427086 -139.119776) (xy 180.393 -139.075633) (xy 180.365704 -139.026998)
			(xy 180.345781 -138.974907) (xy 180.333655 -138.92047) (xy 180.329584 -138.864848) (xy 178.8033 -138.864848)
			(xy 178.8033 -138.865102) (xy 178.802538 -138.891772) (xy 178.802538 -138.89228) (xy 178.800249 -138.918431)
			(xy 178.789413 -138.969794) (xy 178.780948 -138.994642) (xy 178.771776 -139.018723) (xy 178.747857 -139.064368)
			(xy 178.717999 -139.106367) (xy 178.700684 -139.125452) (xy 178.68177 -139.145132) (xy 178.639301 -139.17942)
			(xy 178.592373 -139.207296) (xy 178.567334 -139.218162) (xy 178.555142 -139.225274) (xy 178.541426 -139.236196)
			(xy 178.541426 -139.23645) (xy 178.538979 -139.239896) (xy 178.535144 -139.247427) (xy 178.533806 -139.251436)
			(xy 178.531774 -139.259818) (xy 178.446684 -140.896848) (xy 178.31182 -143.48714) (xy 182.69966 -143.48714)
			(xy 182.69966 -142.62354) (xy 182.70015 -142.593572) (xy 182.707973 -142.53415) (xy 182.723486 -142.476257)
			(xy 182.746422 -142.420884) (xy 182.776389 -142.368978) (xy 182.812876 -142.321428) (xy 182.855256 -142.279048)
			(xy 182.902806 -142.242561) (xy 182.954712 -142.212594) (xy 183.010085 -142.189658) (xy 183.067978 -142.174145)
			(xy 183.1274 -142.166322) (xy 183.187336 -142.166322) (xy 183.246758 -142.174145) (xy 183.304651 -142.189658)
			(xy 183.360024 -142.212594) (xy 183.41193 -142.242561) (xy 183.45948 -142.279048) (xy 183.50186 -142.321428)
			(xy 183.538347 -142.368978) (xy 183.568314 -142.420884) (xy 183.59125 -142.476257) (xy 183.606763 -142.53415)
			(xy 183.614586 -142.593572) (xy 183.615076 -142.62354) (xy 183.615076 -143.48714) (xy 183.614586 -143.517108)
			(xy 183.606763 -143.57653) (xy 183.59125 -143.634423) (xy 183.568314 -143.689796) (xy 183.538347 -143.741702)
			(xy 183.50186 -143.789252) (xy 183.45948 -143.831632) (xy 183.41193 -143.868119) (xy 183.360024 -143.898086)
			(xy 183.304651 -143.921022) (xy 183.246758 -143.936535) (xy 183.187336 -143.944358) (xy 183.1274 -143.944358)
			(xy 183.067978 -143.936535) (xy 183.010085 -143.921022) (xy 182.954712 -143.898086) (xy 182.902806 -143.868119)
			(xy 182.855256 -143.831632) (xy 182.812876 -143.789252) (xy 182.776389 -143.741702) (xy 182.746422 -143.689796)
			(xy 182.723486 -143.634423) (xy 182.707973 -143.57653) (xy 182.70015 -143.517108) (xy 182.69966 -143.48714)
			(xy 178.31182 -143.48714) (xy 178.218097 -145.287238) (xy 180.84546 -145.287238) (xy 180.84546 -144.423638)
			(xy 180.84595 -144.39367) (xy 180.853773 -144.334248) (xy 180.869286 -144.276355) (xy 180.892222 -144.220982)
			(xy 180.922189 -144.169076) (xy 180.958676 -144.121526) (xy 181.001056 -144.079146) (xy 181.048606 -144.042659)
			(xy 181.100512 -144.012692) (xy 181.155885 -143.989756) (xy 181.213778 -143.974243) (xy 181.2732 -143.96642)
			(xy 181.333136 -143.96642) (xy 181.392558 -143.974243) (xy 181.450451 -143.989756) (xy 181.505824 -144.012692)
			(xy 181.55773 -144.042659) (xy 181.60528 -144.079146) (xy 181.64766 -144.121526) (xy 181.684147 -144.169076)
			(xy 181.714114 -144.220982) (xy 181.73705 -144.276355) (xy 181.752563 -144.334248) (xy 181.760386 -144.39367)
			(xy 181.760876 -144.423638) (xy 181.760876 -145.287238) (xy 181.760386 -145.317206) (xy 181.752563 -145.376628)
			(xy 181.73705 -145.434521) (xy 181.714114 -145.489894) (xy 181.684147 -145.5418) (xy 181.64766 -145.58935)
			(xy 181.60528 -145.63173) (xy 181.55773 -145.668217) (xy 181.505824 -145.698184) (xy 181.450451 -145.72112)
			(xy 181.392558 -145.736633) (xy 181.333136 -145.744456) (xy 181.2732 -145.744456) (xy 181.213778 -145.736633)
			(xy 181.155885 -145.72112) (xy 181.100512 -145.698184) (xy 181.048606 -145.668217) (xy 181.001056 -145.63173)
			(xy 180.958676 -145.58935) (xy 180.922189 -145.5418) (xy 180.892222 -145.489894) (xy 180.869286 -145.434521)
			(xy 180.853773 -145.376628) (xy 180.84595 -145.317206) (xy 180.84546 -145.287238) (xy 178.218097 -145.287238)
			(xy 178.124375 -147.087336) (xy 182.69966 -147.087336) (xy 182.69966 -146.223736) (xy 182.70015 -146.193768)
			(xy 182.707973 -146.134346) (xy 182.723486 -146.076453) (xy 182.746422 -146.02108) (xy 182.776389 -145.969174)
			(xy 182.812876 -145.921624) (xy 182.855256 -145.879244) (xy 182.902806 -145.842757) (xy 182.954712 -145.81279)
			(xy 183.010085 -145.789854) (xy 183.067978 -145.774341) (xy 183.1274 -145.766518) (xy 183.187336 -145.766518)
			(xy 183.246758 -145.774341) (xy 183.304651 -145.789854) (xy 183.360024 -145.81279) (xy 183.41193 -145.842757)
			(xy 183.45948 -145.879244) (xy 183.50186 -145.921624) (xy 183.538347 -145.969174) (xy 183.568314 -146.02108)
			(xy 183.59125 -146.076453) (xy 183.606763 -146.134346) (xy 183.614586 -146.193768) (xy 183.615076 -146.223736)
			(xy 183.615076 -147.087336) (xy 183.614586 -147.117304) (xy 183.606763 -147.176726) (xy 183.59125 -147.234619)
			(xy 183.568314 -147.289992) (xy 183.538347 -147.341898) (xy 183.50186 -147.389448) (xy 183.45948 -147.431828)
			(xy 183.41193 -147.468315) (xy 183.360024 -147.498282) (xy 183.304651 -147.521218) (xy 183.246758 -147.536731)
			(xy 183.187336 -147.544554) (xy 183.1274 -147.544554) (xy 183.067978 -147.536731) (xy 183.010085 -147.521218)
			(xy 182.954712 -147.498282) (xy 182.902806 -147.468315) (xy 182.855256 -147.431828) (xy 182.812876 -147.389448)
			(xy 182.776389 -147.341898) (xy 182.746422 -147.289992) (xy 182.723486 -147.234619) (xy 182.707973 -147.176726)
			(xy 182.70015 -147.117304) (xy 182.69966 -147.087336) (xy 178.124375 -147.087336) (xy 178.103784 -147.482814)
			(xy 178.093116 -147.688554) (xy 178.030739 -148.887434) (xy 180.84546 -148.887434) (xy 180.84546 -148.023834)
			(xy 180.84595 -147.993866) (xy 180.853773 -147.934444) (xy 180.869286 -147.876551) (xy 180.892222 -147.821178)
			(xy 180.922189 -147.769272) (xy 180.958676 -147.721722) (xy 181.001056 -147.679342) (xy 181.048606 -147.642855)
			(xy 181.100512 -147.612888) (xy 181.155885 -147.589952) (xy 181.213778 -147.574439) (xy 181.2732 -147.566616)
			(xy 181.333136 -147.566616) (xy 181.392558 -147.574439) (xy 181.450451 -147.589952) (xy 181.505824 -147.612888)
			(xy 181.55773 -147.642855) (xy 181.60528 -147.679342) (xy 181.64766 -147.721722) (xy 181.684147 -147.769272)
			(xy 181.714114 -147.821178) (xy 181.73705 -147.876551) (xy 181.752563 -147.934444) (xy 181.760386 -147.993866)
			(xy 181.760876 -148.023834) (xy 181.760876 -148.887434) (xy 181.760386 -148.917402) (xy 181.752563 -148.976824)
			(xy 181.73705 -149.034717) (xy 181.714114 -149.09009) (xy 181.684147 -149.141996) (xy 181.64766 -149.189546)
			(xy 181.60528 -149.231926) (xy 181.55773 -149.268413) (xy 181.505824 -149.29838) (xy 181.450451 -149.321316)
			(xy 181.392558 -149.336829) (xy 181.333136 -149.344652) (xy 181.2732 -149.344652) (xy 181.213778 -149.336829)
			(xy 181.155885 -149.321316) (xy 181.100512 -149.29838) (xy 181.048606 -149.268413) (xy 181.001056 -149.231926)
			(xy 180.958676 -149.189546) (xy 180.922189 -149.141996) (xy 180.892222 -149.09009) (xy 180.869286 -149.034717)
			(xy 180.853773 -148.976824) (xy 180.84595 -148.917402) (xy 180.84546 -148.887434) (xy 178.030739 -148.887434)
			(xy 177.937094 -150.687278) (xy 182.69966 -150.687278) (xy 182.69966 -149.823678) (xy 182.70015 -149.79371)
			(xy 182.707973 -149.734288) (xy 182.723486 -149.676395) (xy 182.746422 -149.621022) (xy 182.776389 -149.569116)
			(xy 182.812876 -149.521566) (xy 182.855256 -149.479186) (xy 182.902806 -149.442699) (xy 182.954712 -149.412732)
			(xy 183.010085 -149.389796) (xy 183.067978 -149.374283) (xy 183.1274 -149.36646) (xy 183.187336 -149.36646)
			(xy 183.246758 -149.374283) (xy 183.304651 -149.389796) (xy 183.360024 -149.412732) (xy 183.41193 -149.442699)
			(xy 183.45948 -149.479186) (xy 183.50186 -149.521566) (xy 183.538347 -149.569116) (xy 183.568314 -149.621022)
			(xy 183.59125 -149.676395) (xy 183.606763 -149.734288) (xy 183.614586 -149.79371) (xy 183.615076 -149.823678)
			(xy 183.615076 -150.687278) (xy 183.614586 -150.717246) (xy 183.606763 -150.776668) (xy 183.59125 -150.834561)
			(xy 183.568314 -150.889934) (xy 183.538347 -150.94184) (xy 183.50186 -150.98939) (xy 183.45948 -151.03177)
			(xy 183.41193 -151.068257) (xy 183.360024 -151.098224) (xy 183.304651 -151.12116) (xy 183.246758 -151.136673)
			(xy 183.187336 -151.144496) (xy 183.1274 -151.144496) (xy 183.067978 -151.136673) (xy 183.010085 -151.12116)
			(xy 182.954712 -151.098224) (xy 182.902806 -151.068257) (xy 182.855256 -151.03177) (xy 182.812876 -150.98939)
			(xy 182.776389 -150.94184) (xy 182.746422 -150.889934) (xy 182.723486 -150.834561) (xy 182.707973 -150.776668)
			(xy 182.70015 -150.717246) (xy 182.69966 -150.687278) (xy 177.937094 -150.687278) (xy 177.88636 -151.662384)
			(xy 177.843417 -152.487376) (xy 180.84546 -152.487376) (xy 180.84546 -151.623776) (xy 180.84595 -151.593808)
			(xy 180.853773 -151.534386) (xy 180.869286 -151.476493) (xy 180.892222 -151.42112) (xy 180.922189 -151.369214)
			(xy 180.958676 -151.321664) (xy 181.001056 -151.279284) (xy 181.048606 -151.242797) (xy 181.100512 -151.21283)
			(xy 181.155885 -151.189894) (xy 181.213778 -151.174381) (xy 181.2732 -151.166558) (xy 181.333136 -151.166558)
			(xy 181.392558 -151.174381) (xy 181.450451 -151.189894) (xy 181.505824 -151.21283) (xy 181.55773 -151.242797)
			(xy 181.60528 -151.279284) (xy 181.64766 -151.321664) (xy 181.684147 -151.369214) (xy 181.714114 -151.42112)
			(xy 181.73705 -151.476493) (xy 181.752563 -151.534386) (xy 181.760386 -151.593808) (xy 181.760876 -151.623776)
			(xy 181.760876 -152.487376) (xy 181.760386 -152.517344) (xy 181.752563 -152.576766) (xy 181.73705 -152.634659)
			(xy 181.714114 -152.690032) (xy 181.684147 -152.741938) (xy 181.64766 -152.789488) (xy 181.60528 -152.831868)
			(xy 181.55773 -152.868355) (xy 181.505824 -152.898322) (xy 181.450451 -152.921258) (xy 181.392558 -152.936771)
			(xy 181.333136 -152.944594) (xy 181.2732 -152.944594) (xy 181.213778 -152.936771) (xy 181.155885 -152.921258)
			(xy 181.100512 -152.898322) (xy 181.048606 -152.868355) (xy 181.001056 -152.831868) (xy 180.958676 -152.789488)
			(xy 180.922189 -152.741938) (xy 180.892222 -152.690032) (xy 180.869286 -152.634659) (xy 180.853773 -152.576766)
			(xy 180.84595 -152.517344) (xy 180.84546 -152.487376) (xy 177.843417 -152.487376) (xy 177.749731 -154.28722)
			(xy 182.69966 -154.28722) (xy 182.69966 -153.42362) (xy 182.70015 -153.393652) (xy 182.707973 -153.33423)
			(xy 182.723486 -153.276337) (xy 182.746422 -153.220964) (xy 182.776389 -153.169058) (xy 182.812876 -153.121508)
			(xy 182.855256 -153.079128) (xy 182.902806 -153.042641) (xy 182.954712 -153.012674) (xy 183.010085 -152.989738)
			(xy 183.067978 -152.974225) (xy 183.1274 -152.966402) (xy 183.187336 -152.966402) (xy 183.246758 -152.974225)
			(xy 183.304651 -152.989738) (xy 183.360024 -153.012674) (xy 183.41193 -153.042641) (xy 183.45948 -153.079128)
			(xy 183.50186 -153.121508) (xy 183.538347 -153.169058) (xy 183.568314 -153.220964) (xy 183.59125 -153.276337)
			(xy 183.606763 -153.33423) (xy 183.614586 -153.393652) (xy 183.615076 -153.42362) (xy 183.615076 -154.28722)
			(xy 183.614586 -154.317188) (xy 183.606763 -154.37661) (xy 183.59125 -154.434503) (xy 183.568314 -154.489876)
			(xy 183.538347 -154.541782) (xy 183.50186 -154.589332) (xy 183.45948 -154.631712) (xy 183.41193 -154.668199)
			(xy 183.360024 -154.698166) (xy 183.304651 -154.721102) (xy 183.246758 -154.736615) (xy 183.187336 -154.744438)
			(xy 183.1274 -154.744438) (xy 183.067978 -154.736615) (xy 183.010085 -154.721102) (xy 182.954712 -154.698166)
			(xy 182.902806 -154.668199) (xy 182.855256 -154.631712) (xy 182.812876 -154.589332) (xy 182.776389 -154.541782)
			(xy 182.746422 -154.489876) (xy 182.723486 -154.434503) (xy 182.707973 -154.37661) (xy 182.70015 -154.317188)
			(xy 182.69966 -154.28722) (xy 177.749731 -154.28722) (xy 177.656032 -156.087318) (xy 180.84546 -156.087318)
			(xy 180.84546 -155.223718) (xy 180.84595 -155.19375) (xy 180.853773 -155.134328) (xy 180.869286 -155.076435)
			(xy 180.892222 -155.021062) (xy 180.922189 -154.969156) (xy 180.958676 -154.921606) (xy 181.001056 -154.879226)
			(xy 181.048606 -154.842739) (xy 181.100512 -154.812772) (xy 181.155885 -154.789836) (xy 181.213778 -154.774323)
			(xy 181.2732 -154.7665) (xy 181.333136 -154.7665) (xy 181.392558 -154.774323) (xy 181.450451 -154.789836)
			(xy 181.505824 -154.812772) (xy 181.55773 -154.842739) (xy 181.60528 -154.879226) (xy 181.64766 -154.921606)
			(xy 181.684147 -154.969156) (xy 181.714114 -155.021062) (xy 181.73705 -155.076435) (xy 181.752563 -155.134328)
			(xy 181.760386 -155.19375) (xy 181.760876 -155.223718) (xy 181.760876 -156.087318) (xy 181.760386 -156.117286)
			(xy 181.752563 -156.176708) (xy 181.73705 -156.234601) (xy 181.714114 -156.289974) (xy 181.684147 -156.34188)
			(xy 181.64766 -156.38943) (xy 181.60528 -156.43181) (xy 181.55773 -156.468297) (xy 181.505824 -156.498264)
			(xy 181.450451 -156.5212) (xy 181.392558 -156.536713) (xy 181.333136 -156.544536) (xy 181.2732 -156.544536)
			(xy 181.213778 -156.536713) (xy 181.155885 -156.5212) (xy 181.100512 -156.498264) (xy 181.048606 -156.468297)
			(xy 181.001056 -156.43181) (xy 180.958676 -156.38943) (xy 180.922189 -156.34188) (xy 180.892222 -156.289974)
			(xy 180.869286 -156.234601) (xy 180.853773 -156.176708) (xy 180.84595 -156.117286) (xy 180.84546 -156.087318)
			(xy 177.656032 -156.087318) (xy 177.606175 -157.045152) (xy 178.526438 -157.045152) (xy 178.530509 -156.98953)
			(xy 178.542635 -156.935093) (xy 178.562558 -156.883002) (xy 178.589854 -156.834367) (xy 178.62394 -156.790224)
			(xy 178.664089 -156.751515) (xy 178.709447 -156.719064) (xy 178.759047 -156.693563) (xy 178.811831 -156.675556)
			(xy 178.866674 -156.665426) (xy 178.922408 -156.663389) (xy 178.977845 -156.669489) (xy 179.031802 -156.683595)
			(xy 179.083131 -156.705407) (xy 179.130737 -156.734461) (xy 179.173605 -156.770136) (xy 179.210822 -156.811673)
			(xy 179.241595 -156.858186) (xy 179.265267 -156.908683) (xy 179.281335 -156.96209) (xy 179.289455 -157.017266)
			(xy 179.289964 -157.045152) (xy 179.289455 -157.073038) (xy 179.281335 -157.128214) (xy 179.265267 -157.181621)
			(xy 179.241595 -157.232118) (xy 179.210822 -157.278631) (xy 179.173605 -157.320168) (xy 179.130737 -157.355843)
			(xy 179.083131 -157.384897) (xy 179.031802 -157.406709) (xy 178.977845 -157.420815) (xy 178.922408 -157.426915)
			(xy 178.866674 -157.424878) (xy 178.811831 -157.414748) (xy 178.759047 -157.396741) (xy 178.709447 -157.37124)
			(xy 178.664089 -157.338789) (xy 178.62394 -157.30008) (xy 178.589854 -157.255937) (xy 178.562558 -157.207302)
			(xy 178.542635 -157.155211) (xy 178.530509 -157.100774) (xy 178.526438 -157.045152) (xy 177.606175 -157.045152)
			(xy 177.442734 -160.1851) (xy 185.988973 -160.1851) (xy 185.992929 -160.093241) (xy 186.004766 -160.002062)
			(xy 186.024398 -159.912238) (xy 186.051679 -159.824435) (xy 186.086407 -159.739302) (xy 186.128325 -159.657469)
			(xy 186.177123 -159.579542) (xy 186.232438 -159.506099) (xy 186.293863 -159.437683) (xy 186.360942 -159.374801)
			(xy 186.433177 -159.317918) (xy 186.510036 -159.267455) (xy 186.590948 -159.223786) (xy 186.675314 -159.187234)
			(xy 186.76251 -159.15807) (xy 186.851891 -159.13651) (xy 186.942794 -159.122714) (xy 187.034547 -159.116782)
			(xy 187.126469 -159.118761) (xy 187.217882 -159.128634) (xy 187.308107 -159.146329) (xy 187.396478 -159.171714)
			(xy 187.482338 -159.204602) (xy 187.565054 -159.24475) (xy 187.644012 -159.291859) (xy 187.718629 -159.345582)
			(xy 187.78835 -159.40552) (xy 187.852661 -159.47123) (xy 187.911086 -159.542226) (xy 187.963191 -159.61798)
			(xy 188.00859 -159.697934) (xy 188.046949 -159.781494) (xy 188.077982 -159.868043) (xy 188.10146 -159.956939)
			(xy 188.11721 -160.047524) (xy 188.125114 -160.139128) (xy 188.125608 -160.1851) (xy 188.125114 -160.231072)
			(xy 188.11721 -160.322676) (xy 188.10146 -160.413261) (xy 188.077982 -160.502157) (xy 188.046949 -160.588706)
			(xy 188.00859 -160.672266) (xy 187.963191 -160.75222) (xy 187.911086 -160.827974) (xy 187.852661 -160.89897)
			(xy 187.78835 -160.96468) (xy 187.718629 -161.024618) (xy 187.644012 -161.078341) (xy 187.565054 -161.12545)
			(xy 187.482338 -161.165598) (xy 187.396478 -161.198486) (xy 187.308107 -161.223871) (xy 187.217882 -161.241566)
			(xy 187.126469 -161.251439) (xy 187.034547 -161.253418) (xy 186.942794 -161.247486) (xy 186.851891 -161.23369)
			(xy 186.76251 -161.21213) (xy 186.675314 -161.182966) (xy 186.590948 -161.146414) (xy 186.510036 -161.102745)
			(xy 186.433177 -161.052282) (xy 186.360942 -160.995399) (xy 186.293863 -160.932517) (xy 186.232438 -160.864101)
			(xy 186.177123 -160.790658) (xy 186.128325 -160.712731) (xy 186.086407 -160.630898) (xy 186.051679 -160.545765)
			(xy 186.024398 -160.457962) (xy 186.004766 -160.368138) (xy 185.992929 -160.276959) (xy 185.988973 -160.1851)
			(xy 177.442734 -160.1851) (xy 177.136384 -166.070534) (xy 180.295294 -166.070534) (xy 180.299365 -166.014912)
			(xy 180.311491 -165.960475) (xy 180.331414 -165.908384) (xy 180.35871 -165.859749) (xy 180.392796 -165.815606)
			(xy 180.432945 -165.776897) (xy 180.478303 -165.744446) (xy 180.527903 -165.718945) (xy 180.580687 -165.700938)
			(xy 180.63553 -165.690808) (xy 180.691264 -165.688771) (xy 180.746701 -165.694871) (xy 180.800658 -165.708977)
			(xy 180.851987 -165.730789) (xy 180.899593 -165.759843) (xy 180.942461 -165.795518) (xy 180.979678 -165.837055)
			(xy 181.010451 -165.883568) (xy 181.034123 -165.934065) (xy 181.050191 -165.987472) (xy 181.058311 -166.042648)
			(xy 181.05882 -166.070534) (xy 181.058311 -166.09842) (xy 181.050191 -166.153596) (xy 181.034123 -166.207003)
			(xy 181.010451 -166.2575) (xy 180.979678 -166.304013) (xy 180.942461 -166.34555) (xy 180.899593 -166.381225)
			(xy 180.851987 -166.410279) (xy 180.800658 -166.432091) (xy 180.746701 -166.446197) (xy 180.691264 -166.452297)
			(xy 180.63553 -166.45026) (xy 180.580687 -166.44013) (xy 180.527903 -166.422123) (xy 180.478303 -166.396622)
			(xy 180.432945 -166.364171) (xy 180.392796 -166.325462) (xy 180.35871 -166.281319) (xy 180.331414 -166.232684)
			(xy 180.311491 -166.180593) (xy 180.299365 -166.126156) (xy 180.295294 -166.070534) (xy 177.136384 -166.070534)
			(xy 177.103331 -166.705534) (xy 177.211734 -166.705534) (xy 177.215805 -166.649912) (xy 177.227931 -166.595475)
			(xy 177.247854 -166.543384) (xy 177.27515 -166.494749) (xy 177.309236 -166.450606) (xy 177.349385 -166.411897)
			(xy 177.394743 -166.379446) (xy 177.444343 -166.353945) (xy 177.497127 -166.335938) (xy 177.55197 -166.325808)
			(xy 177.607704 -166.323771) (xy 177.663141 -166.329871) (xy 177.717098 -166.343977) (xy 177.768427 -166.365789)
			(xy 177.816033 -166.394843) (xy 177.858901 -166.430518) (xy 177.896118 -166.472055) (xy 177.926891 -166.518568)
			(xy 177.950563 -166.569065) (xy 177.950966 -166.570406) (xy 178.787042 -166.570406) (xy 178.791113 -166.514784)
			(xy 178.803239 -166.460347) (xy 178.823162 -166.408256) (xy 178.850458 -166.359621) (xy 178.884544 -166.315478)
			(xy 178.924693 -166.276769) (xy 178.970051 -166.244318) (xy 179.019651 -166.218817) (xy 179.072435 -166.20081)
			(xy 179.127278 -166.19068) (xy 179.183012 -166.188643) (xy 179.238449 -166.194743) (xy 179.292406 -166.208849)
			(xy 179.343735 -166.230661) (xy 179.391341 -166.259715) (xy 179.434209 -166.29539) (xy 179.471426 -166.336927)
			(xy 179.502199 -166.38344) (xy 179.525871 -166.433937) (xy 179.541939 -166.487344) (xy 179.550059 -166.54252)
			(xy 179.550568 -166.570406) (xy 179.550059 -166.598292) (xy 179.541939 -166.653468) (xy 179.525871 -166.706875)
			(xy 179.502199 -166.757372) (xy 179.471426 -166.803885) (xy 179.434209 -166.845422) (xy 179.391341 -166.881097)
			(xy 179.343735 -166.910151) (xy 179.292406 -166.931963) (xy 179.238449 -166.946069) (xy 179.183012 -166.952169)
			(xy 179.127278 -166.950132) (xy 179.072435 -166.940002) (xy 179.019651 -166.921995) (xy 178.970051 -166.896494)
			(xy 178.924693 -166.864043) (xy 178.884544 -166.825334) (xy 178.850458 -166.781191) (xy 178.823162 -166.732556)
			(xy 178.803239 -166.680465) (xy 178.791113 -166.626028) (xy 178.787042 -166.570406) (xy 177.950966 -166.570406)
			(xy 177.966631 -166.622472) (xy 177.974751 -166.677648) (xy 177.97526 -166.705534) (xy 177.974751 -166.73342)
			(xy 177.966631 -166.788596) (xy 177.950563 -166.842003) (xy 177.926891 -166.8925) (xy 177.896118 -166.939013)
			(xy 177.858901 -166.98055) (xy 177.816033 -167.016225) (xy 177.768427 -167.045279) (xy 177.717098 -167.067091)
			(xy 177.663141 -167.081197) (xy 177.607704 -167.087297) (xy 177.55197 -167.08526) (xy 177.497127 -167.07513)
			(xy 177.444343 -167.057123) (xy 177.394743 -167.031622) (xy 177.349385 -166.999171) (xy 177.309236 -166.960462)
			(xy 177.27515 -166.916319) (xy 177.247854 -166.867684) (xy 177.227931 -166.815593) (xy 177.215805 -166.761156)
			(xy 177.211734 -166.705534) (xy 177.103331 -166.705534) (xy 176.971198 -169.24401) (xy 176.968912 -169.288714)
			(xy 176.897792 -170.654218) (xy 176.810639 -172.329348) (xy 177.947826 -172.329348) (xy 177.951897 -172.273726)
			(xy 177.964023 -172.219289) (xy 177.983946 -172.167198) (xy 178.011242 -172.118563) (xy 178.045328 -172.07442)
			(xy 178.085477 -172.035711) (xy 178.130835 -172.00326) (xy 178.180435 -171.977759) (xy 178.233219 -171.959752)
			(xy 178.288062 -171.949622) (xy 178.343796 -171.947585) (xy 178.399233 -171.953685) (xy 178.45319 -171.967791)
			(xy 178.504519 -171.989603) (xy 178.552125 -172.018657) (xy 178.594993 -172.054332) (xy 178.63221 -172.095869)
			(xy 178.662983 -172.142382) (xy 178.686655 -172.192879) (xy 178.702723 -172.246286) (xy 178.710843 -172.301462)
			(xy 178.711352 -172.329348) (xy 178.711088 -172.343826) (xy 178.885086 -172.343826) (xy 178.889157 -172.288204)
			(xy 178.901283 -172.233767) (xy 178.921206 -172.181676) (xy 178.948502 -172.133041) (xy 178.982588 -172.088898)
			(xy 179.022737 -172.050189) (xy 179.068095 -172.017738) (xy 179.117695 -171.992237) (xy 179.170479 -171.97423)
			(xy 179.225322 -171.9641) (xy 179.281056 -171.962063) (xy 179.336493 -171.968163) (xy 179.39045 -171.982269)
			(xy 179.441779 -172.004081) (xy 179.489385 -172.033135) (xy 179.532253 -172.06881) (xy 179.56947 -172.110347)
			(xy 179.600243 -172.15686) (xy 179.623915 -172.207357) (xy 179.639983 -172.260764) (xy 179.648103 -172.31594)
			(xy 179.648612 -172.343826) (xy 179.648103 -172.371712) (xy 179.639983 -172.426888) (xy 179.623915 -172.480295)
			(xy 179.600243 -172.530792) (xy 179.56947 -172.577305) (xy 179.532253 -172.618842) (xy 179.489385 -172.654517)
			(xy 179.441779 -172.683571) (xy 179.39045 -172.705383) (xy 179.336493 -172.719489) (xy 179.281056 -172.725589)
			(xy 179.225322 -172.723552) (xy 179.170479 -172.713422) (xy 179.117695 -172.695415) (xy 179.068095 -172.669914)
			(xy 179.022737 -172.637463) (xy 178.982588 -172.598754) (xy 178.948502 -172.554611) (xy 178.921206 -172.505976)
			(xy 178.901283 -172.453885) (xy 178.889157 -172.399448) (xy 178.885086 -172.343826) (xy 178.711088 -172.343826)
			(xy 178.710843 -172.357234) (xy 178.702723 -172.41241) (xy 178.686655 -172.465817) (xy 178.662983 -172.516314)
			(xy 178.63221 -172.562827) (xy 178.594993 -172.604364) (xy 178.552125 -172.640039) (xy 178.504519 -172.669093)
			(xy 178.45319 -172.690905) (xy 178.399233 -172.705011) (xy 178.343796 -172.711111) (xy 178.288062 -172.709074)
			(xy 178.233219 -172.698944) (xy 178.180435 -172.680937) (xy 178.130835 -172.655436) (xy 178.085477 -172.622985)
			(xy 178.045328 -172.584276) (xy 178.011242 -172.540133) (xy 177.983946 -172.491498) (xy 177.964023 -172.439407)
			(xy 177.951897 -172.38497) (xy 177.947826 -172.329348) (xy 176.810639 -172.329348) (xy 176.703228 -174.39386)
			(xy 176.609028 -176.204372) (xy 183.126124 -176.204372) (xy 183.130195 -176.14875) (xy 183.142321 -176.094313)
			(xy 183.162244 -176.042222) (xy 183.18954 -175.993587) (xy 183.223626 -175.949444) (xy 183.263775 -175.910735)
			(xy 183.309133 -175.878284) (xy 183.358733 -175.852783) (xy 183.411517 -175.834776) (xy 183.46636 -175.824646)
			(xy 183.522094 -175.822609) (xy 183.577531 -175.828709) (xy 183.631488 -175.842815) (xy 183.682817 -175.864627)
			(xy 183.730423 -175.893681) (xy 183.773291 -175.929356) (xy 183.810508 -175.970893) (xy 183.841281 -176.017406)
			(xy 183.864953 -176.067903) (xy 183.881021 -176.12131) (xy 183.889141 -176.176486) (xy 183.88965 -176.204372)
			(xy 183.889141 -176.232258) (xy 183.881021 -176.287434) (xy 183.864953 -176.340841) (xy 183.841281 -176.391338)
			(xy 183.810508 -176.437851) (xy 183.773291 -176.479388) (xy 183.730423 -176.515063) (xy 183.682817 -176.544117)
			(xy 183.631488 -176.565929) (xy 183.577531 -176.580035) (xy 183.522094 -176.586135) (xy 183.46636 -176.584098)
			(xy 183.411517 -176.573968) (xy 183.358733 -176.555961) (xy 183.309133 -176.53046) (xy 183.263775 -176.498009)
			(xy 183.223626 -176.4593) (xy 183.18954 -176.415157) (xy 183.162244 -176.366522) (xy 183.142321 -176.314431)
			(xy 183.130195 -176.259994) (xy 183.126124 -176.204372) (xy 176.609028 -176.204372) (xy 176.564413 -177.061876)
			(xy 178.352702 -177.061876) (xy 178.356773 -177.006254) (xy 178.368899 -176.951817) (xy 178.388822 -176.899726)
			(xy 178.416118 -176.851091) (xy 178.450204 -176.806948) (xy 178.490353 -176.768239) (xy 178.535711 -176.735788)
			(xy 178.585311 -176.710287) (xy 178.638095 -176.69228) (xy 178.692938 -176.68215) (xy 178.748672 -176.680113)
			(xy 178.804109 -176.686213) (xy 178.858066 -176.700319) (xy 178.909395 -176.722131) (xy 178.957001 -176.751185)
			(xy 178.999869 -176.78686) (xy 179.037086 -176.828397) (xy 179.067859 -176.87491) (xy 179.091531 -176.925407)
			(xy 179.107599 -176.978814) (xy 179.115719 -177.03399) (xy 179.116228 -177.061876) (xy 179.115719 -177.089762)
			(xy 179.107599 -177.144938) (xy 179.091531 -177.198345) (xy 179.067859 -177.248842) (xy 179.037086 -177.295355)
			(xy 178.999869 -177.336892) (xy 178.957001 -177.372567) (xy 178.909395 -177.401621) (xy 178.858066 -177.423433)
			(xy 178.804109 -177.437539) (xy 178.748672 -177.443639) (xy 178.692938 -177.441602) (xy 178.638095 -177.431472)
			(xy 178.585311 -177.413465) (xy 178.535711 -177.387964) (xy 178.490353 -177.355513) (xy 178.450204 -177.316804)
			(xy 178.416118 -177.272661) (xy 178.388822 -177.224026) (xy 178.368899 -177.171935) (xy 178.356773 -177.117498)
			(xy 178.352702 -177.061876) (xy 176.564413 -177.061876) (xy 176.530291 -177.717704) (xy 180.770782 -177.717704)
			(xy 180.774853 -177.662082) (xy 180.786979 -177.607645) (xy 180.806902 -177.555554) (xy 180.834198 -177.506919)
			(xy 180.868284 -177.462776) (xy 180.908433 -177.424067) (xy 180.953791 -177.391616) (xy 181.003391 -177.366115)
			(xy 181.056175 -177.348108) (xy 181.111018 -177.337978) (xy 181.166752 -177.335941) (xy 181.222189 -177.342041)
			(xy 181.276146 -177.356147) (xy 181.327475 -177.377959) (xy 181.375081 -177.407013) (xy 181.417949 -177.442688)
			(xy 181.455166 -177.484225) (xy 181.485939 -177.530738) (xy 181.509611 -177.581235) (xy 181.525679 -177.634642)
			(xy 181.533799 -177.689818) (xy 181.534308 -177.717704) (xy 181.533799 -177.74559) (xy 181.525679 -177.800766)
			(xy 181.509611 -177.854173) (xy 181.485939 -177.90467) (xy 181.455166 -177.951183) (xy 181.417949 -177.99272)
			(xy 181.375081 -178.028395) (xy 181.327475 -178.057449) (xy 181.276146 -178.079261) (xy 181.222189 -178.093367)
			(xy 181.166752 -178.099467) (xy 181.111018 -178.09743) (xy 181.056175 -178.0873) (xy 181.003391 -178.069293)
			(xy 180.953791 -178.043792) (xy 180.908433 -178.011341) (xy 180.868284 -177.972632) (xy 180.834198 -177.928489)
			(xy 180.806902 -177.879854) (xy 180.786979 -177.827763) (xy 180.774853 -177.773326) (xy 180.770782 -177.717704)
			(xy 176.530291 -177.717704) (xy 176.496776 -178.361848) (xy 178.332382 -178.361848) (xy 178.336453 -178.306226)
			(xy 178.348579 -178.251789) (xy 178.368502 -178.199698) (xy 178.395798 -178.151063) (xy 178.429884 -178.10692)
			(xy 178.470033 -178.068211) (xy 178.515391 -178.03576) (xy 178.564991 -178.010259) (xy 178.617775 -177.992252)
			(xy 178.672618 -177.982122) (xy 178.728352 -177.980085) (xy 178.783789 -177.986185) (xy 178.837746 -178.000291)
			(xy 178.889075 -178.022103) (xy 178.936681 -178.051157) (xy 178.979549 -178.086832) (xy 179.016766 -178.128369)
			(xy 179.047539 -178.174882) (xy 179.071211 -178.225379) (xy 179.087279 -178.278786) (xy 179.095399 -178.333962)
			(xy 179.095908 -178.361848) (xy 179.095399 -178.389734) (xy 179.09012 -178.425602) (xy 181.640224 -178.425602)
			(xy 181.644295 -178.36998) (xy 181.656421 -178.315543) (xy 181.676344 -178.263452) (xy 181.70364 -178.214817)
			(xy 181.737726 -178.170674) (xy 181.777875 -178.131965) (xy 181.823233 -178.099514) (xy 181.872833 -178.074013)
			(xy 181.925617 -178.056006) (xy 181.98046 -178.045876) (xy 182.036194 -178.043839) (xy 182.091631 -178.049939)
			(xy 182.145588 -178.064045) (xy 182.196917 -178.085857) (xy 182.244523 -178.114911) (xy 182.287391 -178.150586)
			(xy 182.324608 -178.192123) (xy 182.355381 -178.238636) (xy 182.379053 -178.289133) (xy 182.395121 -178.34254)
			(xy 182.403241 -178.397716) (xy 182.40375 -178.425602) (xy 182.403241 -178.453488) (xy 182.395121 -178.508664)
			(xy 182.379053 -178.562071) (xy 182.355381 -178.612568) (xy 182.324608 -178.659081) (xy 182.287391 -178.700618)
			(xy 182.244523 -178.736293) (xy 182.196917 -178.765347) (xy 182.145588 -178.787159) (xy 182.091631 -178.801265)
			(xy 182.036194 -178.807365) (xy 181.98046 -178.805328) (xy 181.925617 -178.795198) (xy 181.872833 -178.777191)
			(xy 181.823233 -178.75169) (xy 181.777875 -178.719239) (xy 181.737726 -178.68053) (xy 181.70364 -178.636387)
			(xy 181.676344 -178.587752) (xy 181.656421 -178.535661) (xy 181.644295 -178.481224) (xy 181.640224 -178.425602)
			(xy 179.09012 -178.425602) (xy 179.087279 -178.44491) (xy 179.071211 -178.498317) (xy 179.047539 -178.548814)
			(xy 179.016766 -178.595327) (xy 178.979549 -178.636864) (xy 178.936681 -178.672539) (xy 178.889075 -178.701593)
			(xy 178.837746 -178.723405) (xy 178.783789 -178.737511) (xy 178.728352 -178.743611) (xy 178.672618 -178.741574)
			(xy 178.617775 -178.731444) (xy 178.564991 -178.713437) (xy 178.515391 -178.687936) (xy 178.470033 -178.655485)
			(xy 178.429884 -178.616776) (xy 178.395798 -178.572633) (xy 178.368502 -178.523998) (xy 178.348579 -178.471907)
			(xy 178.336453 -178.41747) (xy 178.332382 -178.361848) (xy 176.496776 -178.361848) (xy 176.473358 -178.811936)
			(xy 176.426062 -179.720748) (xy 180.007766 -179.720748) (xy 180.011837 -179.665126) (xy 180.023963 -179.610689)
			(xy 180.043886 -179.558598) (xy 180.071182 -179.509963) (xy 180.105268 -179.46582) (xy 180.145417 -179.427111)
			(xy 180.190775 -179.39466) (xy 180.240375 -179.369159) (xy 180.293159 -179.351152) (xy 180.348002 -179.341022)
			(xy 180.403736 -179.338985) (xy 180.459173 -179.345085) (xy 180.51313 -179.359191) (xy 180.564459 -179.381003)
			(xy 180.612065 -179.410057) (xy 180.644782 -179.437284) (xy 181.43169 -179.437284) (xy 181.435761 -179.381662)
			(xy 181.447887 -179.327225) (xy 181.46781 -179.275134) (xy 181.495106 -179.226499) (xy 181.529192 -179.182356)
			(xy 181.569341 -179.143647) (xy 181.614699 -179.111196) (xy 181.664299 -179.085695) (xy 181.717083 -179.067688)
			(xy 181.771926 -179.057558) (xy 181.82766 -179.055521) (xy 181.883097 -179.061621) (xy 181.937054 -179.075727)
			(xy 181.988383 -179.097539) (xy 182.035989 -179.126593) (xy 182.078857 -179.162268) (xy 182.116074 -179.203805)
			(xy 182.146847 -179.250318) (xy 182.16448 -179.287932) (xy 183.426606 -179.287932) (xy 183.430677 -179.23231)
			(xy 183.442803 -179.177873) (xy 183.462726 -179.125782) (xy 183.490022 -179.077147) (xy 183.524108 -179.033004)
			(xy 183.564257 -178.994295) (xy 183.609615 -178.961844) (xy 183.659215 -178.936343) (xy 183.711999 -178.918336)
			(xy 183.766842 -178.908206) (xy 183.822576 -178.906169) (xy 183.878013 -178.912269) (xy 183.93197 -178.926375)
			(xy 183.983299 -178.948187) (xy 184.030905 -178.977241) (xy 184.073773 -179.012916) (xy 184.11099 -179.054453)
			(xy 184.141763 -179.100966) (xy 184.165435 -179.151463) (xy 184.181503 -179.20487) (xy 184.189623 -179.260046)
			(xy 184.190132 -179.287932) (xy 184.189623 -179.315818) (xy 184.181503 -179.370994) (xy 184.165435 -179.424401)
			(xy 184.141763 -179.474898) (xy 184.11099 -179.521411) (xy 184.073773 -179.562948) (xy 184.030905 -179.598623)
			(xy 183.983299 -179.627677) (xy 183.93197 -179.649489) (xy 183.878013 -179.663595) (xy 183.822576 -179.669695)
			(xy 183.766842 -179.667658) (xy 183.711999 -179.657528) (xy 183.659215 -179.639521) (xy 183.609615 -179.61402)
			(xy 183.564257 -179.581569) (xy 183.524108 -179.54286) (xy 183.490022 -179.498717) (xy 183.462726 -179.450082)
			(xy 183.442803 -179.397991) (xy 183.430677 -179.343554) (xy 183.426606 -179.287932) (xy 182.16448 -179.287932)
			(xy 182.170519 -179.300815) (xy 182.186587 -179.354222) (xy 182.194707 -179.409398) (xy 182.195216 -179.437284)
			(xy 182.194707 -179.46517) (xy 182.186587 -179.520346) (xy 182.170519 -179.573753) (xy 182.146847 -179.62425)
			(xy 182.116074 -179.670763) (xy 182.078857 -179.7123) (xy 182.035989 -179.747975) (xy 181.988383 -179.777029)
			(xy 181.937054 -179.798841) (xy 181.883097 -179.812947) (xy 181.82766 -179.819047) (xy 181.771926 -179.81701)
			(xy 181.717083 -179.80688) (xy 181.664299 -179.788873) (xy 181.614699 -179.763372) (xy 181.569341 -179.730921)
			(xy 181.529192 -179.692212) (xy 181.495106 -179.648069) (xy 181.46781 -179.599434) (xy 181.447887 -179.547343)
			(xy 181.435761 -179.492906) (xy 181.43169 -179.437284) (xy 180.644782 -179.437284) (xy 180.654933 -179.445732)
			(xy 180.69215 -179.487269) (xy 180.722923 -179.533782) (xy 180.746595 -179.584279) (xy 180.762663 -179.637686)
			(xy 180.770783 -179.692862) (xy 180.771292 -179.720748) (xy 180.770783 -179.748634) (xy 180.762663 -179.80381)
			(xy 180.746595 -179.857217) (xy 180.722923 -179.907714) (xy 180.69215 -179.954227) (xy 180.654933 -179.995764)
			(xy 180.612065 -180.031439) (xy 180.564459 -180.060493) (xy 180.51313 -180.082305) (xy 180.459173 -180.096411)
			(xy 180.403736 -180.102511) (xy 180.348002 -180.100474) (xy 180.293159 -180.090344) (xy 180.240375 -180.072337)
			(xy 180.190775 -180.046836) (xy 180.145417 -180.014385) (xy 180.105268 -179.975676) (xy 180.071182 -179.931533)
			(xy 180.043886 -179.882898) (xy 180.023963 -179.830807) (xy 180.011837 -179.77637) (xy 180.007766 -179.720748)
			(xy 176.426062 -179.720748) (xy 176.371919 -180.761132) (xy 182.748172 -180.761132) (xy 182.752243 -180.70551)
			(xy 182.764369 -180.651073) (xy 182.784292 -180.598982) (xy 182.811588 -180.550347) (xy 182.845674 -180.506204)
			(xy 182.885823 -180.467495) (xy 182.931181 -180.435044) (xy 182.980781 -180.409543) (xy 183.033565 -180.391536)
			(xy 183.088408 -180.381406) (xy 183.144142 -180.379369) (xy 183.199579 -180.385469) (xy 183.253536 -180.399575)
			(xy 183.304865 -180.421387) (xy 183.352471 -180.450441) (xy 183.395339 -180.486116) (xy 183.432556 -180.527653)
			(xy 183.463329 -180.574166) (xy 183.487001 -180.624663) (xy 183.503069 -180.67807) (xy 183.511189 -180.733246)
			(xy 183.511698 -180.761132) (xy 183.511189 -180.789018) (xy 183.503069 -180.844194) (xy 183.487001 -180.897601)
			(xy 183.463329 -180.948098) (xy 183.432556 -180.994611) (xy 183.395339 -181.036148) (xy 183.352471 -181.071823)
			(xy 183.304865 -181.100877) (xy 183.253536 -181.122689) (xy 183.199579 -181.136795) (xy 183.144142 -181.142895)
			(xy 183.088408 -181.140858) (xy 183.033565 -181.130728) (xy 182.980781 -181.112721) (xy 182.931181 -181.08722)
			(xy 182.885823 -181.054769) (xy 182.845674 -181.01606) (xy 182.811588 -180.971917) (xy 182.784292 -180.923282)
			(xy 182.764369 -180.871191) (xy 182.752243 -180.816754) (xy 182.748172 -180.761132) (xy 176.371919 -180.761132)
			(xy 176.153005 -184.967626) (xy 183.30494 -184.967626) (xy 183.309011 -184.912004) (xy 183.321137 -184.857567)
			(xy 183.34106 -184.805476) (xy 183.368356 -184.756841) (xy 183.402442 -184.712698) (xy 183.442591 -184.673989)
			(xy 183.487949 -184.641538) (xy 183.537549 -184.616037) (xy 183.590333 -184.59803) (xy 183.645176 -184.5879)
			(xy 183.70091 -184.585863) (xy 183.756347 -184.591963) (xy 183.810304 -184.606069) (xy 183.861633 -184.627881)
			(xy 183.909239 -184.656935) (xy 183.952107 -184.69261) (xy 183.989324 -184.734147) (xy 184.020097 -184.78066)
			(xy 184.043769 -184.831157) (xy 184.059837 -184.884564) (xy 184.067957 -184.93974) (xy 184.068466 -184.967626)
			(xy 184.067957 -184.995512) (xy 184.059837 -185.050688) (xy 184.043769 -185.104095) (xy 184.020097 -185.154592)
			(xy 183.989324 -185.201105) (xy 183.952107 -185.242642) (xy 183.909239 -185.278317) (xy 183.861633 -185.307371)
			(xy 183.810304 -185.329183) (xy 183.756347 -185.343289) (xy 183.70091 -185.349389) (xy 183.645176 -185.347352)
			(xy 183.590333 -185.337222) (xy 183.537549 -185.319215) (xy 183.487949 -185.293714) (xy 183.442591 -185.261263)
			(xy 183.402442 -185.222554) (xy 183.368356 -185.178411) (xy 183.34106 -185.129776) (xy 183.321137 -185.077685)
			(xy 183.309011 -185.023248) (xy 183.30494 -184.967626) (xy 176.153005 -184.967626) (xy 176.149 -185.044588)
			(xy 176.137316 -185.266838) (xy 176.137316 -185.281316) (xy 176.146968 -185.30062) (xy 176.154334 -185.307986)
			(xy 176.174838 -185.328518) (xy 176.210019 -185.374657) (xy 176.237816 -185.425588) (xy 176.257587 -185.480138)
			(xy 176.268878 -185.537052) (xy 176.271429 -185.595018) (xy 176.265181 -185.652703) (xy 176.250278 -185.708779)
			(xy 176.227064 -185.761955) (xy 176.196071 -185.811007) (xy 176.177448 -185.833258) (xy 176.169483 -185.842291)
			(xy 176.152577 -185.859447) (xy 176.143666 -185.867548) (xy 176.128172 -185.880756) (xy 176.12614 -185.882534)
			(xy 176.117504 -185.89117) (xy 176.113186 -185.896504) (xy 176.109591 -185.901646) (xy 176.104721 -185.913203)
			(xy 176.103534 -185.919364) (xy 176.083976 -186.293252) (xy 176.075086 -186.463178) (xy 176.04867 -186.97067)
			(xy 176.010659 -187.701174) (xy 182.793384 -187.701174) (xy 182.797455 -187.645552) (xy 182.809581 -187.591115)
			(xy 182.829504 -187.539024) (xy 182.8568 -187.490389) (xy 182.890886 -187.446246) (xy 182.931035 -187.407537)
			(xy 182.976393 -187.375086) (xy 183.025993 -187.349585) (xy 183.078777 -187.331578) (xy 183.13362 -187.321448)
			(xy 183.189354 -187.319411) (xy 183.244791 -187.325511) (xy 183.298748 -187.339617) (xy 183.350077 -187.361429)
			(xy 183.397683 -187.390483) (xy 183.440551 -187.426158) (xy 183.477768 -187.467695) (xy 183.508541 -187.514208)
			(xy 183.532213 -187.564705) (xy 183.548281 -187.618112) (xy 183.556401 -187.673288) (xy 183.55691 -187.701174)
			(xy 183.556401 -187.72906) (xy 183.548281 -187.784236) (xy 183.532213 -187.837643) (xy 183.508541 -187.88814)
			(xy 183.477768 -187.934653) (xy 183.440551 -187.97619) (xy 183.397683 -188.011865) (xy 183.350077 -188.040919)
			(xy 183.298748 -188.062731) (xy 183.244791 -188.076837) (xy 183.189354 -188.082937) (xy 183.13362 -188.0809)
			(xy 183.078777 -188.07077) (xy 183.025993 -188.052763) (xy 182.976393 -188.027262) (xy 182.931035 -187.994811)
			(xy 182.890886 -187.956102) (xy 182.8568 -187.911959) (xy 182.829504 -187.863324) (xy 182.809581 -187.811233)
			(xy 182.797455 -187.756796) (xy 182.793384 -187.701174) (xy 176.010659 -187.701174) (xy 175.925226 -189.34303)
			(xy 175.873156 -190.344806) (xy 175.800512 -191.737234) (xy 175.77284 -192.270634) (xy 178.101496 -192.270634)
			(xy 178.105567 -192.215012) (xy 178.117693 -192.160575) (xy 178.137616 -192.108484) (xy 178.164912 -192.059849)
			(xy 178.198998 -192.015706) (xy 178.239147 -191.976997) (xy 178.284505 -191.944546) (xy 178.334105 -191.919045)
			(xy 178.386889 -191.901038) (xy 178.441732 -191.890908) (xy 178.497466 -191.888871) (xy 178.552903 -191.894971)
			(xy 178.60686 -191.909077) (xy 178.658189 -191.930889) (xy 178.705795 -191.959943) (xy 178.748663 -191.995618)
			(xy 178.78588 -192.037155) (xy 178.816653 -192.083668) (xy 178.840325 -192.134165) (xy 178.856393 -192.187572)
			(xy 178.864513 -192.242748) (xy 178.865022 -192.270634) (xy 178.864513 -192.29852) (xy 178.856393 -192.353696)
			(xy 178.840325 -192.407103) (xy 178.816653 -192.4576) (xy 178.78588 -192.504113) (xy 178.748663 -192.54565)
			(xy 178.705795 -192.581325) (xy 178.658189 -192.610379) (xy 178.60686 -192.632191) (xy 178.552903 -192.646297)
			(xy 178.497466 -192.652397) (xy 178.441732 -192.65036) (xy 178.386889 -192.64023) (xy 178.334105 -192.622223)
			(xy 178.284505 -192.596722) (xy 178.239147 -192.564271) (xy 178.198998 -192.525562) (xy 178.164912 -192.481419)
			(xy 178.137616 -192.432784) (xy 178.117693 -192.380693) (xy 178.105567 -192.326256) (xy 178.101496 -192.270634)
			(xy 175.77284 -192.270634) (xy 175.763682 -192.447164) (xy 175.761142 -192.496948) (xy 175.761142 -192.499996)
			(xy 175.761606 -192.509376) (xy 175.768434 -192.526854) (xy 175.781101 -192.540698) (xy 175.789336 -192.545208)
			(xy 175.806354 -192.553844) (xy 175.81499 -192.555114) (xy 175.842203 -192.559163) (xy 175.895163 -192.574064)
			(xy 175.945436 -192.596411) (xy 175.991981 -192.625743) (xy 176.033835 -192.661451) (xy 176.07013 -192.702797)
			(xy 176.100116 -192.748924) (xy 176.12317 -192.798877) (xy 176.138816 -192.851622) (xy 176.146731 -192.906066)
			(xy 176.147222 -192.933574) (xy 176.146763 -192.960076) (xy 176.139419 -193.012569) (xy 176.124884 -193.063541)
			(xy 176.103436 -193.112012) (xy 176.075489 -193.15705) (xy 176.041579 -193.197788) (xy 176.002359 -193.233442)
			(xy 175.958584 -193.263328) (xy 175.911094 -193.286869) (xy 175.860805 -193.303614) (xy 175.808682 -193.313241)
			(xy 175.782224 -193.314828) (xy 175.775874 -193.315082) (xy 175.767746 -193.318638) (xy 175.763639 -193.32044)
			(xy 175.756098 -193.325294) (xy 175.75276 -193.32829) (xy 175.730662 -193.349372) (xy 175.724025 -193.356338)
			(xy 175.716045 -193.373828) (xy 175.715168 -193.383408) (xy 175.71466 -193.390266) (xy 175.713898 -193.404744)
			(xy 175.701198 -193.648838) (xy 175.697388 -193.727578) (xy 175.697259 -193.734665) (xy 175.700476 -193.748463)
			(xy 175.703738 -193.754756) (xy 175.70831 -193.762884) (xy 175.742611 -193.794634) (xy 178.101496 -193.794634)
			(xy 178.105567 -193.739012) (xy 178.117693 -193.684575) (xy 178.137616 -193.632484) (xy 178.164912 -193.583849)
			(xy 178.198998 -193.539706) (xy 178.239147 -193.500997) (xy 178.284505 -193.468546) (xy 178.334105 -193.443045)
			(xy 178.386889 -193.425038) (xy 178.441732 -193.414908) (xy 178.497466 -193.412871) (xy 178.552903 -193.418971)
			(xy 178.60686 -193.433077) (xy 178.658189 -193.454889) (xy 178.705795 -193.483943) (xy 178.748663 -193.519618)
			(xy 178.78588 -193.561155) (xy 178.816653 -193.607668) (xy 178.840325 -193.658165) (xy 178.856393 -193.711572)
			(xy 178.864513 -193.766748) (xy 178.865022 -193.794634) (xy 178.864513 -193.82252) (xy 178.856393 -193.877696)
			(xy 178.840325 -193.931103) (xy 178.816653 -193.9816) (xy 178.78588 -194.028113) (xy 178.748663 -194.06965)
			(xy 178.705795 -194.105325) (xy 178.658189 -194.134379) (xy 178.60686 -194.156191) (xy 178.552903 -194.170297)
			(xy 178.497466 -194.176397) (xy 178.441732 -194.17436) (xy 178.386889 -194.16423) (xy 178.334105 -194.146223)
			(xy 178.284505 -194.120722) (xy 178.239147 -194.088271) (xy 178.198998 -194.049562) (xy 178.164912 -194.005419)
			(xy 178.137616 -193.956784) (xy 178.117693 -193.904693) (xy 178.105567 -193.850256) (xy 178.101496 -193.794634)
			(xy 175.742611 -193.794634) (xy 175.769778 -193.81978) (xy 175.775874 -193.825368) (xy 175.79086 -193.832226)
			(xy 175.802544 -193.833496) (xy 175.810164 -193.833496) (xy 175.813212 -193.833242) (xy 175.824472 -193.83196)
			(xy 175.847092 -193.830561) (xy 175.858424 -193.830448) (xy 175.858678 -193.830448) (xy 175.885917 -193.830953)
			(xy 175.939837 -193.838741) (xy 175.992101 -193.85412) (xy 176.041646 -193.876776) (xy 176.087465 -193.906249)
			(xy 176.128626 -193.94194) (xy 176.164291 -193.983123) (xy 176.193736 -194.028959) (xy 176.216362 -194.078518)
			(xy 176.231709 -194.130792) (xy 176.239464 -194.184716) (xy 176.239932 -194.211956) (xy 176.239472 -194.239212)
			(xy 176.23172 -194.293169) (xy 176.216368 -194.345473) (xy 176.193729 -194.39506) (xy 176.164262 -194.440921)
			(xy 176.128569 -194.482121) (xy 176.087375 -194.517821) (xy 176.04152 -194.547296) (xy 175.991937 -194.569945)
			(xy 175.939635 -194.585306) (xy 175.885679 -194.593067) (xy 175.858424 -194.593464) (xy 175.836703 -194.593141)
			(xy 175.793546 -194.588172) (xy 175.772318 -194.583558) (xy 175.761396 -194.581018) (xy 175.750474 -194.583304)
			(xy 175.747172 -194.584066) (xy 175.742671 -194.585475) (xy 175.73424 -194.589698) (xy 175.730408 -194.592448)
			(xy 175.695356 -194.61861) (xy 175.692054 -194.62115) (xy 175.6918 -194.621404) (xy 175.671988 -194.636644)
			(xy 175.667416 -194.639946) (xy 175.659741 -194.646682) (xy 175.650041 -194.664632) (xy 175.64862 -194.674744)
			(xy 175.580548 -195.99021) (xy 175.580548 -195.990464) (xy 175.580607 -196.002565) (xy 175.590556 -196.024585)
			(xy 175.599598 -196.032628) (xy 175.601884 -196.034406) (xy 175.665384 -196.083428) (xy 175.669838 -196.086465)
			(xy 175.679696 -196.090823) (xy 175.684942 -196.092064) (xy 175.690784 -196.09308) (xy 175.704246 -196.09308)
			(xy 175.715422 -196.090286) (xy 175.716184 -196.090032) (xy 175.741654 -196.083007) (xy 175.793912 -196.075235)
			(xy 175.820324 -196.074538) (xy 175.825658 -196.074538) (xy 175.852835 -196.07513) (xy 175.906612 -196.083067)
			(xy 175.958717 -196.098557) (xy 176.008096 -196.121287) (xy 176.053748 -196.150796) (xy 176.094748 -196.186487)
			(xy 176.130267 -196.227638) (xy 176.159584 -196.273413) (xy 176.182106 -196.322887) (xy 176.197377 -196.375057)
			(xy 176.205087 -196.428866) (xy 176.205642 -196.456046) (xy 176.205153 -196.483296) (xy 176.197391 -196.537241)
			(xy 176.182033 -196.589532) (xy 176.159389 -196.639105) (xy 176.129922 -196.684952) (xy 176.094231 -196.72614)
			(xy 176.053043 -196.76183) (xy 176.007195 -196.791295) (xy 175.95762 -196.813937) (xy 175.905329 -196.829294)
			(xy 175.851384 -196.837054) (xy 175.824134 -196.837554) (xy 175.82388 -196.837554) (xy 175.802544 -196.837046)
			(xy 175.801782 -196.837046) (xy 175.79848 -196.836792) (xy 175.797972 -196.836792) (xy 175.76165 -196.832474)
			(xy 175.73919 -196.828376) (xy 175.695382 -196.815519) (xy 175.674274 -196.80682) (xy 175.666654 -196.803772)
			(xy 175.65116 -196.802248) (xy 175.641 -196.80428) (xy 175.636905 -196.805355) (xy 175.62912 -196.808679)
			(xy 175.625506 -196.810884) (xy 175.555656 -196.854826) (xy 175.547528 -196.86143) (xy 175.540162 -196.868796)
			(xy 175.532796 -196.88556) (xy 175.532542 -196.890386) (xy 178.09794 -196.890386) (xy 178.102011 -196.834764)
			(xy 178.114137 -196.780327) (xy 178.13406 -196.728236) (xy 178.161356 -196.679601) (xy 178.195442 -196.635458)
			(xy 178.235591 -196.596749) (xy 178.280949 -196.564298) (xy 178.330549 -196.538797) (xy 178.383333 -196.52079)
			(xy 178.438176 -196.51066) (xy 178.49391 -196.508623) (xy 178.549347 -196.514723) (xy 178.603304 -196.528829)
			(xy 178.654633 -196.550641) (xy 178.702239 -196.579695) (xy 178.745107 -196.61537) (xy 178.782324 -196.656907)
			(xy 178.813097 -196.70342) (xy 178.836769 -196.753917) (xy 178.852837 -196.807324) (xy 178.860957 -196.8625)
			(xy 178.861466 -196.890386) (xy 178.860957 -196.918272) (xy 178.852837 -196.973448) (xy 178.836769 -197.026855)
			(xy 178.813097 -197.077352) (xy 178.782324 -197.123865) (xy 178.745107 -197.165402) (xy 178.702239 -197.201077)
			(xy 178.654633 -197.230131) (xy 178.603304 -197.251943) (xy 178.549347 -197.266049) (xy 178.49391 -197.272149)
			(xy 178.438176 -197.270112) (xy 178.383333 -197.259982) (xy 178.330549 -197.241975) (xy 178.280949 -197.216474)
			(xy 178.235591 -197.184023) (xy 178.195442 -197.145314) (xy 178.161356 -197.101171) (xy 178.13406 -197.052536)
			(xy 178.114137 -197.000445) (xy 178.102011 -196.946008) (xy 178.09794 -196.890386) (xy 175.532542 -196.890386)
			(xy 175.532288 -196.895212) (xy 175.518318 -197.162674) (xy 175.505364 -197.41007) (xy 175.505364 -197.410578)
			(xy 175.50511 -197.414642) (xy 175.505029 -197.423288) (xy 175.50995 -197.439853) (xy 175.520069 -197.45386)
			(xy 175.526954 -197.459092) (xy 175.559212 -197.481444) (xy 175.55972 -197.481444) (xy 175.591978 -197.503542)
			(xy 175.595962 -197.50613) (xy 175.604652 -197.509965) (xy 175.60925 -197.511162) (xy 175.620426 -197.512432)
			(xy 175.648366 -197.512432) (xy 175.658018 -197.508368) (xy 175.681724 -197.498728) (xy 175.731068 -197.485165)
			(xy 175.781783 -197.47832) (xy 175.80737 -197.477888) (xy 175.833976 -197.478354) (xy 175.886672 -197.485755)
			(xy 175.937829 -197.500403) (xy 175.986455 -197.522015) (xy 176.031608 -197.550172) (xy 176.072413 -197.584327)
			(xy 176.108077 -197.623818) (xy 176.137911 -197.667881) (xy 176.161336 -197.715661) (xy 176.177897 -197.766231)
			(xy 176.183036 -197.79234) (xy 176.183036 -197.792848) (xy 176.184814 -197.801738) (xy 176.188878 -197.80885)
			(xy 176.19726 -197.820026) (xy 176.201832 -197.82409) (xy 176.22393 -197.84314) (xy 176.230195 -197.847483)
			(xy 176.244528 -197.852653) (xy 176.252124 -197.8533) (xy 182.599838 -197.8533) (xy 182.600092 -197.8533)
			(xy 182.611708 -197.852667) (xy 182.632528 -197.842342) (xy 182.6467 -197.823923) (xy 182.649622 -197.81266)
			(xy 184.634378 -186.414664) (xy 184.634699 -186.402703) (xy 184.625706 -186.380562) (xy 184.617106 -186.372246)
			(xy 184.539128 -186.31408) (xy 184.528956 -186.308044) (xy 184.505513 -186.305139) (xy 184.49417 -186.308492)
			(xy 184.488328 -186.310778) (xy 184.461922 -186.323216) (xy 184.406276 -186.340832) (xy 184.348601 -186.34979)
			(xy 184.319418 -186.350402) (xy 184.292165 -186.34994) (xy 184.238213 -186.342185) (xy 184.185914 -186.326831)
			(xy 184.136332 -186.30419) (xy 184.090477 -186.274723) (xy 184.049283 -186.23903) (xy 184.013588 -186.197837)
			(xy 183.984119 -186.151984) (xy 183.961475 -186.102403) (xy 183.946119 -186.050105) (xy 183.938361 -185.996153)
			(xy 183.938361 -185.941647) (xy 183.946119 -185.887695) (xy 183.961475 -185.835397) (xy 183.984119 -185.785816)
			(xy 184.013588 -185.739963) (xy 184.049283 -185.69877) (xy 184.090477 -185.663077) (xy 184.136332 -185.63361)
			(xy 184.185914 -185.610969) (xy 184.238213 -185.595615) (xy 184.292165 -185.58786) (xy 184.319418 -185.587386)
			(xy 184.344999 -185.587793) (xy 184.395704 -185.594619) (xy 184.445041 -185.608161) (xy 184.492127 -185.628176)
			(xy 184.536114 -185.654303) (xy 184.576216 -185.686075) (xy 184.594246 -185.704226) (xy 184.595516 -185.705496)
			(xy 184.601928 -185.711294) (xy 184.617598 -185.718569) (xy 184.634798 -185.720187) (xy 184.643268 -185.71845)
			(xy 184.733438 -185.690764) (xy 184.742033 -185.687517) (xy 184.756308 -185.675975) (xy 184.765577 -185.660129)
			(xy 184.767474 -185.65114) (xy 187.162186 -171.901866) (xy 190.09741 -155.047696) (xy 190.096648 -155.045918)
			(xy 190.091568 -155.038552) (xy 190.080646 -155.02763) (xy 190.080138 -155.027122) (xy 190.058974 -155.005474)
			(xy 190.023082 -154.956721) (xy 189.995346 -154.90291) (xy 189.976462 -154.845391) (xy 189.966904 -154.785612)
			(xy 189.966346 -154.755342) (xy 189.966346 -154.74569) (xy 189.966854 -154.737816) (xy 189.967362 -154.731466)
			(xy 189.967362 -154.729688) (xy 189.96787 -154.723084) (xy 189.970773 -154.694823) (xy 189.983877 -154.639544)
			(xy 190.00503 -154.586818) (xy 190.033764 -154.53781) (xy 190.069446 -154.493603) (xy 190.111285 -154.455173)
			(xy 190.158359 -154.423369) (xy 190.18377 -154.410664) (xy 190.187834 -154.408632) (xy 190.20155 -154.400504)
			(xy 190.207392 -154.392884) (xy 190.212472 -154.386534) (xy 190.225172 -154.313382) (xy 190.241682 -154.21864)
			(xy 190.241936 -154.217878) (xy 190.241936 -154.217624) (xy 190.881508 -149.24532) (xy 191.44234 -144.885664)
			(xy 191.52108 -144.274032) (xy 191.521588 -144.267936) (xy 191.533526 -143.00962) (xy 191.537844 -142.56004)
			(xy 191.542162 -142.099792) (xy 191.59855 -136.127744) (xy 191.719454 -123.317762) (xy 191.779906 -116.901976)
			(xy 191.780312 -116.874731) (xy 191.783743 -116.820344) (xy 191.786764 -116.793264) (xy 191.789164 -116.774179)
			(xy 191.79526 -116.736195) (xy 191.798956 -116.717318) (xy 194.094354 -105.24744) (xy 194.290696 -104.266492)
			(xy 194.292474 -104.257602) (xy 194.290442 -104.244394) (xy 194.289172 -104.24033) (xy 194.280166 -104.211244)
			(xy 194.270462 -104.151138) (xy 194.269868 -104.120696) (xy 194.269868 -104.111044) (xy 194.270962 -104.084938)
			(xy 194.279402 -104.033373) (xy 194.29479 -103.98344) (xy 194.31684 -103.936069) (xy 194.345139 -103.892145)
			(xy 194.361816 -103.87203) (xy 194.36334 -103.870252) (xy 194.365372 -103.867458) (xy 194.368287 -103.863352)
			(xy 194.372629 -103.854268) (xy 194.374008 -103.849424) (xy 194.37477 -103.846376) (xy 194.383914 -103.800402)
			(xy 194.397122 -103.734616) (xy 194.415664 -103.64216) (xy 194.415664 -103.641906) (xy 194.420744 -103.617014)
			(xy 194.420744 -103.616506) (xy 194.450716 -103.463852) (xy 194.450716 -103.450898) (xy 194.449446 -103.445056)
			(xy 194.449192 -103.443278) (xy 194.447225 -103.437311) (xy 194.440793 -103.426523) (xy 194.436492 -103.421942)
			(xy 194.429888 -103.415338) (xy 194.426586 -103.413052) (xy 194.402753 -103.394937) (xy 194.360498 -103.352534)
			(xy 194.325377 -103.304058) (xy 194.298251 -103.250695) (xy 194.279783 -103.193753) (xy 194.270428 -103.134627)
			(xy 194.269868 -103.104696) (xy 194.270387 -103.076431) (xy 194.278739 -103.020522) (xy 194.295245 -102.966455)
			(xy 194.319544 -102.915414) (xy 194.351105 -102.868515) (xy 194.389237 -102.826782) (xy 194.433107 -102.79113)
			(xy 194.481755 -102.762337) (xy 194.534117 -102.741034) (xy 194.56146 -102.733856) (xy 194.568572 -102.732078)
			(xy 194.576954 -102.727252) (xy 194.58559 -102.724204) (xy 194.596766 -102.71125) (xy 194.599544 -102.707435)
			(xy 194.60377 -102.698999) (xy 194.605148 -102.694486) (xy 194.614546 -102.648258) (xy 194.621404 -102.613968)
			(xy 194.622166 -102.610412) (xy 194.630802 -102.567232) (xy 194.71259 -102.158546) (xy 194.719448 -102.124256)
			(xy 194.777106 -101.83622) (xy 194.813174 -101.656134) (xy 194.814952 -101.64699) (xy 194.825112 -101.596444)
			(xy 194.82562 -101.59365) (xy 194.827906 -101.581712) (xy 194.831462 -101.562154) (xy 194.832209 -101.551777)
			(xy 194.826298 -101.531852) (xy 194.820032 -101.523546) (xy 194.78879 -101.49078) (xy 194.763898 -101.464872)
			(xy 194.75958 -101.460554) (xy 194.752167 -101.453878) (xy 194.733732 -101.44631) (xy 194.723766 -101.445822)
			(xy 194.71513 -101.445822) (xy 194.711066 -101.44633) (xy 194.696244 -101.448559) (xy 194.666364 -101.450975)
			(xy 194.651376 -101.451156) (xy 194.624125 -101.450669) (xy 194.570177 -101.44291) (xy 194.517882 -101.427553)
			(xy 194.468305 -101.404911) (xy 194.422454 -101.375445) (xy 194.381263 -101.339754) (xy 194.34557 -101.298565)
			(xy 194.3161 -101.252716) (xy 194.293456 -101.20314) (xy 194.278096 -101.150847) (xy 194.270333 -101.096899)
			(xy 194.269868 -101.069648) (xy 194.270349 -101.042514) (xy 194.278046 -100.988794) (xy 194.293277 -100.936707)
			(xy 194.315736 -100.887304) (xy 194.344968 -100.841581) (xy 194.380384 -100.800462) (xy 194.421269 -100.764776)
			(xy 194.466798 -100.735244) (xy 194.516052 -100.712461) (xy 194.568038 -100.696887) (xy 194.621706 -100.688836)
			(xy 194.648836 -100.68814) (xy 194.65163 -100.68814) (xy 194.677646 -100.688579) (xy 194.729194 -100.695651)
			(xy 194.7793 -100.709673) (xy 194.827031 -100.730384) (xy 194.849496 -100.743512) (xy 194.855338 -100.747068)
			(xy 194.872864 -100.752402) (xy 194.882516 -100.753672) (xy 194.883024 -100.753672) (xy 194.887542 -100.753733)
			(xy 194.896485 -100.752458) (xy 194.900804 -100.751132) (xy 194.904614 -100.749608) (xy 194.959224 -100.725732)
			(xy 194.978528 -100.71735) (xy 194.98884 -100.712254) (xy 195.003779 -100.694795) (xy 195.00723 -100.683822)
			(xy 195.4022 -98.712528) (xy 195.946268 -95.993458) (xy 196.348096 -93.985842) (xy 196.46265 -93.413326)
			(xy 196.981318 -90.821764) (xy 197.027038 -90.592656) (xy 197.111112 -90.172286) (xy 197.112648 -90.161921)
			(xy 197.108199 -90.141467) (xy 197.095971 -90.124478) (xy 197.087236 -90.118692) (xy 197.062344 -90.103706)
			(xy 197.061836 -90.103706) (xy 197.018656 -90.078052) (xy 197.014892 -90.076052) (xy 197.006847 -90.073234)
			(xy 197.002654 -90.072464) (xy 196.99605 -90.071956) (xy 196.967348 -90.071956) (xy 196.96334 -90.072022)
			(xy 196.955425 -90.073294) (xy 196.9516 -90.074496) (xy 196.944234 -90.077036) (xy 196.936614 -90.082624)
			(xy 196.93636 -90.082878) (xy 196.916223 -90.097972) (xy 196.872739 -90.123302) (xy 196.826305 -90.142704)
			(xy 196.777726 -90.155841) (xy 196.727842 -90.162486) (xy 196.70268 -90.162888) (xy 196.693282 -90.162888)
			(xy 196.666457 -90.161796) (xy 196.613493 -90.153012) (xy 196.562284 -90.136887) (xy 196.513843 -90.113741)
			(xy 196.469126 -90.084029) (xy 196.429018 -90.048341) (xy 196.394311 -90.00738) (xy 196.365692 -89.961957)
			(xy 196.343725 -89.912969) (xy 196.328846 -89.861385) (xy 196.321348 -89.808224) (xy 196.320918 -89.78138)
			(xy 196.321383 -89.754129) (xy 196.329142 -89.700181) (xy 196.3445 -89.647887) (xy 196.367144 -89.598311)
			(xy 196.396613 -89.552463) (xy 196.432307 -89.511275) (xy 196.4735 -89.475586) (xy 196.519352 -89.446122)
			(xy 196.568931 -89.423484) (xy 196.621226 -89.408132) (xy 196.675175 -89.400379) (xy 196.702426 -89.399872)
			(xy 196.728402 -89.400312) (xy 196.779872 -89.407365) (xy 196.829909 -89.421337) (xy 196.877588 -89.441969)
			(xy 196.922026 -89.46888) (xy 196.962401 -89.501573) (xy 196.997967 -89.539441) (xy 197.028066 -89.581785)
			(xy 197.0405 -89.604596) (xy 197.044056 -89.611454) (xy 197.047612 -89.615264) (xy 197.055987 -89.623601)
			(xy 197.077966 -89.632206) (xy 197.089776 -89.631774) (xy 197.097142 -89.630758) (xy 197.136258 -89.62517)
			(xy 197.141251 -89.62419) (xy 197.150719 -89.62047) (xy 197.155054 -89.617804) (xy 197.155308 -89.617804)
			(xy 197.158939 -89.615194) (xy 197.165326 -89.608936) (xy 197.168008 -89.605358) (xy 197.170294 -89.602056)
			(xy 197.172072 -89.599262) (xy 197.173088 -89.597992) (xy 197.173596 -89.59723) (xy 197.174866 -89.594944)
			(xy 197.191376 -89.569544) (xy 197.196456 -89.562432) (xy 197.196964 -89.561924) (xy 197.206362 -89.549478)
			(xy 197.207378 -89.548462) (xy 197.211442 -89.543636) (xy 197.21195 -89.543128) (xy 197.21322 -89.541604)
			(xy 197.21449 -89.54008) (xy 197.214998 -89.539572) (xy 197.218046 -89.53627) (xy 197.2183 -89.536016)
			(xy 197.233286 -89.518998) (xy 197.234302 -89.517982) (xy 197.237096 -89.512394) (xy 197.243954 -89.499186)
			(xy 197.247002 -89.493344) (xy 197.266052 -89.398856) (xy 197.282816 -89.315036) (xy 197.409816 -88.678512)
			(xy 197.412864 -88.663272) (xy 197.413626 -88.65489) (xy 197.413626 -88.608662) (xy 197.412356 -88.59774)
			(xy 197.410324 -88.589612) (xy 197.407022 -88.58377) (xy 197.395296 -88.562214) (xy 197.37686 -88.516736)
			(xy 197.364403 -88.469271) (xy 197.358132 -88.4206) (xy 197.357746 -88.396064) (xy 197.357746 -88.39581)
			(xy 197.358296 -88.366304) (xy 197.36738 -88.307994) (xy 197.385334 -88.251779) (xy 197.411729 -88.198998)
			(xy 197.445935 -88.15091) (xy 197.487137 -88.108662) (xy 197.5104 -88.090502) (xy 197.515734 -88.08593)
			(xy 197.523354 -88.07831) (xy 197.526944 -88.074054) (xy 197.532333 -88.064312) (xy 197.534022 -88.059006)
			(xy 197.89267 -86.268052) (xy 198.408036 -83.692492) (xy 199.084184 -80.284574) (xy 200.16851 -74.819002)
			(xy 200.169371 -74.80909) (xy 200.164352 -74.789859) (xy 200.152408 -74.773972) (xy 200.144126 -74.768456)
			(xy 200.06183 -74.71918) (xy 200.054903 -74.715354) (xy 200.039509 -74.71172) (xy 200.031604 -74.712068)
			(xy 200.024492 -74.712576) (xy 200.010014 -74.718418) (xy 200.003664 -74.723752) (xy 199.983117 -74.740083)
			(xy 199.938393 -74.767552) (xy 199.890328 -74.788634) (xy 199.839828 -74.802932) (xy 199.787844 -74.810178)
			(xy 199.761602 -74.81062) (xy 199.761094 -74.81062) (xy 199.733842 -74.810134) (xy 199.679893 -74.802376)
			(xy 199.627598 -74.78702) (xy 199.57802 -74.764378) (xy 199.532169 -74.734911) (xy 199.490978 -74.699218)
			(xy 199.455286 -74.658027) (xy 199.425819 -74.612175) (xy 199.403178 -74.562597) (xy 199.387822 -74.510301)
			(xy 199.380066 -74.456352) (xy 199.380066 -74.401848) (xy 199.387822 -74.347899) (xy 199.403178 -74.295603)
			(xy 199.425819 -74.246025) (xy 199.455286 -74.200173) (xy 199.490978 -74.158982) (xy 199.532169 -74.123289)
			(xy 199.57802 -74.093822) (xy 199.627598 -74.07118) (xy 199.679893 -74.055824) (xy 199.733842 -74.048066)
			(xy 199.761094 -74.047604) (xy 199.790557 -74.048152) (xy 199.848782 -74.057214) (xy 199.904921 -74.075123)
			(xy 199.957636 -74.101454) (xy 200.005676 -74.135579) (xy 200.047894 -74.176687) (xy 200.083288 -74.223799)
			(xy 200.097644 -74.249534) (xy 200.099422 -74.252582) (xy 200.10502 -74.260713) (xy 200.12099 -74.272286)
			(xy 200.140149 -74.276968) (xy 200.149968 -74.27595) (xy 200.213722 -74.266552) (xy 200.246488 -74.261726)
			(xy 200.256363 -74.259439) (xy 200.273275 -74.248297) (xy 200.284521 -74.231454) (xy 200.286874 -74.221594)
			(xy 200.467214 -73.312528) (xy 200.468182 -73.306633) (xy 200.467657 -73.2947) (xy 200.466198 -73.288906)
			(xy 200.462896 -73.277222) (xy 200.45426 -73.268078) (xy 200.434768 -73.246733) (xy 200.40179 -73.199263)
			(xy 200.376342 -73.147366) (xy 200.359005 -73.092226) (xy 200.350175 -73.035103) (xy 200.349612 -73.006204)
			(xy 200.349612 -73.004934) (xy 200.350087 -72.977455) (xy 200.357956 -72.923062) (xy 200.373537 -72.870358)
			(xy 200.396509 -72.820431) (xy 200.426397 -72.774309) (xy 200.462585 -72.732946) (xy 200.504325 -72.697194)
			(xy 200.550758 -72.667792) (xy 200.575672 -72.656192) (xy 200.581179 -72.653584) (xy 200.590819 -72.646138)
			(xy 200.594722 -72.64146) (xy 200.598278 -72.637142) (xy 200.603358 -72.62622) (xy 202.49388 -63.098172)
			(xy 202.494879 -63.088903) (xy 202.490898 -63.070707) (xy 202.480638 -63.055162) (xy 202.473306 -63.049404)
			(xy 202.44562 -63.031116) (xy 202.436984 -63.025782) (xy 202.434952 -63.024512) (xy 202.43292 -63.022988)
			(xy 202.431396 -63.021972) (xy 202.428045 -63.020054) (xy 202.420904 -63.017119) (xy 202.417172 -63.01613)
			(xy 202.40498 -63.014606) (xy 202.389232 -63.014606) (xy 202.379834 -63.015622) (xy 202.366372 -63.018924)
			(xy 202.361292 -63.022226) (xy 202.358752 -63.024004) (xy 202.335184 -63.039084) (xy 202.284564 -63.06292)
			(xy 202.231004 -63.0791) (xy 202.175654 -63.087277) (xy 202.147678 -63.087758) (xy 202.14717 -63.087758)
			(xy 202.132692 -63.087504) (xy 202.118976 -63.086488) (xy 202.092754 -63.0841) (xy 202.041278 -63.073024)
			(xy 201.991813 -63.054977) (xy 201.9453 -63.030301) (xy 201.90262 -62.999465) (xy 201.864584 -62.963054)
			(xy 201.831915 -62.92176) (xy 201.805234 -62.876367) (xy 201.785046 -62.827736) (xy 201.771735 -62.776793)
			(xy 201.768202 -62.7507) (xy 201.76744 -62.743334) (xy 201.765662 -62.705996) (xy 201.766124 -62.679076)
			(xy 201.773692 -62.625771) (xy 201.788676 -62.574058) (xy 201.81078 -62.524964) (xy 201.839564 -62.479465)
			(xy 201.874457 -62.438462) (xy 201.914766 -62.402771) (xy 201.959692 -62.373099) (xy 202.008342 -62.350036)
			(xy 202.059751 -62.334039) (xy 202.112897 -62.325426) (xy 202.139804 -62.324488) (xy 202.147932 -62.324488)
			(xy 202.169004 -62.324797) (xy 202.210884 -62.329509) (xy 202.231498 -62.333886) (xy 202.232006 -62.333886)
			(xy 202.239626 -62.335664) (xy 202.242928 -62.336426) (xy 202.248008 -62.336934) (xy 202.248516 -62.336934)
			(xy 202.257347 -62.337446) (xy 202.274499 -62.333168) (xy 202.282044 -62.328552) (xy 202.288648 -62.323218)
			(xy 202.352148 -62.249304) (xy 202.358027 -62.240505) (xy 202.362761 -62.219904) (xy 202.361292 -62.209426)
			(xy 202.358498 -62.199012) (xy 202.357482 -62.196218) (xy 202.348551 -62.173271) (xy 202.335997 -62.125656)
			(xy 202.329674 -62.076821) (xy 202.329288 -62.0522) (xy 202.329288 -62.051438) (xy 202.330558 -62.021212)
			(xy 202.331066 -62.017148) (xy 202.331066 -62.016132) (xy 202.334175 -61.988082) (xy 202.347604 -61.933268)
			(xy 202.368964 -61.881032) (xy 202.397789 -61.832515) (xy 202.43345 -61.788775) (xy 202.475167 -61.750768)
			(xy 202.52203 -61.719323) (xy 202.573015 -61.695129) (xy 202.627009 -61.678712) (xy 202.682832 -61.670432)
			(xy 202.71105 -61.66993) (xy 202.73264 -61.670438) (xy 202.73391 -61.670438) (xy 202.745456 -61.670232)
			(xy 202.766507 -61.660795) (xy 202.781346 -61.643131) (xy 202.78471 -61.632084) (xy 202.831954 -61.393578)
			(xy 202.910694 -60.996576) (xy 202.91171 -60.987432) (xy 202.916536 -60.68187) (xy 202.916028 -60.678314)
			(xy 202.914818 -60.667178) (xy 202.913544 -60.644811) (xy 202.913488 -60.63361) (xy 202.913488 -60.63234)
			(xy 202.913598 -60.618768) (xy 202.915503 -60.591691) (xy 202.917298 -60.578238) (xy 202.917552 -60.576714)
			(xy 202.91806 -60.569856) (xy 202.94854 -58.624978) (xy 202.946 -58.613802) (xy 202.943714 -58.608722)
			(xy 202.932766 -58.583662) (xy 202.917352 -58.531194) (xy 202.909593 -58.477061) (xy 202.90917 -58.449718)
			(xy 202.909424 -58.436002) (xy 202.91044 -58.421016) (xy 202.912663 -58.396676) (xy 202.922567 -58.348812)
			(xy 202.938517 -58.30261) (xy 202.949048 -58.280554) (xy 202.951588 -58.27522) (xy 202.954128 -58.264552)
			(xy 203.038456 -52.860448) (xy 203.089764 -49.568862) (xy 203.08951 -49.565052) (xy 203.089256 -49.563274)
			(xy 201.762106 -39.7383) (xy 201.758325 -39.708655) (xy 201.753876 -39.649052) (xy 201.753216 -39.619174)
			(xy 201.752962 -39.605712) (xy 201.752454 -39.569898) (xy 201.751692 -39.523162) (xy 201.751184 -39.516558)
			(xy 201.66584 -38.931342) (xy 201.661027 -38.895852) (xy 201.655941 -38.824407) (xy 201.65568 -38.788594)
			(xy 201.65568 -38.498526) (xy 201.654664 -38.487858) (xy 201.653902 -38.485572) (xy 201.643231 -38.44497)
			(xy 201.627939 -38.362418) (xy 201.619641 -38.278873) (xy 201.618596 -38.236906) (xy 201.61123 -37.741352)
			(xy 201.61123 -37.741098) (xy 201.610976 -37.726874) (xy 201.610976 -37.724588) (xy 201.611655 -37.676305)
			(xy 201.621212 -37.58021) (xy 201.640012 -37.485489) (xy 201.653394 -37.439092) (xy 201.65568 -37.431472)
			(xy 201.65568 -37.419534) (xy 201.654156 -37.412676) (xy 201.652632 -37.40658) (xy 201.650854 -37.402262)
			(xy 201.6506 -37.401754) (xy 201.629396 -37.351751) (xy 201.596811 -37.248137) (xy 201.585576 -37.194998)
			(xy 201.579212 -37.16138) (xy 201.570566 -37.093502) (xy 201.568304 -37.059362) (xy 201.566526 -37.004244)
			(xy 201.566526 -37.001704) (xy 201.56551 -36.992306) (xy 201.563478 -36.981892) (xy 201.561873 -36.976898)
			(xy 201.556877 -36.967677) (xy 201.553572 -36.963604) (xy 201.505566 -36.912296) (xy 201.496676 -36.908232)
			(xy 201.47153 -36.896294) (xy 201.467212 -36.89604) (xy 201.462386 -36.895532) (xy 201.434259 -36.892514)
			(xy 201.379271 -36.879236) (xy 201.326847 -36.857985) (xy 201.278135 -36.829226) (xy 201.234203 -36.79359)
			(xy 201.196014 -36.751858) (xy 201.164406 -36.704944) (xy 201.140071 -36.653878) (xy 201.123543 -36.599779)
			(xy 201.115184 -36.543832) (xy 201.11466 -36.515548) (xy 201.115172 -36.486982) (xy 201.123698 -36.430489)
			(xy 201.140553 -36.375898) (xy 201.165358 -36.324432) (xy 201.197561 -36.277239) (xy 201.23644 -36.235375)
			(xy 201.281126 -36.199776) (xy 201.330621 -36.171238) (xy 201.383818 -36.150399) (xy 201.439527 -36.137725)
			(xy 201.467974 -36.135056) (xy 201.476864 -36.134294) (xy 201.493628 -36.126928) (xy 201.500994 -36.123626)
			(xy 201.505201 -36.121655) (xy 201.512875 -36.116421) (xy 201.516234 -36.113212) (xy 201.521822 -36.107624)
			(xy 201.527876 -36.100961) (xy 201.53528 -36.084565) (xy 201.5363 -36.07562) (xy 201.536046 -36.050982)
			(xy 201.531728 -36.045902) (xy 201.522838 -36.03752) (xy 201.513694 -36.028884) (xy 201.504042 -36.022534)
			(xy 201.49058 -36.016692) (xy 201.480674 -36.016692) (xy 201.478388 -36.016692) (xy 201.478134 -36.016692)
			(xy 201.45088 -36.016231) (xy 201.396926 -36.008478) (xy 201.344625 -35.993125) (xy 201.295042 -35.970484)
			(xy 201.249186 -35.941016) (xy 201.20799 -35.905323) (xy 201.172294 -35.864129) (xy 201.142825 -35.818274)
			(xy 201.120182 -35.768692) (xy 201.104826 -35.716391) (xy 201.09707 -35.662438) (xy 201.096626 -35.635184)
			(xy 201.096626 -35.633152) (xy 201.09677 -35.615074) (xy 201.100079 -35.579072) (xy 201.10323 -35.56127)
			(xy 201.103992 -35.557714) (xy 201.104754 -35.542728) (xy 201.105262 -35.533076) (xy 201.105262 -35.530536)
			(xy 201.104405 -35.520498) (xy 201.096033 -35.502197) (xy 201.089006 -35.494976) (xy 201.0664 -35.489388)
			(xy 201.028056 -35.479326) (xy 200.952964 -35.453898) (xy 200.880129 -35.422584) (xy 200.810013 -35.385581)
			(xy 200.776332 -35.364674) (xy 200.766426 -35.366452) (xy 200.752493 -35.36869) (xy 200.724397 -35.371361)
			(xy 200.710292 -35.371786) (xy 200.69937 -35.371786) (xy 200.672237 -35.371199) (xy 200.618545 -35.363293)
			(xy 200.566516 -35.347857) (xy 200.5172 -35.325203) (xy 200.471592 -35.295789) (xy 200.430612 -35.260208)
			(xy 200.395089 -35.219179) (xy 200.365739 -35.173529) (xy 200.343155 -35.124181) (xy 200.327792 -35.07213)
			(xy 200.319961 -35.018428) (xy 200.319386 -34.991294) (xy 200.319386 -34.990786) (xy 200.319386 -34.990278)
			(xy 200.319386 -34.987484) (xy 200.319955 -34.963282) (xy 200.326471 -34.91531) (xy 200.339014 -34.868551)
			(xy 200.347834 -34.846006) (xy 200.348342 -34.844482) (xy 200.35012 -34.840164) (xy 200.356724 -34.824162)
			(xy 200.357994 -34.818574) (xy 200.353422 -34.802826) (xy 200.340925 -34.758474) (xy 200.323215 -34.668039)
			(xy 200.313932 -34.576355) (xy 200.313036 -34.530284) (xy 200.313036 -34.519108) (xy 200.313612 -34.477574)
			(xy 200.320813 -34.394817) (xy 200.334867 -34.312943) (xy 200.355677 -34.232521) (xy 200.383099 -34.154107)
			(xy 200.39965 -34.11601) (xy 200.402698 -34.106358) (xy 200.406254 -34.091118) (xy 200.406254 -34.090102)
			(xy 200.402698 -34.074862) (xy 200.39965 -34.06521) (xy 200.382969 -34.026807) (xy 200.355358 -33.947757)
			(xy 200.334477 -33.866669) (xy 200.320474 -33.784115) (xy 200.313447 -33.700677) (xy 200.313036 -33.65881)
			(xy 200.313036 -33.658302) (xy 200.313307 -33.626014) (xy 200.317504 -33.561575) (xy 200.321418 -33.529524)
			(xy 200.324918 -33.504119) (xy 200.334193 -33.453675) (xy 200.33996 -33.428686) (xy 200.343978 -33.412172)
			(xy 200.352998 -33.379399) (xy 200.357994 -33.363154) (xy 200.356216 -33.35528) (xy 200.35393 -33.349692)
			(xy 200.344415 -33.328077) (xy 200.330193 -33.28304) (xy 200.321639 -33.236593) (xy 200.319894 -33.21304)
			(xy 200.319894 -33.208722) (xy 200.319386 -33.19018) (xy 200.319386 -33.18256) (xy 200.32038 -33.155663)
			(xy 200.328997 -33.102533) (xy 200.344996 -33.051143) (xy 200.36806 -33.002511) (xy 200.397731 -32.957604)
			(xy 200.433419 -32.917313) (xy 200.474415 -32.882439) (xy 200.519907 -32.853673) (xy 200.568991 -32.831587)
			(xy 200.620691 -32.816619) (xy 200.673982 -32.809067) (xy 200.700894 -32.808672) (xy 200.701148 -32.808672)
			(xy 200.715619 -32.808784) (xy 200.74448 -32.810942) (xy 200.758806 -32.81299) (xy 200.767626 -32.813989)
			(xy 200.785041 -32.81062) (xy 200.792842 -32.806386) (xy 200.831883 -32.783274) (xy 200.913387 -32.743405)
			(xy 200.998174 -32.711101) (xy 201.085543 -32.686627) (xy 201.174773 -32.670185) (xy 201.265128 -32.661911)
			(xy 201.310494 -32.661352) (xy 201.310748 -32.661352) (xy 201.356087 -32.66188) (xy 201.44639 -32.670137)
			(xy 201.535571 -32.68655) (xy 201.622896 -32.710986) (xy 201.707644 -32.743241) (xy 201.789118 -32.783051)
			(xy 201.828146 -32.806132) (xy 201.835872 -32.810392) (xy 201.853151 -32.81389) (xy 201.861928 -32.81299)
			(xy 201.876634 -32.810911) (xy 201.906258 -32.808752) (xy 201.92111 -32.808672) (xy 201.921872 -32.808672)
			(xy 201.95159 -32.809363) (xy 202.010276 -32.818807) (xy 202.038712 -32.827468) (xy 202.052428 -32.83204)
			(xy 202.063858 -32.831024) (xy 202.071743 -32.830018) (xy 202.086366 -32.823813) (xy 202.09256 -32.818832)
			(xy 202.112118 -32.804608) (xy 202.155298 -32.773112) (xy 202.159077 -32.769921) (xy 202.165472 -32.762378)
			(xy 202.167998 -32.758126) (xy 202.16749 -32.737552) (xy 202.16749 -32.737298) (xy 202.167236 -32.722566)
			(xy 202.167236 -32.720788) (xy 202.16749 -32.696912) (xy 202.169334 -32.647678) (xy 202.181537 -32.549908)
			(xy 202.203334 -32.453821) (xy 202.234512 -32.360355) (xy 202.254104 -32.31515) (xy 202.255882 -32.311086)
			(xy 202.260454 -32.29102) (xy 202.260454 -32.290004) (xy 202.255882 -32.269938) (xy 202.254104 -32.265874)
			(xy 202.234544 -32.220658) (xy 202.203393 -32.127187) (xy 202.181596 -32.031104) (xy 202.169365 -31.933342)
			(xy 202.16749 -31.884112) (xy 202.167236 -31.860236) (xy 202.167236 -31.858458) (xy 202.16749 -31.843218)
			(xy 202.16749 -31.840424) (xy 202.167998 -31.821628) (xy 202.165526 -31.817672) (xy 202.15939 -31.810645)
			(xy 202.155806 -31.807658) (xy 202.110594 -31.774638) (xy 202.110086 -31.774638) (xy 202.090782 -31.760668)
			(xy 202.085318 -31.757163) (xy 202.073099 -31.752795) (xy 202.066652 -31.752032) (xy 202.066144 -31.752032)
			(xy 202.06208 -31.751778) (xy 202.042522 -31.751778) (xy 202.034902 -31.754064) (xy 202.007293 -31.762249)
			(xy 201.950407 -31.771184) (xy 201.921618 -31.771844) (xy 201.919586 -31.771844) (xy 201.903311 -31.771664)
			(xy 201.870881 -31.768866) (xy 201.854816 -31.766256) (xy 201.84491 -31.764478) (xy 201.804924 -31.789198)
			(xy 201.721148 -31.831861) (xy 201.633731 -31.866454) (xy 201.543447 -31.892671) (xy 201.451097 -31.910279)
			(xy 201.357501 -31.919122) (xy 201.310494 -31.919672) (xy 201.264862 -31.919187) (xy 201.173976 -31.9109)
			(xy 201.084227 -31.894339) (xy 200.996369 -31.869644) (xy 200.911135 -31.837022) (xy 200.829239 -31.796746)
			(xy 200.790048 -31.773368) (xy 200.784419 -31.770543) (xy 200.772213 -31.767456) (xy 200.765918 -31.767272)
			(xy 200.759822 -31.767272) (xy 200.756266 -31.76778) (xy 200.75525 -31.768034) (xy 200.75398 -31.768034)
			(xy 200.7362 -31.77032) (xy 200.730866 -31.770828) (xy 200.72985 -31.770828) (xy 200.727818 -31.771082)
			(xy 200.726802 -31.771082) (xy 200.706736 -31.771844) (xy 200.700894 -31.771844) (xy 200.673642 -31.771358)
			(xy 200.619693 -31.763601) (xy 200.567397 -31.748246) (xy 200.517818 -31.725605) (xy 200.471966 -31.696139)
			(xy 200.430774 -31.660448) (xy 200.395079 -31.619258) (xy 200.36561 -31.573408) (xy 200.342965 -31.523831)
			(xy 200.327606 -31.471536) (xy 200.319844 -31.417588) (xy 200.319386 -31.390336) (xy 200.319386 -31.387542)
			(xy 200.319951 -31.363339) (xy 200.32646 -31.315365) (xy 200.338997 -31.268603) (xy 200.347834 -31.246064)
			(xy 200.348342 -31.24454) (xy 200.35012 -31.240222) (xy 200.356724 -31.22422) (xy 200.357994 -31.218632)
			(xy 200.353422 -31.202884) (xy 200.340693 -31.157586) (xy 200.322808 -31.065204) (xy 200.313698 -30.971547)
			(xy 200.313036 -30.9245) (xy 200.313036 -30.91561) (xy 200.313636 -30.878397) (xy 200.319695 -30.804211)
			(xy 200.331272 -30.730684) (xy 200.339452 -30.694376) (xy 200.350818 -30.648428) (xy 200.381096 -30.558742)
			(xy 200.399904 -30.515306) (xy 200.401682 -30.511242) (xy 200.406254 -30.491176) (xy 200.406254 -30.49016)
			(xy 200.401682 -30.470094) (xy 200.399904 -30.46603) (xy 200.383177 -30.42756) (xy 200.355487 -30.348366)
			(xy 200.33455 -30.267126) (xy 200.320513 -30.184414) (xy 200.313475 -30.100815) (xy 200.313036 -30.058868)
			(xy 200.313492 -30.015527) (xy 200.320998 -29.929172) (xy 200.328022 -29.886402) (xy 200.33218 -29.863598)
			(xy 200.342343 -29.818368) (xy 200.348342 -29.795978) (xy 200.358248 -29.76245) (xy 200.35647 -29.755084)
			(xy 200.344766 -29.729286) (xy 200.328248 -29.6751) (xy 200.31991 -29.61907) (xy 200.319386 -29.590746)
			(xy 200.319386 -29.590238) (xy 200.319847 -29.562983) (xy 200.327599 -29.509028) (xy 200.342952 -29.456725)
			(xy 200.365592 -29.40714) (xy 200.395059 -29.361282) (xy 200.430753 -29.320084) (xy 200.471946 -29.284385)
			(xy 200.517801 -29.254913) (xy 200.567384 -29.232267) (xy 200.619685 -29.216909) (xy 200.673639 -29.20915)
			(xy 200.700894 -29.20873) (xy 200.701656 -29.20873) (xy 200.719352 -29.20894) (xy 200.754589 -29.212246)
			(xy 200.772014 -29.215334) (xy 200.776078 -29.216096) (xy 200.77684 -29.21635) (xy 200.816782 -29.191702)
			(xy 200.900455 -29.149169) (xy 200.987754 -29.114684) (xy 201.077906 -29.088552) (xy 201.170114 -29.071004)
			(xy 201.263562 -29.062196) (xy 201.310494 -29.061664) (xy 201.357399 -29.062191) (xy 201.450795 -29.070976)
			(xy 201.542955 -29.088488) (xy 201.633064 -29.114573) (xy 201.720327 -29.149) (xy 201.803975 -29.191464)
			(xy 201.843894 -29.216096) (xy 201.84491 -29.215842) (xy 201.848466 -29.215334) (xy 201.866144 -29.21222)
			(xy 201.90189 -29.20891) (xy 201.91984 -29.20873) (xy 201.920856 -29.20873) (xy 201.946249 -29.209144)
			(xy 201.996583 -29.215894) (xy 202.021186 -29.222192) (xy 202.022964 -29.2227) (xy 202.024234 -29.222954)
			(xy 202.028044 -29.22397) (xy 202.042014 -29.228542) (xy 202.042522 -29.228542) (xy 202.047856 -29.230574)
			(xy 202.060556 -29.231844) (xy 202.066398 -29.231082) (xy 202.077066 -29.228288) (xy 202.089258 -29.221684)
			(xy 202.15225 -29.17571) (xy 202.153012 -29.175202) (xy 202.157838 -29.171646) (xy 202.164442 -29.165296)
			(xy 202.167998 -29.16047) (xy 202.16749 -29.137864) (xy 202.16749 -29.13761) (xy 202.167236 -29.122624)
			(xy 202.167236 -29.120846) (xy 202.16749 -29.09697) (xy 202.169336 -29.047737) (xy 202.181543 -28.949968)
			(xy 202.203344 -28.853882) (xy 202.234525 -28.760418) (xy 202.254104 -28.715208) (xy 202.255882 -28.711144)
			(xy 202.260454 -28.691078) (xy 202.260454 -28.690062) (xy 202.255882 -28.669996) (xy 202.254104 -28.665932)
			(xy 202.237376 -28.627462) (xy 202.209687 -28.548268) (xy 202.18875 -28.467028) (xy 202.174713 -28.384316)
			(xy 202.167674 -28.300717) (xy 202.167236 -28.25877) (xy 202.167692 -28.215429) (xy 202.175198 -28.129074)
			(xy 202.182222 -28.086304) (xy 202.186386 -28.063565) (xy 202.19655 -28.018461) (xy 202.202542 -27.996134)
			(xy 202.202542 -27.995626) (xy 202.209654 -27.972004) (xy 202.209654 -27.971496) (xy 202.212448 -27.962352)
			(xy 202.21067 -27.954986) (xy 202.208384 -27.95016) (xy 202.1988 -27.928472) (xy 202.184465 -27.883273)
			(xy 202.175834 -27.836647) (xy 202.174094 -27.813) (xy 202.174094 -27.808682) (xy 202.173586 -27.79014)
			(xy 202.173586 -27.78252) (xy 202.174583 -27.755624) (xy 202.183204 -27.7025) (xy 202.199207 -27.651114)
			(xy 202.222273 -27.602487) (xy 202.251944 -27.557585) (xy 202.287632 -27.517299) (xy 202.328628 -27.482429)
			(xy 202.374118 -27.453666) (xy 202.423199 -27.431583) (xy 202.474896 -27.416617) (xy 202.528184 -27.409066)
			(xy 202.555094 -27.408632) (xy 202.572715 -27.40874) (xy 202.607824 -27.411789) (xy 202.625198 -27.414728)
			(xy 202.62723 -27.415236) (xy 202.631548 -27.415998) (xy 202.674474 -27.39009) (xy 202.67549 -27.389582)
			(xy 202.678792 -27.387804) (xy 202.696318 -27.377898) (xy 202.697588 -27.375104) (xy 202.698096 -27.37358)
			(xy 202.698604 -27.372564) (xy 202.719686 -27.295348) (xy 202.719432 -27.281632) (xy 202.717654 -27.275028)
			(xy 202.713336 -27.259534) (xy 202.710288 -27.2542) (xy 202.698592 -27.232664) (xy 202.680174 -27.187249)
			(xy 202.667713 -27.139853) (xy 202.661415 -27.091251) (xy 202.661012 -27.066748) (xy 202.661012 -27.057604)
			(xy 202.661266 -27.05354) (xy 202.661266 -27.052778) (xy 202.663552 -27.022552) (xy 202.666656 -26.998918)
			(xy 202.678003 -26.95262) (xy 202.695048 -26.908103) (xy 202.70597 -26.886916) (xy 202.718799 -26.863799)
			(xy 202.749868 -26.821021) (xy 202.786547 -26.782944) (xy 202.807062 -26.766266) (xy 202.809094 -26.764742)
			(xy 202.816206 -26.757884) (xy 202.82916 -26.742136) (xy 202.8317 -26.736802) (xy 202.83424 -26.725118)
			(xy 202.830176 -26.647394) (xy 202.829668 -26.634948) (xy 202.814682 -26.609294) (xy 202.806808 -26.59888)
			(xy 202.799442 -26.591514) (xy 202.791314 -26.584656) (xy 202.789028 -26.583132) (xy 202.767131 -26.567858)
			(xy 202.727425 -26.532168) (xy 202.693078 -26.491295) (xy 202.664761 -26.446035) (xy 202.643025 -26.397272)
			(xy 202.628295 -26.345956) (xy 202.620858 -26.293088) (xy 202.620372 -26.266394) (xy 202.620858 -26.239125)
			(xy 202.62862 -26.185141) (xy 202.643985 -26.132811) (xy 202.666642 -26.083201) (xy 202.696128 -26.03732)
			(xy 202.731843 -25.996103) (xy 202.77306 -25.960388) (xy 202.818941 -25.930902) (xy 202.868551 -25.908245)
			(xy 202.920881 -25.89288) (xy 202.974865 -25.885118) (xy 203.029403 -25.885118) (xy 203.083387 -25.89288)
			(xy 203.135717 -25.908245) (xy 203.185327 -25.930902) (xy 203.231208 -25.960388) (xy 203.272425 -25.996103)
			(xy 203.30814 -26.03732) (xy 203.337626 -26.083201) (xy 203.360283 -26.132811) (xy 203.375648 -26.185141)
			(xy 203.38341 -26.239125) (xy 203.383896 -26.266394) (xy 203.383358 -26.295751) (xy 203.374371 -26.353772)
			(xy 203.356607 -26.409734) (xy 203.330485 -26.462316) (xy 203.296621 -26.510279) (xy 203.255813 -26.552493)
			(xy 203.232766 -26.570686) (xy 203.229464 -26.573226) (xy 203.225654 -26.577036) (xy 203.219558 -26.58491)
			(xy 203.215832 -26.591022) (xy 203.211592 -26.604687) (xy 203.211176 -26.611834) (xy 203.214986 -26.69667)
			(xy 203.219812 -26.706068) (xy 203.220828 -26.708354) (xy 203.233528 -26.72969) (xy 203.237846 -26.734008)
			(xy 203.249022 -26.745438) (xy 203.255372 -26.749756) (xy 203.277232 -26.764967) (xy 203.316884 -26.80052)
			(xy 203.3512 -26.841247) (xy 203.379512 -26.886354) (xy 203.40127 -26.934963) (xy 203.41605 -26.986127)
			(xy 203.423563 -27.038851) (xy 203.424028 -27.065478) (xy 203.424028 -27.07005) (xy 203.423184 -27.100326)
			(xy 203.413101 -27.160046) (xy 203.403962 -27.188922) (xy 203.4032 -27.191208) (xy 203.40066 -27.199336)
			(xy 203.401676 -27.210512) (xy 203.403962 -27.221688) (xy 203.404724 -27.223466) (xy 203.41971 -27.254454)
			(xy 203.420218 -27.254962) (xy 203.428092 -27.27071) (xy 203.44257 -27.298904) (xy 203.444348 -27.30119)
			(xy 203.457302 -27.305254) (xy 203.463906 -27.307286) (xy 203.487772 -27.314951) (xy 203.534784 -27.332358)
			(xy 203.557886 -27.342084) (xy 203.559622 -27.342846) (xy 210.623404 -27.342846) (xy 210.623404 -26.479246)
			(xy 210.623894 -26.449262) (xy 210.631722 -26.389806) (xy 210.647243 -26.331881) (xy 210.670192 -26.276477)
			(xy 210.700176 -26.224543) (xy 210.736682 -26.176967) (xy 210.779087 -26.134562) (xy 210.826663 -26.098056)
			(xy 210.878597 -26.068072) (xy 210.934001 -26.045123) (xy 210.991926 -26.029602) (xy 211.051382 -26.021774)
			(xy 211.11135 -26.021774) (xy 211.170806 -26.029602) (xy 211.228731 -26.045123) (xy 211.284135 -26.068072)
			(xy 211.336069 -26.098056) (xy 211.383645 -26.134562) (xy 211.42605 -26.176967) (xy 211.462556 -26.224543)
			(xy 211.49254 -26.276477) (xy 211.515489 -26.331881) (xy 211.52326 -26.360882) (xy 213.189564 -26.360882)
			(xy 213.193635 -26.30526) (xy 213.205761 -26.250823) (xy 213.225684 -26.198732) (xy 213.25298 -26.150097)
			(xy 213.287066 -26.105954) (xy 213.327215 -26.067245) (xy 213.372573 -26.034794) (xy 213.422173 -26.009293)
			(xy 213.474957 -25.991286) (xy 213.5298 -25.981156) (xy 213.585534 -25.979119) (xy 213.640971 -25.985219)
			(xy 213.694928 -25.999325) (xy 213.746257 -26.021137) (xy 213.793863 -26.050191) (xy 213.836731 -26.085866)
			(xy 213.873948 -26.127403) (xy 213.904721 -26.173916) (xy 213.928393 -26.224413) (xy 213.944461 -26.27782)
			(xy 213.950629 -26.319734) (xy 218.941902 -26.319734) (xy 218.945973 -26.264112) (xy 218.958099 -26.209675)
			(xy 218.978022 -26.157584) (xy 219.005318 -26.108949) (xy 219.039404 -26.064806) (xy 219.079553 -26.026097)
			(xy 219.124911 -25.993646) (xy 219.174511 -25.968145) (xy 219.227295 -25.950138) (xy 219.282138 -25.940008)
			(xy 219.337872 -25.937971) (xy 219.393309 -25.944071) (xy 219.447266 -25.958177) (xy 219.498595 -25.979989)
			(xy 219.546201 -26.009043) (xy 219.575866 -26.03373) (xy 237.4679 -26.03373) (xy 237.471971 -25.978108)
			(xy 237.484097 -25.923671) (xy 237.50402 -25.87158) (xy 237.531316 -25.822945) (xy 237.565402 -25.778802)
			(xy 237.605551 -25.740093) (xy 237.650909 -25.707642) (xy 237.700509 -25.682141) (xy 237.753293 -25.664134)
			(xy 237.808136 -25.654004) (xy 237.86387 -25.651967) (xy 237.919307 -25.658067) (xy 237.973264 -25.672173)
			(xy 238.024593 -25.693985) (xy 238.072199 -25.723039) (xy 238.115067 -25.758714) (xy 238.152284 -25.800251)
			(xy 238.183057 -25.846764) (xy 238.206729 -25.897261) (xy 238.222797 -25.950668) (xy 238.230917 -26.005844)
			(xy 238.231426 -26.03373) (xy 238.230917 -26.061616) (xy 238.222797 -26.116792) (xy 238.206729 -26.170199)
			(xy 238.183057 -26.220696) (xy 238.152284 -26.267209) (xy 238.115067 -26.308746) (xy 238.072199 -26.344421)
			(xy 238.024593 -26.373475) (xy 237.973264 -26.395287) (xy 237.919307 -26.409393) (xy 237.86387 -26.415493)
			(xy 237.808136 -26.413456) (xy 237.753293 -26.403326) (xy 237.700509 -26.385319) (xy 237.650909 -26.359818)
			(xy 237.605551 -26.327367) (xy 237.565402 -26.288658) (xy 237.531316 -26.244515) (xy 237.50402 -26.19588)
			(xy 237.484097 -26.143789) (xy 237.471971 -26.089352) (xy 237.4679 -26.03373) (xy 219.575866 -26.03373)
			(xy 219.589069 -26.044718) (xy 219.626286 -26.086255) (xy 219.657059 -26.132768) (xy 219.680731 -26.183265)
			(xy 219.696799 -26.236672) (xy 219.704919 -26.291848) (xy 219.705428 -26.319734) (xy 219.704919 -26.34762)
			(xy 219.696799 -26.402796) (xy 219.680731 -26.456203) (xy 219.657059 -26.5067) (xy 219.626286 -26.553213)
			(xy 219.589069 -26.59475) (xy 219.546201 -26.630425) (xy 219.498595 -26.659479) (xy 219.447266 -26.681291)
			(xy 219.393309 -26.695397) (xy 219.337872 -26.701497) (xy 219.282138 -26.69946) (xy 219.227295 -26.68933)
			(xy 219.174511 -26.671323) (xy 219.124911 -26.645822) (xy 219.079553 -26.613371) (xy 219.039404 -26.574662)
			(xy 219.005318 -26.530519) (xy 218.978022 -26.481884) (xy 218.958099 -26.429793) (xy 218.945973 -26.375356)
			(xy 218.941902 -26.319734) (xy 213.950629 -26.319734) (xy 213.952581 -26.332996) (xy 213.95309 -26.360882)
			(xy 213.952581 -26.388768) (xy 213.944461 -26.443944) (xy 213.928393 -26.497351) (xy 213.904721 -26.547848)
			(xy 213.873948 -26.594361) (xy 213.836731 -26.635898) (xy 213.793863 -26.671573) (xy 213.746257 -26.700627)
			(xy 213.694928 -26.722439) (xy 213.640971 -26.736545) (xy 213.585534 -26.742645) (xy 213.5298 -26.740608)
			(xy 213.474957 -26.730478) (xy 213.422173 -26.712471) (xy 213.372573 -26.68697) (xy 213.327215 -26.654519)
			(xy 213.287066 -26.61581) (xy 213.25298 -26.571667) (xy 213.225684 -26.523032) (xy 213.205761 -26.470941)
			(xy 213.193635 -26.416504) (xy 213.189564 -26.360882) (xy 211.52326 -26.360882) (xy 211.53101 -26.389806)
			(xy 211.538838 -26.449262) (xy 211.539328 -26.479246) (xy 211.539328 -26.971244) (xy 214.951054 -26.971244)
			(xy 214.955125 -26.915622) (xy 214.967251 -26.861185) (xy 214.987174 -26.809094) (xy 215.01447 -26.760459)
			(xy 215.048556 -26.716316) (xy 215.088705 -26.677607) (xy 215.134063 -26.645156) (xy 215.183663 -26.619655)
			(xy 215.236447 -26.601648) (xy 215.29129 -26.591518) (xy 215.347024 -26.589481) (xy 215.402461 -26.595581)
			(xy 215.456418 -26.609687) (xy 215.507747 -26.631499) (xy 215.555353 -26.660553) (xy 215.598221 -26.696228)
			(xy 215.635438 -26.737765) (xy 215.666211 -26.784278) (xy 215.689883 -26.834775) (xy 215.705951 -26.888182)
			(xy 215.714071 -26.943358) (xy 215.71458 -26.971244) (xy 215.714071 -26.99913) (xy 215.705951 -27.054306)
			(xy 215.689883 -27.107713) (xy 215.666211 -27.15821) (xy 215.635438 -27.204723) (xy 215.598221 -27.24626)
			(xy 215.555353 -27.281935) (xy 215.507747 -27.310989) (xy 215.456418 -27.332801) (xy 215.402461 -27.346907)
			(xy 215.347024 -27.353007) (xy 215.29129 -27.35097) (xy 215.236447 -27.34084) (xy 215.183663 -27.322833)
			(xy 215.134063 -27.297332) (xy 215.088705 -27.264881) (xy 215.048556 -27.226172) (xy 215.01447 -27.182029)
			(xy 214.987174 -27.133394) (xy 214.967251 -27.081303) (xy 214.955125 -27.026866) (xy 214.951054 -26.971244)
			(xy 211.539328 -26.971244) (xy 211.539328 -27.342846) (xy 211.538838 -27.37283) (xy 211.53101 -27.432286)
			(xy 211.515489 -27.490211) (xy 211.49254 -27.545615) (xy 211.462556 -27.597549) (xy 211.42605 -27.645125)
			(xy 211.383645 -27.68753) (xy 211.336069 -27.724036) (xy 211.284135 -27.75402) (xy 211.228731 -27.776969)
			(xy 211.170806 -27.79249) (xy 211.11135 -27.800318) (xy 211.051382 -27.800318) (xy 210.991926 -27.79249)
			(xy 210.934001 -27.776969) (xy 210.878597 -27.75402) (xy 210.826663 -27.724036) (xy 210.779087 -27.68753)
			(xy 210.736682 -27.645125) (xy 210.700176 -27.597549) (xy 210.670192 -27.545615) (xy 210.647243 -27.490211)
			(xy 210.631722 -27.432286) (xy 210.623894 -27.37283) (xy 210.623404 -27.342846) (xy 203.559622 -27.342846)
			(xy 203.588808 -27.355655) (xy 203.648929 -27.386419) (xy 203.678028 -27.403552) (xy 203.685075 -27.407426)
			(xy 203.700731 -27.411059) (xy 203.708762 -27.410664) (xy 203.712572 -27.410156) (xy 203.714096 -27.410156)
			(xy 203.717144 -27.409648) (xy 203.71816 -27.409648) (xy 203.718922 -27.409394) (xy 203.728828 -27.408886)
			(xy 203.730352 -27.408886) (xy 203.738734 -27.408378) (xy 203.74483 -27.408378) (xy 203.748894 -27.408378)
			(xy 203.768198 -27.408886) (xy 203.77785 -27.409648) (xy 203.806903 -27.412388) (xy 203.863747 -27.425579)
			(xy 203.917916 -27.44728) (xy 203.968143 -27.476986) (xy 204.013256 -27.514001) (xy 204.03312 -27.535378)
			(xy 204.033374 -27.535632) (xy 204.040916 -27.543148) (xy 204.060335 -27.551823) (xy 204.070966 -27.552396)
			(xy 204.111098 -27.552396) (xy 204.154616 -27.552857) (xy 204.24132 -27.560444) (xy 204.327033 -27.57556)
			(xy 204.411103 -27.598091) (xy 204.492888 -27.627864) (xy 204.571766 -27.664653) (xy 204.647137 -27.708177)
			(xy 204.718427 -27.758107) (xy 204.785094 -27.814061) (xy 204.816202 -27.844496) (xy 206.085948 -29.114242)
			(xy 212.947504 -29.114242) (xy 212.947504 -28.250642) (xy 212.947994 -28.220674) (xy 212.955817 -28.161252)
			(xy 212.97133 -28.103359) (xy 212.994266 -28.047986) (xy 213.024233 -27.99608) (xy 213.06072 -27.94853)
			(xy 213.1031 -27.90615) (xy 213.15065 -27.869663) (xy 213.202556 -27.839696) (xy 213.257929 -27.81676)
			(xy 213.315822 -27.801247) (xy 213.375244 -27.793424) (xy 213.43518 -27.793424) (xy 213.494602 -27.801247)
			(xy 213.552495 -27.81676) (xy 213.607868 -27.839696) (xy 213.659774 -27.869663) (xy 213.707324 -27.90615)
			(xy 213.749704 -27.94853) (xy 213.786191 -27.99608) (xy 213.816158 -28.047986) (xy 213.839094 -28.103359)
			(xy 213.854607 -28.161252) (xy 213.86243 -28.220674) (xy 213.86292 -28.250642) (xy 213.86292 -28.469082)
			(xy 217.852496 -28.469082) (xy 217.856567 -28.41346) (xy 217.868693 -28.359023) (xy 217.888616 -28.306932)
			(xy 217.915912 -28.258297) (xy 217.949998 -28.214154) (xy 217.990147 -28.175445) (xy 218.035505 -28.142994)
			(xy 218.085105 -28.117493) (xy 218.137889 -28.099486) (xy 218.192732 -28.089356) (xy 218.248466 -28.087319)
			(xy 218.303903 -28.093419) (xy 218.35786 -28.107525) (xy 218.409189 -28.129337) (xy 218.425245 -28.139136)
			(xy 234.597954 -28.139136) (xy 234.602025 -28.083514) (xy 234.614151 -28.029077) (xy 234.634074 -27.976986)
			(xy 234.66137 -27.928351) (xy 234.695456 -27.884208) (xy 234.735605 -27.845499) (xy 234.780963 -27.813048)
			(xy 234.830563 -27.787547) (xy 234.883347 -27.76954) (xy 234.93819 -27.75941) (xy 234.993924 -27.757373)
			(xy 235.049361 -27.763473) (xy 235.103318 -27.777579) (xy 235.154647 -27.799391) (xy 235.202253 -27.828445)
			(xy 235.245121 -27.86412) (xy 235.282338 -27.905657) (xy 235.313111 -27.95217) (xy 235.336783 -28.002667)
			(xy 235.352851 -28.056074) (xy 235.360971 -28.11125) (xy 235.36148 -28.139136) (xy 235.867954 -28.139136)
			(xy 235.872025 -28.083514) (xy 235.884151 -28.029077) (xy 235.904074 -27.976986) (xy 235.93137 -27.928351)
			(xy 235.965456 -27.884208) (xy 236.005605 -27.845499) (xy 236.050963 -27.813048) (xy 236.100563 -27.787547)
			(xy 236.153347 -27.76954) (xy 236.20819 -27.75941) (xy 236.263924 -27.757373) (xy 236.319361 -27.763473)
			(xy 236.373318 -27.777579) (xy 236.424647 -27.799391) (xy 236.472253 -27.828445) (xy 236.515121 -27.86412)
			(xy 236.552338 -27.905657) (xy 236.583111 -27.95217) (xy 236.606783 -28.002667) (xy 236.622851 -28.056074)
			(xy 236.630971 -28.11125) (xy 236.63148 -28.139136) (xy 236.630971 -28.167022) (xy 236.622851 -28.222198)
			(xy 236.606783 -28.275605) (xy 236.583111 -28.326102) (xy 236.552338 -28.372615) (xy 236.515121 -28.414152)
			(xy 236.472253 -28.449827) (xy 236.424647 -28.478881) (xy 236.373318 -28.500693) (xy 236.319361 -28.514799)
			(xy 236.263924 -28.520899) (xy 236.20819 -28.518862) (xy 236.153347 -28.508732) (xy 236.100563 -28.490725)
			(xy 236.050963 -28.465224) (xy 236.005605 -28.432773) (xy 235.965456 -28.394064) (xy 235.93137 -28.349921)
			(xy 235.904074 -28.301286) (xy 235.884151 -28.249195) (xy 235.872025 -28.194758) (xy 235.867954 -28.139136)
			(xy 235.36148 -28.139136) (xy 235.360971 -28.167022) (xy 235.352851 -28.222198) (xy 235.336783 -28.275605)
			(xy 235.313111 -28.326102) (xy 235.282338 -28.372615) (xy 235.245121 -28.414152) (xy 235.202253 -28.449827)
			(xy 235.154647 -28.478881) (xy 235.103318 -28.500693) (xy 235.049361 -28.514799) (xy 234.993924 -28.520899)
			(xy 234.93819 -28.518862) (xy 234.883347 -28.508732) (xy 234.830563 -28.490725) (xy 234.780963 -28.465224)
			(xy 234.735605 -28.432773) (xy 234.695456 -28.394064) (xy 234.66137 -28.349921) (xy 234.634074 -28.301286)
			(xy 234.614151 -28.249195) (xy 234.602025 -28.194758) (xy 234.597954 -28.139136) (xy 218.425245 -28.139136)
			(xy 218.456795 -28.158391) (xy 218.499663 -28.194066) (xy 218.53688 -28.235603) (xy 218.567653 -28.282116)
			(xy 218.591325 -28.332613) (xy 218.607393 -28.38602) (xy 218.615513 -28.441196) (xy 218.616022 -28.469082)
			(xy 218.615513 -28.496968) (xy 218.607393 -28.552144) (xy 218.591325 -28.605551) (xy 218.567653 -28.656048)
			(xy 218.53688 -28.702561) (xy 218.499663 -28.744098) (xy 218.456795 -28.779773) (xy 218.409189 -28.808827)
			(xy 218.35786 -28.830639) (xy 218.303903 -28.844745) (xy 218.248466 -28.850845) (xy 218.192732 -28.848808)
			(xy 218.137889 -28.838678) (xy 218.085105 -28.820671) (xy 218.035505 -28.79517) (xy 217.990147 -28.762719)
			(xy 217.949998 -28.72401) (xy 217.915912 -28.679867) (xy 217.888616 -28.631232) (xy 217.868693 -28.579141)
			(xy 217.856567 -28.524704) (xy 217.852496 -28.469082) (xy 213.86292 -28.469082) (xy 213.86292 -29.114242)
			(xy 213.86243 -29.14421) (xy 213.854607 -29.203632) (xy 213.839094 -29.261525) (xy 213.816158 -29.316898)
			(xy 213.786191 -29.368804) (xy 213.749704 -29.416354) (xy 213.707324 -29.458734) (xy 213.659774 -29.495221)
			(xy 213.607868 -29.525188) (xy 213.552495 -29.548124) (xy 213.494602 -29.563637) (xy 213.43518 -29.57146)
			(xy 213.375244 -29.57146) (xy 213.315822 -29.563637) (xy 213.257929 -29.548124) (xy 213.202556 -29.525188)
			(xy 213.15065 -29.495221) (xy 213.1031 -29.458734) (xy 213.06072 -29.416354) (xy 213.024233 -29.368804)
			(xy 212.994266 -29.316898) (xy 212.97133 -29.261525) (xy 212.955817 -29.203632) (xy 212.947994 -29.14421)
			(xy 212.947504 -29.114242) (xy 206.085948 -29.114242) (xy 207.356964 -30.385258) (xy 207.390657 -30.41975)
			(xy 207.451941 -30.494199) (xy 207.505753 -30.574216) (xy 207.55159 -30.659054) (xy 207.570832 -30.703266)
			(xy 207.662613 -30.92069) (xy 215.589612 -30.92069) (xy 215.589612 -30.05709) (xy 215.590102 -30.027122)
			(xy 215.597925 -29.9677) (xy 215.613438 -29.909807) (xy 215.636374 -29.854434) (xy 215.666341 -29.802528)
			(xy 215.702828 -29.754978) (xy 215.745208 -29.712598) (xy 215.792758 -29.676111) (xy 215.844664 -29.646144)
			(xy 215.900037 -29.623208) (xy 215.95793 -29.607695) (xy 216.017352 -29.599872) (xy 216.077288 -29.599872)
			(xy 216.13671 -29.607695) (xy 216.194603 -29.623208) (xy 216.249976 -29.646144) (xy 216.301882 -29.676111)
			(xy 216.349432 -29.712598) (xy 216.391812 -29.754978) (xy 216.428299 -29.802528) (xy 216.458266 -29.854434)
			(xy 216.481202 -29.909807) (xy 216.496715 -29.9677) (xy 216.504538 -30.027122) (xy 216.505028 -30.05709)
			(xy 216.505028 -30.376876) (xy 233.088942 -30.376876) (xy 233.089499 -30.34796) (xy 233.098218 -30.29079)
			(xy 233.115467 -30.235592) (xy 233.140851 -30.183629) (xy 233.173789 -30.136095) (xy 233.213525 -30.094077)
			(xy 233.236008 -30.075886) (xy 233.244813 -30.068276) (xy 233.254997 -30.047378) (xy 233.255566 -30.035754)
			(xy 233.255566 -29.955998) (xy 233.255026 -29.944366) (xy 233.244839 -29.923456) (xy 233.236008 -29.915866)
			(xy 233.21351 -29.897692) (xy 233.173775 -29.855669) (xy 233.140838 -29.808131) (xy 233.115452 -29.756166)
			(xy 233.098199 -29.700965) (xy 233.089474 -29.643793) (xy 233.088942 -29.614876) (xy 233.089428 -29.587625)
			(xy 233.097184 -29.533677) (xy 233.112539 -29.481382) (xy 233.135181 -29.431805) (xy 233.164647 -29.385955)
			(xy 233.200338 -29.344764) (xy 233.241529 -29.309073) (xy 233.287379 -29.279607) (xy 233.336956 -29.256965)
			(xy 233.389251 -29.24161) (xy 233.443199 -29.233854) (xy 233.497701 -29.233854) (xy 233.551649 -29.24161)
			(xy 233.603944 -29.256965) (xy 233.653521 -29.279607) (xy 233.699371 -29.309073) (xy 233.740562 -29.344764)
			(xy 233.776253 -29.385955) (xy 233.805719 -29.431805) (xy 233.828361 -29.481382) (xy 233.843716 -29.533677)
			(xy 233.851472 -29.587625) (xy 233.851958 -29.614876) (xy 233.851438 -29.643793) (xy 233.842712 -29.700965)
			(xy 233.825455 -29.756164) (xy 233.800064 -29.808126) (xy 233.76712 -29.85566) (xy 233.727378 -29.897676)
			(xy 233.704892 -29.915866) (xy 233.696109 -29.923497) (xy 233.685912 -29.944379) (xy 233.685334 -29.955998)
			(xy 233.685334 -30.035754) (xy 233.685845 -30.04739) (xy 233.696053 -30.0683) (xy 233.704892 -30.075886)
			(xy 233.727367 -30.094087) (xy 233.767103 -30.136104) (xy 233.800043 -30.183637) (xy 233.825433 -30.235597)
			(xy 233.842691 -30.290792) (xy 233.851422 -30.347961) (xy 233.851958 -30.376876) (xy 236.129068 -30.376876)
			(xy 236.129615 -30.34796) (xy 236.138335 -30.290789) (xy 236.155585 -30.23559) (xy 236.180971 -30.183627)
			(xy 236.213911 -30.136093) (xy 236.25365 -30.094076) (xy 236.276134 -30.075886) (xy 236.284943 -30.068281)
			(xy 236.295124 -30.047378) (xy 236.295692 -30.035754) (xy 236.295692 -29.955998) (xy 236.295143 -29.944367)
			(xy 236.284961 -29.923457) (xy 236.276134 -29.915866) (xy 236.253641 -29.897686) (xy 236.213905 -29.855665)
			(xy 236.180966 -29.808128) (xy 236.155579 -29.756164) (xy 236.138325 -29.700964) (xy 236.1296 -29.643793)
			(xy 236.129068 -29.614876) (xy 236.129554 -29.587625) (xy 236.13731 -29.533677) (xy 236.152665 -29.481382)
			(xy 236.175307 -29.431805) (xy 236.204773 -29.385955) (xy 236.240464 -29.344764) (xy 236.281655 -29.309073)
			(xy 236.327505 -29.279607) (xy 236.377082 -29.256965) (xy 236.429377 -29.24161) (xy 236.483325 -29.233854)
			(xy 236.537827 -29.233854) (xy 236.591775 -29.24161) (xy 236.64407 -29.256965) (xy 236.693647 -29.279607)
			(xy 236.739497 -29.309073) (xy 236.780688 -29.344764) (xy 236.816379 -29.385955) (xy 236.845845 -29.431805)
			(xy 236.868487 -29.481382) (xy 236.883842 -29.533677) (xy 236.891598 -29.587625) (xy 236.892084 -29.614876)
			(xy 236.891554 -29.643793) (xy 236.882829 -29.700964) (xy 236.865573 -29.756162) (xy 236.840184 -29.808124)
			(xy 236.807242 -29.855658) (xy 236.767503 -29.897676) (xy 236.745018 -29.915866) (xy 236.736222 -29.923484)
			(xy 236.726036 -29.944377) (xy 236.72546 -29.955998) (xy 236.72546 -30.035754) (xy 236.725961 -30.047391)
			(xy 236.736175 -30.068302) (xy 236.745018 -30.075886) (xy 236.767499 -30.09408) (xy 236.807233 -30.1361)
			(xy 236.840172 -30.183634) (xy 236.865561 -30.235595) (xy 236.882818 -30.290792) (xy 236.891548 -30.34796)
			(xy 236.892084 -30.376876) (xy 236.891598 -30.404127) (xy 236.883842 -30.458075) (xy 236.868487 -30.51037)
			(xy 236.845845 -30.559947) (xy 236.816379 -30.605797) (xy 236.780688 -30.646988) (xy 236.739497 -30.682679)
			(xy 236.693647 -30.712145) (xy 236.64407 -30.734787) (xy 236.591775 -30.750142) (xy 236.537827 -30.757898)
			(xy 236.483325 -30.757898) (xy 236.429377 -30.750142) (xy 236.377082 -30.734787) (xy 236.327505 -30.712145)
			(xy 236.281655 -30.682679) (xy 236.240464 -30.646988) (xy 236.204773 -30.605797) (xy 236.175307 -30.559947)
			(xy 236.152665 -30.51037) (xy 236.13731 -30.458075) (xy 236.129554 -30.404127) (xy 236.129068 -30.376876)
			(xy 233.851958 -30.376876) (xy 233.851472 -30.404127) (xy 233.843716 -30.458075) (xy 233.828361 -30.51037)
			(xy 233.805719 -30.559947) (xy 233.776253 -30.605797) (xy 233.740562 -30.646988) (xy 233.699371 -30.682679)
			(xy 233.653521 -30.712145) (xy 233.603944 -30.734787) (xy 233.551649 -30.750142) (xy 233.497701 -30.757898)
			(xy 233.443199 -30.757898) (xy 233.389251 -30.750142) (xy 233.336956 -30.734787) (xy 233.287379 -30.712145)
			(xy 233.241529 -30.682679) (xy 233.200338 -30.646988) (xy 233.164647 -30.605797) (xy 233.135181 -30.559947)
			(xy 233.112539 -30.51037) (xy 233.097184 -30.458075) (xy 233.089428 -30.404127) (xy 233.088942 -30.376876)
			(xy 216.505028 -30.376876) (xy 216.505028 -30.92069) (xy 216.504538 -30.950658) (xy 216.496715 -31.01008)
			(xy 216.481202 -31.067973) (xy 216.458266 -31.123346) (xy 216.428299 -31.175252) (xy 216.391812 -31.222802)
			(xy 216.349432 -31.265182) (xy 216.301882 -31.301669) (xy 216.249976 -31.331636) (xy 216.194603 -31.354572)
			(xy 216.13671 -31.370085) (xy 216.077288 -31.377908) (xy 216.017352 -31.377908) (xy 215.95793 -31.370085)
			(xy 215.900037 -31.354572) (xy 215.844664 -31.331636) (xy 215.792758 -31.301669) (xy 215.745208 -31.265182)
			(xy 215.702828 -31.222802) (xy 215.666341 -31.175252) (xy 215.636374 -31.123346) (xy 215.613438 -31.067973)
			(xy 215.597925 -31.01008) (xy 215.590102 -30.950658) (xy 215.589612 -30.92069) (xy 207.662613 -30.92069)
			(xy 207.696816 -31.001716) (xy 207.699356 -31.005526) (xy 207.725068 -31.045427) (xy 207.769595 -31.129266)
			(xy 207.788256 -31.172912) (xy 208.426923 -32.714184) (xy 212.947504 -32.714184) (xy 212.947504 -31.850584)
			(xy 212.947994 -31.820616) (xy 212.955817 -31.761194) (xy 212.97133 -31.703301) (xy 212.994266 -31.647928)
			(xy 213.024233 -31.596022) (xy 213.06072 -31.548472) (xy 213.1031 -31.506092) (xy 213.15065 -31.469605)
			(xy 213.202556 -31.439638) (xy 213.257929 -31.416702) (xy 213.315822 -31.401189) (xy 213.375244 -31.393366)
			(xy 213.43518 -31.393366) (xy 213.494602 -31.401189) (xy 213.552495 -31.416702) (xy 213.607868 -31.439638)
			(xy 213.659774 -31.469605) (xy 213.707324 -31.506092) (xy 213.749704 -31.548472) (xy 213.764598 -31.567882)
			(xy 233.198668 -31.567882) (xy 233.202739 -31.51226) (xy 233.214865 -31.457823) (xy 233.234788 -31.405732)
			(xy 233.262084 -31.357097) (xy 233.29617 -31.312954) (xy 233.336319 -31.274245) (xy 233.381677 -31.241794)
			(xy 233.431277 -31.216293) (xy 233.484061 -31.198286) (xy 233.538904 -31.188156) (xy 233.594638 -31.186119)
			(xy 233.650075 -31.192219) (xy 233.704032 -31.206325) (xy 233.755361 -31.228137) (xy 233.802967 -31.257191)
			(xy 233.845835 -31.292866) (xy 233.883052 -31.334403) (xy 233.913825 -31.380916) (xy 233.937497 -31.431413)
			(xy 233.953565 -31.48482) (xy 233.961685 -31.539996) (xy 233.962194 -31.567882) (xy 233.961685 -31.595768)
			(xy 233.953565 -31.650944) (xy 233.937497 -31.704351) (xy 233.930505 -31.719266) (xy 234.485432 -31.719266)
			(xy 234.489503 -31.663644) (xy 234.501629 -31.609207) (xy 234.521552 -31.557116) (xy 234.548848 -31.508481)
			(xy 234.582934 -31.464338) (xy 234.623083 -31.425629) (xy 234.668441 -31.393178) (xy 234.718041 -31.367677)
			(xy 234.770825 -31.34967) (xy 234.825668 -31.33954) (xy 234.881402 -31.337503) (xy 234.936839 -31.343603)
			(xy 234.990796 -31.357709) (xy 235.042125 -31.379521) (xy 235.089731 -31.408575) (xy 235.132599 -31.44425)
			(xy 235.169816 -31.485787) (xy 235.200589 -31.5323) (xy 235.224261 -31.582797) (xy 235.240329 -31.636204)
			(xy 235.244479 -31.664402) (xy 235.76102 -31.664402) (xy 235.765091 -31.60878) (xy 235.777217 -31.554343)
			(xy 235.79714 -31.502252) (xy 235.824436 -31.453617) (xy 235.858522 -31.409474) (xy 235.898671 -31.370765)
			(xy 235.944029 -31.338314) (xy 235.993629 -31.312813) (xy 236.046413 -31.294806) (xy 236.101256 -31.284676)
			(xy 236.15699 -31.282639) (xy 236.212427 -31.288739) (xy 236.266384 -31.302845) (xy 236.317713 -31.324657)
			(xy 236.365319 -31.353711) (xy 236.408187 -31.389386) (xy 236.445404 -31.430923) (xy 236.476177 -31.477436)
			(xy 236.499849 -31.527933) (xy 236.515917 -31.58134) (xy 236.524037 -31.636516) (xy 236.524546 -31.664402)
			(xy 236.524037 -31.692288) (xy 236.515917 -31.747464) (xy 236.506977 -31.777178) (xy 237.026194 -31.777178)
			(xy 237.030265 -31.721556) (xy 237.042391 -31.667119) (xy 237.062314 -31.615028) (xy 237.08961 -31.566393)
			(xy 237.123696 -31.52225) (xy 237.163845 -31.483541) (xy 237.209203 -31.45109) (xy 237.258803 -31.425589)
			(xy 237.311587 -31.407582) (xy 237.36643 -31.397452) (xy 237.422164 -31.395415) (xy 237.477601 -31.401515)
			(xy 237.531558 -31.415621) (xy 237.582887 -31.437433) (xy 237.630493 -31.466487) (xy 237.673361 -31.502162)
			(xy 237.710578 -31.543699) (xy 237.741351 -31.590212) (xy 237.765023 -31.640709) (xy 237.781091 -31.694116)
			(xy 237.789211 -31.749292) (xy 237.78972 -31.777178) (xy 237.789211 -31.805064) (xy 237.781091 -31.86024)
			(xy 237.765023 -31.913647) (xy 237.741351 -31.964144) (xy 237.710578 -32.010657) (xy 237.673361 -32.052194)
			(xy 237.630493 -32.087869) (xy 237.582887 -32.116923) (xy 237.531558 -32.138735) (xy 237.477601 -32.152841)
			(xy 237.422164 -32.158941) (xy 237.36643 -32.156904) (xy 237.311587 -32.146774) (xy 237.258803 -32.128767)
			(xy 237.209203 -32.103266) (xy 237.163845 -32.070815) (xy 237.123696 -32.032106) (xy 237.08961 -31.987963)
			(xy 237.062314 -31.939328) (xy 237.042391 -31.887237) (xy 237.030265 -31.8328) (xy 237.026194 -31.777178)
			(xy 236.506977 -31.777178) (xy 236.499849 -31.800871) (xy 236.476177 -31.851368) (xy 236.445404 -31.897881)
			(xy 236.408187 -31.939418) (xy 236.365319 -31.975093) (xy 236.317713 -32.004147) (xy 236.266384 -32.025959)
			(xy 236.212427 -32.040065) (xy 236.15699 -32.046165) (xy 236.101256 -32.044128) (xy 236.046413 -32.033998)
			(xy 235.993629 -32.015991) (xy 235.944029 -31.99049) (xy 235.898671 -31.958039) (xy 235.858522 -31.91933)
			(xy 235.824436 -31.875187) (xy 235.79714 -31.826552) (xy 235.777217 -31.774461) (xy 235.765091 -31.720024)
			(xy 235.76102 -31.664402) (xy 235.244479 -31.664402) (xy 235.248449 -31.69138) (xy 235.248958 -31.719266)
			(xy 235.248449 -31.747152) (xy 235.240329 -31.802328) (xy 235.224261 -31.855735) (xy 235.200589 -31.906232)
			(xy 235.169816 -31.952745) (xy 235.132599 -31.994282) (xy 235.089731 -32.029957) (xy 235.042125 -32.059011)
			(xy 234.990796 -32.080823) (xy 234.936839 -32.094929) (xy 234.881402 -32.101029) (xy 234.825668 -32.098992)
			(xy 234.770825 -32.088862) (xy 234.718041 -32.070855) (xy 234.668441 -32.045354) (xy 234.623083 -32.012903)
			(xy 234.582934 -31.974194) (xy 234.548848 -31.930051) (xy 234.521552 -31.881416) (xy 234.501629 -31.829325)
			(xy 234.489503 -31.774888) (xy 234.485432 -31.719266) (xy 233.930505 -31.719266) (xy 233.913825 -31.754848)
			(xy 233.883052 -31.801361) (xy 233.845835 -31.842898) (xy 233.802967 -31.878573) (xy 233.755361 -31.907627)
			(xy 233.704032 -31.929439) (xy 233.650075 -31.943545) (xy 233.594638 -31.949645) (xy 233.538904 -31.947608)
			(xy 233.484061 -31.937478) (xy 233.431277 -31.919471) (xy 233.381677 -31.89397) (xy 233.336319 -31.861519)
			(xy 233.29617 -31.82281) (xy 233.262084 -31.778667) (xy 233.234788 -31.730032) (xy 233.214865 -31.677941)
			(xy 233.202739 -31.623504) (xy 233.198668 -31.567882) (xy 213.764598 -31.567882) (xy 213.786191 -31.596022)
			(xy 213.816158 -31.647928) (xy 213.839094 -31.703301) (xy 213.854607 -31.761194) (xy 213.86243 -31.820616)
			(xy 213.86292 -31.850584) (xy 213.86292 -32.714184) (xy 213.86243 -32.744152) (xy 213.854607 -32.803574)
			(xy 213.839094 -32.861467) (xy 213.816158 -32.91684) (xy 213.786191 -32.968746) (xy 213.749704 -33.016296)
			(xy 213.707324 -33.058676) (xy 213.659774 -33.095163) (xy 213.607868 -33.12513) (xy 213.552495 -33.148066)
			(xy 213.494602 -33.163579) (xy 213.43518 -33.171402) (xy 213.375244 -33.171402) (xy 213.315822 -33.163579)
			(xy 213.257929 -33.148066) (xy 213.202556 -33.12513) (xy 213.15065 -33.095163) (xy 213.1031 -33.058676)
			(xy 213.06072 -33.016296) (xy 213.024233 -32.968746) (xy 212.994266 -32.91684) (xy 212.97133 -32.861467)
			(xy 212.955817 -32.803574) (xy 212.947994 -32.744152) (xy 212.947504 -32.714184) (xy 208.426923 -32.714184)
			(xy 208.466182 -32.808926) (xy 208.469992 -32.818324) (xy 208.476596 -32.825182) (xy 208.479729 -32.828319)
			(xy 208.486883 -32.833556) (xy 208.49082 -32.835596) (xy 208.493868 -32.836866) (xy 208.501996 -32.840422)
			(xy 208.50352 -32.841184) (xy 208.528071 -32.852569) (xy 208.57396 -32.881252) (xy 208.615333 -32.916135)
			(xy 208.651357 -32.956518) (xy 208.681309 -33.001589) (xy 208.704586 -33.050443) (xy 208.720721 -33.102098)
			(xy 208.729389 -33.155515) (xy 208.730342 -33.18256) (xy 208.730342 -33.20161) (xy 208.72958 -33.216596)
			(xy 208.72958 -33.217104) (xy 208.728564 -33.233614) (xy 208.727802 -33.239202) (xy 208.727294 -33.242758)
			(xy 208.727294 -33.243266) (xy 208.723758 -33.265396) (xy 208.712174 -33.30869) (xy 208.70418 -33.329626)
			(xy 208.700878 -33.3375) (xy 208.698592 -33.347406) (xy 208.697231 -33.355156) (xy 208.698796 -33.370803)
			(xy 208.70164 -33.37814) (xy 208.769712 -33.542478) (xy 208.921858 -33.909254) (xy 208.921858 -33.909762)
			(xy 209.179284 -34.520886) (xy 215.589612 -34.520886) (xy 215.589612 -33.657286) (xy 215.590102 -33.627318)
			(xy 215.597925 -33.567896) (xy 215.613438 -33.510003) (xy 215.636374 -33.45463) (xy 215.666341 -33.402724)
			(xy 215.702828 -33.355174) (xy 215.745208 -33.312794) (xy 215.792758 -33.276307) (xy 215.844664 -33.24634)
			(xy 215.900037 -33.223404) (xy 215.95793 -33.207891) (xy 216.017352 -33.200068) (xy 216.077288 -33.200068)
			(xy 216.13671 -33.207891) (xy 216.194603 -33.223404) (xy 216.249976 -33.24634) (xy 216.301882 -33.276307)
			(xy 216.349432 -33.312794) (xy 216.391812 -33.355174) (xy 216.428299 -33.402724) (xy 216.458266 -33.45463)
			(xy 216.481202 -33.510003) (xy 216.496715 -33.567896) (xy 216.504538 -33.627318) (xy 216.505028 -33.657286)
			(xy 216.505028 -34.520886) (xy 216.504538 -34.550854) (xy 216.496715 -34.610276) (xy 216.481202 -34.668169)
			(xy 216.458266 -34.723542) (xy 216.428299 -34.775448) (xy 216.391812 -34.822998) (xy 216.349432 -34.865378)
			(xy 216.301882 -34.901865) (xy 216.249976 -34.931832) (xy 216.194603 -34.954768) (xy 216.13671 -34.970281)
			(xy 216.077288 -34.978104) (xy 216.017352 -34.978104) (xy 215.95793 -34.970281) (xy 215.900037 -34.954768)
			(xy 215.844664 -34.931832) (xy 215.792758 -34.901865) (xy 215.745208 -34.865378) (xy 215.702828 -34.822998)
			(xy 215.666341 -34.775448) (xy 215.636374 -34.723542) (xy 215.613438 -34.668169) (xy 215.597925 -34.610276)
			(xy 215.590102 -34.550854) (xy 215.589612 -34.520886) (xy 209.179284 -34.520886) (xy 209.492667 -35.264852)
			(xy 236.102396 -35.264852) (xy 236.106467 -35.20923) (xy 236.118593 -35.154793) (xy 236.138516 -35.102702)
			(xy 236.165812 -35.054067) (xy 236.199898 -35.009924) (xy 236.240047 -34.971215) (xy 236.285405 -34.938764)
			(xy 236.335005 -34.913263) (xy 236.387789 -34.895256) (xy 236.442632 -34.885126) (xy 236.498366 -34.883089)
			(xy 236.553803 -34.889189) (xy 236.60776 -34.903295) (xy 236.659089 -34.925107) (xy 236.706695 -34.954161)
			(xy 236.749563 -34.989836) (xy 236.78678 -35.031373) (xy 236.817553 -35.077886) (xy 236.841225 -35.128383)
			(xy 236.857293 -35.18179) (xy 236.865413 -35.236966) (xy 236.865922 -35.264852) (xy 236.865413 -35.292738)
			(xy 236.857293 -35.347914) (xy 236.841225 -35.401321) (xy 236.817553 -35.451818) (xy 236.78678 -35.498331)
			(xy 236.749563 -35.539868) (xy 236.706695 -35.575543) (xy 236.659089 -35.604597) (xy 236.60776 -35.626409)
			(xy 236.553803 -35.640515) (xy 236.498366 -35.646615) (xy 236.442632 -35.644578) (xy 236.387789 -35.634448)
			(xy 236.335005 -35.616441) (xy 236.285405 -35.59094) (xy 236.240047 -35.558489) (xy 236.199898 -35.51978)
			(xy 236.165812 -35.475637) (xy 236.138516 -35.427002) (xy 236.118593 -35.374911) (xy 236.106467 -35.320474)
			(xy 236.102396 -35.264852) (xy 209.492667 -35.264852) (xy 209.750414 -35.876738) (xy 224.917252 -35.876738)
			(xy 224.921323 -35.821116) (xy 224.933449 -35.766679) (xy 224.953372 -35.714588) (xy 224.980668 -35.665953)
			(xy 225.014754 -35.62181) (xy 225.054903 -35.583101) (xy 225.100261 -35.55065) (xy 225.149861 -35.525149)
			(xy 225.202645 -35.507142) (xy 225.257488 -35.497012) (xy 225.313222 -35.494975) (xy 225.368659 -35.501075)
			(xy 225.422616 -35.515181) (xy 225.473945 -35.536993) (xy 225.521551 -35.566047) (xy 225.564419 -35.601722)
			(xy 225.601636 -35.643259) (xy 225.632409 -35.689772) (xy 225.656081 -35.740269) (xy 225.672149 -35.793676)
			(xy 225.680269 -35.848852) (xy 225.680778 -35.876738) (xy 228.988872 -35.876738) (xy 228.992943 -35.821116)
			(xy 229.005069 -35.766679) (xy 229.024992 -35.714588) (xy 229.052288 -35.665953) (xy 229.086374 -35.62181)
			(xy 229.126523 -35.583101) (xy 229.171881 -35.55065) (xy 229.221481 -35.525149) (xy 229.274265 -35.507142)
			(xy 229.329108 -35.497012) (xy 229.384842 -35.494975) (xy 229.440279 -35.501075) (xy 229.494236 -35.515181)
			(xy 229.545565 -35.536993) (xy 229.593171 -35.566047) (xy 229.636039 -35.601722) (xy 229.673256 -35.643259)
			(xy 229.704029 -35.689772) (xy 229.727701 -35.740269) (xy 229.743769 -35.793676) (xy 229.751889 -35.848852)
			(xy 229.752398 -35.876738) (xy 229.751889 -35.904624) (xy 229.743769 -35.9598) (xy 229.727701 -36.013207)
			(xy 229.704029 -36.063704) (xy 229.673256 -36.110217) (xy 229.636039 -36.151754) (xy 229.593171 -36.187429)
			(xy 229.545565 -36.216483) (xy 229.494236 -36.238295) (xy 229.440279 -36.252401) (xy 229.384842 -36.258501)
			(xy 229.329108 -36.256464) (xy 229.274265 -36.246334) (xy 229.221481 -36.228327) (xy 229.171881 -36.202826)
			(xy 229.126523 -36.170375) (xy 229.086374 -36.131666) (xy 229.052288 -36.087523) (xy 229.024992 -36.038888)
			(xy 229.005069 -35.986797) (xy 228.992943 -35.93236) (xy 228.988872 -35.876738) (xy 225.680778 -35.876738)
			(xy 225.680269 -35.904624) (xy 225.672149 -35.9598) (xy 225.656081 -36.013207) (xy 225.632409 -36.063704)
			(xy 225.601636 -36.110217) (xy 225.564419 -36.151754) (xy 225.521551 -36.187429) (xy 225.473945 -36.216483)
			(xy 225.422616 -36.238295) (xy 225.368659 -36.252401) (xy 225.313222 -36.258501) (xy 225.257488 -36.256464)
			(xy 225.202645 -36.246334) (xy 225.149861 -36.228327) (xy 225.100261 -36.202826) (xy 225.054903 -36.170375)
			(xy 225.014754 -36.131666) (xy 224.980668 -36.087523) (xy 224.953372 -36.038888) (xy 224.933449 -35.986797)
			(xy 224.921323 -35.93236) (xy 224.917252 -35.876738) (xy 209.750414 -35.876738) (xy 210.017148 -36.50996)
			(xy 226.81387 -36.50996) (xy 226.817941 -36.454338) (xy 226.830067 -36.399901) (xy 226.84999 -36.34781)
			(xy 226.877286 -36.299175) (xy 226.911372 -36.255032) (xy 226.951521 -36.216323) (xy 226.996879 -36.183872)
			(xy 227.046479 -36.158371) (xy 227.099263 -36.140364) (xy 227.154106 -36.130234) (xy 227.20984 -36.128197)
			(xy 227.265277 -36.134297) (xy 227.319234 -36.148403) (xy 227.370563 -36.170215) (xy 227.418169 -36.199269)
			(xy 227.461037 -36.234944) (xy 227.498254 -36.276481) (xy 227.529027 -36.322994) (xy 227.552699 -36.373491)
			(xy 227.568767 -36.426898) (xy 227.572692 -36.453572) (xy 230.12857 -36.453572) (xy 230.132641 -36.39795)
			(xy 230.144767 -36.343513) (xy 230.16469 -36.291422) (xy 230.191986 -36.242787) (xy 230.226072 -36.198644)
			(xy 230.266221 -36.159935) (xy 230.311579 -36.127484) (xy 230.361179 -36.101983) (xy 230.413963 -36.083976)
			(xy 230.468806 -36.073846) (xy 230.52454 -36.071809) (xy 230.579977 -36.077909) (xy 230.633934 -36.092015)
			(xy 230.685263 -36.113827) (xy 230.732869 -36.142881) (xy 230.775737 -36.178556) (xy 230.812954 -36.220093)
			(xy 230.843727 -36.266606) (xy 230.853263 -36.286948) (xy 237.400336 -36.286948) (xy 237.404407 -36.231326)
			(xy 237.416533 -36.176889) (xy 237.436456 -36.124798) (xy 237.463752 -36.076163) (xy 237.497838 -36.03202)
			(xy 237.537987 -35.993311) (xy 237.583345 -35.96086) (xy 237.632945 -35.935359) (xy 237.685729 -35.917352)
			(xy 237.740572 -35.907222) (xy 237.796306 -35.905185) (xy 237.851743 -35.911285) (xy 237.9057 -35.925391)
			(xy 237.957029 -35.947203) (xy 238.004635 -35.976257) (xy 238.047503 -36.011932) (xy 238.08472 -36.053469)
			(xy 238.115493 -36.099982) (xy 238.139165 -36.150479) (xy 238.155233 -36.203886) (xy 238.163353 -36.259062)
			(xy 238.163862 -36.286948) (xy 238.163353 -36.314834) (xy 238.155233 -36.37001) (xy 238.139165 -36.423417)
			(xy 238.115493 -36.473914) (xy 238.08472 -36.520427) (xy 238.047503 -36.561964) (xy 238.004635 -36.597639)
			(xy 237.957029 -36.626693) (xy 237.9057 -36.648505) (xy 237.851743 -36.662611) (xy 237.796306 -36.668711)
			(xy 237.740572 -36.666674) (xy 237.685729 -36.656544) (xy 237.632945 -36.638537) (xy 237.583345 -36.613036)
			(xy 237.537987 -36.580585) (xy 237.497838 -36.541876) (xy 237.463752 -36.497733) (xy 237.436456 -36.449098)
			(xy 237.416533 -36.397007) (xy 237.404407 -36.34257) (xy 237.400336 -36.286948) (xy 230.853263 -36.286948)
			(xy 230.867399 -36.317103) (xy 230.883467 -36.37051) (xy 230.891587 -36.425686) (xy 230.892096 -36.453572)
			(xy 230.891587 -36.481458) (xy 230.883467 -36.536634) (xy 230.867399 -36.590041) (xy 230.843727 -36.640538)
			(xy 230.812954 -36.687051) (xy 230.775737 -36.728588) (xy 230.732869 -36.764263) (xy 230.685263 -36.793317)
			(xy 230.633934 -36.815129) (xy 230.579977 -36.829235) (xy 230.52454 -36.835335) (xy 230.468806 -36.833298)
			(xy 230.413963 -36.823168) (xy 230.361179 -36.805161) (xy 230.311579 -36.77966) (xy 230.266221 -36.747209)
			(xy 230.226072 -36.7085) (xy 230.191986 -36.664357) (xy 230.16469 -36.615722) (xy 230.144767 -36.563631)
			(xy 230.132641 -36.509194) (xy 230.12857 -36.453572) (xy 227.572692 -36.453572) (xy 227.576887 -36.482074)
			(xy 227.577396 -36.50996) (xy 227.576887 -36.537846) (xy 227.568767 -36.593022) (xy 227.552699 -36.646429)
			(xy 227.529027 -36.696926) (xy 227.498254 -36.743439) (xy 227.461037 -36.784976) (xy 227.418169 -36.820651)
			(xy 227.370563 -36.849705) (xy 227.319234 -36.871517) (xy 227.265277 -36.885623) (xy 227.20984 -36.891723)
			(xy 227.154106 -36.889686) (xy 227.099263 -36.879556) (xy 227.046479 -36.861549) (xy 226.996879 -36.836048)
			(xy 226.951521 -36.803597) (xy 226.911372 -36.764888) (xy 226.877286 -36.720745) (xy 226.84999 -36.67211)
			(xy 226.830067 -36.620019) (xy 226.817941 -36.565582) (xy 226.81387 -36.50996) (xy 210.017148 -36.50996)
			(xy 210.263232 -37.09416) (xy 210.282766 -37.142217) (xy 210.312926 -37.241479) (xy 210.32343 -37.29228)
			(xy 210.358737 -37.47516) (xy 223.959164 -37.47516) (xy 223.963235 -37.419538) (xy 223.975361 -37.365101)
			(xy 223.995284 -37.31301) (xy 224.02258 -37.264375) (xy 224.056666 -37.220232) (xy 224.096815 -37.181523)
			(xy 224.142173 -37.149072) (xy 224.191773 -37.123571) (xy 224.244557 -37.105564) (xy 224.2994 -37.095434)
			(xy 224.355134 -37.093397) (xy 224.410571 -37.099497) (xy 224.464528 -37.113603) (xy 224.515857 -37.135415)
			(xy 224.563463 -37.164469) (xy 224.606331 -37.200144) (xy 224.643548 -37.241681) (xy 224.674321 -37.288194)
			(xy 224.697993 -37.338691) (xy 224.714061 -37.392098) (xy 224.722181 -37.447274) (xy 224.72269 -37.47516)
			(xy 224.722181 -37.503046) (xy 224.714061 -37.558222) (xy 224.697993 -37.611629) (xy 224.674321 -37.662126)
			(xy 224.674168 -37.662358) (xy 226.14839 -37.662358) (xy 226.152461 -37.606736) (xy 226.164587 -37.552299)
			(xy 226.18451 -37.500208) (xy 226.211806 -37.451573) (xy 226.245892 -37.40743) (xy 226.286041 -37.368721)
			(xy 226.331399 -37.33627) (xy 226.380999 -37.310769) (xy 226.433783 -37.292762) (xy 226.488626 -37.282632)
			(xy 226.54436 -37.280595) (xy 226.599797 -37.286695) (xy 226.653754 -37.300801) (xy 226.705083 -37.322613)
			(xy 226.752689 -37.351667) (xy 226.795557 -37.387342) (xy 226.832774 -37.428879) (xy 226.863547 -37.475392)
			(xy 226.887219 -37.525889) (xy 226.903287 -37.579296) (xy 226.911407 -37.634472) (xy 226.911916 -37.662358)
			(xy 226.911407 -37.690244) (xy 226.903287 -37.74542) (xy 226.894653 -37.774118) (xy 237.66475 -37.774118)
			(xy 237.668821 -37.718496) (xy 237.680947 -37.664059) (xy 237.70087 -37.611968) (xy 237.728166 -37.563333)
			(xy 237.762252 -37.51919) (xy 237.802401 -37.480481) (xy 237.847759 -37.44803) (xy 237.897359 -37.422529)
			(xy 237.950143 -37.404522) (xy 238.004986 -37.394392) (xy 238.06072 -37.392355) (xy 238.116157 -37.398455)
			(xy 238.170114 -37.412561) (xy 238.221443 -37.434373) (xy 238.269049 -37.463427) (xy 238.311917 -37.499102)
			(xy 238.349134 -37.540639) (xy 238.379907 -37.587152) (xy 238.403579 -37.637649) (xy 238.419647 -37.691056)
			(xy 238.427767 -37.746232) (xy 238.428276 -37.774118) (xy 238.427767 -37.802004) (xy 238.419647 -37.85718)
			(xy 238.403579 -37.910587) (xy 238.379907 -37.961084) (xy 238.349134 -38.007597) (xy 238.311917 -38.049134)
			(xy 238.269049 -38.084809) (xy 238.221443 -38.113863) (xy 238.170114 -38.135675) (xy 238.116157 -38.149781)
			(xy 238.06072 -38.155881) (xy 238.004986 -38.153844) (xy 237.950143 -38.143714) (xy 237.897359 -38.125707)
			(xy 237.847759 -38.100206) (xy 237.802401 -38.067755) (xy 237.762252 -38.029046) (xy 237.728166 -37.984903)
			(xy 237.70087 -37.936268) (xy 237.680947 -37.884177) (xy 237.668821 -37.82974) (xy 237.66475 -37.774118)
			(xy 226.894653 -37.774118) (xy 226.887219 -37.798827) (xy 226.863547 -37.849324) (xy 226.832774 -37.895837)
			(xy 226.795557 -37.937374) (xy 226.752689 -37.973049) (xy 226.705083 -38.002103) (xy 226.653754 -38.023915)
			(xy 226.599797 -38.038021) (xy 226.54436 -38.044121) (xy 226.488626 -38.042084) (xy 226.433783 -38.031954)
			(xy 226.380999 -38.013947) (xy 226.331399 -37.988446) (xy 226.286041 -37.955995) (xy 226.245892 -37.917286)
			(xy 226.211806 -37.873143) (xy 226.18451 -37.824508) (xy 226.164587 -37.772417) (xy 226.152461 -37.71798)
			(xy 226.14839 -37.662358) (xy 224.674168 -37.662358) (xy 224.643548 -37.708639) (xy 224.606331 -37.750176)
			(xy 224.563463 -37.785851) (xy 224.515857 -37.814905) (xy 224.464528 -37.836717) (xy 224.410571 -37.850823)
			(xy 224.355134 -37.856923) (xy 224.2994 -37.854886) (xy 224.244557 -37.844756) (xy 224.191773 -37.826749)
			(xy 224.142173 -37.801248) (xy 224.096815 -37.768797) (xy 224.056666 -37.730088) (xy 224.02258 -37.685945)
			(xy 223.995284 -37.63731) (xy 223.975361 -37.585219) (xy 223.963235 -37.530782) (xy 223.959164 -37.47516)
			(xy 210.358737 -37.47516) (xy 210.433666 -37.863272) (xy 210.442123 -37.910057) (xy 210.451157 -38.004708)
			(xy 210.4517 -38.052248) (xy 210.451575 -38.079798) (xy 210.44865 -38.134821) (xy 210.445858 -38.16223)
			(xy 210.445604 -38.1635) (xy 210.381961 -38.729948) (xy 229.90102 -38.729948) (xy 229.90102 -38.675452)
			(xy 229.908775 -38.621512) (xy 229.924128 -38.569224) (xy 229.946766 -38.519653) (xy 229.976228 -38.473808)
			(xy 230.011914 -38.432623) (xy 230.053098 -38.396935) (xy 230.098942 -38.367472) (xy 230.148512 -38.344832)
			(xy 230.2008 -38.329478) (xy 230.25474 -38.321721) (xy 230.281988 -38.321234) (xy 230.310293 -38.321717)
			(xy 230.366282 -38.330068) (xy 230.420422 -38.346604) (xy 230.471523 -38.37096) (xy 230.518463 -38.402602)
			(xy 230.56021 -38.440834) (xy 230.595847 -38.484818) (xy 230.610664 -38.50894) (xy 230.618212 -38.521009)
			(xy 230.638841 -38.540613) (xy 230.664084 -38.553754) (xy 230.691975 -38.55941) (xy 230.720342 -38.557139)
			(xy 230.746979 -38.547119) (xy 230.769809 -38.53013) (xy 230.778812 -38.5191) (xy 230.796997 -38.496222)
			(xy 230.83916 -38.455758) (xy 230.886996 -38.422191) (xy 230.939388 -38.396304) (xy 230.995113 -38.378703)
			(xy 231.052869 -38.369797) (xy 231.082088 -38.36924) (xy 231.109345 -38.369606) (xy 231.163304 -38.377363)
			(xy 231.21561 -38.39272) (xy 231.265198 -38.415364) (xy 231.311058 -38.444836) (xy 231.352258 -38.480534)
			(xy 231.387957 -38.521732) (xy 231.41743 -38.567592) (xy 231.440076 -38.617179) (xy 231.455435 -38.669484)
			(xy 231.463193 -38.723443) (xy 231.463193 -38.777957) (xy 231.455435 -38.831916) (xy 231.440076 -38.884221)
			(xy 231.41743 -38.933808) (xy 231.387957 -38.979668) (xy 231.352258 -39.020866) (xy 231.311058 -39.056564)
			(xy 231.265198 -39.086036) (xy 231.21561 -39.10868) (xy 231.163304 -39.124037) (xy 231.109345 -39.131794)
			(xy 231.082088 -39.132256) (xy 231.053785 -39.131718) (xy 230.997798 -39.123377) (xy 230.943659 -39.106852)
			(xy 230.892558 -39.082505) (xy 230.845617 -39.050872) (xy 230.803869 -39.012646) (xy 230.76823 -38.968669)
			(xy 230.753412 -38.94455) (xy 230.745765 -38.93255) (xy 230.725156 -38.912952) (xy 230.699935 -38.89981)
			(xy 230.672064 -38.894147) (xy 230.643714 -38.896404) (xy 230.617091 -38.906405) (xy 230.594266 -38.923372)
			(xy 230.585264 -38.93439) (xy 230.567091 -38.957277) (xy 230.524925 -38.997741) (xy 230.477087 -39.031307)
			(xy 230.424693 -39.057193) (xy 230.368966 -39.074792) (xy 230.311208 -39.083695) (xy 230.281988 -39.08425)
			(xy 230.25474 -39.083679) (xy 230.2008 -39.075922) (xy 230.148512 -39.060568) (xy 230.098942 -39.037928)
			(xy 230.053098 -39.008465) (xy 230.011914 -38.972777) (xy 229.976228 -38.931592) (xy 229.946766 -38.885747)
			(xy 229.924128 -38.836176) (xy 229.908775 -38.783888) (xy 229.90102 -38.729948) (xy 210.381961 -38.729948)
			(xy 210.38185 -38.730936) (xy 210.351878 -38.997636) (xy 210.351624 -39.003224) (xy 210.351624 -39.269924)
			(xy 210.351376 -39.300485) (xy 210.347563 -39.361489) (xy 210.344004 -39.391844) (xy 210.339686 -39.422832)
			(xy 210.335622 -39.446454) (xy 210.331304 -39.468298) (xy 210.260946 -39.812976) (xy 210.260184 -39.817548)
			(xy 210.234022 -40.049958) (xy 210.230974 -40.076882) (xy 210.228196 -40.100332) (xy 210.220699 -40.146961)
			(xy 210.215988 -40.1701) (xy 210.081368 -40.812974) (xy 210.081876 -40.813482) (xy 210.090766 -40.821356)
			(xy 210.14944 -40.872664) (xy 210.149948 -40.872918) (xy 210.152234 -40.87495) (xy 210.16087 -40.878252)
			(xy 210.162648 -40.879014) (xy 210.166966 -40.880284) (xy 210.167474 -40.880284) (xy 210.17103 -40.881046)
			(xy 210.195414 -40.871096) (xy 210.246182 -40.857084) (xy 210.298368 -40.849993) (xy 210.3247 -40.84955)
			(xy 210.324954 -40.84955) (xy 210.352025 -40.850003) (xy 210.405652 -40.857451) (xy 210.457743 -40.87221)
			(xy 210.507306 -40.894001) (xy 210.553397 -40.922407) (xy 210.595139 -40.956889) (xy 210.613752 -40.97655)
			(xy 210.619594 -40.976804) (xy 210.690714 -40.976804) (xy 210.696556 -40.97655) (xy 210.715193 -40.956914)
			(xy 210.756935 -40.922443) (xy 210.803023 -40.894042) (xy 210.852581 -40.872253) (xy 210.904666 -40.857491)
			(xy 210.958286 -40.850036) (xy 210.985354 -40.84955) (xy 211.013355 -40.850023) (xy 211.068787 -40.857987)
			(xy 211.122522 -40.873759) (xy 211.173465 -40.897019) (xy 211.220579 -40.927292) (xy 211.262905 -40.963963)
			(xy 211.29958 -41.006284) (xy 211.329859 -41.053394) (xy 211.353125 -41.104335) (xy 211.368903 -41.158068)
			(xy 211.376874 -41.213499) (xy 211.376874 -41.269501) (xy 211.368903 -41.324932) (xy 211.353125 -41.378665)
			(xy 211.329859 -41.429606) (xy 211.29958 -41.476716) (xy 211.262905 -41.519037) (xy 211.220579 -41.555708)
			(xy 211.173465 -41.585981) (xy 211.122522 -41.609241) (xy 211.068787 -41.625013) (xy 211.013355 -41.632977)
			(xy 210.985354 -41.633394) (xy 210.958283 -41.632941) (xy 210.904657 -41.625494) (xy 210.852566 -41.610733)
			(xy 210.803004 -41.588941) (xy 210.756915 -41.560533) (xy 210.715176 -41.526048) (xy 210.696556 -41.506394)
			(xy 210.690714 -41.50614) (xy 210.619594 -41.50614) (xy 210.613752 -41.506394) (xy 210.595117 -41.526032)
			(xy 210.553376 -41.56051) (xy 210.507289 -41.588915) (xy 210.457731 -41.610708) (xy 210.405645 -41.625474)
			(xy 210.352023 -41.632932) (xy 210.324954 -41.633394) (xy 210.298754 -41.632955) (xy 210.246822 -41.625969)
			(xy 210.196283 -41.612129) (xy 210.148038 -41.591681) (xy 210.102946 -41.564988) (xy 210.061811 -41.532528)
			(xy 210.043268 -41.514014) (xy 210.037426 -41.512998) (xy 210.033202 -41.512319) (xy 210.024649 -41.512183)
			(xy 210.020408 -41.512744) (xy 210.008724 -41.51503) (xy 209.97672 -41.525444) (xy 209.958686 -41.531286)
			(xy 209.930746 -41.54043) (xy 209.928968 -41.541192) (xy 209.892138 -41.717722) (xy 209.822034 -42.052494)
			(xy 209.559764 -43.305222) (xy 212.407246 -43.305222) (xy 212.407714 -43.277852) (xy 212.415529 -43.223672)
			(xy 212.431018 -43.171169) (xy 212.453859 -43.121422) (xy 212.483584 -43.075455) (xy 212.501226 -43.054524)
			(xy 212.50148 -43.05427) (xy 212.507053 -43.047174) (xy 212.513306 -43.030264) (xy 212.513672 -43.02125)
			(xy 212.513672 -42.954194) (xy 212.513324 -42.945176) (xy 212.507071 -42.928259) (xy 212.50148 -42.921174)
			(xy 212.501226 -42.921174) (xy 212.501226 -42.92092) (xy 212.483587 -42.899988) (xy 212.453874 -42.854015)
			(xy 212.431038 -42.804268) (xy 212.415547 -42.751767) (xy 212.407719 -42.697591) (xy 212.407246 -42.670222)
			(xy 212.407798 -42.641484) (xy 212.416416 -42.584659) (xy 212.43346 -42.529769) (xy 212.458545 -42.478057)
			(xy 212.491103 -42.430692) (xy 212.51037 -42.409364) (xy 212.516974 -42.402506) (xy 212.524086 -42.384472)
			(xy 212.524086 -42.295572) (xy 212.516974 -42.277538) (xy 212.51037 -42.27068) (xy 212.491123 -42.249333)
			(xy 212.458562 -42.201973) (xy 212.433473 -42.150264) (xy 212.416424 -42.095377) (xy 212.4078 -42.038553)
			(xy 212.407798 -41.981079) (xy 212.416417 -41.924255) (xy 212.433461 -41.869366) (xy 212.458546 -41.817655)
			(xy 212.491103 -41.770292) (xy 212.51037 -41.748964) (xy 212.516974 -41.742106) (xy 212.524086 -41.724072)
			(xy 212.524086 -41.635172) (xy 212.516974 -41.617138) (xy 212.51037 -41.61028) (xy 212.491115 -41.588939)
			(xy 212.458545 -41.541582) (xy 212.433449 -41.489873) (xy 212.416395 -41.434986) (xy 212.407769 -41.37816)
			(xy 212.407246 -41.349422) (xy 212.407732 -41.322171) (xy 212.415488 -41.268223) (xy 212.430843 -41.215928)
			(xy 212.453485 -41.166351) (xy 212.482951 -41.120501) (xy 212.518642 -41.07931) (xy 212.559833 -41.043619)
			(xy 212.605683 -41.014153) (xy 212.65526 -40.991511) (xy 212.707555 -40.976156) (xy 212.761503 -40.9684)
			(xy 212.816005 -40.9684) (xy 212.869953 -40.976156) (xy 212.922248 -40.991511) (xy 212.971825 -41.014153)
			(xy 213.017675 -41.043619) (xy 213.058866 -41.07931) (xy 213.094557 -41.120501) (xy 213.124023 -41.166351)
			(xy 213.146665 -41.215928) (xy 213.16202 -41.268223) (xy 213.169776 -41.322171) (xy 213.170262 -41.349422)
			(xy 213.169735 -41.378161) (xy 213.161111 -41.434987) (xy 213.14406 -41.489877) (xy 213.11897 -41.541589)
			(xy 213.086407 -41.588952) (xy 213.067138 -41.61028) (xy 213.060534 -41.617138) (xy 213.053422 -41.635172)
			(xy 213.053422 -41.724072) (xy 213.060534 -41.742106) (xy 213.067138 -41.748964) (xy 213.086432 -41.770271)
			(xy 213.119 -41.817636) (xy 213.144093 -41.869351) (xy 213.161143 -41.924245) (xy 213.169765 -41.981075)
			(xy 213.169762 -42.038557) (xy 213.161136 -42.095387) (xy 213.144081 -42.150279) (xy 213.118984 -42.201992)
			(xy 213.086412 -42.249354) (xy 213.067138 -42.27068) (xy 213.060534 -42.277538) (xy 213.053422 -42.295572)
			(xy 213.053422 -42.384472) (xy 213.060534 -42.402506) (xy 213.067138 -42.409364) (xy 213.086415 -42.430686)
			(xy 213.118981 -42.478049) (xy 213.144073 -42.529762) (xy 213.161122 -42.584654) (xy 213.169743 -42.641483)
			(xy 213.170262 -42.670222) (xy 213.169818 -42.697593) (xy 213.161996 -42.751774) (xy 213.146503 -42.804277)
			(xy 213.125946 -42.849038) (xy 214.991948 -42.849038) (xy 214.996019 -42.793416) (xy 215.008145 -42.738979)
			(xy 215.028068 -42.686888) (xy 215.055364 -42.638253) (xy 215.08945 -42.59411) (xy 215.129599 -42.555401)
			(xy 215.174957 -42.52295) (xy 215.224557 -42.497449) (xy 215.277341 -42.479442) (xy 215.332184 -42.469312)
			(xy 215.387918 -42.467275) (xy 215.443355 -42.473375) (xy 215.497312 -42.487481) (xy 215.548641 -42.509293)
			(xy 215.596247 -42.538347) (xy 215.639115 -42.574022) (xy 215.676332 -42.615559) (xy 215.707105 -42.662072)
			(xy 215.730777 -42.712569) (xy 215.746845 -42.765976) (xy 215.754965 -42.821152) (xy 215.755326 -42.84091)
			(xy 221.033084 -42.84091) (xy 221.037155 -42.785288) (xy 221.049281 -42.730851) (xy 221.069204 -42.67876)
			(xy 221.0965 -42.630125) (xy 221.130586 -42.585982) (xy 221.170735 -42.547273) (xy 221.216093 -42.514822)
			(xy 221.265693 -42.489321) (xy 221.318477 -42.471314) (xy 221.37332 -42.461184) (xy 221.429054 -42.459147)
			(xy 221.484491 -42.465247) (xy 221.538448 -42.479353) (xy 221.589777 -42.501165) (xy 221.637383 -42.530219)
			(xy 221.680251 -42.565894) (xy 221.717468 -42.607431) (xy 221.748241 -42.653944) (xy 221.771913 -42.704441)
			(xy 221.787981 -42.757848) (xy 221.796101 -42.813024) (xy 221.79661 -42.84091) (xy 221.796101 -42.868796)
			(xy 221.787981 -42.923972) (xy 221.771913 -42.977379) (xy 221.748241 -43.027876) (xy 221.717468 -43.074389)
			(xy 221.680251 -43.115926) (xy 221.637383 -43.151601) (xy 221.589777 -43.180655) (xy 221.538448 -43.202467)
			(xy 221.484491 -43.216573) (xy 221.429054 -43.222673) (xy 221.37332 -43.220636) (xy 221.318477 -43.210506)
			(xy 221.265693 -43.192499) (xy 221.216093 -43.166998) (xy 221.170735 -43.134547) (xy 221.130586 -43.095838)
			(xy 221.0965 -43.051695) (xy 221.069204 -43.00306) (xy 221.049281 -42.950969) (xy 221.037155 -42.896532)
			(xy 221.033084 -42.84091) (xy 215.755326 -42.84091) (xy 215.755474 -42.849038) (xy 215.754965 -42.876924)
			(xy 215.746845 -42.9321) (xy 215.730777 -42.985507) (xy 215.707105 -43.036004) (xy 215.676332 -43.082517)
			(xy 215.639115 -43.124054) (xy 215.596247 -43.159729) (xy 215.548641 -43.188783) (xy 215.497312 -43.210595)
			(xy 215.443355 -43.224701) (xy 215.387918 -43.230801) (xy 215.332184 -43.228764) (xy 215.277341 -43.218634)
			(xy 215.224557 -43.200627) (xy 215.174957 -43.175126) (xy 215.129599 -43.142675) (xy 215.08945 -43.103966)
			(xy 215.055364 -43.059823) (xy 215.028068 -43.011188) (xy 215.008145 -42.959097) (xy 214.996019 -42.90466)
			(xy 214.991948 -42.849038) (xy 213.125946 -42.849038) (xy 213.123656 -42.854024) (xy 213.093926 -42.899989)
			(xy 213.076282 -42.92092) (xy 213.076028 -42.921174) (xy 213.070438 -42.928258) (xy 213.064195 -42.945177)
			(xy 213.063836 -42.954194) (xy 213.063836 -43.02125) (xy 213.064209 -43.030265) (xy 213.070445 -43.047183)
			(xy 213.076028 -43.05427) (xy 213.076282 -43.05427) (xy 213.076282 -43.054524) (xy 213.093896 -43.075476)
			(xy 213.123612 -43.121443) (xy 213.146453 -43.171186) (xy 213.16195 -43.223682) (xy 213.169785 -43.277854)
			(xy 213.170262 -43.305222) (xy 213.169776 -43.332473) (xy 213.16202 -43.386421) (xy 213.146665 -43.438716)
			(xy 213.124023 -43.488293) (xy 213.094557 -43.534143) (xy 213.058866 -43.575334) (xy 213.017675 -43.611025)
			(xy 212.971825 -43.640491) (xy 212.922248 -43.663133) (xy 212.869953 -43.678488) (xy 212.816005 -43.686244)
			(xy 212.761503 -43.686244) (xy 212.707555 -43.678488) (xy 212.65526 -43.663133) (xy 212.605683 -43.640491)
			(xy 212.559833 -43.611025) (xy 212.518642 -43.575334) (xy 212.482951 -43.534143) (xy 212.453485 -43.488293)
			(xy 212.430843 -43.438716) (xy 212.415488 -43.386421) (xy 212.407732 -43.332473) (xy 212.407246 -43.305222)
			(xy 209.559764 -43.305222) (xy 209.469522 -43.73626) (xy 214.313006 -43.73626) (xy 214.317077 -43.680638)
			(xy 214.329203 -43.626201) (xy 214.349126 -43.57411) (xy 214.376422 -43.525475) (xy 214.410508 -43.481332)
			(xy 214.450657 -43.442623) (xy 214.496015 -43.410172) (xy 214.545615 -43.384671) (xy 214.598399 -43.366664)
			(xy 214.653242 -43.356534) (xy 214.708976 -43.354497) (xy 214.764413 -43.360597) (xy 214.81837 -43.374703)
			(xy 214.869699 -43.396515) (xy 214.917305 -43.425569) (xy 214.960173 -43.461244) (xy 214.99739 -43.502781)
			(xy 215.028163 -43.549294) (xy 215.051835 -43.599791) (xy 215.067903 -43.653198) (xy 215.076023 -43.708374)
			(xy 215.076532 -43.73626) (xy 215.076023 -43.764146) (xy 215.067903 -43.819322) (xy 215.056594 -43.85691)
			(xy 218.819728 -43.85691) (xy 218.823799 -43.801288) (xy 218.835925 -43.746851) (xy 218.855848 -43.69476)
			(xy 218.883144 -43.646125) (xy 218.91723 -43.601982) (xy 218.957379 -43.563273) (xy 219.002737 -43.530822)
			(xy 219.052337 -43.505321) (xy 219.105121 -43.487314) (xy 219.159964 -43.477184) (xy 219.215698 -43.475147)
			(xy 219.271135 -43.481247) (xy 219.325092 -43.495353) (xy 219.376421 -43.517165) (xy 219.424027 -43.546219)
			(xy 219.466895 -43.581894) (xy 219.504112 -43.623431) (xy 219.534885 -43.669944) (xy 219.558557 -43.720441)
			(xy 219.574625 -43.773848) (xy 219.582745 -43.829024) (xy 219.583254 -43.85691) (xy 219.582745 -43.884796)
			(xy 219.574625 -43.939972) (xy 219.558557 -43.993379) (xy 219.534885 -44.043876) (xy 219.504112 -44.090389)
			(xy 219.466895 -44.131926) (xy 219.424027 -44.167601) (xy 219.376421 -44.196655) (xy 219.325092 -44.218467)
			(xy 219.271135 -44.232573) (xy 219.215698 -44.238673) (xy 219.159964 -44.236636) (xy 219.105121 -44.226506)
			(xy 219.052337 -44.208499) (xy 219.002737 -44.182998) (xy 218.957379 -44.150547) (xy 218.91723 -44.111838)
			(xy 218.883144 -44.067695) (xy 218.855848 -44.01906) (xy 218.835925 -43.966969) (xy 218.823799 -43.912532)
			(xy 218.819728 -43.85691) (xy 215.056594 -43.85691) (xy 215.051835 -43.872729) (xy 215.028163 -43.923226)
			(xy 214.99739 -43.969739) (xy 214.960173 -44.011276) (xy 214.917305 -44.046951) (xy 214.869699 -44.076005)
			(xy 214.81837 -44.097817) (xy 214.764413 -44.111923) (xy 214.708976 -44.118023) (xy 214.653242 -44.115986)
			(xy 214.598399 -44.105856) (xy 214.545615 -44.087849) (xy 214.496015 -44.062348) (xy 214.450657 -44.029897)
			(xy 214.410508 -43.991188) (xy 214.376422 -43.947045) (xy 214.349126 -43.89841) (xy 214.329203 -43.846319)
			(xy 214.317077 -43.791882) (xy 214.313006 -43.73626) (xy 209.469522 -43.73626) (xy 209.180982 -45.114464)
			(xy 214.165432 -45.114464) (xy 214.169503 -45.058842) (xy 214.181629 -45.004405) (xy 214.201552 -44.952314)
			(xy 214.228848 -44.903679) (xy 214.262934 -44.859536) (xy 214.303083 -44.820827) (xy 214.348441 -44.788376)
			(xy 214.398041 -44.762875) (xy 214.450825 -44.744868) (xy 214.505668 -44.734738) (xy 214.561402 -44.732701)
			(xy 214.616839 -44.738801) (xy 214.670796 -44.752907) (xy 214.722125 -44.774719) (xy 214.769731 -44.803773)
			(xy 214.812599 -44.839448) (xy 214.842581 -44.87291) (xy 221.033084 -44.87291) (xy 221.037155 -44.817288)
			(xy 221.049281 -44.762851) (xy 221.069204 -44.71076) (xy 221.0965 -44.662125) (xy 221.130586 -44.617982)
			(xy 221.170735 -44.579273) (xy 221.216093 -44.546822) (xy 221.265693 -44.521321) (xy 221.318477 -44.503314)
			(xy 221.37332 -44.493184) (xy 221.429054 -44.491147) (xy 221.484491 -44.497247) (xy 221.538448 -44.511353)
			(xy 221.589777 -44.533165) (xy 221.637383 -44.562219) (xy 221.680251 -44.597894) (xy 221.717468 -44.639431)
			(xy 221.748241 -44.685944) (xy 221.771913 -44.736441) (xy 221.787981 -44.789848) (xy 221.796101 -44.845024)
			(xy 221.79661 -44.87291) (xy 221.796101 -44.900796) (xy 221.787981 -44.955972) (xy 221.771913 -45.009379)
			(xy 221.748241 -45.059876) (xy 221.717468 -45.106389) (xy 221.680251 -45.147926) (xy 221.637383 -45.183601)
			(xy 221.589777 -45.212655) (xy 221.538448 -45.234467) (xy 221.484491 -45.248573) (xy 221.429054 -45.254673)
			(xy 221.37332 -45.252636) (xy 221.318477 -45.242506) (xy 221.265693 -45.224499) (xy 221.216093 -45.198998)
			(xy 221.170735 -45.166547) (xy 221.130586 -45.127838) (xy 221.0965 -45.083695) (xy 221.069204 -45.03506)
			(xy 221.049281 -44.982969) (xy 221.037155 -44.928532) (xy 221.033084 -44.87291) (xy 214.842581 -44.87291)
			(xy 214.849816 -44.880985) (xy 214.880589 -44.927498) (xy 214.904261 -44.977995) (xy 214.920329 -45.031402)
			(xy 214.928449 -45.086578) (xy 214.928958 -45.114464) (xy 214.928449 -45.14235) (xy 214.920329 -45.197526)
			(xy 214.904261 -45.250933) (xy 214.880589 -45.30143) (xy 214.849816 -45.347943) (xy 214.844174 -45.35424)
			(xy 218.803726 -45.35424) (xy 218.807797 -45.298618) (xy 218.819923 -45.244181) (xy 218.839846 -45.19209)
			(xy 218.867142 -45.143455) (xy 218.901228 -45.099312) (xy 218.941377 -45.060603) (xy 218.986735 -45.028152)
			(xy 219.036335 -45.002651) (xy 219.089119 -44.984644) (xy 219.143962 -44.974514) (xy 219.199696 -44.972477)
			(xy 219.255133 -44.978577) (xy 219.30909 -44.992683) (xy 219.360419 -45.014495) (xy 219.408025 -45.043549)
			(xy 219.450893 -45.079224) (xy 219.48811 -45.120761) (xy 219.518883 -45.167274) (xy 219.542555 -45.217771)
			(xy 219.558623 -45.271178) (xy 219.566743 -45.326354) (xy 219.567252 -45.35424) (xy 219.566743 -45.382126)
			(xy 219.558623 -45.437302) (xy 219.542555 -45.490709) (xy 219.518883 -45.541206) (xy 219.48811 -45.587719)
			(xy 219.450893 -45.629256) (xy 219.408025 -45.664931) (xy 219.360419 -45.693985) (xy 219.30909 -45.715797)
			(xy 219.255133 -45.729903) (xy 219.199696 -45.736003) (xy 219.143962 -45.733966) (xy 219.089119 -45.723836)
			(xy 219.036335 -45.705829) (xy 218.986735 -45.680328) (xy 218.941377 -45.647877) (xy 218.901228 -45.609168)
			(xy 218.867142 -45.565025) (xy 218.839846 -45.51639) (xy 218.819923 -45.464299) (xy 218.807797 -45.409862)
			(xy 218.803726 -45.35424) (xy 214.844174 -45.35424) (xy 214.812599 -45.38948) (xy 214.769731 -45.425155)
			(xy 214.722125 -45.454209) (xy 214.670796 -45.476021) (xy 214.616839 -45.490127) (xy 214.561402 -45.496227)
			(xy 214.505668 -45.49419) (xy 214.450825 -45.48406) (xy 214.398041 -45.466053) (xy 214.348441 -45.440552)
			(xy 214.303083 -45.408101) (xy 214.262934 -45.369392) (xy 214.228848 -45.325249) (xy 214.201552 -45.276614)
			(xy 214.181629 -45.224523) (xy 214.169503 -45.170086) (xy 214.165432 -45.114464) (xy 209.180982 -45.114464)
			(xy 208.978377 -46.082204) (xy 212.152484 -46.082204) (xy 212.152981 -46.054953) (xy 212.160737 -46.001006)
			(xy 212.176091 -45.948712) (xy 212.198732 -45.899136) (xy 212.228197 -45.853286) (xy 212.263887 -45.812095)
			(xy 212.305076 -45.776404) (xy 212.350925 -45.746937) (xy 212.400501 -45.724296) (xy 212.452795 -45.70894)
			(xy 212.506741 -45.701182) (xy 212.533992 -45.700696) (xy 212.560894 -45.701164) (xy 212.614164 -45.708735)
			(xy 212.665842 -45.723713) (xy 212.714904 -45.745802) (xy 212.760376 -45.774564) (xy 212.801358 -45.809428)
			(xy 212.837036 -45.849703) (xy 212.852254 -45.871892) (xy 212.859366 -45.882814) (xy 212.882226 -45.894752)
			(xy 212.994494 -45.89272) (xy 213.016846 -45.879766) (xy 213.023704 -45.86859) (xy 213.038636 -45.844996)
			(xy 213.074314 -45.802044) (xy 213.11587 -45.764751) (xy 213.162418 -45.733912) (xy 213.212964 -45.710188)
			(xy 213.266428 -45.694083) (xy 213.321668 -45.685943) (xy 213.349586 -45.685456) (xy 213.376579 -45.685925)
			(xy 213.430027 -45.693529) (xy 213.48187 -45.708588) (xy 213.531075 -45.7308) (xy 213.576659 -45.759723)
			(xy 213.59749 -45.776896) (xy 213.605618 -45.784008) (xy 213.626192 -45.790104) (xy 213.711536 -45.779182)
			(xy 213.722087 -45.777435) (xy 213.740367 -45.766361) (xy 213.746842 -45.757846) (xy 213.762176 -45.736601)
			(xy 213.797766 -45.698148) (xy 213.838287 -45.664931) (xy 213.882973 -45.637574) (xy 213.930984 -45.616593)
			(xy 213.981416 -45.602383) (xy 214.033318 -45.595211) (xy 214.059516 -45.594778) (xy 214.086765 -45.595293)
			(xy 214.140709 -45.603051) (xy 214.193 -45.618407) (xy 214.242574 -45.641049) (xy 214.28842 -45.670514)
			(xy 214.329607 -45.706204) (xy 214.365295 -45.747393) (xy 214.394759 -45.79324) (xy 214.417398 -45.842815)
			(xy 214.432752 -45.895106) (xy 214.440508 -45.949051) (xy 214.440508 -46.003549) (xy 214.432752 -46.057494)
			(xy 214.417398 -46.109785) (xy 214.394759 -46.15936) (xy 214.365295 -46.205207) (xy 214.329607 -46.246396)
			(xy 214.28842 -46.282086) (xy 214.242574 -46.311551) (xy 214.193 -46.334193) (xy 214.140709 -46.349549)
			(xy 214.086765 -46.357307) (xy 214.059516 -46.357794) (xy 214.032524 -46.357312) (xy 213.979077 -46.349709)
			(xy 213.927234 -46.334653) (xy 213.878029 -46.312444) (xy 213.832444 -46.283525) (xy 213.811612 -46.266354)
			(xy 213.803484 -46.259242) (xy 213.78291 -46.253146) (xy 213.697566 -46.264068) (xy 213.68702 -46.265833)
			(xy 213.668739 -46.276896) (xy 213.66226 -46.285404) (xy 213.644649 -46.309706) (xy 213.603052 -46.352965)
			(xy 213.579456 -46.37151) (xy 213.571582 -46.377352) (xy 213.561168 -46.394878) (xy 213.54796 -46.485302)
			(xy 213.552786 -46.504606) (xy 213.558628 -46.51248) (xy 213.558628 -46.512734) (xy 213.576125 -46.537482)
			(xy 213.603931 -46.591333) (xy 213.622869 -46.648904) (xy 213.630072 -46.693836) (xy 218.776296 -46.693836)
			(xy 218.776782 -46.666585) (xy 218.784538 -46.612637) (xy 218.799893 -46.560342) (xy 218.822535 -46.510765)
			(xy 218.852001 -46.464915) (xy 218.887692 -46.423724) (xy 218.928883 -46.388033) (xy 218.974733 -46.358567)
			(xy 219.02431 -46.335925) (xy 219.076605 -46.32057) (xy 219.130553 -46.312814) (xy 219.185055 -46.312814)
			(xy 219.239003 -46.32057) (xy 219.291298 -46.335925) (xy 219.340875 -46.358567) (xy 219.386725 -46.388033)
			(xy 219.427916 -46.423724) (xy 219.463607 -46.464915) (xy 219.493073 -46.510765) (xy 219.515715 -46.560342)
			(xy 219.53107 -46.612637) (xy 219.538826 -46.666585) (xy 219.539312 -46.693836) (xy 219.538838 -46.720263)
			(xy 219.531528 -46.772611) (xy 219.517056 -46.823446) (xy 219.495696 -46.871793) (xy 219.482162 -46.894496)
			(xy 219.481908 -46.89475) (xy 219.476571 -46.904768) (xy 219.474316 -46.927318) (xy 219.47759 -46.938184)
			(xy 219.503752 -47.01286) (xy 219.508136 -47.023375) (xy 219.524225 -47.039464) (xy 219.53474 -47.043848)
			(xy 219.534994 -47.043848) (xy 219.559513 -47.052891) (xy 219.605964 -47.076839) (xy 219.648715 -47.106899)
			(xy 219.686965 -47.142511) (xy 219.72 -47.183007) (xy 219.747202 -47.227631) (xy 219.768063 -47.275548)
			(xy 219.782192 -47.325863) (xy 219.789325 -47.377635) (xy 219.789756 -47.403766) (xy 219.78927 -47.431017)
			(xy 219.787747 -47.441612) (xy 221.061786 -47.441612) (xy 221.065857 -47.38599) (xy 221.077983 -47.331553)
			(xy 221.097906 -47.279462) (xy 221.125202 -47.230827) (xy 221.159288 -47.186684) (xy 221.199437 -47.147975)
			(xy 221.244795 -47.115524) (xy 221.294395 -47.090023) (xy 221.347179 -47.072016) (xy 221.402022 -47.061886)
			(xy 221.457756 -47.059849) (xy 221.513193 -47.065949) (xy 221.56715 -47.080055) (xy 221.618479 -47.101867)
			(xy 221.666085 -47.130921) (xy 221.708953 -47.166596) (xy 221.74617 -47.208133) (xy 221.776943 -47.254646)
			(xy 221.800615 -47.305143) (xy 221.816683 -47.35855) (xy 221.824803 -47.413726) (xy 221.825312 -47.441612)
			(xy 221.824803 -47.469498) (xy 221.816683 -47.524674) (xy 221.800615 -47.578081) (xy 221.776943 -47.628578)
			(xy 221.74617 -47.675091) (xy 221.708953 -47.716628) (xy 221.666085 -47.752303) (xy 221.618479 -47.781357)
			(xy 221.56715 -47.803169) (xy 221.513193 -47.817275) (xy 221.457756 -47.823375) (xy 221.402022 -47.821338)
			(xy 221.347179 -47.811208) (xy 221.294395 -47.793201) (xy 221.244795 -47.7677) (xy 221.199437 -47.735249)
			(xy 221.159288 -47.69654) (xy 221.125202 -47.652397) (xy 221.097906 -47.603762) (xy 221.077983 -47.551671)
			(xy 221.065857 -47.497234) (xy 221.061786 -47.441612) (xy 219.787747 -47.441612) (xy 219.781514 -47.484965)
			(xy 219.766159 -47.53726) (xy 219.743517 -47.586837) (xy 219.714051 -47.632687) (xy 219.67836 -47.673878)
			(xy 219.637169 -47.709569) (xy 219.591319 -47.739035) (xy 219.541742 -47.761677) (xy 219.489447 -47.777032)
			(xy 219.435499 -47.784788) (xy 219.380997 -47.784788) (xy 219.327049 -47.777032) (xy 219.274754 -47.761677)
			(xy 219.225177 -47.739035) (xy 219.179327 -47.709569) (xy 219.138136 -47.673878) (xy 219.102445 -47.632687)
			(xy 219.072979 -47.586837) (xy 219.050337 -47.53726) (xy 219.034982 -47.484965) (xy 219.027226 -47.431017)
			(xy 219.02674 -47.403766) (xy 219.027208 -47.377338) (xy 219.034518 -47.324991) (xy 219.048993 -47.274155)
			(xy 219.070354 -47.225809) (xy 219.08389 -47.203106) (xy 219.084144 -47.202852) (xy 219.089479 -47.192833)
			(xy 219.091738 -47.170284) (xy 219.088462 -47.159418) (xy 219.0623 -47.084742) (xy 219.057937 -47.074216)
			(xy 219.041834 -47.058131) (xy 219.031312 -47.053754) (xy 219.031058 -47.053754) (xy 219.006551 -47.04468)
			(xy 218.960098 -47.020739) (xy 218.917346 -46.990683) (xy 218.879094 -46.955077) (xy 218.846057 -46.914584)
			(xy 218.818854 -46.869964) (xy 218.797991 -46.822049) (xy 218.783861 -46.771736) (xy 218.776727 -46.719966)
			(xy 218.776296 -46.693836) (xy 213.630072 -46.693836) (xy 213.632462 -46.708745) (xy 213.63305 -46.739048)
			(xy 213.632567 -46.766299) (xy 213.624805 -46.820244) (xy 213.609446 -46.872536) (xy 213.586802 -46.922111)
			(xy 213.557335 -46.967959) (xy 213.521643 -47.009148) (xy 213.480454 -47.044838) (xy 213.434606 -47.074305)
			(xy 213.385031 -47.096948) (xy 213.332738 -47.112306) (xy 213.278793 -47.120067) (xy 213.251542 -47.120556)
			(xy 213.225508 -47.120134) (xy 213.173924 -47.11304) (xy 213.123782 -47.099005) (xy 213.076011 -47.078288)
			(xy 213.031498 -47.051275) (xy 213.011004 -47.035212) (xy 213.003253 -47.029461) (xy 212.984838 -47.023726)
			(xy 212.97519 -47.024036) (xy 212.895434 -47.030386) (xy 212.877654 -47.039022) (xy 212.871304 -47.046388)
			(xy 212.853144 -47.066054) (xy 212.812232 -47.100574) (xy 212.766898 -47.129041) (xy 212.718033 -47.150895)
			(xy 212.666593 -47.165708) (xy 212.613589 -47.17319) (xy 212.586824 -47.173642) (xy 212.559575 -47.1731)
			(xy 212.505631 -47.165347) (xy 212.453339 -47.149997) (xy 212.403765 -47.127361) (xy 212.357916 -47.0979)
			(xy 212.316726 -47.062215) (xy 212.281034 -47.021031) (xy 212.251567 -46.975186) (xy 212.228923 -46.925615)
			(xy 212.213565 -46.873326) (xy 212.205805 -46.819383) (xy 212.205316 -46.792134) (xy 212.205836 -46.76336)
			(xy 212.214488 -46.706465) (xy 212.231585 -46.651515) (xy 212.256739 -46.599754) (xy 212.289381 -46.552359)
			(xy 212.308694 -46.531022) (xy 212.31606 -46.523148) (xy 212.323172 -46.503336) (xy 212.315806 -46.40707)
			(xy 212.3059 -46.388274) (xy 212.297518 -46.38167) (xy 212.275333 -46.363446) (xy 212.236123 -46.32151)
			(xy 212.203638 -46.274174) (xy 212.178609 -46.222506) (xy 212.161603 -46.167672) (xy 212.153002 -46.110909)
			(xy 212.152484 -46.082204) (xy 208.978377 -46.082204) (xy 208.843626 -46.72584) (xy 208.647792 -47.68088)
			(xy 208.519474 -48.30699) (xy 218.653866 -48.30699) (xy 218.657937 -48.251368) (xy 218.670063 -48.196931)
			(xy 218.689986 -48.14484) (xy 218.717282 -48.096205) (xy 218.751368 -48.052062) (xy 218.791517 -48.013353)
			(xy 218.836875 -47.980902) (xy 218.886475 -47.955401) (xy 218.939259 -47.937394) (xy 218.994102 -47.927264)
			(xy 219.049836 -47.925227) (xy 219.105273 -47.931327) (xy 219.15923 -47.945433) (xy 219.210559 -47.967245)
			(xy 219.258165 -47.996299) (xy 219.301033 -48.031974) (xy 219.33825 -48.073511) (xy 219.369023 -48.120024)
			(xy 219.392695 -48.170521) (xy 219.408763 -48.223928) (xy 219.416883 -48.279104) (xy 219.417392 -48.30699)
			(xy 219.416883 -48.334876) (xy 219.408763 -48.390052) (xy 219.392695 -48.443459) (xy 219.369023 -48.493956)
			(xy 219.33825 -48.540469) (xy 219.301033 -48.582006) (xy 219.258165 -48.617681) (xy 219.210559 -48.646735)
			(xy 219.15923 -48.668547) (xy 219.105273 -48.682653) (xy 219.049836 -48.688753) (xy 218.994102 -48.686716)
			(xy 218.939259 -48.676586) (xy 218.886475 -48.658579) (xy 218.836875 -48.633078) (xy 218.791517 -48.600627)
			(xy 218.751368 -48.561918) (xy 218.717282 -48.517775) (xy 218.689986 -48.46914) (xy 218.670063 -48.417049)
			(xy 218.657937 -48.362612) (xy 218.653866 -48.30699) (xy 208.519474 -48.30699) (xy 208.428063 -48.753014)
			(xy 215.2683 -48.753014) (xy 215.272371 -48.697392) (xy 215.284497 -48.642955) (xy 215.30442 -48.590864)
			(xy 215.331716 -48.542229) (xy 215.365802 -48.498086) (xy 215.405951 -48.459377) (xy 215.451309 -48.426926)
			(xy 215.500909 -48.401425) (xy 215.553693 -48.383418) (xy 215.608536 -48.373288) (xy 215.66427 -48.371251)
			(xy 215.719707 -48.377351) (xy 215.773664 -48.391457) (xy 215.824993 -48.413269) (xy 215.872599 -48.442323)
			(xy 215.915467 -48.477998) (xy 215.952684 -48.519535) (xy 215.983457 -48.566048) (xy 216.007129 -48.616545)
			(xy 216.023197 -48.669952) (xy 216.031317 -48.725128) (xy 216.031826 -48.753014) (xy 216.031317 -48.7809)
			(xy 216.023197 -48.836076) (xy 216.020753 -48.8442) (xy 216.287348 -48.8442) (xy 216.291419 -48.788578)
			(xy 216.303545 -48.734141) (xy 216.323468 -48.68205) (xy 216.350764 -48.633415) (xy 216.38485 -48.589272)
			(xy 216.424999 -48.550563) (xy 216.470357 -48.518112) (xy 216.519957 -48.492611) (xy 216.572741 -48.474604)
			(xy 216.627584 -48.464474) (xy 216.683318 -48.462437) (xy 216.738755 -48.468537) (xy 216.792712 -48.482643)
			(xy 216.844041 -48.504455) (xy 216.891647 -48.533509) (xy 216.934515 -48.569184) (xy 216.971732 -48.610721)
			(xy 217.002505 -48.657234) (xy 217.026177 -48.707731) (xy 217.042245 -48.761138) (xy 217.050365 -48.816314)
			(xy 217.050874 -48.8442) (xy 217.050365 -48.872086) (xy 217.047367 -48.89246) (xy 217.314016 -48.89246)
			(xy 217.318087 -48.836838) (xy 217.330213 -48.782401) (xy 217.350136 -48.73031) (xy 217.377432 -48.681675)
			(xy 217.411518 -48.637532) (xy 217.451667 -48.598823) (xy 217.497025 -48.566372) (xy 217.546625 -48.540871)
			(xy 217.599409 -48.522864) (xy 217.654252 -48.512734) (xy 217.709986 -48.510697) (xy 217.765423 -48.516797)
			(xy 217.81938 -48.530903) (xy 217.870709 -48.552715) (xy 217.918315 -48.581769) (xy 217.961183 -48.617444)
			(xy 217.9984 -48.658981) (xy 218.029173 -48.705494) (xy 218.052845 -48.755991) (xy 218.068913 -48.809398)
			(xy 218.077033 -48.864574) (xy 218.077542 -48.89246) (xy 218.077033 -48.920346) (xy 218.074595 -48.93691)
			(xy 221.033084 -48.93691) (xy 221.037155 -48.881288) (xy 221.049281 -48.826851) (xy 221.069204 -48.77476)
			(xy 221.0965 -48.726125) (xy 221.130586 -48.681982) (xy 221.170735 -48.643273) (xy 221.216093 -48.610822)
			(xy 221.265693 -48.585321) (xy 221.318477 -48.567314) (xy 221.37332 -48.557184) (xy 221.429054 -48.555147)
			(xy 221.484491 -48.561247) (xy 221.538448 -48.575353) (xy 221.589777 -48.597165) (xy 221.637383 -48.626219)
			(xy 221.680251 -48.661894) (xy 221.717468 -48.703431) (xy 221.748241 -48.749944) (xy 221.771913 -48.800441)
			(xy 221.787981 -48.853848) (xy 221.796101 -48.909024) (xy 221.79661 -48.93691) (xy 221.796101 -48.964796)
			(xy 221.787981 -49.019972) (xy 221.771913 -49.073379) (xy 221.748241 -49.123876) (xy 221.717468 -49.170389)
			(xy 221.680251 -49.211926) (xy 221.637383 -49.247601) (xy 221.589777 -49.276655) (xy 221.538448 -49.298467)
			(xy 221.484491 -49.312573) (xy 221.429054 -49.318673) (xy 221.37332 -49.316636) (xy 221.318477 -49.306506)
			(xy 221.265693 -49.288499) (xy 221.216093 -49.262998) (xy 221.170735 -49.230547) (xy 221.130586 -49.191838)
			(xy 221.0965 -49.147695) (xy 221.069204 -49.09906) (xy 221.049281 -49.046969) (xy 221.037155 -48.992532)
			(xy 221.033084 -48.93691) (xy 218.074595 -48.93691) (xy 218.068913 -48.975522) (xy 218.052845 -49.028929)
			(xy 218.029173 -49.079426) (xy 217.9984 -49.125939) (xy 217.961183 -49.167476) (xy 217.918315 -49.203151)
			(xy 217.870709 -49.232205) (xy 217.81938 -49.254017) (xy 217.765423 -49.268123) (xy 217.709986 -49.274223)
			(xy 217.654252 -49.272186) (xy 217.599409 -49.262056) (xy 217.546625 -49.244049) (xy 217.497025 -49.218548)
			(xy 217.451667 -49.186097) (xy 217.411518 -49.147388) (xy 217.377432 -49.103245) (xy 217.350136 -49.05461)
			(xy 217.330213 -49.002519) (xy 217.318087 -48.948082) (xy 217.314016 -48.89246) (xy 217.047367 -48.89246)
			(xy 217.042245 -48.927262) (xy 217.026177 -48.980669) (xy 217.002505 -49.031166) (xy 216.971732 -49.077679)
			(xy 216.934515 -49.119216) (xy 216.891647 -49.154891) (xy 216.844041 -49.183945) (xy 216.792712 -49.205757)
			(xy 216.738755 -49.219863) (xy 216.683318 -49.225963) (xy 216.627584 -49.223926) (xy 216.572741 -49.213796)
			(xy 216.519957 -49.195789) (xy 216.470357 -49.170288) (xy 216.424999 -49.137837) (xy 216.38485 -49.099128)
			(xy 216.350764 -49.054985) (xy 216.323468 -49.00635) (xy 216.303545 -48.954259) (xy 216.291419 -48.899822)
			(xy 216.287348 -48.8442) (xy 216.020753 -48.8442) (xy 216.007129 -48.889483) (xy 215.983457 -48.93998)
			(xy 215.952684 -48.986493) (xy 215.915467 -49.02803) (xy 215.872599 -49.063705) (xy 215.824993 -49.092759)
			(xy 215.773664 -49.114571) (xy 215.719707 -49.128677) (xy 215.66427 -49.134777) (xy 215.608536 -49.13274)
			(xy 215.553693 -49.12261) (xy 215.500909 -49.104603) (xy 215.451309 -49.079102) (xy 215.405951 -49.046651)
			(xy 215.365802 -49.007942) (xy 215.331716 -48.963799) (xy 215.30442 -48.915164) (xy 215.284497 -48.863073)
			(xy 215.272371 -48.808636) (xy 215.2683 -48.753014) (xy 208.428063 -48.753014) (xy 208.289906 -49.42713)
			(xy 208.289144 -49.435258) (xy 208.289144 -49.95291) (xy 221.033084 -49.95291) (xy 221.037155 -49.897288)
			(xy 221.049281 -49.842851) (xy 221.069204 -49.79076) (xy 221.0965 -49.742125) (xy 221.130586 -49.697982)
			(xy 221.170735 -49.659273) (xy 221.216093 -49.626822) (xy 221.265693 -49.601321) (xy 221.318477 -49.583314)
			(xy 221.37332 -49.573184) (xy 221.429054 -49.571147) (xy 221.484491 -49.577247) (xy 221.538448 -49.591353)
			(xy 221.589777 -49.613165) (xy 221.637383 -49.642219) (xy 221.680251 -49.677894) (xy 221.717468 -49.719431)
			(xy 221.748241 -49.765944) (xy 221.771913 -49.816441) (xy 221.787981 -49.869848) (xy 221.796101 -49.925024)
			(xy 221.79661 -49.95291) (xy 221.796101 -49.980796) (xy 221.787981 -50.035972) (xy 221.771913 -50.089379)
			(xy 221.748241 -50.139876) (xy 221.717468 -50.186389) (xy 221.680251 -50.227926) (xy 221.637383 -50.263601)
			(xy 221.589777 -50.292655) (xy 221.538448 -50.314467) (xy 221.484491 -50.328573) (xy 221.429054 -50.334673)
			(xy 221.37332 -50.332636) (xy 221.318477 -50.322506) (xy 221.265693 -50.304499) (xy 221.216093 -50.278998)
			(xy 221.170735 -50.246547) (xy 221.130586 -50.207838) (xy 221.0965 -50.163695) (xy 221.069204 -50.11506)
			(xy 221.049281 -50.062969) (xy 221.037155 -50.008532) (xy 221.033084 -49.95291) (xy 208.289144 -49.95291)
			(xy 208.289144 -51.019456) (xy 218.849446 -51.019456) (xy 218.853517 -50.963834) (xy 218.865643 -50.909397)
			(xy 218.885566 -50.857306) (xy 218.912862 -50.808671) (xy 218.946948 -50.764528) (xy 218.987097 -50.725819)
			(xy 219.032455 -50.693368) (xy 219.082055 -50.667867) (xy 219.134839 -50.64986) (xy 219.189682 -50.63973)
			(xy 219.245416 -50.637693) (xy 219.300853 -50.643793) (xy 219.35481 -50.657899) (xy 219.406139 -50.679711)
			(xy 219.453745 -50.708765) (xy 219.496613 -50.74444) (xy 219.53383 -50.785977) (xy 219.564603 -50.83249)
			(xy 219.588275 -50.882987) (xy 219.604343 -50.936394) (xy 219.612463 -50.99157) (xy 219.612972 -51.019456)
			(xy 219.612463 -51.047342) (xy 219.604343 -51.102518) (xy 219.588275 -51.155925) (xy 219.564603 -51.206422)
			(xy 219.53383 -51.252935) (xy 219.496613 -51.294472) (xy 219.453745 -51.330147) (xy 219.406139 -51.359201)
			(xy 219.35481 -51.381013) (xy 219.300853 -51.395119) (xy 219.245416 -51.401219) (xy 219.189682 -51.399182)
			(xy 219.134839 -51.389052) (xy 219.082055 -51.371045) (xy 219.032455 -51.345544) (xy 218.987097 -51.313093)
			(xy 218.946948 -51.274384) (xy 218.912862 -51.230241) (xy 218.885566 -51.181606) (xy 218.865643 -51.129515)
			(xy 218.853517 -51.075078) (xy 218.849446 -51.019456) (xy 208.289144 -51.019456) (xy 208.289144 -52.035456)
			(xy 221.041212 -52.035456) (xy 221.045283 -51.979834) (xy 221.057409 -51.925397) (xy 221.077332 -51.873306)
			(xy 221.104628 -51.824671) (xy 221.138714 -51.780528) (xy 221.178863 -51.741819) (xy 221.224221 -51.709368)
			(xy 221.273821 -51.683867) (xy 221.326605 -51.66586) (xy 221.381448 -51.65573) (xy 221.437182 -51.653693)
			(xy 221.492619 -51.659793) (xy 221.546576 -51.673899) (xy 221.597905 -51.695711) (xy 221.645511 -51.724765)
			(xy 221.688379 -51.76044) (xy 221.725596 -51.801977) (xy 221.756369 -51.84849) (xy 221.780041 -51.898987)
			(xy 221.796109 -51.952394) (xy 221.804229 -52.00757) (xy 221.804738 -52.035456) (xy 221.804229 -52.063342)
			(xy 221.796109 -52.118518) (xy 221.780041 -52.171925) (xy 221.756369 -52.222422) (xy 221.725596 -52.268935)
			(xy 221.688379 -52.310472) (xy 221.645511 -52.346147) (xy 221.597905 -52.375201) (xy 221.546576 -52.397013)
			(xy 221.492619 -52.411119) (xy 221.437182 -52.417219) (xy 221.381448 -52.415182) (xy 221.326605 -52.405052)
			(xy 221.273821 -52.387045) (xy 221.224221 -52.361544) (xy 221.178863 -52.329093) (xy 221.138714 -52.290384)
			(xy 221.104628 -52.246241) (xy 221.077332 -52.197606) (xy 221.057409 -52.145515) (xy 221.045283 -52.091078)
			(xy 221.041212 -52.035456) (xy 208.289144 -52.035456) (xy 208.289144 -52.546504) (xy 208.290922 -52.558442)
			(xy 208.292954 -52.56657) (xy 208.294224 -52.569872) (xy 208.296764 -52.577492) (xy 208.298034 -52.580286)
			(xy 208.303114 -52.5907) (xy 208.304638 -52.593494) (xy 208.305146 -52.594002) (xy 208.306924 -52.596542)
			(xy 208.308956 -52.598574) (xy 208.309718 -52.599336) (xy 208.317084 -52.610512) (xy 208.317338 -52.61102)
			(xy 208.318608 -52.613052) (xy 208.324281 -52.621567) (xy 208.33483 -52.639101) (xy 208.33969 -52.648104)
			(xy 208.347056 -52.662836) (xy 208.347564 -52.663598) (xy 208.347564 -52.663852) (xy 208.348072 -52.664868)
			(xy 208.35937 -52.690285) (xy 208.375319 -52.743569) (xy 208.383377 -52.798602) (xy 208.383886 -52.826412)
			(xy 208.383886 -52.82692) (xy 208.38324 -52.859379) (xy 208.372265 -52.923361) (xy 208.362042 -52.954174)
			(xy 208.361534 -52.955444) (xy 208.35493 -52.975764) (xy 208.350612 -52.985416) (xy 208.337912 -53.007768)
			(xy 208.337658 -53.00853) (xy 208.333086 -53.016658) (xy 208.332578 -53.01742) (xy 208.324704 -53.030374)
			(xy 208.319028 -53.039237) (xy 208.306828 -53.056392) (xy 208.30032 -53.064664) (xy 208.294732 -53.071776)
			(xy 208.291938 -53.079396) (xy 208.289652 -53.089302) (xy 208.289652 -53.08981) (xy 208.289144 -53.095906)
			(xy 208.289144 -53.18252) (xy 208.289188 -53.186391) (xy 208.290329 -53.194049) (xy 208.29143 -53.19776)
			(xy 208.30032 -53.22316) (xy 208.3054 -53.229764) (xy 208.321972 -53.252223) (xy 208.349068 -53.301018)
			(xy 208.368765 -53.35324) (xy 208.380644 -53.407775) (xy 208.38445 -53.463459) (xy 208.380102 -53.519103)
			(xy 208.367693 -53.57352) (xy 208.347489 -53.625548) (xy 208.319919 -53.674078) (xy 208.303114 -53.696362)
			(xy 208.301336 -53.698648) (xy 208.300066 -53.700172) (xy 208.294478 -53.710586) (xy 208.292213 -53.715375)
			(xy 208.289531 -53.725622) (xy 208.289144 -53.730906) (xy 208.289144 -53.81752) (xy 208.289188 -53.821391)
			(xy 208.290329 -53.829049) (xy 208.29143 -53.83276) (xy 208.30032 -53.85816) (xy 208.3054 -53.864764)
			(xy 208.321972 -53.887223) (xy 208.349068 -53.936018) (xy 208.368765 -53.98824) (xy 208.380644 -54.042775)
			(xy 208.38445 -54.098459) (xy 208.380102 -54.154103) (xy 208.367693 -54.20852) (xy 208.347489 -54.260548)
			(xy 208.319919 -54.309078) (xy 208.303114 -54.331362) (xy 208.301336 -54.333648) (xy 208.300066 -54.335172)
			(xy 208.294478 -54.345586) (xy 208.292213 -54.350375) (xy 208.289531 -54.360622) (xy 208.289144 -54.365906)
			(xy 208.289144 -54.461664) (xy 208.289222 -54.465874) (xy 208.290621 -54.474175) (xy 208.291938 -54.478174)
			(xy 208.294732 -54.486302) (xy 208.30032 -54.49316) (xy 208.316033 -54.513515) (xy 208.342425 -54.557647)
			(xy 208.362649 -54.604924) (xy 208.376335 -54.654491) (xy 208.383237 -54.705447) (xy 208.383632 -54.731158)
			(xy 208.383632 -54.73954) (xy 208.382424 -54.769638) (xy 208.378542 -54.791102) (xy 210.27644 -54.791102)
			(xy 210.276897 -54.763731) (xy 210.284716 -54.709552) (xy 210.300206 -54.657048) (xy 210.32305 -54.607301)
			(xy 210.352777 -54.561335) (xy 210.37042 -54.540404) (xy 210.370674 -54.54015) (xy 210.376254 -54.53306)
			(xy 210.382503 -54.516145) (xy 210.382866 -54.50713) (xy 210.382866 -54.440074) (xy 210.382529 -54.431055)
			(xy 210.376268 -54.414138) (xy 210.370674 -54.407054) (xy 210.37042 -54.407054) (xy 210.37042 -54.4068)
			(xy 210.352782 -54.385866) (xy 210.323057 -54.339898) (xy 210.300212 -54.290152) (xy 210.284716 -54.23765)
			(xy 210.276887 -54.183472) (xy 210.276887 -54.128731) (xy 210.284715 -54.074553) (xy 210.300211 -54.022051)
			(xy 210.323056 -53.972305) (xy 210.35278 -53.926337) (xy 210.37042 -53.905404) (xy 210.370674 -53.90515)
			(xy 210.376254 -53.89806) (xy 210.382503 -53.881145) (xy 210.382866 -53.87213) (xy 210.382866 -53.805074)
			(xy 210.382529 -53.796055) (xy 210.376268 -53.779138) (xy 210.370674 -53.772054) (xy 210.37042 -53.772054)
			(xy 210.37042 -53.7718) (xy 210.352782 -53.750866) (xy 210.323057 -53.704898) (xy 210.300212 -53.655152)
			(xy 210.284716 -53.60265) (xy 210.276887 -53.548472) (xy 210.276887 -53.493731) (xy 210.284715 -53.439553)
			(xy 210.300211 -53.387051) (xy 210.323056 -53.337305) (xy 210.35278 -53.291337) (xy 210.37042 -53.270404)
			(xy 210.370674 -53.27015) (xy 210.376254 -53.26306) (xy 210.382503 -53.246145) (xy 210.382866 -53.23713)
			(xy 210.382866 -53.170074) (xy 210.382529 -53.161055) (xy 210.376268 -53.144138) (xy 210.370674 -53.137054)
			(xy 210.37042 -53.137054) (xy 210.37042 -53.1368) (xy 210.352771 -53.115876) (xy 210.32306 -53.069901)
			(xy 210.300225 -53.020152) (xy 210.284737 -52.967649) (xy 210.276912 -52.913472) (xy 210.27644 -52.886102)
			(xy 210.276926 -52.858851) (xy 210.284682 -52.804903) (xy 210.300037 -52.752608) (xy 210.322679 -52.703031)
			(xy 210.352145 -52.657181) (xy 210.387836 -52.61599) (xy 210.429027 -52.580299) (xy 210.474877 -52.550833)
			(xy 210.524454 -52.528191) (xy 210.576749 -52.512836) (xy 210.630697 -52.50508) (xy 210.685199 -52.50508)
			(xy 210.739147 -52.512836) (xy 210.791442 -52.528191) (xy 210.830551 -52.546052) (xy 215.779573 -52.546052)
			(xy 215.779573 -52.491548) (xy 215.78733 -52.4376) (xy 215.802686 -52.385304) (xy 215.825327 -52.335726)
			(xy 215.854794 -52.289875) (xy 215.890487 -52.248684) (xy 215.931678 -52.212992) (xy 215.977529 -52.183525)
			(xy 216.027108 -52.160884) (xy 216.079403 -52.145529) (xy 216.133352 -52.137773) (xy 216.160604 -52.13731)
			(xy 216.187974 -52.137771) (xy 216.242154 -52.14559) (xy 216.294657 -52.16108) (xy 216.344404 -52.183923)
			(xy 216.39037 -52.213648) (xy 216.411302 -52.23129) (xy 216.411556 -52.231544) (xy 216.418647 -52.237124)
			(xy 216.435561 -52.243373) (xy 216.444576 -52.243736) (xy 216.511632 -52.243736) (xy 216.520649 -52.243387)
			(xy 216.537566 -52.237133) (xy 216.544652 -52.231544) (xy 216.544652 -52.23129) (xy 216.544906 -52.23129)
			(xy 216.565839 -52.213649) (xy 216.611807 -52.183925) (xy 216.661553 -52.161079) (xy 216.714055 -52.145583)
			(xy 216.768233 -52.137754) (xy 216.822975 -52.137754) (xy 216.877153 -52.145583) (xy 216.929655 -52.161079)
			(xy 216.979401 -52.183925) (xy 217.025369 -52.213649) (xy 217.046302 -52.23129) (xy 217.046556 -52.231544)
			(xy 217.053647 -52.237124) (xy 217.070561 -52.243373) (xy 217.079576 -52.243736) (xy 217.146632 -52.243736)
			(xy 217.155649 -52.243387) (xy 217.172566 -52.237133) (xy 217.179652 -52.231544) (xy 217.179652 -52.23129)
			(xy 217.179906 -52.23129) (xy 217.200824 -52.213633) (xy 217.246801 -52.183924) (xy 217.296552 -52.161092)
			(xy 217.349056 -52.145605) (xy 217.403234 -52.137782) (xy 217.430604 -52.13731) (xy 217.457856 -52.13776)
			(xy 217.511806 -52.145517) (xy 217.564103 -52.160874) (xy 217.613682 -52.183516) (xy 217.659534 -52.212984)
			(xy 217.700726 -52.248677) (xy 217.736419 -52.289869) (xy 217.765886 -52.335722) (xy 217.788528 -52.385301)
			(xy 217.803883 -52.437598) (xy 217.81164 -52.491548) (xy 217.81164 -52.546052) (xy 217.805695 -52.587398)
			(xy 218.855288 -52.587398) (xy 218.859359 -52.531776) (xy 218.871485 -52.477339) (xy 218.891408 -52.425248)
			(xy 218.918704 -52.376613) (xy 218.95279 -52.33247) (xy 218.992939 -52.293761) (xy 219.038297 -52.26131)
			(xy 219.087897 -52.235809) (xy 219.140681 -52.217802) (xy 219.195524 -52.207672) (xy 219.251258 -52.205635)
			(xy 219.306695 -52.211735) (xy 219.360652 -52.225841) (xy 219.411981 -52.247653) (xy 219.459587 -52.276707)
			(xy 219.502455 -52.312382) (xy 219.539672 -52.353919) (xy 219.570445 -52.400432) (xy 219.594117 -52.450929)
			(xy 219.610185 -52.504336) (xy 219.618305 -52.559512) (xy 219.618814 -52.587398) (xy 219.618305 -52.615284)
			(xy 219.610185 -52.67046) (xy 219.594117 -52.723867) (xy 219.570445 -52.774364) (xy 219.539672 -52.820877)
			(xy 219.502455 -52.862414) (xy 219.459587 -52.898089) (xy 219.411981 -52.927143) (xy 219.360652 -52.948955)
			(xy 219.306695 -52.963061) (xy 219.251258 -52.969161) (xy 219.195524 -52.967124) (xy 219.140681 -52.956994)
			(xy 219.087897 -52.938987) (xy 219.038297 -52.913486) (xy 218.992939 -52.881035) (xy 218.95279 -52.842326)
			(xy 218.918704 -52.798183) (xy 218.891408 -52.749548) (xy 218.871485 -52.697457) (xy 218.859359 -52.64302)
			(xy 218.855288 -52.587398) (xy 217.805695 -52.587398) (xy 217.803883 -52.600002) (xy 217.788528 -52.652299)
			(xy 217.765886 -52.701878) (xy 217.736419 -52.747731) (xy 217.700726 -52.788923) (xy 217.659534 -52.824616)
			(xy 217.613682 -52.854084) (xy 217.564103 -52.876726) (xy 217.511806 -52.892083) (xy 217.457856 -52.89984)
			(xy 217.430604 -52.900326) (xy 217.403233 -52.899876) (xy 217.349053 -52.892057) (xy 217.296549 -52.876565)
			(xy 217.246802 -52.853719) (xy 217.200836 -52.82399) (xy 217.179906 -52.806346) (xy 217.179652 -52.806092)
			(xy 217.172555 -52.80052) (xy 217.155646 -52.794265) (xy 217.146632 -52.7939) (xy 217.079576 -52.7939)
			(xy 217.070558 -52.794246) (xy 217.053641 -52.800501) (xy 217.046556 -52.806092) (xy 217.046302 -52.806346)
			(xy 217.025369 -52.823987) (xy 216.979401 -52.853711) (xy 216.929655 -52.876557) (xy 216.877153 -52.892053)
			(xy 216.822975 -52.899882) (xy 216.768233 -52.899882) (xy 216.714055 -52.892053) (xy 216.661553 -52.876557)
			(xy 216.611807 -52.853711) (xy 216.565839 -52.823987) (xy 216.544906 -52.806346) (xy 216.544652 -52.806092)
			(xy 216.537555 -52.80052) (xy 216.520646 -52.794265) (xy 216.511632 -52.7939) (xy 216.444576 -52.7939)
			(xy 216.435558 -52.794246) (xy 216.418641 -52.800501) (xy 216.411556 -52.806092) (xy 216.411556 -52.806346)
			(xy 216.411302 -52.806346) (xy 216.390373 -52.823989) (xy 216.3444 -52.853702) (xy 216.294652 -52.876538)
			(xy 216.24215 -52.892028) (xy 216.187974 -52.899854) (xy 216.160604 -52.900326) (xy 216.133352 -52.899827)
			(xy 216.079403 -52.892071) (xy 216.027108 -52.876716) (xy 215.977529 -52.854075) (xy 215.931678 -52.824608)
			(xy 215.890487 -52.788916) (xy 215.854794 -52.747725) (xy 215.825327 -52.701874) (xy 215.802686 -52.652296)
			(xy 215.78733 -52.6) (xy 215.779573 -52.546052) (xy 210.830551 -52.546052) (xy 210.841019 -52.550833)
			(xy 210.886869 -52.580299) (xy 210.92806 -52.61599) (xy 210.963751 -52.657181) (xy 210.993217 -52.703031)
			(xy 211.015859 -52.752608) (xy 211.031214 -52.804903) (xy 211.03897 -52.858851) (xy 211.039456 -52.886102)
			(xy 211.039002 -52.913473) (xy 211.031183 -52.967653) (xy 211.015692 -53.020156) (xy 210.992847 -53.069903)
			(xy 210.963119 -53.115869) (xy 210.945476 -53.1368) (xy 210.945222 -53.137054) (xy 210.939639 -53.144143)
			(xy 210.933392 -53.161058) (xy 210.93303 -53.170074) (xy 210.93303 -53.23713) (xy 210.933366 -53.246149)
			(xy 210.939627 -53.263066) (xy 210.945222 -53.27015) (xy 210.945476 -53.27015) (xy 210.945476 -53.270404)
			(xy 210.963119 -53.291335) (xy 210.992843 -53.337303) (xy 211.015688 -53.38705) (xy 211.031184 -53.439552)
			(xy 211.039012 -53.493731) (xy 211.039012 -53.548472) (xy 211.031183 -53.602651) (xy 211.015687 -53.655153)
			(xy 210.992842 -53.704899) (xy 210.963117 -53.750867) (xy 210.946546 -53.77053) (xy 211.310728 -53.77053)
			(xy 211.311257 -53.741613) (xy 211.319983 -53.684442) (xy 211.337238 -53.629243) (xy 211.362627 -53.577281)
			(xy 211.395569 -53.529747) (xy 211.435309 -53.48773) (xy 211.457794 -53.46954) (xy 211.466572 -53.461905)
			(xy 211.476772 -53.441025) (xy 211.477352 -53.429408) (xy 211.477352 -53.349652) (xy 211.476843 -53.338016)
			(xy 211.466635 -53.317106) (xy 211.457794 -53.30952) (xy 211.435319 -53.291319) (xy 211.395583 -53.249301)
			(xy 211.362644 -53.201768) (xy 211.337254 -53.149809) (xy 211.319996 -53.094613) (xy 211.311264 -53.037445)
			(xy 211.310728 -53.00853) (xy 211.311183 -52.981276) (xy 211.318937 -52.927323) (xy 211.334291 -52.875023)
			(xy 211.356933 -52.825441) (xy 211.386401 -52.779586) (xy 211.422096 -52.738392) (xy 211.46329 -52.702697)
			(xy 211.509146 -52.67323) (xy 211.558729 -52.650589) (xy 211.611029 -52.635236) (xy 211.664982 -52.627483)
			(xy 211.692236 -52.627022) (xy 211.718551 -52.627458) (xy 211.770681 -52.634699) (xy 211.821325 -52.649023)
			(xy 211.869524 -52.670162) (xy 211.914367 -52.697713) (xy 211.955005 -52.731158) (xy 211.97316 -52.750212)
			(xy 211.980693 -52.7576) (xy 211.999964 -52.766132) (xy 212.010498 -52.766722) (xy 212.085174 -52.766722)
			(xy 212.095723 -52.766186) (xy 212.115018 -52.757655) (xy 212.122512 -52.750212) (xy 212.140671 -52.73116)
			(xy 212.1813 -52.697702) (xy 212.226139 -52.670142) (xy 212.274339 -52.649003) (xy 212.324986 -52.634685)
			(xy 212.37712 -52.62746) (xy 212.403436 -52.627022) (xy 212.43069 -52.627444) (xy 212.484641 -52.635207)
			(xy 212.536939 -52.650568) (xy 212.586518 -52.673215) (xy 212.63237 -52.702688) (xy 212.67356 -52.738386)
			(xy 212.709251 -52.779583) (xy 212.738716 -52.82544) (xy 212.761355 -52.875023) (xy 212.776707 -52.927324)
			(xy 212.78446 -52.981276) (xy 212.784944 -53.00853) (xy 212.784481 -53.036197) (xy 212.78225 -53.051456)
			(xy 221.041212 -53.051456) (xy 221.045283 -52.995834) (xy 221.057409 -52.941397) (xy 221.077332 -52.889306)
			(xy 221.104628 -52.840671) (xy 221.138714 -52.796528) (xy 221.178863 -52.757819) (xy 221.224221 -52.725368)
			(xy 221.273821 -52.699867) (xy 221.326605 -52.68186) (xy 221.381448 -52.67173) (xy 221.437182 -52.669693)
			(xy 221.492619 -52.675793) (xy 221.546576 -52.689899) (xy 221.597905 -52.711711) (xy 221.645511 -52.740765)
			(xy 221.688379 -52.77644) (xy 221.725596 -52.817977) (xy 221.756369 -52.86449) (xy 221.780041 -52.914987)
			(xy 221.796109 -52.968394) (xy 221.804229 -53.02357) (xy 221.804738 -53.051456) (xy 221.804229 -53.079342)
			(xy 221.796109 -53.134518) (xy 221.780041 -53.187925) (xy 221.756369 -53.238422) (xy 221.725596 -53.284935)
			(xy 221.688379 -53.326472) (xy 221.645511 -53.362147) (xy 221.597905 -53.391201) (xy 221.546576 -53.413013)
			(xy 221.492619 -53.427119) (xy 221.437182 -53.433219) (xy 221.381448 -53.431182) (xy 221.326605 -53.421052)
			(xy 221.273821 -53.403045) (xy 221.224221 -53.377544) (xy 221.178863 -53.345093) (xy 221.138714 -53.306384)
			(xy 221.104628 -53.262241) (xy 221.077332 -53.213606) (xy 221.057409 -53.161515) (xy 221.045283 -53.107078)
			(xy 221.041212 -53.051456) (xy 212.78225 -53.051456) (xy 212.776476 -53.09095) (xy 212.760653 -53.143974)
			(xy 212.737342 -53.194159) (xy 212.707033 -53.240454) (xy 212.670359 -53.28189) (xy 212.628089 -53.317599)
			(xy 212.604858 -53.332634) (xy 212.595169 -53.339256) (xy 212.58273 -53.359128) (xy 212.580982 -53.370734)
			(xy 212.573108 -53.450744) (xy 212.572469 -53.462382) (xy 212.580556 -53.484219) (xy 212.588602 -53.492654)
			(xy 212.588856 -53.492908) (xy 212.607415 -53.511011) (xy 212.639997 -53.551337) (xy 212.666814 -53.595707)
			(xy 212.687371 -53.643301) (xy 212.701289 -53.693242) (xy 212.70831 -53.744608) (xy 212.708744 -53.77053)
			(xy 212.70825 -53.79778) (xy 212.700491 -53.851726) (xy 212.685133 -53.904018) (xy 212.662491 -53.953593)
			(xy 212.633025 -53.999442) (xy 212.597335 -54.040631) (xy 212.556147 -54.076322) (xy 212.510299 -54.105789)
			(xy 212.460724 -54.128431) (xy 212.408432 -54.143789) (xy 212.354486 -54.15155) (xy 212.327236 -54.152038)
			(xy 212.299866 -54.151566) (xy 212.245686 -54.143752) (xy 212.193183 -54.128265) (xy 212.143436 -54.105424)
			(xy 212.097469 -54.0757) (xy 212.076538 -54.058058) (xy 212.076284 -54.057804) (xy 212.069206 -54.052205)
			(xy 212.052283 -54.045966) (xy 212.043264 -54.045612) (xy 211.976208 -54.045612) (xy 211.967191 -54.04597)
			(xy 211.950274 -54.052217) (xy 211.943188 -54.057804) (xy 211.943188 -54.058058) (xy 211.942934 -54.058058)
			(xy 211.921995 -54.075688) (xy 211.876024 -54.105403) (xy 211.826279 -54.128241) (xy 211.77378 -54.143734)
			(xy 211.719605 -54.151564) (xy 211.692236 -54.152038) (xy 211.664985 -54.151511) (xy 211.611038 -54.14376)
			(xy 211.558743 -54.12841) (xy 211.509165 -54.105774) (xy 211.463314 -54.076312) (xy 211.422121 -54.040625)
			(xy 211.386427 -53.999439) (xy 211.356958 -53.953593) (xy 211.334313 -53.904018) (xy 211.318954 -53.851726)
			(xy 211.311193 -53.797781) (xy 211.310728 -53.77053) (xy 210.946546 -53.77053) (xy 210.945476 -53.7718)
			(xy 210.945222 -53.772054) (xy 210.939639 -53.779143) (xy 210.933392 -53.796058) (xy 210.93303 -53.805074)
			(xy 210.93303 -53.87213) (xy 210.933366 -53.881149) (xy 210.939627 -53.898066) (xy 210.945222 -53.90515)
			(xy 210.945476 -53.90515) (xy 210.945476 -53.905404) (xy 210.963119 -53.926335) (xy 210.992843 -53.972303)
			(xy 211.015688 -54.02205) (xy 211.031184 -54.074552) (xy 211.039012 -54.128731) (xy 211.039012 -54.183472)
			(xy 211.031183 -54.237651) (xy 211.015687 -54.290153) (xy 211.001895 -54.320186) (xy 213.23046 -54.320186)
			(xy 213.230903 -54.292815) (xy 213.238724 -54.238634) (xy 213.254218 -54.18613) (xy 213.277065 -54.136384)
			(xy 213.306796 -54.090418) (xy 213.32444 -54.069488) (xy 213.324694 -54.069234) (xy 213.330272 -54.062141)
			(xy 213.336524 -54.045229) (xy 213.336886 -54.036214) (xy 213.336886 -53.969158) (xy 213.336504 -53.960144)
			(xy 213.330274 -53.943226) (xy 213.324694 -53.936138) (xy 213.32444 -53.936138) (xy 213.32444 -53.935884)
			(xy 213.306833 -53.914926) (xy 213.277115 -53.868961) (xy 213.254272 -53.81922) (xy 213.238774 -53.766725)
			(xy 213.230938 -53.712553) (xy 213.23046 -53.685186) (xy 213.230946 -53.657935) (xy 213.238702 -53.603987)
			(xy 213.254057 -53.551692) (xy 213.276699 -53.502115) (xy 213.306165 -53.456265) (xy 213.341856 -53.415074)
			(xy 213.383047 -53.379383) (xy 213.428897 -53.349917) (xy 213.478474 -53.327275) (xy 213.530769 -53.31192)
			(xy 213.584717 -53.304164) (xy 213.639219 -53.304164) (xy 213.693167 -53.31192) (xy 213.745462 -53.327275)
			(xy 213.795039 -53.349917) (xy 213.840889 -53.379383) (xy 213.88208 -53.415074) (xy 213.917771 -53.456265)
			(xy 213.947237 -53.502115) (xy 213.969879 -53.551692) (xy 213.985234 -53.603987) (xy 213.99299 -53.657935)
			(xy 213.993476 -53.685186) (xy 213.993008 -53.712556) (xy 213.985191 -53.766735) (xy 213.969703 -53.819239)
			(xy 213.946862 -53.868986) (xy 213.917137 -53.914952) (xy 213.899496 -53.935884) (xy 213.899242 -53.936138)
			(xy 213.893668 -53.943233) (xy 213.887415 -53.960144) (xy 213.88705 -53.969158) (xy 213.88705 -54.036214)
			(xy 213.88739 -54.045233) (xy 213.893648 -54.06215) (xy 213.899242 -54.069234) (xy 213.899496 -54.069234)
			(xy 213.899496 -54.069488) (xy 213.917142 -54.090414) (xy 213.946853 -54.136389) (xy 213.969688 -54.186138)
			(xy 213.985177 -54.23864) (xy 213.993003 -54.292816) (xy 213.993476 -54.320186) (xy 213.99299 -54.347437)
			(xy 213.985234 -54.401385) (xy 213.969879 -54.45368) (xy 213.947237 -54.503257) (xy 213.917771 -54.549107)
			(xy 213.88208 -54.590298) (xy 213.840889 -54.625989) (xy 213.795039 -54.655455) (xy 213.745462 -54.678097)
			(xy 213.693167 -54.693452) (xy 213.639219 -54.701208) (xy 213.584717 -54.701208) (xy 213.530769 -54.693452)
			(xy 213.478474 -54.678097) (xy 213.428897 -54.655455) (xy 213.383047 -54.625989) (xy 213.341856 -54.590298)
			(xy 213.306165 -54.549107) (xy 213.276699 -54.503257) (xy 213.254057 -54.45368) (xy 213.238702 -54.401385)
			(xy 213.230946 -54.347437) (xy 213.23046 -54.320186) (xy 211.001895 -54.320186) (xy 210.992842 -54.339899)
			(xy 210.963117 -54.385867) (xy 210.945476 -54.4068) (xy 210.945222 -54.407054) (xy 210.939639 -54.414143)
			(xy 210.933392 -54.431058) (xy 210.93303 -54.440074) (xy 210.93303 -54.50713) (xy 210.933366 -54.516149)
			(xy 210.939627 -54.533066) (xy 210.945222 -54.54015) (xy 210.945476 -54.54015) (xy 210.945476 -54.540404)
			(xy 210.963127 -54.561327) (xy 210.992838 -54.607302) (xy 211.015672 -54.657052) (xy 211.03116 -54.709554)
			(xy 211.038984 -54.763732) (xy 211.039101 -54.770528) (xy 214.171022 -54.770528) (xy 214.171499 -54.743158)
			(xy 214.179313 -54.688979) (xy 214.1948 -54.636476) (xy 214.217639 -54.586729) (xy 214.247362 -54.540762)
			(xy 214.265002 -54.51983) (xy 214.265256 -54.519576) (xy 214.270865 -54.512505) (xy 214.277097 -54.495576)
			(xy 214.277448 -54.486556) (xy 214.277448 -54.4195) (xy 214.277102 -54.410482) (xy 214.270848 -54.393564)
			(xy 214.265256 -54.38648) (xy 214.265002 -54.38648) (xy 214.265002 -54.386226) (xy 214.247362 -54.365295)
			(xy 214.21765 -54.319322) (xy 214.194814 -54.269574) (xy 214.179324 -54.217073) (xy 214.171496 -54.162897)
			(xy 214.171022 -54.135528) (xy 214.171508 -54.108277) (xy 214.179264 -54.054329) (xy 214.194619 -54.002034)
			(xy 214.217261 -53.952457) (xy 214.246727 -53.906607) (xy 214.282418 -53.865416) (xy 214.323609 -53.829725)
			(xy 214.369459 -53.800259) (xy 214.419036 -53.777617) (xy 214.471331 -53.762262) (xy 214.525279 -53.754506)
			(xy 214.579781 -53.754506) (xy 214.633729 -53.762262) (xy 214.686024 -53.777617) (xy 214.735601 -53.800259)
			(xy 214.781451 -53.829725) (xy 214.822642 -53.865416) (xy 214.858333 -53.906607) (xy 214.887799 -53.952457)
			(xy 214.892874 -53.96357) (xy 218.872052 -53.96357) (xy 218.876123 -53.907948) (xy 218.888249 -53.853511)
			(xy 218.908172 -53.80142) (xy 218.935468 -53.752785) (xy 218.969554 -53.708642) (xy 219.009703 -53.669933)
			(xy 219.055061 -53.637482) (xy 219.104661 -53.611981) (xy 219.157445 -53.593974) (xy 219.212288 -53.583844)
			(xy 219.268022 -53.581807) (xy 219.323459 -53.587907) (xy 219.377416 -53.602013) (xy 219.428745 -53.623825)
			(xy 219.476351 -53.652879) (xy 219.519219 -53.688554) (xy 219.556436 -53.730091) (xy 219.587209 -53.776604)
			(xy 219.610881 -53.827101) (xy 219.626949 -53.880508) (xy 219.635069 -53.935684) (xy 219.635578 -53.96357)
			(xy 219.635069 -53.991456) (xy 219.626949 -54.046632) (xy 219.610881 -54.100039) (xy 219.587209 -54.150536)
			(xy 219.556436 -54.197049) (xy 219.519219 -54.238586) (xy 219.476351 -54.274261) (xy 219.428745 -54.303315)
			(xy 219.377416 -54.325127) (xy 219.323459 -54.339233) (xy 219.268022 -54.345333) (xy 219.212288 -54.343296)
			(xy 219.157445 -54.333166) (xy 219.104661 -54.315159) (xy 219.055061 -54.289658) (xy 219.009703 -54.257207)
			(xy 218.969554 -54.218498) (xy 218.935468 -54.174355) (xy 218.908172 -54.12572) (xy 218.888249 -54.073629)
			(xy 218.876123 -54.019192) (xy 218.872052 -53.96357) (xy 214.892874 -53.96357) (xy 214.910441 -54.002034)
			(xy 214.925796 -54.054329) (xy 214.933552 -54.108277) (xy 214.934038 -54.135528) (xy 214.933603 -54.1629)
			(xy 214.92578 -54.217081) (xy 214.910285 -54.269585) (xy 214.887436 -54.319331) (xy 214.857703 -54.365296)
			(xy 214.840058 -54.386226) (xy 214.839804 -54.38648) (xy 214.83422 -54.393568) (xy 214.827972 -54.410484)
			(xy 214.827612 -54.4195) (xy 214.827612 -54.486556) (xy 214.827988 -54.495571) (xy 214.834222 -54.512488)
			(xy 214.839804 -54.519576) (xy 214.840058 -54.519576) (xy 214.840058 -54.51983) (xy 214.857671 -54.540783)
			(xy 214.887388 -54.586749) (xy 214.91023 -54.636492) (xy 214.925727 -54.688988) (xy 214.933561 -54.74316)
			(xy 214.934038 -54.770528) (xy 214.933552 -54.797779) (xy 214.925796 -54.851727) (xy 214.910441 -54.904022)
			(xy 214.887799 -54.953599) (xy 214.858333 -54.999449) (xy 214.822642 -55.04064) (xy 214.781451 -55.076331)
			(xy 214.735601 -55.105797) (xy 214.686024 -55.128439) (xy 214.633729 -55.143794) (xy 214.579781 -55.15155)
			(xy 214.525279 -55.15155) (xy 214.471331 -55.143794) (xy 214.419036 -55.128439) (xy 214.369459 -55.105797)
			(xy 214.323609 -55.076331) (xy 214.282418 -55.04064) (xy 214.246727 -54.999449) (xy 214.217261 -54.953599)
			(xy 214.194619 -54.904022) (xy 214.179264 -54.851727) (xy 214.171508 -54.797779) (xy 214.171022 -54.770528)
			(xy 211.039101 -54.770528) (xy 211.039456 -54.791102) (xy 211.03897 -54.818353) (xy 211.031214 -54.872301)
			(xy 211.015859 -54.924596) (xy 210.993217 -54.974173) (xy 210.963751 -55.020023) (xy 210.92806 -55.061214)
			(xy 210.886869 -55.096905) (xy 210.841019 -55.126371) (xy 210.791442 -55.149013) (xy 210.739147 -55.164368)
			(xy 210.685199 -55.172124) (xy 210.630697 -55.172124) (xy 210.576749 -55.164368) (xy 210.524454 -55.149013)
			(xy 210.474877 -55.126371) (xy 210.429027 -55.096905) (xy 210.387836 -55.061214) (xy 210.352145 -55.020023)
			(xy 210.322679 -54.974173) (xy 210.300037 -54.924596) (xy 210.284682 -54.872301) (xy 210.276926 -54.818353)
			(xy 210.27644 -54.791102) (xy 208.378542 -54.791102) (xy 208.371703 -54.82891) (xy 208.351812 -54.885764)
			(xy 208.323243 -54.938792) (xy 208.3054 -54.96306) (xy 208.30032 -54.969664) (xy 208.29143 -54.995064)
			(xy 208.290362 -54.998783) (xy 208.289213 -55.006435) (xy 208.289144 -55.010304) (xy 208.289144 -55.722266)
			(xy 219.934026 -55.722266) (xy 219.938097 -55.666644) (xy 219.950223 -55.612207) (xy 219.970146 -55.560116)
			(xy 219.997442 -55.511481) (xy 220.031528 -55.467338) (xy 220.071677 -55.428629) (xy 220.117035 -55.396178)
			(xy 220.166635 -55.370677) (xy 220.219419 -55.35267) (xy 220.274262 -55.34254) (xy 220.329996 -55.340503)
			(xy 220.385433 -55.346603) (xy 220.43939 -55.360709) (xy 220.490719 -55.382521) (xy 220.538325 -55.411575)
			(xy 220.581193 -55.44725) (xy 220.61841 -55.488787) (xy 220.649183 -55.5353) (xy 220.672855 -55.585797)
			(xy 220.688923 -55.639204) (xy 220.697043 -55.69438) (xy 220.697552 -55.722266) (xy 220.697043 -55.750152)
			(xy 220.688923 -55.805328) (xy 220.672855 -55.858735) (xy 220.649183 -55.909232) (xy 220.61841 -55.955745)
			(xy 220.581193 -55.997282) (xy 220.538325 -56.032957) (xy 220.490719 -56.062011) (xy 220.43939 -56.083823)
			(xy 220.385433 -56.097929) (xy 220.329996 -56.104029) (xy 220.274262 -56.101992) (xy 220.219419 -56.091862)
			(xy 220.166635 -56.073855) (xy 220.117035 -56.048354) (xy 220.071677 -56.015903) (xy 220.031528 -55.977194)
			(xy 219.997442 -55.933051) (xy 219.970146 -55.884416) (xy 219.950223 -55.832325) (xy 219.938097 -55.777888)
			(xy 219.934026 -55.722266) (xy 208.289144 -55.722266) (xy 208.289144 -55.923434) (xy 208.289398 -55.92699)
			(xy 208.289398 -55.93334) (xy 208.289652 -55.949596) (xy 208.289652 -55.950104) (xy 208.289652 -55.950866)
			(xy 208.289398 -55.96636) (xy 208.289398 -55.97271) (xy 208.289144 -55.973472) (xy 208.28127 -56.31688)
			(xy 208.276952 -56.50103) (xy 208.27619 -56.532526) (xy 208.27625 -56.537266) (xy 208.277917 -56.546597)
			(xy 208.279492 -56.551068) (xy 208.288382 -56.573928) (xy 208.29397 -56.580532) (xy 208.310817 -56.60125)
			(xy 208.339165 -56.646502) (xy 208.360933 -56.695262) (xy 208.375698 -56.746578) (xy 208.38317 -56.799451)
			(xy 208.383632 -56.82615) (xy 208.383632 -56.833516) (xy 208.383378 -56.842406) (xy 208.381726 -56.87006)
			(xy 208.371428 -56.924493) (xy 208.353359 -56.976861) (xy 208.339868 -57.002934) (xy 215.663526 -57.002934)
			(xy 215.664026 -56.974842) (xy 215.67225 -56.919265) (xy 215.688538 -56.865495) (xy 215.71254 -56.814696)
			(xy 215.743734 -56.767969) (xy 215.781447 -56.726325) (xy 215.824861 -56.690664) (xy 215.848692 -56.675782)
			(xy 215.857582 -56.670448) (xy 215.869774 -56.65343) (xy 215.890094 -56.560212) (xy 215.885776 -56.539638)
			(xy 215.879934 -56.531002) (xy 215.863937 -56.506936) (xy 215.838592 -56.455006) (xy 215.821366 -56.399848)
			(xy 215.81265 -56.342724) (xy 215.812116 -56.313832) (xy 215.812585 -56.286579) (xy 215.820338 -56.232627)
			(xy 215.835692 -56.180328) (xy 215.858332 -56.130746) (xy 215.887799 -56.084892) (xy 215.923492 -56.043698)
			(xy 215.964685 -56.008004) (xy 216.010539 -55.978536) (xy 216.06012 -55.955894) (xy 216.112419 -55.94054)
			(xy 216.166371 -55.932786) (xy 216.193624 -55.932324) (xy 216.220995 -55.93277) (xy 216.275175 -55.940592)
			(xy 216.327679 -55.956085) (xy 216.377425 -55.978932) (xy 216.423391 -56.008661) (xy 216.444322 -56.026304)
			(xy 216.444576 -56.026558) (xy 216.45166 -56.032148) (xy 216.468579 -56.038391) (xy 216.477596 -56.03875)
			(xy 216.544652 -56.03875) (xy 216.553668 -56.038381) (xy 216.570586 -56.032143) (xy 216.577672 -56.026558)
			(xy 216.577672 -56.026304) (xy 216.577926 -56.026304) (xy 216.598859 -56.008663) (xy 216.644827 -55.978939)
			(xy 216.694573 -55.956093) (xy 216.747075 -55.940597) (xy 216.801253 -55.932768) (xy 216.855995 -55.932768)
			(xy 216.910173 -55.940597) (xy 216.962675 -55.956093) (xy 217.012421 -55.978939) (xy 217.058389 -56.008663)
			(xy 217.079322 -56.026304) (xy 217.079576 -56.026558) (xy 217.08666 -56.032148) (xy 217.103579 -56.038391)
			(xy 217.112596 -56.03875) (xy 217.179652 -56.03875) (xy 217.188668 -56.038381) (xy 217.205586 -56.032143)
			(xy 217.212672 -56.026558) (xy 217.212672 -56.026304) (xy 217.212926 -56.026304) (xy 217.233876 -56.008687)
			(xy 217.279844 -55.978971) (xy 217.329587 -55.956131) (xy 217.382083 -55.940635) (xy 217.436256 -55.932801)
			(xy 217.463624 -55.932324) (xy 217.490876 -55.932747) (xy 217.544826 -55.940507) (xy 217.597122 -55.955866)
			(xy 217.646701 -55.97851) (xy 217.692552 -56.00798) (xy 217.733743 -56.043674) (xy 217.769435 -56.084867)
			(xy 217.798901 -56.13072) (xy 217.821542 -56.1803) (xy 217.836898 -56.232597) (xy 217.844654 -56.286548)
			(xy 217.844654 -56.297068) (xy 218.186506 -56.297068) (xy 218.190577 -56.241446) (xy 218.202703 -56.187009)
			(xy 218.222626 -56.134918) (xy 218.249922 -56.086283) (xy 218.284008 -56.04214) (xy 218.324157 -56.003431)
			(xy 218.369515 -55.97098) (xy 218.419115 -55.945479) (xy 218.471899 -55.927472) (xy 218.526742 -55.917342)
			(xy 218.582476 -55.915305) (xy 218.637913 -55.921405) (xy 218.69187 -55.935511) (xy 218.743199 -55.957323)
			(xy 218.790805 -55.986377) (xy 218.833673 -56.022052) (xy 218.87089 -56.063589) (xy 218.901663 -56.110102)
			(xy 218.925335 -56.160599) (xy 218.941403 -56.214006) (xy 218.949523 -56.269182) (xy 218.950032 -56.297068)
			(xy 218.949523 -56.324954) (xy 218.941403 -56.38013) (xy 218.925335 -56.433537) (xy 218.901663 -56.484034)
			(xy 218.87089 -56.530547) (xy 218.833673 -56.572084) (xy 218.790805 -56.607759) (xy 218.743199 -56.636813)
			(xy 218.69187 -56.658625) (xy 218.637913 -56.672731) (xy 218.582476 -56.678831) (xy 218.526742 -56.676794)
			(xy 218.471899 -56.666664) (xy 218.419115 -56.648657) (xy 218.369515 -56.623156) (xy 218.324157 -56.590705)
			(xy 218.284008 -56.551996) (xy 218.249922 -56.507853) (xy 218.222626 -56.459218) (xy 218.202703 -56.407127)
			(xy 218.190577 -56.35269) (xy 218.186506 -56.297068) (xy 217.844654 -56.297068) (xy 217.844654 -56.341052)
			(xy 217.836898 -56.395003) (xy 217.821542 -56.4473) (xy 217.798901 -56.49688) (xy 217.769435 -56.542733)
			(xy 217.733743 -56.583926) (xy 217.692552 -56.61962) (xy 217.646701 -56.64909) (xy 217.597122 -56.671734)
			(xy 217.544826 -56.687093) (xy 217.490876 -56.694853) (xy 217.463624 -56.69534) (xy 217.436254 -56.694874)
			(xy 217.382074 -56.687059) (xy 217.32957 -56.67157) (xy 217.279823 -56.648728) (xy 217.233857 -56.619002)
			(xy 217.212926 -56.60136) (xy 217.212672 -56.601106) (xy 217.205568 -56.595544) (xy 217.188665 -56.589282)
			(xy 217.179652 -56.588914) (xy 217.112596 -56.588914) (xy 217.103579 -56.589266) (xy 217.086661 -56.595517)
			(xy 217.079576 -56.601106) (xy 217.079576 -56.60136) (xy 217.079322 -56.60136) (xy 217.058389 -56.619001)
			(xy 217.012421 -56.648725) (xy 216.962675 -56.671571) (xy 216.910173 -56.687067) (xy 216.855995 -56.694896)
			(xy 216.801253 -56.694896) (xy 216.747075 -56.687067) (xy 216.694573 -56.671571) (xy 216.644827 -56.648725)
			(xy 216.598859 -56.619001) (xy 216.577926 -56.60136) (xy 216.577672 -56.601106) (xy 216.570568 -56.595544)
			(xy 216.553665 -56.589282) (xy 216.544652 -56.588914) (xy 216.477596 -56.588914) (xy 216.468579 -56.589266)
			(xy 216.451661 -56.595517) (xy 216.444576 -56.601106) (xy 216.444068 -56.60136) (xy 216.431333 -56.612303)
			(xy 216.404242 -56.632145) (xy 216.389966 -56.640984) (xy 216.381076 -56.646318) (xy 216.368884 -56.663336)
			(xy 216.348564 -56.756554) (xy 216.352882 -56.777128) (xy 216.358724 -56.785764) (xy 216.374714 -56.809834)
			(xy 216.400058 -56.861764) (xy 216.417286 -56.91692) (xy 216.426005 -56.974042) (xy 216.426542 -57.002934)
			(xy 216.426056 -57.030185) (xy 216.425774 -57.032144) (xy 219.585792 -57.032144) (xy 219.589863 -56.976522)
			(xy 219.601989 -56.922085) (xy 219.621912 -56.869994) (xy 219.649208 -56.821359) (xy 219.683294 -56.777216)
			(xy 219.723443 -56.738507) (xy 219.768801 -56.706056) (xy 219.818401 -56.680555) (xy 219.871185 -56.662548)
			(xy 219.926028 -56.652418) (xy 219.981762 -56.650381) (xy 220.037199 -56.656481) (xy 220.091156 -56.670587)
			(xy 220.142485 -56.692399) (xy 220.190091 -56.721453) (xy 220.232959 -56.757128) (xy 220.270176 -56.798665)
			(xy 220.300949 -56.845178) (xy 220.324621 -56.895675) (xy 220.340689 -56.949082) (xy 220.348809 -57.004258)
			(xy 220.349318 -57.032144) (xy 220.348809 -57.06003) (xy 220.340689 -57.115206) (xy 220.324621 -57.168613)
			(xy 220.300949 -57.21911) (xy 220.270176 -57.265623) (xy 220.232959 -57.30716) (xy 220.190091 -57.342835)
			(xy 220.142485 -57.371889) (xy 220.091156 -57.393701) (xy 220.037199 -57.407807) (xy 219.981762 -57.413907)
			(xy 219.926028 -57.41187) (xy 219.871185 -57.40174) (xy 219.818401 -57.383733) (xy 219.768801 -57.358232)
			(xy 219.723443 -57.325781) (xy 219.683294 -57.287072) (xy 219.649208 -57.242929) (xy 219.621912 -57.194294)
			(xy 219.601989 -57.142203) (xy 219.589863 -57.087766) (xy 219.585792 -57.032144) (xy 216.425774 -57.032144)
			(xy 216.4183 -57.084133) (xy 216.402945 -57.136428) (xy 216.380303 -57.186005) (xy 216.350837 -57.231855)
			(xy 216.315146 -57.273046) (xy 216.273955 -57.308737) (xy 216.228105 -57.338203) (xy 216.178528 -57.360845)
			(xy 216.126233 -57.3762) (xy 216.072285 -57.383956) (xy 216.017783 -57.383956) (xy 215.963835 -57.3762)
			(xy 215.91154 -57.360845) (xy 215.861963 -57.338203) (xy 215.816113 -57.308737) (xy 215.774922 -57.273046)
			(xy 215.739231 -57.231855) (xy 215.709765 -57.186005) (xy 215.687123 -57.136428) (xy 215.671768 -57.084133)
			(xy 215.664012 -57.030185) (xy 215.663526 -57.002934) (xy 208.339868 -57.002934) (xy 208.3279 -57.026063)
			(xy 208.295587 -57.071061) (xy 208.276698 -57.091326) (xy 208.270094 -57.098184) (xy 208.268062 -57.102756)
			(xy 208.266284 -57.107074) (xy 208.26603 -57.107328) (xy 208.264563 -57.110991) (xy 208.262645 -57.118645)
			(xy 208.26222 -57.122568) (xy 208.261458 -57.15889) (xy 208.261204 -57.169304) (xy 208.26857 -57.1881)
			(xy 208.275682 -57.195466) (xy 208.2958 -57.216936) (xy 208.329854 -57.264914) (xy 208.356137 -57.317552)
			(xy 208.374027 -57.373601) (xy 208.383098 -57.431733) (xy 208.383632 -57.46115) (xy 208.383632 -57.46242)
			(xy 208.383378 -57.478422) (xy 208.383124 -57.48274) (xy 208.383124 -57.483248) (xy 208.3813 -57.508247)
			(xy 208.371906 -57.557483) (xy 208.356131 -57.60506) (xy 208.345532 -57.627774) (xy 208.339182 -57.640982)
			(xy 208.33461 -57.648856) (xy 208.334356 -57.64911) (xy 208.331054 -57.654698) (xy 208.317303 -57.677245)
			(xy 208.284548 -57.718672) (xy 208.265776 -57.737248) (xy 208.261966 -57.741312) (xy 208.260188 -57.743344)
			(xy 208.256473 -57.748204) (xy 208.251203 -57.75924) (xy 208.249774 -57.765188) (xy 208.246726 -57.77865)
			(xy 208.246726 -57.78119) (xy 208.26222 -57.817004) (xy 208.269332 -57.824116) (xy 208.290574 -57.845785)
			(xy 208.326607 -57.894606) (xy 208.354457 -57.948515) (xy 208.373423 -58.006152) (xy 208.383027 -58.066065)
			(xy 208.383632 -58.096404) (xy 208.383554 -58.109142) (xy 208.3819 -58.134563) (xy 208.38033 -58.147204)
			(xy 208.380076 -58.149998) (xy 208.375562 -58.178128) (xy 208.35927 -58.232719) (xy 208.335026 -58.284273)
			(xy 208.319624 -58.30824) (xy 208.314036 -58.316368) (xy 208.310988 -58.320686) (xy 208.304892 -58.329068)
			(xy 208.300574 -58.334148) (xy 208.296002 -58.341514) (xy 208.294986 -58.343546) (xy 208.292526 -58.348872)
			(xy 208.289835 -58.360288) (xy 208.289652 -58.366152) (xy 208.289652 -58.387234) (xy 208.289508 -58.392673)
			(xy 208.287198 -58.403304) (xy 208.28508 -58.408316) (xy 208.278984 -58.421778) (xy 208.275361 -58.43044)
			(xy 208.274124 -58.449162) (xy 208.27975 -58.467062) (xy 208.285334 -58.47461) (xy 208.290922 -58.481722)
			(xy 208.294478 -58.486294) (xy 208.294986 -58.487056) (xy 208.29651 -58.488834) (xy 208.312727 -58.509221)
			(xy 208.340072 -58.553559) (xy 208.361138 -58.601202) (xy 208.375535 -58.651266) (xy 208.379597 -58.679334)
			(xy 216.095326 -58.679334) (xy 216.095741 -58.653018) (xy 216.102985 -58.600887) (xy 216.117314 -58.550243)
			(xy 216.138456 -58.502044) (xy 216.166012 -58.457202) (xy 216.19946 -58.416565) (xy 216.218516 -58.39841)
			(xy 216.225918 -58.390889) (xy 216.234442 -58.371608) (xy 216.235026 -58.361072) (xy 216.235026 -58.286396)
			(xy 216.234505 -58.275846) (xy 216.225963 -58.256551) (xy 216.218516 -58.249058) (xy 216.19945 -58.230913)
			(xy 216.165993 -58.190281) (xy 216.138435 -58.145439) (xy 216.117298 -58.097236) (xy 216.102984 -58.046587)
			(xy 216.095762 -57.994451) (xy 216.095326 -57.968134) (xy 216.095812 -57.940883) (xy 216.103568 -57.886935)
			(xy 216.118923 -57.83464) (xy 216.141565 -57.785063) (xy 216.171031 -57.739213) (xy 216.206722 -57.698022)
			(xy 216.247913 -57.662331) (xy 216.293763 -57.632865) (xy 216.34334 -57.610223) (xy 216.395635 -57.594868)
			(xy 216.449583 -57.587112) (xy 216.504085 -57.587112) (xy 216.558033 -57.594868) (xy 216.610328 -57.610223)
			(xy 216.659905 -57.632865) (xy 216.705755 -57.662331) (xy 216.746946 -57.698022) (xy 216.782637 -57.739213)
			(xy 216.812103 -57.785063) (xy 216.834745 -57.83464) (xy 216.8501 -57.886935) (xy 216.857856 -57.940883)
			(xy 216.858342 -57.968134) (xy 216.857916 -57.99445) (xy 216.850675 -58.046581) (xy 216.836349 -58.097225)
			(xy 216.815209 -58.145424) (xy 216.787655 -58.190266) (xy 216.754208 -58.230903) (xy 216.735152 -58.249058)
			(xy 216.727775 -58.2566) (xy 216.719235 -58.275864) (xy 216.718642 -58.286396) (xy 216.718642 -58.361072)
			(xy 216.719161 -58.371623) (xy 216.727702 -58.390919) (xy 216.735152 -58.39841) (xy 216.754215 -58.416558)
			(xy 216.78767 -58.45719) (xy 216.815226 -58.502032) (xy 216.836363 -58.550235) (xy 216.850679 -58.600883)
			(xy 216.857904 -58.653018) (xy 216.858342 -58.679334) (xy 216.857856 -58.706585) (xy 216.8501 -58.760533)
			(xy 216.834745 -58.812828) (xy 216.812103 -58.862405) (xy 216.782637 -58.908255) (xy 216.746946 -58.949446)
			(xy 216.705755 -58.985137) (xy 216.659905 -59.014603) (xy 216.610328 -59.037245) (xy 216.558033 -59.0526)
			(xy 216.504085 -59.060356) (xy 216.449583 -59.060356) (xy 216.395635 -59.0526) (xy 216.34334 -59.037245)
			(xy 216.293763 -59.014603) (xy 216.247913 -58.985137) (xy 216.206722 -58.949446) (xy 216.171031 -58.908255)
			(xy 216.141565 -58.862405) (xy 216.118923 -58.812828) (xy 216.103568 -58.760533) (xy 216.095812 -58.706585)
			(xy 216.095326 -58.679334) (xy 208.379597 -58.679334) (xy 208.382996 -58.702822) (xy 208.383632 -58.728864)
			(xy 208.383632 -58.730896) (xy 208.383632 -58.731658) (xy 208.383632 -58.732166) (xy 208.383067 -58.761085)
			(xy 208.374271 -58.818251) (xy 208.356935 -58.873431) (xy 208.331459 -58.925358) (xy 208.298428 -58.972837)
			(xy 208.2586 -59.014779) (xy 208.236058 -59.032902) (xy 208.235804 -59.032902) (xy 208.231493 -59.03649)
			(xy 208.224438 -59.045206) (xy 208.221834 -59.050174) (xy 208.219294 -59.055254) (xy 208.2165 -59.065922)
			(xy 208.194132 -60.01925) (xy 216.235784 -60.01925) (xy 216.235784 -59.96475) (xy 216.24354 -59.910804)
			(xy 216.258894 -59.858511) (xy 216.281534 -59.808935) (xy 216.310999 -59.763086) (xy 216.346688 -59.721897)
			(xy 216.387877 -59.686206) (xy 216.433725 -59.65674) (xy 216.4833 -59.634098) (xy 216.535592 -59.618742)
			(xy 216.589538 -59.610985) (xy 216.616788 -59.610498) (xy 216.644158 -59.610972) (xy 216.698337 -59.618788)
			(xy 216.75084 -59.634275) (xy 216.800587 -59.657115) (xy 216.846554 -59.686838) (xy 216.867486 -59.704478)
			(xy 216.86774 -59.704732) (xy 216.874837 -59.710303) (xy 216.891746 -59.716558) (xy 216.90076 -59.716924)
			(xy 216.967816 -59.716924) (xy 216.976833 -59.716569) (xy 216.99375 -59.710319) (xy 217.000836 -59.704732)
			(xy 217.000836 -59.704478) (xy 217.00109 -59.704478) (xy 217.022023 -59.686837) (xy 217.067991 -59.657113)
			(xy 217.117737 -59.634267) (xy 217.170239 -59.618771) (xy 217.224417 -59.610942) (xy 217.279159 -59.610942)
			(xy 217.333337 -59.618771) (xy 217.385839 -59.634267) (xy 217.435585 -59.657113) (xy 217.481553 -59.686837)
			(xy 217.502486 -59.704478) (xy 217.50274 -59.704732) (xy 217.509837 -59.710303) (xy 217.526746 -59.716558)
			(xy 217.53576 -59.716924) (xy 217.602816 -59.716924) (xy 217.611833 -59.716569) (xy 217.62875 -59.710319)
			(xy 217.635836 -59.704732) (xy 217.635836 -59.704478) (xy 217.63609 -59.704478) (xy 217.657012 -59.686827)
			(xy 217.702988 -59.657117) (xy 217.752738 -59.634284) (xy 217.805241 -59.618796) (xy 217.859418 -59.610971)
			(xy 217.886788 -59.610498) (xy 217.914042 -59.610949) (xy 217.967995 -59.618704) (xy 218.020295 -59.634059)
			(xy 218.069877 -59.656702) (xy 218.115733 -59.68617) (xy 218.156928 -59.721864) (xy 218.192623 -59.763058)
			(xy 218.222093 -59.808912) (xy 218.244736 -59.858494) (xy 218.260093 -59.910793) (xy 218.267851 -59.964746)
			(xy 218.267851 -60.019254) (xy 218.260093 -60.073207) (xy 218.244736 -60.125506) (xy 218.222093 -60.175088)
			(xy 218.192623 -60.220942) (xy 218.156928 -60.262136) (xy 218.115733 -60.29783) (xy 218.069877 -60.327298)
			(xy 218.020295 -60.349941) (xy 217.967995 -60.365296) (xy 217.914042 -60.373051) (xy 217.886788 -60.373514)
			(xy 217.859418 -60.373052) (xy 217.805239 -60.365232) (xy 217.752736 -60.349742) (xy 217.702989 -60.3269)
			(xy 217.657022 -60.297175) (xy 217.63609 -60.279534) (xy 217.635836 -60.27928) (xy 217.628745 -60.2737)
			(xy 217.611832 -60.26745) (xy 217.602816 -60.267088) (xy 217.53576 -60.267088) (xy 217.526741 -60.267428)
			(xy 217.509825 -60.273688) (xy 217.50274 -60.27928) (xy 217.502486 -60.279534) (xy 217.481553 -60.297175)
			(xy 217.435585 -60.326899) (xy 217.385839 -60.349745) (xy 217.333337 -60.365241) (xy 217.279159 -60.37307)
			(xy 217.224417 -60.37307) (xy 217.170239 -60.365241) (xy 217.117737 -60.349745) (xy 217.067991 -60.326899)
			(xy 217.022023 -60.297175) (xy 217.00109 -60.279534) (xy 217.000836 -60.27928) (xy 216.993745 -60.2737)
			(xy 216.976832 -60.26745) (xy 216.967816 -60.267088) (xy 216.90076 -60.267088) (xy 216.891741 -60.267428)
			(xy 216.874825 -60.273688) (xy 216.86774 -60.27928) (xy 216.86774 -60.279534) (xy 216.867486 -60.279534)
			(xy 216.846537 -60.297152) (xy 216.800568 -60.326865) (xy 216.750825 -60.349705) (xy 216.698328 -60.365201)
			(xy 216.644156 -60.373036) (xy 216.616788 -60.373514) (xy 216.589538 -60.373015) (xy 216.535592 -60.365258)
			(xy 216.4833 -60.349902) (xy 216.433725 -60.32726) (xy 216.387877 -60.297794) (xy 216.346688 -60.262103)
			(xy 216.310999 -60.220914) (xy 216.281534 -60.175065) (xy 216.258894 -60.125489) (xy 216.24354 -60.073196)
			(xy 216.235784 -60.01925) (xy 208.194132 -60.01925) (xy 208.175606 -60.80887) (xy 208.17408 -60.854432)
			(xy 208.163647 -60.945002) (xy 208.154778 -60.989718) (xy 208.154778 -60.990226) (xy 208.1403 -61.062362)
			(xy 208.140046 -61.062616) (xy 208.125822 -61.13399) (xy 208.062322 -61.45149) (xy 208.061814 -61.45403)
			(xy 208.053178 -61.504068) (xy 207.714007 -63.213552) (xy 216.220765 -63.213552) (xy 216.220765 -63.159048)
			(xy 216.228522 -63.105098) (xy 216.243878 -63.052801) (xy 216.26652 -63.003222) (xy 216.295987 -62.95737)
			(xy 216.33168 -62.916179) (xy 216.372872 -62.880486) (xy 216.418724 -62.851019) (xy 216.468303 -62.828377)
			(xy 216.5206 -62.813022) (xy 216.57455 -62.805265) (xy 216.601802 -62.804802) (xy 216.629172 -62.805266)
			(xy 216.683351 -62.813085) (xy 216.735855 -62.828574) (xy 216.785601 -62.851416) (xy 216.831568 -62.881141)
			(xy 216.8525 -62.898782) (xy 216.852754 -62.899036) (xy 216.859847 -62.904613) (xy 216.876759 -62.910865)
			(xy 216.885774 -62.911228) (xy 216.95283 -62.911228) (xy 216.961848 -62.910879) (xy 216.978764 -62.904625)
			(xy 216.98585 -62.899036) (xy 216.98585 -62.898782) (xy 216.986104 -62.898782) (xy 217.007037 -62.881141)
			(xy 217.053005 -62.851417) (xy 217.102751 -62.828571) (xy 217.155253 -62.813075) (xy 217.209431 -62.805246)
			(xy 217.264173 -62.805246) (xy 217.318351 -62.813075) (xy 217.370853 -62.828571) (xy 217.420599 -62.851417)
			(xy 217.466567 -62.881141) (xy 217.4875 -62.898782) (xy 217.487754 -62.899036) (xy 217.494847 -62.904613)
			(xy 217.511759 -62.910865) (xy 217.520774 -62.911228) (xy 217.58783 -62.911228) (xy 217.596848 -62.910879)
			(xy 217.613764 -62.904625) (xy 217.62085 -62.899036) (xy 217.62085 -62.898782) (xy 217.621104 -62.898782)
			(xy 217.642021 -62.881125) (xy 217.687999 -62.851416) (xy 217.73775 -62.828584) (xy 217.790254 -62.813097)
			(xy 217.844432 -62.805274) (xy 217.871802 -62.804802) (xy 217.899054 -62.805268) (xy 217.953003 -62.813025)
			(xy 218.005299 -62.828381) (xy 218.054877 -62.851022) (xy 218.100728 -62.88049) (xy 218.141919 -62.916182)
			(xy 218.177612 -62.957373) (xy 218.207079 -63.003225) (xy 218.22972 -63.052803) (xy 218.245076 -63.105099)
			(xy 218.252832 -63.159048) (xy 218.252832 -63.213552) (xy 218.245076 -63.267501) (xy 218.22972 -63.319797)
			(xy 218.207079 -63.369375) (xy 218.177612 -63.415227) (xy 218.141919 -63.456418) (xy 218.100728 -63.49211)
			(xy 218.054877 -63.521578) (xy 218.005299 -63.544219) (xy 217.953003 -63.559575) (xy 217.899054 -63.567332)
			(xy 217.871802 -63.567818) (xy 217.844431 -63.567371) (xy 217.79025 -63.559551) (xy 217.737746 -63.544059)
			(xy 217.687999 -63.521213) (xy 217.642034 -63.491482) (xy 217.621104 -63.473838) (xy 217.62085 -63.473584)
			(xy 217.613755 -63.46801) (xy 217.596845 -63.461756) (xy 217.58783 -63.461392) (xy 217.520774 -63.461392)
			(xy 217.511756 -63.461739) (xy 217.494839 -63.467994) (xy 217.487754 -63.473584) (xy 217.4875 -63.473838)
			(xy 217.466567 -63.491479) (xy 217.420599 -63.521203) (xy 217.370853 -63.544049) (xy 217.318351 -63.559545)
			(xy 217.264173 -63.567374) (xy 217.209431 -63.567374) (xy 217.155253 -63.559545) (xy 217.102751 -63.544049)
			(xy 217.053005 -63.521203) (xy 217.007037 -63.491479) (xy 216.986104 -63.473838) (xy 216.98585 -63.473584)
			(xy 216.978755 -63.46801) (xy 216.961845 -63.461756) (xy 216.95283 -63.461392) (xy 216.885774 -63.461392)
			(xy 216.876756 -63.461739) (xy 216.859839 -63.467994) (xy 216.852754 -63.473584) (xy 216.852754 -63.473838)
			(xy 216.8525 -63.473838) (xy 216.831584 -63.491497) (xy 216.785606 -63.521205) (xy 216.735855 -63.544036)
			(xy 216.683351 -63.559523) (xy 216.629172 -63.567347) (xy 216.601802 -63.567818) (xy 216.57455 -63.567335)
			(xy 216.5206 -63.559578) (xy 216.468303 -63.544223) (xy 216.418724 -63.521581) (xy 216.372872 -63.492114)
			(xy 216.33168 -63.456421) (xy 216.295987 -63.41523) (xy 216.26652 -63.369378) (xy 216.243878 -63.319799)
			(xy 216.228522 -63.267502) (xy 216.220765 -63.213552) (xy 207.714007 -63.213552) (xy 207.339534 -65.100962)
			(xy 214.232488 -65.100962) (xy 214.236559 -65.04534) (xy 214.248685 -64.990903) (xy 214.268608 -64.938812)
			(xy 214.295904 -64.890177) (xy 214.32999 -64.846034) (xy 214.370139 -64.807325) (xy 214.415497 -64.774874)
			(xy 214.465097 -64.749373) (xy 214.517881 -64.731366) (xy 214.572724 -64.721236) (xy 214.628458 -64.719199)
			(xy 214.683895 -64.725299) (xy 214.737852 -64.739405) (xy 214.789181 -64.761217) (xy 214.836787 -64.790271)
			(xy 214.879655 -64.825946) (xy 214.916872 -64.867483) (xy 214.947645 -64.913996) (xy 214.971317 -64.964493)
			(xy 214.987385 -65.0179) (xy 214.995505 -65.073076) (xy 214.996014 -65.100962) (xy 214.995505 -65.128848)
			(xy 214.987385 -65.184024) (xy 214.971317 -65.237431) (xy 214.947645 -65.287928) (xy 214.916872 -65.334441)
			(xy 214.879655 -65.375978) (xy 214.836787 -65.411653) (xy 214.789181 -65.440707) (xy 214.737852 -65.462519)
			(xy 214.683895 -65.476625) (xy 214.628458 -65.482725) (xy 214.572724 -65.480688) (xy 214.517881 -65.470558)
			(xy 214.465097 -65.452551) (xy 214.415497 -65.42705) (xy 214.370139 -65.394599) (xy 214.32999 -65.35589)
			(xy 214.295904 -65.311747) (xy 214.268608 -65.263112) (xy 214.248685 -65.211021) (xy 214.236559 -65.156584)
			(xy 214.232488 -65.100962) (xy 207.339534 -65.100962) (xy 207.209666 -65.75552) (xy 208.446622 -65.75552)
			(xy 208.450693 -65.699898) (xy 208.462819 -65.645461) (xy 208.482742 -65.59337) (xy 208.510038 -65.544735)
			(xy 208.544124 -65.500592) (xy 208.584273 -65.461883) (xy 208.629631 -65.429432) (xy 208.679231 -65.403931)
			(xy 208.732015 -65.385924) (xy 208.786858 -65.375794) (xy 208.842592 -65.373757) (xy 208.898029 -65.379857)
			(xy 208.951986 -65.393963) (xy 209.003315 -65.415775) (xy 209.050921 -65.444829) (xy 209.093789 -65.480504)
			(xy 209.131006 -65.522041) (xy 209.161779 -65.568554) (xy 209.185451 -65.619051) (xy 209.201519 -65.672458)
			(xy 209.209639 -65.727634) (xy 209.210148 -65.75552) (xy 209.209639 -65.783406) (xy 209.201519 -65.838582)
			(xy 209.185451 -65.891989) (xy 209.161779 -65.942486) (xy 209.131006 -65.988999) (xy 209.093789 -66.030536)
			(xy 209.050921 -66.066211) (xy 209.003315 -66.095265) (xy 208.951986 -66.117077) (xy 208.898029 -66.131183)
			(xy 208.842592 -66.137283) (xy 208.786858 -66.135246) (xy 208.732015 -66.125116) (xy 208.679231 -66.107109)
			(xy 208.629631 -66.081608) (xy 208.584273 -66.049157) (xy 208.544124 -66.010448) (xy 208.510038 -65.966305)
			(xy 208.482742 -65.91767) (xy 208.462819 -65.865579) (xy 208.450693 -65.811142) (xy 208.446622 -65.75552)
			(xy 207.209666 -65.75552) (xy 206.93717 -67.128949) (xy 208.466698 -67.128949) (xy 208.466698 -67.074451)
			(xy 208.474454 -67.020507) (xy 208.489808 -66.968216) (xy 208.512447 -66.918642) (xy 208.541911 -66.872794)
			(xy 208.577599 -66.831606) (xy 208.618786 -66.795917) (xy 208.664633 -66.766452) (xy 208.714206 -66.743811)
			(xy 208.766497 -66.728456) (xy 208.820441 -66.720699) (xy 208.84769 -66.720212) (xy 208.87506 -66.720681)
			(xy 208.929239 -66.728498) (xy 208.981742 -66.743986) (xy 209.031489 -66.766827) (xy 209.077456 -66.796551)
			(xy 209.098388 -66.814192) (xy 209.098642 -66.814446) (xy 209.105737 -66.82002) (xy 209.122647 -66.826273)
			(xy 209.131662 -66.826638) (xy 209.198718 -66.826638) (xy 209.207735 -66.826282) (xy 209.224651 -66.820033)
			(xy 209.231738 -66.814446) (xy 209.231738 -66.814192) (xy 209.231992 -66.814192) (xy 209.252915 -66.796542)
			(xy 209.298891 -66.766832) (xy 209.34864 -66.743998) (xy 209.401143 -66.72851) (xy 209.45532 -66.720684)
			(xy 209.48269 -66.720212) (xy 209.509945 -66.720634) (xy 209.5639 -66.72839) (xy 209.616202 -66.743746)
			(xy 209.665786 -66.76639) (xy 209.711642 -66.795859) (xy 209.752838 -66.831554) (xy 209.788535 -66.87275)
			(xy 209.818006 -66.918606) (xy 209.84065 -66.968189) (xy 209.856007 -67.020491) (xy 209.863765 -67.074445)
			(xy 209.863765 -67.128955) (xy 209.856007 -67.182909) (xy 209.84065 -67.235211) (xy 209.818006 -67.284794)
			(xy 209.788535 -67.33065) (xy 209.752838 -67.371846) (xy 209.711642 -67.407541) (xy 209.665786 -67.43701)
			(xy 209.616202 -67.459654) (xy 209.5639 -67.47501) (xy 209.509945 -67.482766) (xy 209.48269 -67.483228)
			(xy 209.455319 -67.482785) (xy 209.401138 -67.474965) (xy 209.348634 -67.459471) (xy 209.298887 -67.436624)
			(xy 209.252922 -67.406893) (xy 209.231992 -67.389248) (xy 209.231738 -67.388994) (xy 209.224645 -67.383417)
			(xy 209.207733 -67.377165) (xy 209.198718 -67.376802) (xy 209.131662 -67.376802) (xy 209.122643 -67.377141)
			(xy 209.105726 -67.383401) (xy 209.098642 -67.388994) (xy 209.098642 -67.389248) (xy 209.098388 -67.389248)
			(xy 209.077427 -67.406851) (xy 209.031463 -67.43657) (xy 208.981723 -67.459414) (xy 208.929228 -67.474913)
			(xy 208.875057 -67.48275) (xy 208.84769 -67.483228) (xy 208.820441 -67.482701) (xy 208.766497 -67.474944)
			(xy 208.714206 -67.459589) (xy 208.664633 -67.436948) (xy 208.618786 -67.407483) (xy 208.577599 -67.371794)
			(xy 208.541911 -67.330606) (xy 208.512447 -67.284758) (xy 208.489808 -67.235184) (xy 208.474454 -67.182893)
			(xy 208.466698 -67.128949) (xy 206.93717 -67.128949) (xy 206.865922 -67.488054) (xy 212.879176 -67.488054)
			(xy 212.883247 -67.432432) (xy 212.895373 -67.377995) (xy 212.915296 -67.325904) (xy 212.942592 -67.277269)
			(xy 212.976678 -67.233126) (xy 213.016827 -67.194417) (xy 213.062185 -67.161966) (xy 213.111785 -67.136465)
			(xy 213.164569 -67.118458) (xy 213.219412 -67.108328) (xy 213.275146 -67.106291) (xy 213.330583 -67.112391)
			(xy 213.38454 -67.126497) (xy 213.435869 -67.148309) (xy 213.483475 -67.177363) (xy 213.526343 -67.213038)
			(xy 213.56356 -67.254575) (xy 213.594333 -67.301088) (xy 213.618005 -67.351585) (xy 213.634073 -67.404992)
			(xy 213.642193 -67.460168) (xy 213.642702 -67.488054) (xy 213.642193 -67.51594) (xy 213.639008 -67.537584)
			(xy 214.171274 -67.537584) (xy 214.175345 -67.481962) (xy 214.187471 -67.427525) (xy 214.207394 -67.375434)
			(xy 214.23469 -67.326799) (xy 214.268776 -67.282656) (xy 214.308925 -67.243947) (xy 214.354283 -67.211496)
			(xy 214.403883 -67.185995) (xy 214.456667 -67.167988) (xy 214.51151 -67.157858) (xy 214.567244 -67.155821)
			(xy 214.622681 -67.161921) (xy 214.676638 -67.176027) (xy 214.727967 -67.197839) (xy 214.775573 -67.226893)
			(xy 214.818441 -67.262568) (xy 214.855658 -67.304105) (xy 214.886431 -67.350618) (xy 214.910103 -67.401115)
			(xy 214.926171 -67.454522) (xy 214.934291 -67.509698) (xy 214.9348 -67.537584) (xy 214.934291 -67.56547)
			(xy 214.930246 -67.592956) (xy 215.445338 -67.592956) (xy 215.449409 -67.537334) (xy 215.461535 -67.482897)
			(xy 215.481458 -67.430806) (xy 215.508754 -67.382171) (xy 215.54284 -67.338028) (xy 215.582989 -67.299319)
			(xy 215.628347 -67.266868) (xy 215.677947 -67.241367) (xy 215.730731 -67.22336) (xy 215.785574 -67.21323)
			(xy 215.841308 -67.211193) (xy 215.896745 -67.217293) (xy 215.950702 -67.231399) (xy 216.002031 -67.253211)
			(xy 216.049637 -67.282265) (xy 216.092505 -67.31794) (xy 216.129722 -67.359477) (xy 216.160495 -67.40599)
			(xy 216.184167 -67.456487) (xy 216.200235 -67.509894) (xy 216.208352 -67.565048) (xy 218.546716 -67.565048)
			(xy 218.546716 -67.510552) (xy 218.554471 -67.456612) (xy 218.569824 -67.404324) (xy 218.592461 -67.354753)
			(xy 218.621923 -67.308908) (xy 218.657609 -67.267723) (xy 218.698792 -67.232035) (xy 218.744636 -67.202571)
			(xy 218.794205 -67.179931) (xy 218.846492 -67.164576) (xy 218.900432 -67.156818) (xy 218.92768 -67.15633)
			(xy 218.95505 -67.1568) (xy 219.009229 -67.164616) (xy 219.061733 -67.180104) (xy 219.11148 -67.202945)
			(xy 219.157446 -67.232669) (xy 219.178378 -67.25031) (xy 219.178632 -67.250564) (xy 219.185728 -67.256136)
			(xy 219.202638 -67.26239) (xy 219.211652 -67.262756) (xy 219.278708 -67.262756) (xy 219.287726 -67.262412)
			(xy 219.304644 -67.256156) (xy 219.311728 -67.250564) (xy 219.311728 -67.25031) (xy 219.311982 -67.25031)
			(xy 219.332911 -67.232667) (xy 219.378885 -67.202956) (xy 219.428633 -67.18012) (xy 219.481134 -67.16463)
			(xy 219.535311 -67.156803) (xy 219.56268 -67.15633) (xy 219.589937 -67.156716) (xy 219.643895 -67.164471)
			(xy 219.696201 -67.179827) (xy 219.745788 -67.20247) (xy 219.791648 -67.231941) (xy 219.832848 -67.267638)
			(xy 219.868547 -67.308836) (xy 219.89802 -67.354694) (xy 219.920666 -67.404281) (xy 219.936025 -67.456585)
			(xy 219.943783 -67.510543) (xy 219.943783 -67.565057) (xy 219.936025 -67.619015) (xy 219.920666 -67.671319)
			(xy 219.89802 -67.720906) (xy 219.868547 -67.766764) (xy 219.832848 -67.807962) (xy 219.791648 -67.843659)
			(xy 219.745788 -67.87313) (xy 219.696201 -67.895773) (xy 219.643895 -67.911129) (xy 219.589937 -67.918884)
			(xy 219.56268 -67.919346) (xy 219.535309 -67.918905) (xy 219.481128 -67.911083) (xy 219.428624 -67.895589)
			(xy 219.378878 -67.872741) (xy 219.332912 -67.84301) (xy 219.311982 -67.825366) (xy 219.311728 -67.825112)
			(xy 219.304637 -67.819532) (xy 219.287724 -67.813281) (xy 219.278708 -67.81292) (xy 219.211652 -67.81292)
			(xy 219.202637 -67.813298) (xy 219.18572 -67.81953) (xy 219.178632 -67.825112) (xy 219.178632 -67.825366)
			(xy 219.178378 -67.825366) (xy 219.157423 -67.842977) (xy 219.111457 -67.872694) (xy 219.061715 -67.895536)
			(xy 219.00922 -67.911034) (xy 218.955048 -67.918869) (xy 218.92768 -67.919346) (xy 218.900432 -67.918782)
			(xy 218.846492 -67.911024) (xy 218.794205 -67.895669) (xy 218.744636 -67.873029) (xy 218.698792 -67.843565)
			(xy 218.657609 -67.807877) (xy 218.621923 -67.766692) (xy 218.592461 -67.720847) (xy 218.569824 -67.671276)
			(xy 218.554471 -67.618988) (xy 218.546716 -67.565048) (xy 216.208352 -67.565048) (xy 216.208355 -67.56507)
			(xy 216.208864 -67.592956) (xy 216.208355 -67.620842) (xy 216.200235 -67.676018) (xy 216.184167 -67.729425)
			(xy 216.160495 -67.779922) (xy 216.129722 -67.826435) (xy 216.092505 -67.867972) (xy 216.049637 -67.903647)
			(xy 216.002031 -67.932701) (xy 215.950702 -67.954513) (xy 215.896745 -67.968619) (xy 215.841308 -67.974719)
			(xy 215.785574 -67.972682) (xy 215.730731 -67.962552) (xy 215.677947 -67.944545) (xy 215.628347 -67.919044)
			(xy 215.582989 -67.886593) (xy 215.54284 -67.847884) (xy 215.508754 -67.803741) (xy 215.481458 -67.755106)
			(xy 215.461535 -67.703015) (xy 215.449409 -67.648578) (xy 215.445338 -67.592956) (xy 214.930246 -67.592956)
			(xy 214.926171 -67.620646) (xy 214.910103 -67.674053) (xy 214.886431 -67.72455) (xy 214.855658 -67.771063)
			(xy 214.818441 -67.8126) (xy 214.775573 -67.848275) (xy 214.727967 -67.877329) (xy 214.676638 -67.899141)
			(xy 214.622681 -67.913247) (xy 214.567244 -67.919347) (xy 214.51151 -67.91731) (xy 214.456667 -67.90718)
			(xy 214.403883 -67.889173) (xy 214.354283 -67.863672) (xy 214.308925 -67.831221) (xy 214.268776 -67.792512)
			(xy 214.23469 -67.748369) (xy 214.207394 -67.699734) (xy 214.187471 -67.647643) (xy 214.175345 -67.593206)
			(xy 214.171274 -67.537584) (xy 213.639008 -67.537584) (xy 213.634073 -67.571116) (xy 213.618005 -67.624523)
			(xy 213.594333 -67.67502) (xy 213.56356 -67.721533) (xy 213.526343 -67.76307) (xy 213.483475 -67.798745)
			(xy 213.435869 -67.827799) (xy 213.38454 -67.849611) (xy 213.330583 -67.863717) (xy 213.275146 -67.869817)
			(xy 213.219412 -67.86778) (xy 213.164569 -67.85765) (xy 213.111785 -67.839643) (xy 213.062185 -67.814142)
			(xy 213.016827 -67.781691) (xy 212.976678 -67.742982) (xy 212.942592 -67.698839) (xy 212.915296 -67.650204)
			(xy 212.895373 -67.598113) (xy 212.883247 -67.543676) (xy 212.879176 -67.488054) (xy 206.865922 -67.488054)
			(xy 206.647963 -68.586604) (xy 210.725258 -68.586604) (xy 210.725712 -68.559233) (xy 210.733531 -68.505053)
			(xy 210.749022 -68.452549) (xy 210.771867 -68.402803) (xy 210.801595 -68.356837) (xy 210.819238 -68.335906)
			(xy 210.819492 -68.335652) (xy 210.825062 -68.328554) (xy 210.831319 -68.311646) (xy 210.831684 -68.302632)
			(xy 210.831684 -68.235576) (xy 210.831342 -68.226558) (xy 210.825084 -68.209641) (xy 210.819492 -68.202556)
			(xy 210.819238 -68.202556) (xy 210.819238 -68.202302) (xy 210.801592 -68.181375) (xy 210.77188 -68.135401)
			(xy 210.749045 -68.085653) (xy 210.733555 -68.033151) (xy 210.72573 -67.978974) (xy 210.725258 -67.951604)
			(xy 210.725781 -67.924354) (xy 210.733536 -67.87041) (xy 210.748889 -67.818118) (xy 210.771528 -67.768543)
			(xy 210.80099 -67.722694) (xy 210.836678 -67.681505) (xy 210.877864 -67.645813) (xy 210.923709 -67.616346)
			(xy 210.973282 -67.593703) (xy 211.025573 -67.578345) (xy 211.079516 -67.570584) (xy 211.106766 -67.570096)
			(xy 211.133081 -67.570521) (xy 211.185212 -67.577764) (xy 211.235855 -67.592092) (xy 211.284054 -67.613233)
			(xy 211.328896 -67.640786) (xy 211.369534 -67.674231) (xy 211.38769 -67.693286) (xy 211.395215 -67.700683)
			(xy 211.414492 -67.709211) (xy 211.425028 -67.709796) (xy 211.499704 -67.709796) (xy 211.510256 -67.709284)
			(xy 211.529551 -67.700737) (xy 211.537042 -67.693286) (xy 211.555181 -67.674214) (xy 211.595815 -67.640759)
			(xy 211.640659 -67.613203) (xy 211.688863 -67.592067) (xy 211.739513 -67.577753) (xy 211.791649 -67.570532)
			(xy 211.817966 -67.570096) (xy 211.845335 -67.570583) (xy 211.899514 -67.578396) (xy 211.952016 -67.59388)
			(xy 212.001764 -67.616717) (xy 212.047732 -67.646437) (xy 212.068664 -67.664076) (xy 212.068918 -67.66433)
			(xy 212.075993 -67.669934) (xy 212.092919 -67.676169) (xy 212.101938 -67.676522) (xy 212.168994 -67.676522)
			(xy 212.17801 -67.676157) (xy 212.194927 -67.669914) (xy 212.202014 -67.66433) (xy 212.202014 -67.664076)
			(xy 212.202268 -67.664076) (xy 212.223198 -67.646435) (xy 212.269172 -67.616724) (xy 212.31892 -67.593889)
			(xy 212.371421 -67.578398) (xy 212.425597 -67.57057) (xy 212.452966 -67.570096) (xy 212.480218 -67.570587)
			(xy 212.534168 -67.578339) (xy 212.586466 -67.593691) (xy 212.636046 -67.61633) (xy 212.6819 -67.645795)
			(xy 212.723093 -67.681486) (xy 212.758787 -67.722676) (xy 212.788255 -67.768527) (xy 212.810898 -67.818106)
			(xy 212.826254 -67.870402) (xy 212.834011 -67.924352) (xy 212.834474 -67.951604) (xy 212.834017 -67.978975)
			(xy 212.826198 -68.033154) (xy 212.810707 -68.085658) (xy 212.787863 -68.135405) (xy 212.758136 -68.181371)
			(xy 212.740494 -68.202302) (xy 212.74024 -68.202556) (xy 212.734659 -68.209646) (xy 212.72841 -68.22656)
			(xy 212.728048 -68.235576) (xy 212.728048 -68.302632) (xy 212.728379 -68.311652) (xy 212.734643 -68.328569)
			(xy 212.74024 -68.335652) (xy 212.740494 -68.335652) (xy 212.740494 -68.335906) (xy 212.758148 -68.356826)
			(xy 212.787858 -68.402802) (xy 212.810691 -68.452552) (xy 212.826179 -68.505056) (xy 212.834002 -68.559234)
			(xy 212.834474 -68.586604) (xy 212.834048 -68.613858) (xy 212.82629 -68.667813) (xy 212.810932 -68.720113)
			(xy 212.794299 -68.75653) (xy 216.270332 -68.75653) (xy 216.270808 -68.72916) (xy 216.278622 -68.674981)
			(xy 216.294108 -68.622478) (xy 216.316948 -68.572731) (xy 216.346671 -68.526764) (xy 216.364312 -68.505832)
			(xy 216.364566 -68.505578) (xy 216.370176 -68.498508) (xy 216.376407 -68.481578) (xy 216.376758 -68.472558)
			(xy 216.376758 -68.405502) (xy 216.376409 -68.396484) (xy 216.370157 -68.379567) (xy 216.364566 -68.372482)
			(xy 216.364312 -68.372482) (xy 216.364312 -68.372228) (xy 216.346674 -68.351295) (xy 216.316962 -68.305322)
			(xy 216.294126 -68.255575) (xy 216.278634 -68.203075) (xy 216.270806 -68.148899) (xy 216.270332 -68.12153)
			(xy 216.270783 -68.094276) (xy 216.278537 -68.040323) (xy 216.293892 -67.988022) (xy 216.316533 -67.938439)
			(xy 216.346002 -67.892584) (xy 216.381697 -67.85139) (xy 216.422892 -67.815696) (xy 216.468748 -67.786229)
			(xy 216.518331 -67.763588) (xy 216.570632 -67.748235) (xy 216.624586 -67.740483) (xy 216.65184 -67.740022)
			(xy 216.679209 -67.740518) (xy 216.733387 -67.748328) (xy 216.78589 -67.76381) (xy 216.835638 -67.786645)
			(xy 216.881606 -67.816363) (xy 216.902538 -67.834002) (xy 216.902792 -67.834256) (xy 216.909872 -67.839852)
			(xy 216.926794 -67.846092) (xy 216.935812 -67.846448) (xy 217.002868 -67.846448) (xy 217.011885 -67.846087)
			(xy 217.028802 -67.839843) (xy 217.035888 -67.834256) (xy 217.035888 -67.834002) (xy 217.036142 -67.834002)
			(xy 217.057085 -67.816377) (xy 217.103055 -67.786663) (xy 217.1528 -67.763824) (xy 217.205298 -67.74833)
			(xy 217.259472 -67.740498) (xy 217.28684 -67.740022) (xy 217.313155 -67.740456) (xy 217.365285 -67.747696)
			(xy 217.415929 -67.762022) (xy 217.464128 -67.78316) (xy 217.508971 -67.810713) (xy 217.549609 -67.844158)
			(xy 217.567764 -67.863212) (xy 217.575295 -67.870602) (xy 217.594568 -67.879133) (xy 217.605102 -67.879722)
			(xy 217.679778 -67.879722) (xy 217.690327 -67.879188) (xy 217.709622 -67.870655) (xy 217.717116 -67.863212)
			(xy 217.735273 -67.844158) (xy 217.775902 -67.8107) (xy 217.820742 -67.783141) (xy 217.868943 -67.762002)
			(xy 217.91959 -67.747685) (xy 217.971724 -67.74046) (xy 217.99804 -67.740022) (xy 218.025294 -67.740441)
			(xy 218.079245 -67.748203) (xy 218.131543 -67.763565) (xy 218.181122 -67.786213) (xy 218.226974 -67.815686)
			(xy 218.268165 -67.851385) (xy 218.303856 -67.892582) (xy 218.33332 -67.938439) (xy 218.355959 -67.988023)
			(xy 218.371311 -68.040323) (xy 218.379064 -68.094276) (xy 218.379548 -68.12153) (xy 218.379112 -68.148901)
			(xy 218.371289 -68.203082) (xy 218.355794 -68.255586) (xy 218.332945 -68.305333) (xy 218.303213 -68.351298)
			(xy 218.285568 -68.372228) (xy 218.285314 -68.372482) (xy 218.27973 -68.379571) (xy 218.273481 -68.396486)
			(xy 218.273122 -68.405502) (xy 218.273122 -68.472558) (xy 218.273494 -68.481573) (xy 218.279731 -68.498491)
			(xy 218.285314 -68.505578) (xy 218.285568 -68.505578) (xy 218.285568 -68.505832) (xy 218.303184 -68.526783)
			(xy 218.3329 -68.57275) (xy 218.355741 -68.622493) (xy 218.371238 -68.674989) (xy 218.379071 -68.729162)
			(xy 218.379548 -68.75653) (xy 218.37905 -68.78378) (xy 218.371291 -68.837725) (xy 218.355934 -68.890017)
			(xy 218.333292 -68.939592) (xy 218.303826 -68.98544) (xy 218.268136 -69.026629) (xy 218.226948 -69.06232)
			(xy 218.181101 -69.091787) (xy 218.131527 -69.11443) (xy 218.079235 -69.129789) (xy 218.02529 -69.13755)
			(xy 217.99804 -69.138038) (xy 217.971724 -69.13763) (xy 217.919592 -69.130386) (xy 217.868947 -69.116057)
			(xy 217.820748 -69.094913) (xy 217.775906 -69.067355) (xy 217.73527 -69.033905) (xy 217.717116 -69.014848)
			(xy 217.709584 -69.007459) (xy 217.690312 -68.998926) (xy 217.679778 -68.998338) (xy 217.605102 -68.998338)
			(xy 217.594549 -68.998843) (xy 217.575253 -69.007394) (xy 217.567764 -69.014848) (xy 217.549628 -69.033923)
			(xy 217.508993 -69.067377) (xy 217.464148 -69.094932) (xy 217.415944 -69.116067) (xy 217.365294 -69.13038)
			(xy 217.313157 -69.137601) (xy 217.28684 -69.138038) (xy 217.25947 -69.137564) (xy 217.205291 -69.12975)
			(xy 217.152787 -69.114264) (xy 217.10304 -69.091424) (xy 217.057073 -69.061699) (xy 217.036142 -69.044058)
			(xy 217.035888 -69.043804) (xy 217.028809 -69.038207) (xy 217.011886 -69.031966) (xy 217.002868 -69.031612)
			(xy 216.935812 -69.031612) (xy 216.926795 -69.031972) (xy 216.909878 -69.038217) (xy 216.902792 -69.043804)
			(xy 216.902792 -69.044058) (xy 216.902538 -69.044058) (xy 216.881597 -69.061686) (xy 216.835627 -69.091401)
			(xy 216.785882 -69.11424) (xy 216.733383 -69.129733) (xy 216.679209 -69.137563) (xy 216.65184 -69.138038)
			(xy 216.624589 -69.137508) (xy 216.570643 -69.129757) (xy 216.518348 -69.114407) (xy 216.46877 -69.091772)
			(xy 216.422918 -69.062311) (xy 216.381726 -69.026624) (xy 216.346031 -68.985438) (xy 216.316562 -68.939592)
			(xy 216.293917 -68.890018) (xy 216.278558 -68.837726) (xy 216.270797 -68.78378) (xy 216.270332 -68.75653)
			(xy 212.794299 -68.75653) (xy 212.788286 -68.769696) (xy 212.758815 -68.81555) (xy 212.723117 -68.856744)
			(xy 212.68192 -68.892437) (xy 212.636062 -68.921904) (xy 212.586478 -68.944545) (xy 212.534175 -68.959898)
			(xy 212.480221 -68.967651) (xy 212.452966 -68.968112) (xy 212.425595 -68.967663) (xy 212.371416 -68.959841)
			(xy 212.318912 -68.944347) (xy 212.269166 -68.921502) (xy 212.223199 -68.891774) (xy 212.202268 -68.874132)
			(xy 212.202014 -68.873878) (xy 212.194929 -68.868289) (xy 212.178011 -68.862044) (xy 212.168994 -68.861686)
			(xy 212.101938 -68.861686) (xy 212.092923 -68.862064) (xy 212.076006 -68.868297) (xy 212.068918 -68.873878)
			(xy 212.068918 -68.874132) (xy 212.068664 -68.874132) (xy 212.047723 -68.89176) (xy 212.001752 -68.921472)
			(xy 211.952007 -68.94431) (xy 211.899508 -68.959804) (xy 211.845334 -68.967636) (xy 211.817966 -68.968112)
			(xy 211.791651 -68.967663) (xy 211.739522 -68.960424) (xy 211.688879 -68.946101) (xy 211.640681 -68.924965)
			(xy 211.595837 -68.897416) (xy 211.555198 -68.863975) (xy 211.537042 -68.844922) (xy 211.529504 -68.83754)
			(xy 211.510236 -68.829004) (xy 211.499704 -68.828412) (xy 211.425028 -68.828412) (xy 211.414478 -68.828939)
			(xy 211.395182 -68.837475) (xy 211.38769 -68.844922) (xy 211.369537 -68.86398) (xy 211.328906 -68.897436)
			(xy 211.284065 -68.924994) (xy 211.235864 -68.946132) (xy 211.185216 -68.960449) (xy 211.133082 -68.967673)
			(xy 211.106766 -68.968112) (xy 211.079514 -68.967654) (xy 211.025566 -68.959893) (xy 210.973271 -68.944534)
			(xy 210.923693 -68.921889) (xy 210.877843 -68.892419) (xy 210.836654 -68.856725) (xy 210.800963 -68.815532)
			(xy 210.771497 -68.76968) (xy 210.748856 -68.720101) (xy 210.733501 -68.667805) (xy 210.725744 -68.613856)
			(xy 210.725258 -68.586604) (xy 206.647963 -68.586604) (xy 206.058845 -71.555864) (xy 213.294466 -71.555864)
			(xy 213.298537 -71.500242) (xy 213.310663 -71.445805) (xy 213.330586 -71.393714) (xy 213.357882 -71.345079)
			(xy 213.391968 -71.300936) (xy 213.432117 -71.262227) (xy 213.477475 -71.229776) (xy 213.527075 -71.204275)
			(xy 213.579859 -71.186268) (xy 213.634702 -71.176138) (xy 213.690436 -71.174101) (xy 213.745873 -71.180201)
			(xy 213.79983 -71.194307) (xy 213.851159 -71.216119) (xy 213.898765 -71.245173) (xy 213.941633 -71.280848)
			(xy 213.97885 -71.322385) (xy 214.009623 -71.368898) (xy 214.033295 -71.419395) (xy 214.049363 -71.472802)
			(xy 214.057483 -71.527978) (xy 214.057992 -71.555864) (xy 214.057483 -71.58375) (xy 214.051644 -71.623428)
			(xy 214.80348 -71.623428) (xy 214.807551 -71.567806) (xy 214.819677 -71.513369) (xy 214.8396 -71.461278)
			(xy 214.866896 -71.412643) (xy 214.900982 -71.3685) (xy 214.941131 -71.329791) (xy 214.986489 -71.29734)
			(xy 215.036089 -71.271839) (xy 215.088873 -71.253832) (xy 215.143716 -71.243702) (xy 215.19945 -71.241665)
			(xy 215.254887 -71.247765) (xy 215.308844 -71.261871) (xy 215.360173 -71.283683) (xy 215.407779 -71.312737)
			(xy 215.450647 -71.348412) (xy 215.487864 -71.389949) (xy 215.518637 -71.436462) (xy 215.542309 -71.486959)
			(xy 215.558377 -71.540366) (xy 215.566497 -71.595542) (xy 215.567006 -71.623428) (xy 215.566497 -71.651314)
			(xy 215.558377 -71.70649) (xy 215.542309 -71.759897) (xy 215.518637 -71.810394) (xy 215.487864 -71.856907)
			(xy 215.450647 -71.898444) (xy 215.407779 -71.934119) (xy 215.360173 -71.963173) (xy 215.308844 -71.984985)
			(xy 215.254887 -71.999091) (xy 215.19945 -72.005191) (xy 215.143716 -72.003154) (xy 215.088873 -71.993024)
			(xy 215.036089 -71.975017) (xy 214.986489 -71.949516) (xy 214.941131 -71.917065) (xy 214.900982 -71.878356)
			(xy 214.866896 -71.834213) (xy 214.8396 -71.785578) (xy 214.819677 -71.733487) (xy 214.807551 -71.67905)
			(xy 214.80348 -71.623428) (xy 214.051644 -71.623428) (xy 214.049363 -71.638926) (xy 214.033295 -71.692333)
			(xy 214.009623 -71.74283) (xy 213.97885 -71.789343) (xy 213.941633 -71.83088) (xy 213.898765 -71.866555)
			(xy 213.851159 -71.895609) (xy 213.79983 -71.917421) (xy 213.745873 -71.931527) (xy 213.690436 -71.937627)
			(xy 213.634702 -71.93559) (xy 213.579859 -71.92546) (xy 213.527075 -71.907453) (xy 213.477475 -71.881952)
			(xy 213.432117 -71.849501) (xy 213.391968 -71.810792) (xy 213.357882 -71.766649) (xy 213.330586 -71.718014)
			(xy 213.310663 -71.665923) (xy 213.298537 -71.611486) (xy 213.294466 -71.555864) (xy 206.058845 -71.555864)
			(xy 205.07579 -76.510642) (xy 205.07833 -76.519532) (xy 205.078584 -76.520294) (xy 205.078584 -76.520548)
			(xy 205.079092 -76.522326) (xy 205.085538 -76.546721) (xy 205.092676 -76.59667) (xy 205.093316 -76.621894)
			(xy 205.093316 -76.628498) (xy 205.092765 -76.652726) (xy 205.086272 -76.700753) (xy 205.080362 -76.724256)
			(xy 205.073536 -76.748199) (xy 205.05451 -76.794209) (xy 205.029652 -76.837347) (xy 205.01483 -76.857352)
			(xy 205.012036 -76.861162) (xy 205.00467 -76.87691) (xy 205.00086 -76.888594) (xy 204.866979 -77.563472)
			(xy 205.228442 -77.563472) (xy 205.232513 -77.50785) (xy 205.244639 -77.453413) (xy 205.264562 -77.401322)
			(xy 205.291858 -77.352687) (xy 205.325944 -77.308544) (xy 205.366093 -77.269835) (xy 205.411451 -77.237384)
			(xy 205.461051 -77.211883) (xy 205.513835 -77.193876) (xy 205.568678 -77.183746) (xy 205.624412 -77.181709)
			(xy 205.679849 -77.187809) (xy 205.733806 -77.201915) (xy 205.785135 -77.223727) (xy 205.832741 -77.252781)
			(xy 205.875609 -77.288456) (xy 205.912826 -77.329993) (xy 205.943599 -77.376506) (xy 205.967271 -77.427003)
			(xy 205.983339 -77.48041) (xy 205.991459 -77.535586) (xy 205.991968 -77.563472) (xy 207.251806 -77.563472)
			(xy 207.255877 -77.50785) (xy 207.268003 -77.453413) (xy 207.287926 -77.401322) (xy 207.315222 -77.352687)
			(xy 207.349308 -77.308544) (xy 207.389457 -77.269835) (xy 207.434815 -77.237384) (xy 207.484415 -77.211883)
			(xy 207.537199 -77.193876) (xy 207.592042 -77.183746) (xy 207.647776 -77.181709) (xy 207.703213 -77.187809)
			(xy 207.75717 -77.201915) (xy 207.808499 -77.223727) (xy 207.856105 -77.252781) (xy 207.898973 -77.288456)
			(xy 207.93619 -77.329993) (xy 207.966963 -77.376506) (xy 207.990635 -77.427003) (xy 208.006703 -77.48041)
			(xy 208.014823 -77.535586) (xy 208.015332 -77.563472) (xy 208.014823 -77.591358) (xy 208.006703 -77.646534)
			(xy 207.990635 -77.699941) (xy 207.966963 -77.750438) (xy 207.93619 -77.796951) (xy 207.898973 -77.838488)
			(xy 207.856105 -77.874163) (xy 207.808499 -77.903217) (xy 207.75717 -77.925029) (xy 207.703213 -77.939135)
			(xy 207.647776 -77.945235) (xy 207.592042 -77.943198) (xy 207.537199 -77.933068) (xy 207.484415 -77.915061)
			(xy 207.434815 -77.88956) (xy 207.389457 -77.857109) (xy 207.349308 -77.8184) (xy 207.315222 -77.774257)
			(xy 207.287926 -77.725622) (xy 207.268003 -77.673531) (xy 207.255877 -77.619094) (xy 207.251806 -77.563472)
			(xy 205.991968 -77.563472) (xy 205.991459 -77.591358) (xy 205.983339 -77.646534) (xy 205.967271 -77.699941)
			(xy 205.943599 -77.750438) (xy 205.912826 -77.796951) (xy 205.875609 -77.838488) (xy 205.832741 -77.874163)
			(xy 205.785135 -77.903217) (xy 205.733806 -77.925029) (xy 205.679849 -77.939135) (xy 205.624412 -77.945235)
			(xy 205.568678 -77.943198) (xy 205.513835 -77.933068) (xy 205.461051 -77.915061) (xy 205.411451 -77.88956)
			(xy 205.366093 -77.857109) (xy 205.325944 -77.8184) (xy 205.291858 -77.774257) (xy 205.264562 -77.725622)
			(xy 205.244639 -77.673531) (xy 205.232513 -77.619094) (xy 205.228442 -77.563472) (xy 204.866979 -77.563472)
			(xy 204.603146 -78.893416) (xy 205.222856 -78.893416) (xy 205.223342 -78.866165) (xy 205.231098 -78.812217)
			(xy 205.246453 -78.759922) (xy 205.269095 -78.710345) (xy 205.298561 -78.664495) (xy 205.334252 -78.623304)
			(xy 205.375443 -78.587613) (xy 205.421293 -78.558147) (xy 205.47087 -78.535505) (xy 205.523165 -78.52015)
			(xy 205.577113 -78.512394) (xy 205.631615 -78.512394) (xy 205.685563 -78.52015) (xy 205.737858 -78.535505)
			(xy 205.787435 -78.558147) (xy 205.820617 -78.579472) (xy 208.52714 -78.579472) (xy 208.531211 -78.52385)
			(xy 208.543337 -78.469413) (xy 208.56326 -78.417322) (xy 208.590556 -78.368687) (xy 208.624642 -78.324544)
			(xy 208.664791 -78.285835) (xy 208.710149 -78.253384) (xy 208.759749 -78.227883) (xy 208.812533 -78.209876)
			(xy 208.867376 -78.199746) (xy 208.92311 -78.197709) (xy 208.978547 -78.203809) (xy 209.032504 -78.217915)
			(xy 209.083833 -78.239727) (xy 209.131439 -78.268781) (xy 209.174307 -78.304456) (xy 209.211524 -78.345993)
			(xy 209.242297 -78.392506) (xy 209.265969 -78.443003) (xy 209.282037 -78.49641) (xy 209.290157 -78.551586)
			(xy 209.290666 -78.579472) (xy 209.290157 -78.607358) (xy 209.282037 -78.662534) (xy 209.265969 -78.715941)
			(xy 209.242297 -78.766438) (xy 209.211524 -78.812951) (xy 209.174307 -78.854488) (xy 209.131439 -78.890163)
			(xy 209.083833 -78.919217) (xy 209.032504 -78.941029) (xy 208.978547 -78.955135) (xy 208.92311 -78.961235)
			(xy 208.867376 -78.959198) (xy 208.812533 -78.949068) (xy 208.759749 -78.931061) (xy 208.710149 -78.90556)
			(xy 208.664791 -78.873109) (xy 208.624642 -78.8344) (xy 208.590556 -78.790257) (xy 208.56326 -78.741622)
			(xy 208.543337 -78.689531) (xy 208.531211 -78.635094) (xy 208.52714 -78.579472) (xy 205.820617 -78.579472)
			(xy 205.833285 -78.587613) (xy 205.874476 -78.623304) (xy 205.910167 -78.664495) (xy 205.939633 -78.710345)
			(xy 205.962275 -78.759922) (xy 205.97763 -78.812217) (xy 205.985386 -78.866165) (xy 205.985872 -78.893416)
			(xy 205.985368 -78.920818) (xy 205.977525 -78.975057) (xy 205.962002 -79.027617) (xy 205.939119 -79.077414)
			(xy 205.909346 -79.123425) (xy 205.873296 -79.164703) (xy 205.831712 -79.200399) (xy 205.808834 -79.215488)
			(xy 205.796619 -79.223762) (xy 205.77725 -79.246004) (xy 205.765038 -79.27285) (xy 205.761002 -79.302066)
			(xy 205.765476 -79.331218) (xy 205.778088 -79.357878) (xy 205.797789 -79.379827) (xy 205.810104 -79.387954)
			(xy 205.833506 -79.402938) (xy 205.876109 -79.438611) (xy 205.913087 -79.480087) (xy 205.943657 -79.526489)
			(xy 205.967172 -79.576835) (xy 205.972761 -79.595472) (xy 207.251806 -79.595472) (xy 207.255877 -79.53985)
			(xy 207.268003 -79.485413) (xy 207.287926 -79.433322) (xy 207.315222 -79.384687) (xy 207.349308 -79.340544)
			(xy 207.389457 -79.301835) (xy 207.434815 -79.269384) (xy 207.484415 -79.243883) (xy 207.537199 -79.225876)
			(xy 207.592042 -79.215746) (xy 207.647776 -79.213709) (xy 207.703213 -79.219809) (xy 207.75717 -79.233915)
			(xy 207.808499 -79.255727) (xy 207.856105 -79.284781) (xy 207.898973 -79.320456) (xy 207.93619 -79.361993)
			(xy 207.966963 -79.408506) (xy 207.990635 -79.459003) (xy 208.006703 -79.51241) (xy 208.014823 -79.567586)
			(xy 208.015332 -79.595472) (xy 208.014823 -79.623358) (xy 208.006703 -79.678534) (xy 207.990635 -79.731941)
			(xy 207.966963 -79.782438) (xy 207.93619 -79.828951) (xy 207.898973 -79.870488) (xy 207.856105 -79.906163)
			(xy 207.808499 -79.935217) (xy 207.75717 -79.957029) (xy 207.703213 -79.971135) (xy 207.647776 -79.977235)
			(xy 207.592042 -79.975198) (xy 207.537199 -79.965068) (xy 207.484415 -79.947061) (xy 207.434815 -79.92156)
			(xy 207.389457 -79.889109) (xy 207.349308 -79.8504) (xy 207.315222 -79.806257) (xy 207.287926 -79.757622)
			(xy 207.268003 -79.705531) (xy 207.255877 -79.651094) (xy 207.251806 -79.595472) (xy 205.972761 -79.595472)
			(xy 205.983134 -79.63006) (xy 205.991207 -79.685037) (xy 205.991714 -79.71282) (xy 205.991228 -79.740071)
			(xy 205.983472 -79.794019) (xy 205.968117 -79.846314) (xy 205.945475 -79.895891) (xy 205.916009 -79.941741)
			(xy 205.880318 -79.982932) (xy 205.839127 -80.018623) (xy 205.793277 -80.048089) (xy 205.7437 -80.070731)
			(xy 205.691405 -80.086086) (xy 205.637457 -80.093842) (xy 205.582955 -80.093842) (xy 205.529007 -80.086086)
			(xy 205.476712 -80.070731) (xy 205.427135 -80.048089) (xy 205.381285 -80.018623) (xy 205.340094 -79.982932)
			(xy 205.304403 -79.941741) (xy 205.274937 -79.895891) (xy 205.252295 -79.846314) (xy 205.23694 -79.794019)
			(xy 205.229184 -79.740071) (xy 205.228698 -79.71282) (xy 205.22912 -79.685415) (xy 205.236974 -79.63117)
			(xy 205.252509 -79.578608) (xy 205.275405 -79.528809) (xy 205.305191 -79.482798) (xy 205.341254 -79.441523)
			(xy 205.382852 -79.405833) (xy 205.405736 -79.390748) (xy 205.417919 -79.382429) (xy 205.437292 -79.360199)
			(xy 205.449509 -79.333362) (xy 205.453552 -79.304153) (xy 205.449083 -79.275007) (xy 205.436475 -79.248351)
			(xy 205.416779 -79.226407) (xy 205.404466 -79.218282) (xy 205.381051 -79.203317) (xy 205.338444 -79.167644)
			(xy 205.301465 -79.126165) (xy 205.270895 -79.07976) (xy 205.247382 -79.02941) (xy 205.231425 -78.976181)
			(xy 205.223359 -78.921201) (xy 205.222856 -78.893416) (xy 204.603146 -78.893416) (xy 204.484986 -79.489046)
			(xy 204.262268 -80.611472) (xy 205.228442 -80.611472) (xy 205.232513 -80.55585) (xy 205.244639 -80.501413)
			(xy 205.264562 -80.449322) (xy 205.291858 -80.400687) (xy 205.325944 -80.356544) (xy 205.366093 -80.317835)
			(xy 205.411451 -80.285384) (xy 205.461051 -80.259883) (xy 205.513835 -80.241876) (xy 205.568678 -80.231746)
			(xy 205.624412 -80.229709) (xy 205.679849 -80.235809) (xy 205.733806 -80.249915) (xy 205.785135 -80.271727)
			(xy 205.832741 -80.300781) (xy 205.875609 -80.336456) (xy 205.912826 -80.377993) (xy 205.943599 -80.424506)
			(xy 205.967271 -80.475003) (xy 205.983339 -80.52841) (xy 205.991459 -80.583586) (xy 205.991968 -80.611472)
			(xy 205.991459 -80.639358) (xy 205.983339 -80.694534) (xy 205.967271 -80.747941) (xy 205.943599 -80.798438)
			(xy 205.912826 -80.844951) (xy 205.875609 -80.886488) (xy 205.832741 -80.922163) (xy 205.785135 -80.951217)
			(xy 205.733806 -80.973029) (xy 205.679849 -80.987135) (xy 205.624412 -80.993235) (xy 205.568678 -80.991198)
			(xy 205.513835 -80.981068) (xy 205.461051 -80.963061) (xy 205.411451 -80.93756) (xy 205.366093 -80.905109)
			(xy 205.325944 -80.8664) (xy 205.291858 -80.822257) (xy 205.264562 -80.773622) (xy 205.244639 -80.721531)
			(xy 205.232513 -80.667094) (xy 205.228442 -80.611472) (xy 204.262268 -80.611472) (xy 204.149775 -81.1784)
			(xy 207.161382 -81.1784) (xy 207.165453 -81.122778) (xy 207.177579 -81.068341) (xy 207.197502 -81.01625)
			(xy 207.224798 -80.967615) (xy 207.258884 -80.923472) (xy 207.299033 -80.884763) (xy 207.344391 -80.852312)
			(xy 207.393991 -80.826811) (xy 207.446775 -80.808804) (xy 207.501618 -80.798674) (xy 207.557352 -80.796637)
			(xy 207.612789 -80.802737) (xy 207.666746 -80.816843) (xy 207.718075 -80.838655) (xy 207.765681 -80.867709)
			(xy 207.808549 -80.903384) (xy 207.845766 -80.944921) (xy 207.876539 -80.991434) (xy 207.900211 -81.041931)
			(xy 207.916279 -81.095338) (xy 207.924399 -81.150514) (xy 207.924908 -81.1784) (xy 207.924399 -81.206286)
			(xy 207.916279 -81.261462) (xy 207.900211 -81.314869) (xy 207.876539 -81.365366) (xy 207.845766 -81.411879)
			(xy 207.808549 -81.453416) (xy 207.765681 -81.489091) (xy 207.718075 -81.518145) (xy 207.666746 -81.539957)
			(xy 207.612789 -81.554063) (xy 207.557352 -81.560163) (xy 207.501618 -81.558126) (xy 207.446775 -81.547996)
			(xy 207.393991 -81.529989) (xy 207.344391 -81.504488) (xy 207.299033 -81.472037) (xy 207.258884 -81.433328)
			(xy 207.224798 -81.389185) (xy 207.197502 -81.34055) (xy 207.177579 -81.288459) (xy 207.165453 -81.234022)
			(xy 207.161382 -81.1784) (xy 204.149775 -81.1784) (xy 204.060667 -81.627472) (xy 205.228442 -81.627472)
			(xy 205.232513 -81.57185) (xy 205.244639 -81.517413) (xy 205.264562 -81.465322) (xy 205.291858 -81.416687)
			(xy 205.325944 -81.372544) (xy 205.366093 -81.333835) (xy 205.411451 -81.301384) (xy 205.461051 -81.275883)
			(xy 205.513835 -81.257876) (xy 205.568678 -81.247746) (xy 205.624412 -81.245709) (xy 205.679849 -81.251809)
			(xy 205.733806 -81.265915) (xy 205.785135 -81.287727) (xy 205.832741 -81.316781) (xy 205.875609 -81.352456)
			(xy 205.912826 -81.393993) (xy 205.943599 -81.440506) (xy 205.967271 -81.491003) (xy 205.983339 -81.54441)
			(xy 205.991459 -81.599586) (xy 205.991968 -81.627472) (xy 205.991459 -81.655358) (xy 205.983339 -81.710534)
			(xy 205.967271 -81.763941) (xy 205.943599 -81.814438) (xy 205.912826 -81.860951) (xy 205.875609 -81.902488)
			(xy 205.832741 -81.938163) (xy 205.785135 -81.967217) (xy 205.733806 -81.989029) (xy 205.679849 -82.003135)
			(xy 205.624412 -82.009235) (xy 205.568678 -82.007198) (xy 205.513835 -81.997068) (xy 205.461051 -81.979061)
			(xy 205.411451 -81.95356) (xy 205.366093 -81.921109) (xy 205.325944 -81.8824) (xy 205.291858 -81.838257)
			(xy 205.264562 -81.789622) (xy 205.244639 -81.737531) (xy 205.232513 -81.683094) (xy 205.228442 -81.627472)
			(xy 204.060667 -81.627472) (xy 203.859066 -82.643472) (xy 205.228442 -82.643472) (xy 205.232513 -82.58785)
			(xy 205.244639 -82.533413) (xy 205.264562 -82.481322) (xy 205.291858 -82.432687) (xy 205.325944 -82.388544)
			(xy 205.366093 -82.349835) (xy 205.411451 -82.317384) (xy 205.461051 -82.291883) (xy 205.513835 -82.273876)
			(xy 205.568678 -82.263746) (xy 205.624412 -82.261709) (xy 205.679849 -82.267809) (xy 205.733806 -82.281915)
			(xy 205.785135 -82.303727) (xy 205.832741 -82.332781) (xy 205.875609 -82.368456) (xy 205.912826 -82.409993)
			(xy 205.943599 -82.456506) (xy 205.967271 -82.507003) (xy 205.983339 -82.56041) (xy 205.991459 -82.615586)
			(xy 205.991968 -82.643472) (xy 205.991459 -82.671358) (xy 205.983339 -82.726534) (xy 205.967271 -82.779941)
			(xy 205.943599 -82.830438) (xy 205.912826 -82.876951) (xy 205.875609 -82.918488) (xy 205.832741 -82.954163)
			(xy 205.785135 -82.983217) (xy 205.733806 -83.005029) (xy 205.679849 -83.019135) (xy 205.624412 -83.025235)
			(xy 205.568678 -83.023198) (xy 205.513835 -83.013068) (xy 205.461051 -82.995061) (xy 205.411451 -82.96956)
			(xy 205.366093 -82.937109) (xy 205.325944 -82.8984) (xy 205.291858 -82.854257) (xy 205.264562 -82.805622)
			(xy 205.244639 -82.753531) (xy 205.232513 -82.699094) (xy 205.228442 -82.643472) (xy 203.859066 -82.643472)
			(xy 203.851002 -82.684112) (xy 203.852018 -82.688938) (xy 203.85278 -82.692494) (xy 203.853034 -82.694018)
			(xy 203.856396 -82.71231) (xy 203.859961 -82.749334) (xy 203.860146 -82.767932) (xy 203.860146 -82.775298)
			(xy 203.859329 -82.798816) (xy 203.852643 -82.845396) (xy 203.840285 -82.890803) (xy 203.831698 -82.912712)
			(xy 203.824811 -82.929105) (xy 203.808398 -82.960651) (xy 203.798932 -82.975704) (xy 203.796392 -82.979768)
			(xy 203.790804 -82.992976) (xy 203.787756 -83.002882) (xy 203.602498 -83.93684) (xy 205.22057 -83.93684)
			(xy 205.22057 -83.936586) (xy 205.221056 -83.909335) (xy 205.228812 -83.855387) (xy 205.244167 -83.803092)
			(xy 205.266809 -83.753515) (xy 205.296275 -83.707665) (xy 205.331966 -83.666474) (xy 205.373157 -83.630783)
			(xy 205.419007 -83.601317) (xy 205.468584 -83.578675) (xy 205.520879 -83.56332) (xy 205.574827 -83.555564)
			(xy 205.629329 -83.555564) (xy 205.683277 -83.56332) (xy 205.735572 -83.578675) (xy 205.785149 -83.601317)
			(xy 205.830999 -83.630783) (xy 205.87219 -83.666474) (xy 205.907881 -83.707665) (xy 205.937347 -83.753515)
			(xy 205.959989 -83.803092) (xy 205.975344 -83.855387) (xy 205.9831 -83.909335) (xy 205.983586 -83.936586)
			(xy 205.98313 -83.963925) (xy 205.975343 -84.018044) (xy 205.95991 -84.070498) (xy 205.937149 -84.120212)
			(xy 205.907526 -84.166168) (xy 205.871646 -84.207426) (xy 205.851252 -84.225638) (xy 205.842616 -84.23275)
			(xy 205.833472 -84.253324) (xy 205.834488 -84.353654) (xy 205.84414 -84.373466) (xy 205.85303 -84.380832)
			(xy 205.874382 -84.399018) (xy 205.911993 -84.440622) (xy 205.943101 -84.487289) (xy 205.967035 -84.538011)
			(xy 205.983278 -84.591693) (xy 205.99148 -84.647175) (xy 205.991968 -84.675218) (xy 205.991968 -84.675472)
			(xy 205.991482 -84.702723) (xy 205.983726 -84.756671) (xy 205.968371 -84.808966) (xy 205.945729 -84.858543)
			(xy 205.916263 -84.904393) (xy 205.880572 -84.945584) (xy 205.839381 -84.981275) (xy 205.793531 -85.010741)
			(xy 205.743954 -85.033383) (xy 205.691659 -85.048738) (xy 205.637711 -85.056494) (xy 205.583209 -85.056494)
			(xy 205.529261 -85.048738) (xy 205.476966 -85.033383) (xy 205.427389 -85.010741) (xy 205.381539 -84.981275)
			(xy 205.340348 -84.945584) (xy 205.304657 -84.904393) (xy 205.275191 -84.858543) (xy 205.252549 -84.808966)
			(xy 205.237194 -84.756671) (xy 205.229438 -84.702723) (xy 205.228952 -84.675472) (xy 205.2294 -84.648133)
			(xy 205.237192 -84.594015) (xy 205.252628 -84.541562) (xy 205.27539 -84.491848) (xy 205.305014 -84.445892)
			(xy 205.340893 -84.404633) (xy 205.361286 -84.38642) (xy 205.369922 -84.379308) (xy 205.379066 -84.358734)
			(xy 205.37805 -84.258404) (xy 205.368398 -84.238592) (xy 205.359508 -84.231226) (xy 205.338172 -84.213024)
			(xy 205.300562 -84.171421) (xy 205.269454 -84.124757) (xy 205.245517 -84.074038) (xy 205.22927 -84.02036)
			(xy 205.221062 -83.964881) (xy 205.22057 -83.93684) (xy 203.602498 -83.93684) (xy 203.517754 -84.364068)
			(xy 203.516738 -84.373974) (xy 203.516738 -84.451444) (xy 203.522326 -84.46008) (xy 203.538003 -84.483991)
			(xy 203.562844 -84.535485) (xy 203.579739 -84.590105) (xy 203.58831 -84.646632) (xy 203.588874 -84.675218)
			(xy 203.588874 -84.675472) (xy 203.588374 -84.703602) (xy 203.580115 -84.759253) (xy 203.563771 -84.813087)
			(xy 203.539698 -84.863937) (xy 203.508418 -84.9107) (xy 203.470608 -84.952361) (xy 203.42709 -84.988018)
			(xy 203.4032 -85.002878) (xy 203.398628 -85.005672) (xy 203.393294 -85.013546) (xy 203.390435 -85.017912)
			(xy 203.38635 -85.027513) (xy 203.385166 -85.032596) (xy 203.336652 -85.277198) (xy 203.336144 -85.281516)
			(xy 203.33589 -85.284818) (xy 203.336344 -85.295229) (xy 203.344506 -85.314381) (xy 203.359574 -85.328747)
			(xy 203.369164 -85.332824) (xy 203.369418 -85.332824) (xy 203.396658 -85.343288) (xy 203.447848 -85.371295)
			(xy 203.494177 -85.406771) (xy 203.534563 -85.448888) (xy 203.568065 -85.496663) (xy 203.593901 -85.548983)
			(xy 203.611468 -85.604626) (xy 203.620358 -85.662296) (xy 203.620878 -85.691472) (xy 203.620394 -85.718712)
			(xy 203.612648 -85.772639) (xy 203.597307 -85.824915) (xy 203.574686 -85.874477) (xy 203.545244 -85.920316)
			(xy 203.509579 -85.961501) (xy 203.468418 -85.997192) (xy 203.422598 -86.026665) (xy 203.373051 -86.049319)
			(xy 203.320785 -86.064694) (xy 203.266864 -86.072476) (xy 203.239624 -86.07298) (xy 203.239116 -86.07298)
			(xy 203.222606 -86.072726) (xy 203.213585 -86.072674) (xy 203.196403 -86.07813) (xy 203.189078 -86.083394)
			(xy 203.181966 -86.089236) (xy 203.172568 -86.104476) (xy 203.021438 -86.86546) (xy 203.020156 -86.87569)
			(xy 203.024864 -86.895744) (xy 203.030582 -86.904322) (xy 203.03236 -86.906354) (xy 203.032614 -86.906608)
			(xy 203.036261 -86.910757) (xy 203.044972 -86.917546) (xy 203.049886 -86.92007) (xy 203.060046 -86.924896)
			(xy 207.177894 -86.924896) (xy 207.187965 -86.925318) (xy 207.206571 -86.93303) (xy 207.213962 -86.939882)
			(xy 207.45958 -87.1855) (xy 207.465257 -87.190698) (xy 207.478961 -87.197687) (xy 207.486504 -87.199216)
			(xy 207.487012 -87.199216) (xy 207.49514 -87.199978) (xy 213.346792 -87.199978) (xy 213.356444 -87.198962)
			(xy 213.363688 -87.197335) (xy 213.376858 -87.190495) (xy 213.382352 -87.1855) (xy 213.812374 -86.755478)
			(xy 213.817356 -86.749976) (xy 213.824191 -86.736808) (xy 213.825836 -86.72957) (xy 213.826852 -86.719918)
			(xy 213.826852 -82.917284) (xy 213.826665 -82.910844) (xy 213.823458 -82.89837) (xy 213.820502 -82.892646)
			(xy 213.816438 -82.886804) (xy 213.806532 -82.876644) (xy 213.801706 -82.872834) (xy 213.794086 -82.869786)
			(xy 213.767285 -82.859088) (xy 213.716996 -82.830788) (xy 213.671543 -82.795236) (xy 213.631961 -82.753246)
			(xy 213.599155 -82.705774) (xy 213.573871 -82.653902) (xy 213.556687 -82.598815) (xy 213.547995 -82.541769)
			(xy 213.547452 -82.512916) (xy 213.54753 -82.500178) (xy 213.549182 -82.474757) (xy 213.550754 -82.462116)
			(xy 213.554201 -82.438781) (xy 213.566126 -82.393143) (xy 213.583605 -82.34933) (xy 213.594696 -82.328512)
			(xy 213.597236 -82.323686) (xy 213.597236 -80.028542) (xy 213.597764 -80.002518) (xy 213.605932 -79.951115)
			(xy 213.622026 -79.901619) (xy 213.645653 -79.855242) (xy 213.676231 -79.813124) (xy 213.694264 -79.794354)
			(xy 221.510098 -71.97852) (xy 221.528869 -71.960489) (xy 221.570987 -71.929911) (xy 221.617363 -71.906287)
			(xy 221.66686 -71.890196) (xy 221.718263 -71.882034) (xy 221.744286 -71.881492) (xy 222.207328 -71.881492)
			(xy 222.216726 -71.88073) (xy 222.224152 -71.879079) (xy 222.237588 -71.87196) (xy 222.243142 -71.86676)
			(xy 223.39681 -70.712838) (xy 223.397572 -70.705218) (xy 223.397572 -67.63385) (xy 223.397405 -67.627841)
			(xy 223.394579 -67.616159) (xy 223.391984 -67.610736) (xy 223.390147 -67.60726) (xy 223.385557 -67.600877)
			(xy 223.38284 -67.598036) (xy 223.133666 -67.348862) (xy 223.115555 -67.330081) (xy 223.084872 -67.287883)
			(xy 223.061174 -67.241402) (xy 223.045045 -67.191784) (xy 223.036883 -67.140253) (xy 223.036384 -67.114166)
			(xy 223.036384 -66.33083) (xy 223.036868 -66.304742) (xy 223.045031 -66.253209) (xy 223.061162 -66.203589)
			(xy 223.084861 -66.157107) (xy 223.115545 -66.114907) (xy 223.133666 -66.096134) (xy 223.898206 -65.331594)
			(xy 223.903196 -65.326096) (xy 223.910044 -65.31293) (xy 223.911668 -65.305686) (xy 223.912684 -65.296034)
			(xy 223.912684 -64.058546) (xy 223.914208 -64.028066) (xy 223.915366 -64.016725) (xy 223.919052 -63.994226)
			(xy 223.921574 -63.983108) (xy 223.922844 -63.977266) (xy 223.922844 -63.730632) (xy 223.923344 -63.705344)
			(xy 223.931261 -63.65539) (xy 223.946889 -63.607288) (xy 223.969844 -63.56222) (xy 223.999562 -63.521295)
			(xy 224.017078 -63.503048) (xy 224.762314 -62.757812) (xy 224.76751 -62.752134) (xy 224.774495 -62.738429)
			(xy 224.77603 -62.730888) (xy 224.77603 -62.73038) (xy 224.776792 -62.722252) (xy 224.776792 -60.077604)
			(xy 224.77603 -60.073286) (xy 224.774252 -60.062872) (xy 224.774252 -60.062364) (xy 224.770728 -60.039348)
			(xy 224.766911 -59.992937) (xy 224.766632 -59.969654) (xy 224.766632 -53.473604) (xy 224.767114 -53.440728)
			(xy 224.774512 -53.375393) (xy 224.789173 -53.311295) (xy 224.81091 -53.249239) (xy 224.839453 -53.190004)
			(xy 224.874442 -53.134334) (xy 224.915438 -53.082926) (xy 224.938336 -53.05933) (xy 227.891086 -50.106834)
			(xy 227.896071 -50.101334) (xy 227.902906 -50.088165) (xy 227.904548 -50.080926) (xy 227.905564 -50.071274)
			(xy 227.905564 -40.18153) (xy 227.90606 -40.14743) (xy 227.913977 -40.07969) (xy 227.929706 -40.013327)
			(xy 227.953032 -39.949239) (xy 227.98364 -39.888293) (xy 228.021117 -39.831312) (xy 228.064956 -39.779067)
			(xy 228.114563 -39.732264) (xy 228.169269 -39.691538) (xy 228.228333 -39.657437) (xy 228.290956 -39.630424)
			(xy 228.356292 -39.610864) (xy 228.423456 -39.599021) (xy 228.491542 -39.595056) (xy 228.559628 -39.599021)
			(xy 228.626792 -39.610864) (xy 228.692128 -39.630424) (xy 228.754751 -39.657437) (xy 228.813815 -39.691538)
			(xy 228.868521 -39.732264) (xy 228.918128 -39.779067) (xy 228.961967 -39.831312) (xy 228.999444 -39.888293)
			(xy 229.030052 -39.949239) (xy 229.038329 -39.97198) (xy 232.0958 -39.97198) (xy 232.099871 -39.916358)
			(xy 232.111997 -39.861921) (xy 232.13192 -39.80983) (xy 232.159216 -39.761195) (xy 232.193302 -39.717052)
			(xy 232.233451 -39.678343) (xy 232.278809 -39.645892) (xy 232.328409 -39.620391) (xy 232.381193 -39.602384)
			(xy 232.436036 -39.592254) (xy 232.49177 -39.590217) (xy 232.547207 -39.596317) (xy 232.601164 -39.610423)
			(xy 232.652493 -39.632235) (xy 232.700099 -39.661289) (xy 232.742967 -39.696964) (xy 232.780184 -39.738501)
			(xy 232.810957 -39.785014) (xy 232.834629 -39.835511) (xy 232.850697 -39.888918) (xy 232.858817 -39.944094)
			(xy 232.859326 -39.97198) (xy 232.858817 -39.999866) (xy 232.850697 -40.055042) (xy 232.834629 -40.108449)
			(xy 232.810957 -40.158946) (xy 232.780184 -40.205459) (xy 232.742967 -40.246996) (xy 232.700099 -40.282671)
			(xy 232.652493 -40.311725) (xy 232.601164 -40.333537) (xy 232.547207 -40.347643) (xy 232.49177 -40.353743)
			(xy 232.436036 -40.351706) (xy 232.381193 -40.341576) (xy 232.328409 -40.323569) (xy 232.278809 -40.298068)
			(xy 232.233451 -40.265617) (xy 232.193302 -40.226908) (xy 232.159216 -40.182765) (xy 232.13192 -40.13413)
			(xy 232.111997 -40.082039) (xy 232.099871 -40.027602) (xy 232.0958 -39.97198) (xy 229.038329 -39.97198)
			(xy 229.053378 -40.013327) (xy 229.069107 -40.07969) (xy 229.077024 -40.14743) (xy 229.07752 -40.18153)
			(xy 229.07752 -40.971724) (xy 232.794046 -40.971724) (xy 232.798117 -40.916102) (xy 232.810243 -40.861665)
			(xy 232.830166 -40.809574) (xy 232.857462 -40.760939) (xy 232.891548 -40.716796) (xy 232.931697 -40.678087)
			(xy 232.977055 -40.645636) (xy 233.026655 -40.620135) (xy 233.079439 -40.602128) (xy 233.134282 -40.591998)
			(xy 233.190016 -40.589961) (xy 233.245453 -40.596061) (xy 233.29941 -40.610167) (xy 233.350739 -40.631979)
			(xy 233.398345 -40.661033) (xy 233.441213 -40.696708) (xy 233.47843 -40.738245) (xy 233.509203 -40.784758)
			(xy 233.532875 -40.835255) (xy 233.548943 -40.888662) (xy 233.557063 -40.943838) (xy 233.557572 -40.971724)
			(xy 233.557063 -40.99961) (xy 233.548943 -41.054786) (xy 233.532875 -41.108193) (xy 233.509203 -41.15869)
			(xy 233.47843 -41.205203) (xy 233.441213 -41.24674) (xy 233.398345 -41.282415) (xy 233.350739 -41.311469)
			(xy 233.29941 -41.333281) (xy 233.245453 -41.347387) (xy 233.190016 -41.353487) (xy 233.134282 -41.35145)
			(xy 233.079439 -41.34132) (xy 233.026655 -41.323313) (xy 232.977055 -41.297812) (xy 232.931697 -41.265361)
			(xy 232.891548 -41.226652) (xy 232.857462 -41.182509) (xy 232.830166 -41.133874) (xy 232.810243 -41.081783)
			(xy 232.798117 -41.027346) (xy 232.794046 -40.971724) (xy 229.07752 -40.971724) (xy 229.07752 -50.33518)
			(xy 229.077039 -50.368056) (xy 229.069642 -50.433392) (xy 229.054982 -50.49749) (xy 229.033244 -50.559545)
			(xy 229.004701 -50.61878) (xy 228.969711 -50.67445) (xy 228.928713 -50.725857) (xy 228.905816 -50.749454)
			(xy 225.95332 -53.701696) (xy 225.950615 -53.704547) (xy 225.946022 -53.710926) (xy 225.944176 -53.714396)
			(xy 225.9416 -53.719824) (xy 225.938789 -53.731504) (xy 225.938588 -53.73751) (xy 225.938588 -58.535824)
			(xy 225.939858 -58.537602) (xy 225.983292 -58.581036) (xy 226.100628 -58.698471) (xy 229.808523 -58.698471)
			(xy 229.808523 -58.601777) (xy 229.816508 -58.505414) (xy 229.832424 -58.410039) (xy 229.85616 -58.316305)
			(xy 229.887557 -58.22485) (xy 229.926398 -58.136301) (xy 229.972419 -58.051261) (xy 230.025305 -57.970313)
			(xy 230.084696 -57.894008) (xy 230.150184 -57.822868) (xy 230.221324 -57.75738) (xy 230.297629 -57.697989)
			(xy 230.378577 -57.645103) (xy 230.463617 -57.599082) (xy 230.552166 -57.560241) (xy 230.643621 -57.528844)
			(xy 230.737355 -57.505108) (xy 230.83273 -57.489192) (xy 230.929093 -57.481207) (xy 231.025787 -57.481207)
			(xy 231.12215 -57.489192) (xy 231.217525 -57.505108) (xy 231.311259 -57.528844) (xy 231.402714 -57.560241)
			(xy 231.491263 -57.599082) (xy 231.576303 -57.645103) (xy 231.657251 -57.697989) (xy 231.733556 -57.75738)
			(xy 231.804696 -57.822868) (xy 231.870184 -57.894008) (xy 231.929575 -57.970313) (xy 231.982461 -58.051261)
			(xy 232.028482 -58.136301) (xy 232.067323 -58.22485) (xy 232.09872 -58.316305) (xy 232.122456 -58.410039)
			(xy 232.138372 -58.505414) (xy 232.146357 -58.601777) (xy 232.146856 -58.650124) (xy 232.146357 -58.698471)
			(xy 232.138372 -58.794834) (xy 232.122456 -58.890209) (xy 232.09872 -58.983943) (xy 232.067323 -59.075398)
			(xy 232.028482 -59.163947) (xy 231.982461 -59.248987) (xy 231.929575 -59.329935) (xy 231.870184 -59.40624)
			(xy 231.804696 -59.47738) (xy 231.733556 -59.542868) (xy 231.657251 -59.602259) (xy 231.576303 -59.655145)
			(xy 231.491263 -59.701166) (xy 231.402714 -59.740007) (xy 231.311259 -59.771404) (xy 231.217525 -59.79514)
			(xy 231.12215 -59.811056) (xy 231.025787 -59.819041) (xy 230.929093 -59.819041) (xy 230.83273 -59.811056)
			(xy 230.737355 -59.79514) (xy 230.643621 -59.771404) (xy 230.552166 -59.740007) (xy 230.463617 -59.701166)
			(xy 230.378577 -59.655145) (xy 230.297629 -59.602259) (xy 230.221324 -59.542868) (xy 230.150184 -59.47738)
			(xy 230.084696 -59.40624) (xy 230.025305 -59.329935) (xy 229.972419 -59.248987) (xy 229.926398 -59.163947)
			(xy 229.887557 -59.075398) (xy 229.85616 -58.983943) (xy 229.832424 -58.890209) (xy 229.816508 -58.794834)
			(xy 229.808523 -58.698471) (xy 226.100628 -58.698471) (xy 226.284536 -58.882534) (xy 226.290176 -58.887641)
			(xy 226.303747 -58.894503) (xy 226.311206 -58.895996) (xy 226.311714 -58.895996) (xy 226.319842 -58.896758)
			(xy 226.603306 -58.896758) (xy 226.616514 -58.89498) (xy 226.628452 -58.891424) (xy 226.634548 -58.889138)
			(xy 226.644454 -58.884566) (xy 226.67208 -58.867294) (xy 226.731188 -58.83989) (xy 226.793585 -58.821145)
			(xy 226.858009 -58.811439) (xy 226.89058 -58.810652) (xy 226.894136 -58.810652) (xy 226.93122 -58.812176)
			(xy 226.935284 -58.811922) (xy 226.9363 -58.811922) (xy 226.968812 -58.810652) (xy 226.96932 -58.810652)
			(xy 226.999288 -58.811143) (xy 227.05871 -58.818968) (xy 227.116603 -58.834482) (xy 227.171976 -58.857419)
			(xy 227.223882 -58.887387) (xy 227.271432 -58.923873) (xy 227.313814 -58.966253) (xy 227.350302 -59.013801)
			(xy 227.380272 -59.065706) (xy 227.403211 -59.121078) (xy 227.418728 -59.17897) (xy 227.426555 -59.238392)
			(xy 227.427028 -59.26836) (xy 227.427028 -59.900566) (xy 227.427282 -60.13196) (xy 227.426813 -60.161589)
			(xy 227.419172 -60.220351) (xy 227.404026 -60.27764) (xy 227.381626 -60.332501) (xy 227.352347 -60.384019)
			(xy 227.316675 -60.431337) (xy 227.275205 -60.473665) (xy 227.228629 -60.510299) (xy 227.177721 -60.540628)
			(xy 227.123331 -60.564148) (xy 227.066365 -60.580465) (xy 227.037138 -60.58535) (xy 227.036884 -60.58535)
			(xy 227.033836 -60.585858) (xy 227.026978 -60.587636) (xy 227.021898 -60.589668) (xy 227.012246 -60.593732)
			(xy 227.000562 -60.600844) (xy 226.981512 -60.616084) (xy 226.977448 -60.621926) (xy 226.972876 -60.628022)
			(xy 226.958398 -60.668916) (xy 226.958398 -60.669424) (xy 226.947476 -60.70092) (xy 226.94642 -60.704577)
			(xy 226.945266 -60.712101) (xy 226.94519 -60.715906) (xy 226.94519 -60.726828) (xy 226.945698 -60.734448)
			(xy 227.350574 -61.13907) (xy 227.37445 -61.162946) (xy 227.398891 -61.188116) (xy 227.442217 -61.243298)
			(xy 227.47864 -61.303263) (xy 227.507636 -61.36715) (xy 227.518722 -61.400436) (xy 227.518976 -61.40069)
			(xy 227.522125 -61.404099) (xy 227.529407 -61.409849) (xy 227.533454 -61.41212) (xy 227.535994 -61.41339)
			(xy 227.541836 -61.41614) (xy 227.554429 -61.418969) (xy 227.560886 -61.418978) (xy 227.592636 -61.417708)
			(xy 227.59289 -61.417708) (xy 227.630482 -61.419486) (xy 227.632768 -61.41974) (xy 227.638102 -61.41974)
			(xy 227.63988 -61.419486) (xy 227.667058 -61.41847) (xy 227.673408 -61.41847) (xy 227.700396 -61.419335)
			(xy 227.753734 -61.427734) (xy 227.805354 -61.44357) (xy 227.854226 -61.466527) (xy 227.899372 -61.496146)
			(xy 227.939891 -61.531835) (xy 227.974972 -61.572881) (xy 228.003915 -61.618464) (xy 228.026141 -61.667672)
			(xy 228.041205 -61.719523) (xy 228.048808 -61.77298) (xy 228.049328 -61.799978) (xy 231.00614 -61.799978)
			(xy 231.010211 -61.744356) (xy 231.022337 -61.689919) (xy 231.04226 -61.637828) (xy 231.069556 -61.589193)
			(xy 231.103642 -61.54505) (xy 231.143791 -61.506341) (xy 231.189149 -61.47389) (xy 231.238749 -61.448389)
			(xy 231.291533 -61.430382) (xy 231.346376 -61.420252) (xy 231.40211 -61.418215) (xy 231.457547 -61.424315)
			(xy 231.511504 -61.438421) (xy 231.562833 -61.460233) (xy 231.610439 -61.489287) (xy 231.653307 -61.524962)
			(xy 231.690524 -61.566499) (xy 231.721297 -61.613012) (xy 231.744969 -61.663509) (xy 231.761037 -61.716916)
			(xy 231.769157 -61.772092) (xy 231.769666 -61.799978) (xy 231.769157 -61.827864) (xy 231.761037 -61.88304)
			(xy 231.744969 -61.936447) (xy 231.721297 -61.986944) (xy 231.690524 -62.033457) (xy 231.653307 -62.074994)
			(xy 231.610439 -62.110669) (xy 231.562833 -62.139723) (xy 231.511504 -62.161535) (xy 231.457547 -62.175641)
			(xy 231.40211 -62.181741) (xy 231.346376 -62.179704) (xy 231.291533 -62.169574) (xy 231.238749 -62.151567)
			(xy 231.189149 -62.126066) (xy 231.143791 -62.093615) (xy 231.103642 -62.054906) (xy 231.069556 -62.010763)
			(xy 231.04226 -61.962128) (xy 231.022337 -61.910037) (xy 231.010211 -61.8556) (xy 231.00614 -61.799978)
			(xy 228.049328 -61.799978) (xy 228.048886 -61.826621) (xy 228.041472 -61.879389) (xy 228.026786 -61.930612)
			(xy 228.005114 -61.979292) (xy 227.976877 -62.024482) (xy 227.942625 -62.065302) (xy 227.903025 -62.100957)
			(xy 227.858848 -62.130754) (xy 227.810954 -62.154111) (xy 227.760275 -62.170575) (xy 227.734114 -62.175644)
			(xy 227.73386 -62.175644) (xy 227.729542 -62.176406) (xy 227.712524 -62.178946) (xy 227.71227 -62.178946)
			(xy 227.70846 -62.179454) (xy 227.708206 -62.179454) (xy 227.692712 -62.181232) (xy 227.687632 -62.181486)
			(xy 227.667312 -62.181486) (xy 227.643182 -62.180724) (xy 227.638864 -62.180724) (xy 227.631944 -62.181099)
			(xy 227.618682 -62.185096) (xy 227.612702 -62.188598) (xy 227.606098 -62.193932) (xy 227.551742 -62.24524)
			(xy 227.5459 -62.251844) (xy 227.5459 -62.94374) (xy 227.5459 -62.943994) (xy 227.5459 -62.944502)
			(xy 227.545392 -62.972442) (xy 227.545646 -62.97295) (xy 227.559108 -62.983618) (xy 227.562588 -62.986218)
			(xy 227.57025 -62.990308) (xy 227.574348 -62.991746) (xy 227.603043 -63.000128) (xy 231.00614 -63.000128)
			(xy 231.010211 -62.944506) (xy 231.022337 -62.890069) (xy 231.04226 -62.837978) (xy 231.069556 -62.789343)
			(xy 231.103642 -62.7452) (xy 231.143791 -62.706491) (xy 231.189149 -62.67404) (xy 231.238749 -62.648539)
			(xy 231.291533 -62.630532) (xy 231.346376 -62.620402) (xy 231.40211 -62.618365) (xy 231.457547 -62.624465)
			(xy 231.511504 -62.638571) (xy 231.562833 -62.660383) (xy 231.610439 -62.689437) (xy 231.653307 -62.725112)
			(xy 231.690524 -62.766649) (xy 231.721297 -62.813162) (xy 231.744969 -62.863659) (xy 231.761037 -62.917066)
			(xy 231.769157 -62.972242) (xy 231.769666 -63.000128) (xy 231.769157 -63.028014) (xy 231.761037 -63.08319)
			(xy 231.744969 -63.136597) (xy 231.721297 -63.187094) (xy 231.690524 -63.233607) (xy 231.653307 -63.275144)
			(xy 231.610439 -63.310819) (xy 231.562833 -63.339873) (xy 231.511504 -63.361685) (xy 231.457547 -63.375791)
			(xy 231.40211 -63.381891) (xy 231.346376 -63.379854) (xy 231.291533 -63.369724) (xy 231.238749 -63.351717)
			(xy 231.189149 -63.326216) (xy 231.143791 -63.293765) (xy 231.103642 -63.255056) (xy 231.069556 -63.210913)
			(xy 231.04226 -63.162278) (xy 231.022337 -63.110187) (xy 231.010211 -63.05575) (xy 231.00614 -63.000128)
			(xy 227.603043 -63.000128) (xy 227.607083 -63.001308) (xy 227.670218 -63.027096) (xy 227.729868 -63.060155)
			(xy 227.7852 -63.100023) (xy 227.83544 -63.146142) (xy 227.879886 -63.197868) (xy 227.917917 -63.254477)
			(xy 227.949002 -63.31518) (xy 227.972705 -63.379126) (xy 227.988696 -63.445424) (xy 227.996751 -63.513145)
			(xy 227.997258 -63.547244) (xy 227.997258 -63.96228) (xy 227.997766 -63.96482) (xy 227.997766 -63.965328)
			(xy 227.99802 -63.966344) (xy 227.998274 -63.967868) (xy 227.999036 -63.972186) (xy 228.002902 -63.996703)
			(xy 228.006973 -64.046173) (xy 228.007164 -64.070992) (xy 228.007164 -64.478662) (xy 228.006722 -64.511517)
			(xy 227.999369 -64.576815) (xy 227.984751 -64.640878) (xy 227.963051 -64.702902) (xy 227.934544 -64.762107)
			(xy 227.899586 -64.817747) (xy 227.858619 -64.869123) (xy 227.835714 -64.892682) (xy 227.796598 -64.931798)
			(xy 227.790056 -64.93896) (xy 227.782433 -64.956778) (xy 227.781959 -64.976153) (xy 227.784914 -64.985392)
			(xy 227.797106 -65.014602) (xy 227.802186 -65.016634) (xy 227.80752 -65.018666) (xy 227.833174 -65.018412)
			(xy 227.839016 -65.018412) (xy 227.872036 -65.019682) (xy 227.87483 -65.019936) (xy 227.877878 -65.019936)
			(xy 227.880672 -65.019682) (xy 227.913438 -65.018412) (xy 227.9142 -65.018412) (xy 227.94145 -65.018898)
			(xy 227.995395 -65.026654) (xy 228.047687 -65.042009) (xy 228.097261 -65.064649) (xy 228.143109 -65.094113)
			(xy 228.184297 -65.129803) (xy 228.219987 -65.170991) (xy 228.249451 -65.216839) (xy 228.272091 -65.266413)
			(xy 228.287446 -65.318705) (xy 228.295202 -65.37265) (xy 228.295202 -65.42715) (xy 228.287446 -65.481095)
			(xy 228.272091 -65.533387) (xy 228.249451 -65.582961) (xy 228.219987 -65.628809) (xy 228.184297 -65.669997)
			(xy 228.143109 -65.705687) (xy 228.097261 -65.735151) (xy 228.047687 -65.757791) (xy 227.995395 -65.773146)
			(xy 227.94145 -65.780902) (xy 227.9142 -65.781428) (xy 227.880926 -65.780158) (xy 227.878132 -65.779904)
			(xy 227.875084 -65.779904) (xy 227.87229 -65.780158) (xy 227.839016 -65.781428) (xy 227.811763 -65.780943)
			(xy 227.757813 -65.773189) (xy 227.705515 -65.757835) (xy 227.655935 -65.735195) (xy 227.610081 -65.70573)
			(xy 227.568887 -65.670038) (xy 227.533192 -65.628848) (xy 227.503722 -65.582997) (xy 227.481077 -65.533419)
			(xy 227.465719 -65.481122) (xy 227.457959 -65.427172) (xy 227.457508 -65.39992) (xy 227.457508 -65.394586)
			(xy 227.457762 -65.378838) (xy 227.440236 -65.352676) (xy 227.43287 -65.349628) (xy 227.432616 -65.349628)
			(xy 227.412296 -65.3415) (xy 227.398834 -65.33896) (xy 227.388928 -65.339468) (xy 226.927664 -65.800732)
			(xy 226.927664 -65.812416) (xy 226.930966 -65.840102) (xy 226.930966 -65.84061) (xy 226.937824 -65.895474)
			(xy 226.938586 -65.898268) (xy 226.939348 -65.900808) (xy 226.940737 -65.90553) (xy 226.945082 -65.914359)
			(xy 226.947984 -65.918334) (xy 226.953572 -65.9257) (xy 226.961954 -65.93078) (xy 226.985834 -65.945679)
			(xy 227.029341 -65.981386) (xy 227.067139 -66.02309) (xy 227.09841 -66.069887) (xy 227.122478 -66.120766)
			(xy 227.138822 -66.174624) (xy 227.147087 -66.230298) (xy 227.147628 -66.25844) (xy 227.147552 -66.271178)
			(xy 227.145902 -66.2966) (xy 227.144326 -66.30924) (xy 227.140341 -66.335452) (xy 227.12607 -66.386515)
			(xy 227.104873 -66.435112) (xy 227.077159 -66.480311) (xy 227.043459 -66.521242) (xy 227.004422 -66.557119)
			(xy 226.960798 -66.587251) (xy 226.937316 -66.599562) (xy 226.936198 -66.60007) (xy 231.00614 -66.60007)
			(xy 231.010211 -66.544448) (xy 231.022337 -66.490011) (xy 231.04226 -66.43792) (xy 231.069556 -66.389285)
			(xy 231.103642 -66.345142) (xy 231.143791 -66.306433) (xy 231.189149 -66.273982) (xy 231.238749 -66.248481)
			(xy 231.291533 -66.230474) (xy 231.346376 -66.220344) (xy 231.40211 -66.218307) (xy 231.457547 -66.224407)
			(xy 231.511504 -66.238513) (xy 231.562833 -66.260325) (xy 231.610439 -66.289379) (xy 231.653307 -66.325054)
			(xy 231.690524 -66.366591) (xy 231.721297 -66.413104) (xy 231.744969 -66.463601) (xy 231.761037 -66.517008)
			(xy 231.769157 -66.572184) (xy 231.769666 -66.60007) (xy 231.769157 -66.627956) (xy 231.761037 -66.683132)
			(xy 231.744969 -66.736539) (xy 231.721297 -66.787036) (xy 231.690524 -66.833549) (xy 231.653307 -66.875086)
			(xy 231.610439 -66.910761) (xy 231.562833 -66.939815) (xy 231.511504 -66.961627) (xy 231.457547 -66.975733)
			(xy 231.40211 -66.981833) (xy 231.346376 -66.979796) (xy 231.291533 -66.969666) (xy 231.238749 -66.951659)
			(xy 231.189149 -66.926158) (xy 231.143791 -66.893707) (xy 231.103642 -66.854998) (xy 231.069556 -66.810855)
			(xy 231.04226 -66.76222) (xy 231.022337 -66.710129) (xy 231.010211 -66.655692) (xy 231.00614 -66.60007)
			(xy 226.936198 -66.60007) (xy 226.909376 -66.612262) (xy 226.899978 -66.616072) (xy 226.871784 -66.644266)
			(xy 226.870157 -66.64873) (xy 226.868368 -66.658059) (xy 226.868228 -66.662808) (xy 226.868228 -67.369944)
			(xy 226.983542 -67.369944) (xy 226.987613 -67.314322) (xy 226.999739 -67.259885) (xy 227.019662 -67.207794)
			(xy 227.046958 -67.159159) (xy 227.081044 -67.115016) (xy 227.121193 -67.076307) (xy 227.166551 -67.043856)
			(xy 227.216151 -67.018355) (xy 227.268935 -67.000348) (xy 227.323778 -66.990218) (xy 227.379512 -66.988181)
			(xy 227.434949 -66.994281) (xy 227.488906 -67.008387) (xy 227.540235 -67.030199) (xy 227.587841 -67.059253)
			(xy 227.630709 -67.094928) (xy 227.667926 -67.136465) (xy 227.698699 -67.182978) (xy 227.722371 -67.233475)
			(xy 227.738439 -67.286882) (xy 227.746559 -67.342058) (xy 227.747068 -67.369944) (xy 227.746559 -67.39783)
			(xy 227.738439 -67.453006) (xy 227.722371 -67.506413) (xy 227.698699 -67.55691) (xy 227.667926 -67.603423)
			(xy 227.630709 -67.64496) (xy 227.587841 -67.680635) (xy 227.540235 -67.709689) (xy 227.488906 -67.731501)
			(xy 227.434949 -67.745607) (xy 227.379512 -67.751707) (xy 227.323778 -67.74967) (xy 227.268935 -67.73954)
			(xy 227.216151 -67.721533) (xy 227.166551 -67.696032) (xy 227.121193 -67.663581) (xy 227.081044 -67.624872)
			(xy 227.046958 -67.580729) (xy 227.019662 -67.532094) (xy 226.999739 -67.480003) (xy 226.987613 -67.425566)
			(xy 226.983542 -67.369944) (xy 226.868228 -67.369944) (xy 226.868228 -69.091048) (xy 227.444554 -69.091048)
			(xy 227.445004 -69.064761) (xy 227.452209 -69.012684) (xy 227.466505 -68.962092) (xy 227.487618 -68.913945)
			(xy 227.515148 -68.869156) (xy 227.548573 -68.828577) (xy 227.587259 -68.792976) (xy 227.63047 -68.763031)
			(xy 227.677387 -68.739309) (xy 227.70211 -68.730368) (xy 227.702364 -68.730368) (xy 227.712221 -68.726236)
			(xy 227.727715 -68.711555) (xy 227.732336 -68.70192) (xy 227.765864 -68.621402) (xy 227.765102 -68.599812)
			(xy 227.76053 -68.59016) (xy 227.748579 -68.564207) (xy 227.731715 -68.509616) (xy 227.723191 -68.45312)
			(xy 227.722684 -68.424552) (xy 227.722684 -68.424298) (xy 227.72317 -68.397047) (xy 227.730926 -68.343099)
			(xy 227.746281 -68.290804) (xy 227.768923 -68.241227) (xy 227.798389 -68.195377) (xy 227.83408 -68.154186)
			(xy 227.875271 -68.118495) (xy 227.921121 -68.089029) (xy 227.970698 -68.066387) (xy 228.022993 -68.051032)
			(xy 228.076941 -68.043276) (xy 228.131443 -68.043276) (xy 228.185391 -68.051032) (xy 228.237686 -68.066387)
			(xy 228.287263 -68.089029) (xy 228.333113 -68.118495) (xy 228.374304 -68.154186) (xy 228.409995 -68.195377)
			(xy 228.439461 -68.241227) (xy 228.462103 -68.290804) (xy 228.477458 -68.343099) (xy 228.485214 -68.397047)
			(xy 228.4857 -68.424298) (xy 228.485254 -68.450584) (xy 228.478044 -68.50266) (xy 228.463745 -68.553251)
			(xy 228.44263 -68.601396) (xy 228.415099 -68.646183) (xy 228.381674 -68.686762) (xy 228.34299 -68.722363)
			(xy 228.299781 -68.75231) (xy 228.252866 -68.776035) (xy 228.228144 -68.784978) (xy 228.22789 -68.784978)
			(xy 228.218015 -68.789074) (xy 228.202529 -68.80378) (xy 228.197918 -68.813426) (xy 228.16439 -68.893944)
			(xy 228.165152 -68.915534) (xy 228.169724 -68.925186) (xy 228.181687 -68.951134) (xy 228.198548 -69.005727)
			(xy 228.207066 -69.062225) (xy 228.20757 -69.090794) (xy 228.20757 -69.091048) (xy 228.207084 -69.118299)
			(xy 228.199328 -69.172247) (xy 228.183973 -69.224542) (xy 228.161331 -69.274119) (xy 228.131865 -69.319969)
			(xy 228.096174 -69.36116) (xy 228.054983 -69.396851) (xy 228.009133 -69.426317) (xy 227.959556 -69.448959)
			(xy 227.907261 -69.464314) (xy 227.853313 -69.47207) (xy 227.798811 -69.47207) (xy 227.744863 -69.464314)
			(xy 227.692568 -69.448959) (xy 227.642991 -69.426317) (xy 227.597141 -69.396851) (xy 227.55595 -69.36116)
			(xy 227.520259 -69.319969) (xy 227.490793 -69.274119) (xy 227.468151 -69.224542) (xy 227.452796 -69.172247)
			(xy 227.44504 -69.118299) (xy 227.444554 -69.091048) (xy 226.868228 -69.091048) (xy 226.868228 -70.050406)
			(xy 226.86899 -70.058534) (xy 226.86899 -70.059042) (xy 226.870592 -70.06656) (xy 226.877569 -70.080247)
			(xy 226.882706 -70.085966) (xy 227.778818 -70.982078) (xy 227.784316 -70.987068) (xy 227.797481 -70.993917)
			(xy 227.804726 -70.99554) (xy 227.814378 -70.996556) (xy 230.426514 -70.996556) (xy 230.437634 -70.995988)
			(xy 230.457791 -70.986588) (xy 230.472092 -70.969554) (xy 230.475536 -70.958964) (xy 230.498142 -70.860666)
			(xy 230.498904 -70.856094) (xy 230.499886 -70.845409) (xy 230.493861 -70.824834) (xy 230.479943 -70.808527)
			(xy 230.470456 -70.803516) (xy 230.427021 -70.782066) (xy 230.343504 -70.732969) (xy 230.264336 -70.677128)
			(xy 230.190062 -70.614926) (xy 230.121191 -70.54679) (xy 230.058196 -70.473188) (xy 230.001508 -70.394624)
			(xy 229.951518 -70.311638) (xy 229.908568 -70.224799) (xy 229.872952 -70.134703) (xy 229.844916 -70.041969)
			(xy 229.824651 -69.947232) (xy 229.812296 -69.851143) (xy 229.807938 -69.754361) (xy 229.811604 -69.657551)
			(xy 229.823271 -69.561376) (xy 229.842857 -69.466497) (xy 229.870229 -69.373564) (xy 229.9052 -69.283216)
			(xy 229.947528 -69.196072) (xy 229.996923 -69.11273) (xy 230.053047 -69.033763) (xy 230.115514 -68.959712)
			(xy 230.183896 -68.891085) (xy 230.257723 -68.828353) (xy 230.336489 -68.771947) (xy 230.419653 -68.722254)
			(xy 230.506645 -68.679615) (xy 230.596868 -68.644322) (xy 230.689702 -68.616617) (xy 230.784511 -68.596691)
			(xy 230.880643 -68.584681) (xy 230.97744 -68.580668) (xy 231.074237 -68.584681) (xy 231.170369 -68.596691)
			(xy 231.265178 -68.616617) (xy 231.358012 -68.644322) (xy 231.448235 -68.679615) (xy 231.535227 -68.722254)
			(xy 231.618391 -68.771947) (xy 231.697157 -68.828353) (xy 231.770984 -68.891085) (xy 231.839366 -68.959712)
			(xy 231.901833 -69.033763) (xy 231.957957 -69.11273) (xy 232.007352 -69.196072) (xy 232.04968 -69.283216)
			(xy 232.084651 -69.373564) (xy 232.112023 -69.466497) (xy 232.131609 -69.561376) (xy 232.143276 -69.657551)
			(xy 232.146942 -69.754361) (xy 232.142584 -69.851143) (xy 232.130229 -69.947232) (xy 232.109964 -70.041969)
			(xy 232.081928 -70.134703) (xy 232.046312 -70.224799) (xy 232.003362 -70.311638) (xy 231.953372 -70.394624)
			(xy 231.896684 -70.473188) (xy 231.833689 -70.54679) (xy 231.764818 -70.614926) (xy 231.690544 -70.677128)
			(xy 231.611376 -70.732969) (xy 231.527859 -70.782066) (xy 231.484424 -70.803516) (xy 231.48417 -70.80377)
			(xy 231.476629 -70.80778) (xy 231.464563 -70.819853) (xy 231.460548 -70.827392) (xy 231.456738 -70.835012)
			(xy 231.45496 -70.851776) (xy 231.478836 -70.956932) (xy 231.480868 -70.96379) (xy 231.484924 -70.973201)
			(xy 231.499073 -70.988) (xy 231.517877 -70.996101) (xy 231.528112 -70.996556) (xy 231.861106 -70.996556)
			(xy 231.870758 -70.99554) (xy 231.878001 -70.993911) (xy 231.891166 -70.987065) (xy 231.896666 -70.982078)
			(xy 232.432606 -70.446138) (xy 232.437589 -70.440637) (xy 232.444423 -70.427469) (xy 232.446068 -70.42023)
			(xy 232.447084 -70.410578) (xy 232.447084 -42.854118) (xy 232.444798 -42.8498) (xy 232.430028 -42.821642)
			(xy 232.409036 -42.761627) (xy 232.398285 -42.698962) (xy 232.397554 -42.667174) (xy 232.397554 -42.65803)
			(xy 232.398596 -42.630108) (xy 232.407841 -42.575004) (xy 232.425024 -42.521837) (xy 232.449778 -42.471745)
			(xy 232.481573 -42.425799) (xy 232.51973 -42.384983) (xy 232.563432 -42.350168) (xy 232.611745 -42.322099)
			(xy 232.663635 -42.301378) (xy 232.717993 -42.288446) (xy 232.773655 -42.283581) (xy 232.829432 -42.286887)
			(xy 232.884129 -42.298293) (xy 232.936579 -42.317554) (xy 232.985658 -42.34426) (xy 233.030317 -42.377839)
			(xy 233.069601 -42.417572) (xy 233.102669 -42.46261) (xy 233.128815 -42.51199) (xy 233.147479 -42.564655)
			(xy 233.158262 -42.619479) (xy 233.160062 -42.647362) (xy 233.16057 -42.663872) (xy 233.16057 -42.665904)
			(xy 233.159918 -42.697905) (xy 233.149239 -42.76101) (xy 233.128181 -42.821448) (xy 233.113326 -42.8498)
			(xy 233.11104 -42.854118) (xy 233.11104 -48.789458) (xy 238.952913 -48.789458) (xy 238.952913 -48.734942)
			(xy 238.960672 -48.680982) (xy 238.976032 -48.628675) (xy 238.99868 -48.579087) (xy 239.028155 -48.533227)
			(xy 239.063857 -48.492028) (xy 239.105059 -48.456331) (xy 239.150922 -48.42686) (xy 239.200513 -48.404218)
			(xy 239.252821 -48.388863) (xy 239.306782 -48.38111) (xy 239.33404 -48.38065) (xy 239.36141 -48.381139)
			(xy 239.415588 -48.388949) (xy 239.468091 -48.404432) (xy 239.517839 -48.427269) (xy 239.563806 -48.45699)
			(xy 239.584738 -48.47463) (xy 239.584992 -48.474884) (xy 239.592078 -48.480472) (xy 239.608995 -48.486718)
			(xy 239.618012 -48.487076) (xy 239.685068 -48.487076) (xy 239.694084 -48.486709) (xy 239.711001 -48.480469)
			(xy 239.718088 -48.474884) (xy 239.718088 -48.47463) (xy 239.718342 -48.47463) (xy 239.739289 -48.457009)
			(xy 239.785257 -48.427294) (xy 239.835001 -48.404454) (xy 239.887498 -48.388958) (xy 239.941672 -48.381126)
			(xy 239.96904 -48.38065) (xy 239.996286 -48.381223) (xy 240.050224 -48.388983) (xy 240.102508 -48.40434)
			(xy 240.152075 -48.426981) (xy 240.197915 -48.456445) (xy 240.239096 -48.492133) (xy 240.274779 -48.533317)
			(xy 240.304238 -48.579161) (xy 240.326874 -48.62873) (xy 240.342225 -48.681015) (xy 240.34998 -48.734954)
			(xy 240.34998 -48.789446) (xy 240.342225 -48.843385) (xy 240.326874 -48.89567) (xy 240.304238 -48.945239)
			(xy 240.274779 -48.991083) (xy 240.239096 -49.032267) (xy 240.197915 -49.067955) (xy 240.152075 -49.097419)
			(xy 240.102508 -49.12006) (xy 240.050224 -49.135417) (xy 239.996286 -49.143177) (xy 239.96904 -49.143666)
			(xy 239.94167 -49.143185) (xy 239.887491 -49.135372) (xy 239.834988 -49.119887) (xy 239.785241 -49.097048)
			(xy 239.739274 -49.067326) (xy 239.718342 -49.049686) (xy 239.718088 -49.049432) (xy 239.711015 -49.043826)
			(xy 239.694088 -49.037593) (xy 239.685068 -49.03724) (xy 239.618012 -49.03724) (xy 239.608995 -49.037594)
			(xy 239.592077 -49.043843) (xy 239.584992 -49.049432) (xy 239.584992 -49.049686) (xy 239.584738 -49.049686)
			(xy 239.563801 -49.067319) (xy 239.51783 -49.097032) (xy 239.468083 -49.119869) (xy 239.415584 -49.135362)
			(xy 239.361409 -49.143191) (xy 239.33404 -49.143666) (xy 239.306782 -49.14329) (xy 239.252821 -49.135537)
			(xy 239.200513 -49.120182) (xy 239.150922 -49.09754) (xy 239.105059 -49.068069) (xy 239.063857 -49.032372)
			(xy 239.028155 -48.991173) (xy 238.99868 -48.945313) (xy 238.976032 -48.895725) (xy 238.960672 -48.843418)
			(xy 238.952913 -48.789458) (xy 233.11104 -48.789458) (xy 233.11104 -49.72995) (xy 238.502698 -49.72995)
			(xy 238.502698 -49.67545) (xy 238.510454 -49.621506) (xy 238.525808 -49.569214) (xy 238.548448 -49.519639)
			(xy 238.577913 -49.473792) (xy 238.613602 -49.432604) (xy 238.65479 -49.396914) (xy 238.700638 -49.367449)
			(xy 238.750212 -49.344809) (xy 238.802504 -49.329455) (xy 238.856448 -49.321698) (xy 238.883698 -49.321212)
			(xy 238.911068 -49.321676) (xy 238.965248 -49.329494) (xy 239.017751 -49.344983) (xy 239.067498 -49.367826)
			(xy 239.113464 -49.397551) (xy 239.134396 -49.415192) (xy 239.13465 -49.415446) (xy 239.141743 -49.421023)
			(xy 239.158655 -49.427274) (xy 239.16767 -49.427638) (xy 239.234726 -49.427638) (xy 239.243743 -49.427285)
			(xy 239.26066 -49.421034) (xy 239.267746 -49.415446) (xy 239.267746 -49.415192) (xy 239.268 -49.415192)
			(xy 239.28892 -49.397538) (xy 239.334896 -49.367829) (xy 239.384647 -49.344996) (xy 239.43715 -49.329508)
			(xy 239.491328 -49.321684) (xy 239.518698 -49.321212) (xy 239.545952 -49.321635) (xy 239.599906 -49.329392)
			(xy 239.652207 -49.344749) (xy 239.70179 -49.367392) (xy 239.747646 -49.396862) (xy 239.788841 -49.432557)
			(xy 239.824537 -49.473752) (xy 239.854007 -49.519608) (xy 239.876651 -49.569191) (xy 239.892008 -49.621492)
			(xy 239.899765 -49.675446) (xy 239.899765 -49.729954) (xy 239.892008 -49.783908) (xy 239.876651 -49.836209)
			(xy 239.854007 -49.885792) (xy 239.824537 -49.931648) (xy 239.788841 -49.972843) (xy 239.747646 -50.008538)
			(xy 239.70179 -50.038008) (xy 239.652207 -50.060651) (xy 239.599906 -50.076008) (xy 239.545952 -50.083765)
			(xy 239.518698 -50.084228) (xy 239.491327 -50.083781) (xy 239.437146 -50.075961) (xy 239.384642 -50.060469)
			(xy 239.334896 -50.037622) (xy 239.28893 -50.007892) (xy 239.268 -49.990248) (xy 239.267746 -49.989994)
			(xy 239.260651 -49.98442) (xy 239.243741 -49.978166) (xy 239.234726 -49.977802) (xy 239.16767 -49.977802)
			(xy 239.158652 -49.978144) (xy 239.141735 -49.984402) (xy 239.13465 -49.989994) (xy 239.13465 -49.990248)
			(xy 239.134396 -49.990248) (xy 239.11347 -50.007894) (xy 239.067496 -50.037607) (xy 239.017747 -50.060442)
			(xy 238.965245 -50.075931) (xy 238.911068 -50.083756) (xy 238.883698 -50.084228) (xy 238.856448 -50.083702)
			(xy 238.802504 -50.075945) (xy 238.750212 -50.060591) (xy 238.700638 -50.037951) (xy 238.65479 -50.008486)
			(xy 238.613602 -49.972796) (xy 238.577913 -49.931608) (xy 238.548448 -49.885761) (xy 238.525808 -49.836186)
			(xy 238.510454 -49.783894) (xy 238.502698 -49.72995) (xy 233.11104 -49.72995) (xy 233.11104 -51.222449)
			(xy 236.270302 -51.222449) (xy 236.270302 -51.167951) (xy 236.278058 -51.114007) (xy 236.293412 -51.061717)
			(xy 236.316051 -51.012143) (xy 236.345514 -50.966296) (xy 236.381203 -50.925109) (xy 236.42239 -50.889419)
			(xy 236.468236 -50.859955) (xy 236.517809 -50.837315) (xy 236.570099 -50.82196) (xy 236.624043 -50.814203)
			(xy 236.651292 -50.813716) (xy 236.679384 -50.814201) (xy 236.734962 -50.822428) (xy 236.788732 -50.838719)
			(xy 236.83953 -50.862723) (xy 236.886257 -50.89392) (xy 236.927902 -50.931634) (xy 236.963562 -50.97505)
			(xy 236.978444 -50.998882) (xy 236.983778 -51.007772) (xy 237.000796 -51.019964) (xy 237.094014 -51.040284)
			(xy 237.114588 -51.035966) (xy 237.123224 -51.030124) (xy 237.147282 -51.014114) (xy 237.199215 -50.988773)
			(xy 237.254375 -50.97155) (xy 237.311501 -50.962838) (xy 237.340394 -50.962306) (xy 237.367647 -50.962761)
			(xy 237.421599 -50.970517) (xy 237.473898 -50.985873) (xy 237.523479 -51.008516) (xy 237.569333 -51.037985)
			(xy 237.610526 -51.07368) (xy 237.64622 -51.114873) (xy 237.675688 -51.160728) (xy 237.698329 -51.210309)
			(xy 237.713684 -51.262609) (xy 237.72144 -51.316561) (xy 237.721902 -51.343814) (xy 237.721444 -51.371185)
			(xy 237.713624 -51.425364) (xy 237.698133 -51.477867) (xy 237.67529 -51.527614) (xy 237.645564 -51.57358)
			(xy 237.627922 -51.594512) (xy 237.627668 -51.594766) (xy 237.622086 -51.601856) (xy 237.615838 -51.61877)
			(xy 237.615476 -51.627786) (xy 237.615476 -51.694842) (xy 237.615866 -51.703855) (xy 237.622091 -51.720772)
			(xy 237.627668 -51.727862) (xy 237.627922 -51.727862) (xy 237.627922 -51.728116) (xy 237.645574 -51.749039)
			(xy 237.675295 -51.795009) (xy 237.698136 -51.844758) (xy 237.713629 -51.897261) (xy 237.721456 -51.95144)
			(xy 237.721454 -52.006181) (xy 237.713625 -52.06036) (xy 237.698129 -52.112862) (xy 237.675285 -52.162609)
			(xy 237.645562 -52.208578) (xy 237.627922 -52.229512) (xy 237.627668 -52.229766) (xy 237.622086 -52.236856)
			(xy 237.615838 -52.25377) (xy 237.615476 -52.262786) (xy 237.615476 -52.329842) (xy 237.615866 -52.338855)
			(xy 237.622091 -52.355772) (xy 237.627668 -52.362862) (xy 237.627922 -52.362862) (xy 237.627922 -52.363116)
			(xy 237.645539 -52.384066) (xy 237.675253 -52.430034) (xy 237.698093 -52.479777) (xy 237.713589 -52.532274)
			(xy 237.721424 -52.586446) (xy 237.721902 -52.613814) (xy 237.721416 -52.641065) (xy 237.71366 -52.695013)
			(xy 237.698305 -52.747308) (xy 237.675663 -52.796885) (xy 237.646197 -52.842735) (xy 237.610506 -52.883926)
			(xy 237.569315 -52.919617) (xy 237.523465 -52.949083) (xy 237.473888 -52.971725) (xy 237.421593 -52.98708)
			(xy 237.367645 -52.994836) (xy 237.313143 -52.994836) (xy 237.259195 -52.98708) (xy 237.2069 -52.971725)
			(xy 237.157323 -52.949083) (xy 237.111473 -52.919617) (xy 237.070282 -52.883926) (xy 237.034591 -52.842735)
			(xy 237.005125 -52.796885) (xy 236.982483 -52.747308) (xy 236.967128 -52.695013) (xy 236.959372 -52.641065)
			(xy 236.958886 -52.613814) (xy 236.959364 -52.586444) (xy 236.967179 -52.532266) (xy 236.982666 -52.479763)
			(xy 237.005505 -52.430016) (xy 237.035226 -52.384048) (xy 237.052866 -52.363116) (xy 237.05312 -52.362862)
			(xy 237.058689 -52.355763) (xy 237.064946 -52.338856) (xy 237.065312 -52.329842) (xy 237.065312 -52.262786)
			(xy 237.064959 -52.253769) (xy 237.058708 -52.236852) (xy 237.05312 -52.229766) (xy 237.052866 -52.229766)
			(xy 237.052866 -52.229512) (xy 237.035237 -52.208569) (xy 237.005509 -52.162604) (xy 236.98266 -52.11286)
			(xy 236.967161 -52.060359) (xy 236.959331 -52.006181) (xy 236.959329 -51.95144) (xy 236.967157 -51.897262)
			(xy 236.982653 -51.84476) (xy 237.005499 -51.795015) (xy 237.035225 -51.749048) (xy 237.052866 -51.728116)
			(xy 237.05312 -51.727862) (xy 237.058689 -51.720763) (xy 237.064946 -51.703856) (xy 237.065312 -51.694842)
			(xy 237.065312 -51.627786) (xy 237.064959 -51.618769) (xy 237.058708 -51.601852) (xy 237.05312 -51.594766)
			(xy 237.052866 -51.594258) (xy 237.041923 -51.581523) (xy 237.022081 -51.554432) (xy 237.013242 -51.540156)
			(xy 237.007908 -51.531266) (xy 236.99089 -51.519074) (xy 236.897672 -51.498754) (xy 236.877098 -51.503072)
			(xy 236.868462 -51.508914) (xy 236.844411 -51.524934) (xy 236.792475 -51.550272) (xy 236.737313 -51.567492)
			(xy 236.680186 -51.576201) (xy 236.651292 -51.576732) (xy 236.624043 -51.576197) (xy 236.570099 -51.56844)
			(xy 236.517809 -51.553085) (xy 236.468236 -51.530445) (xy 236.42239 -51.500981) (xy 236.381203 -51.465291)
			(xy 236.345514 -51.424104) (xy 236.316051 -51.378257) (xy 236.293412 -51.328683) (xy 236.278058 -51.276393)
			(xy 236.270302 -51.222449) (xy 233.11104 -51.222449) (xy 233.11104 -51.654249) (xy 234.593902 -51.654249)
			(xy 234.593902 -51.599751) (xy 234.601658 -51.545807) (xy 234.617012 -51.493517) (xy 234.639651 -51.443943)
			(xy 234.669114 -51.398096) (xy 234.704803 -51.356909) (xy 234.74599 -51.321219) (xy 234.791836 -51.291755)
			(xy 234.841409 -51.269115) (xy 234.893699 -51.25376) (xy 234.947643 -51.246003) (xy 234.974892 -51.245516)
			(xy 235.001206 -51.245984) (xy 235.053335 -51.253218) (xy 235.103978 -51.267536) (xy 235.152177 -51.288669)
			(xy 235.19702 -51.316215) (xy 235.23766 -51.349654) (xy 235.255816 -51.368706) (xy 235.263329 -51.376117)
			(xy 235.282616 -51.384636) (xy 235.293154 -51.385216) (xy 235.36783 -51.385216) (xy 235.378376 -51.384658)
			(xy 235.397672 -51.376143) (xy 235.405168 -51.368706) (xy 235.423299 -51.349626) (xy 235.463934 -51.31617)
			(xy 235.508779 -51.288615) (xy 235.556985 -51.26748) (xy 235.607637 -51.253169) (xy 235.659774 -51.245951)
			(xy 235.686092 -51.245516) (xy 235.713347 -51.24593) (xy 235.767302 -51.253687) (xy 235.819604 -51.269043)
			(xy 235.869189 -51.291687) (xy 235.915046 -51.321156) (xy 235.956242 -51.356852) (xy 235.991939 -51.398048)
			(xy 236.021409 -51.443904) (xy 236.044054 -51.493488) (xy 236.059411 -51.54579) (xy 236.067169 -51.599745)
			(xy 236.067169 -51.654255) (xy 236.059411 -51.70821) (xy 236.044054 -51.760512) (xy 236.021409 -51.810096)
			(xy 235.991939 -51.855952) (xy 235.956242 -51.897148) (xy 235.915046 -51.932844) (xy 235.869189 -51.962313)
			(xy 235.819604 -51.984957) (xy 235.767302 -52.000313) (xy 235.713347 -52.00807) (xy 235.686092 -52.008532)
			(xy 235.659778 -52.00806) (xy 235.60765 -52.000824) (xy 235.557008 -51.986506) (xy 235.508809 -51.965374)
			(xy 235.463966 -51.937829) (xy 235.423325 -51.904393) (xy 235.405168 -51.885342) (xy 235.397654 -51.877931)
			(xy 235.378369 -51.869411) (xy 235.36783 -51.868832) (xy 235.293154 -51.868832) (xy 235.282605 -51.869367)
			(xy 235.263309 -51.877897) (xy 235.255816 -51.885342) (xy 235.237654 -51.904391) (xy 235.197025 -51.937847)
			(xy 235.152185 -51.965406) (xy 235.103986 -51.986545) (xy 235.05334 -52.000864) (xy 235.001208 -52.008092)
			(xy 234.974892 -52.008532) (xy 234.947643 -52.007997) (xy 234.893699 -52.00024) (xy 234.841409 -51.984885)
			(xy 234.791836 -51.962245) (xy 234.74599 -51.932781) (xy 234.704803 -51.897091) (xy 234.669114 -51.855904)
			(xy 234.639651 -51.810057) (xy 234.617012 -51.760483) (xy 234.601658 -51.708193) (xy 234.593902 -51.654249)
			(xy 233.11104 -51.654249) (xy 233.11104 -53.718714) (xy 236.97514 -53.718714) (xy 236.979211 -53.663092)
			(xy 236.991337 -53.608655) (xy 237.01126 -53.556564) (xy 237.038556 -53.507929) (xy 237.072642 -53.463786)
			(xy 237.112791 -53.425077) (xy 237.158149 -53.392626) (xy 237.207749 -53.367125) (xy 237.260533 -53.349118)
			(xy 237.315376 -53.338988) (xy 237.37111 -53.336951) (xy 237.426547 -53.343051) (xy 237.480504 -53.357157)
			(xy 237.531833 -53.378969) (xy 237.579439 -53.408023) (xy 237.622307 -53.443698) (xy 237.659524 -53.485235)
			(xy 237.690297 -53.531748) (xy 237.713969 -53.582245) (xy 237.730037 -53.635652) (xy 237.738157 -53.690828)
			(xy 237.738666 -53.718714) (xy 237.738157 -53.7466) (xy 237.730037 -53.801776) (xy 237.713969 -53.855183)
			(xy 237.690297 -53.90568) (xy 237.659524 -53.952193) (xy 237.622307 -53.99373) (xy 237.579439 -54.029405)
			(xy 237.531833 -54.058459) (xy 237.480504 -54.080271) (xy 237.426547 -54.094377) (xy 237.37111 -54.100477)
			(xy 237.315376 -54.09844) (xy 237.260533 -54.08831) (xy 237.207749 -54.070303) (xy 237.158149 -54.044802)
			(xy 237.112791 -54.012351) (xy 237.072642 -53.973642) (xy 237.038556 -53.929499) (xy 237.01126 -53.880864)
			(xy 236.991337 -53.828773) (xy 236.979211 -53.774336) (xy 236.97514 -53.718714) (xy 233.11104 -53.718714)
			(xy 233.11104 -54.309518) (xy 237.727234 -54.309518) (xy 237.731305 -54.253896) (xy 237.743431 -54.199459)
			(xy 237.763354 -54.147368) (xy 237.79065 -54.098733) (xy 237.824736 -54.05459) (xy 237.864885 -54.015881)
			(xy 237.910243 -53.98343) (xy 237.959843 -53.957929) (xy 238.012627 -53.939922) (xy 238.06747 -53.929792)
			(xy 238.123204 -53.927755) (xy 238.178641 -53.933855) (xy 238.232598 -53.947961) (xy 238.283927 -53.969773)
			(xy 238.331533 -53.998827) (xy 238.374401 -54.034502) (xy 238.411618 -54.076039) (xy 238.442391 -54.122552)
			(xy 238.466063 -54.173049) (xy 238.47449 -54.20106) (xy 239.961418 -54.20106) (xy 239.965489 -54.145438)
			(xy 239.977615 -54.091001) (xy 239.997538 -54.03891) (xy 240.024834 -53.990275) (xy 240.05892 -53.946132)
			(xy 240.099069 -53.907423) (xy 240.144427 -53.874972) (xy 240.194027 -53.849471) (xy 240.246811 -53.831464)
			(xy 240.301654 -53.821334) (xy 240.357388 -53.819297) (xy 240.412825 -53.825397) (xy 240.466782 -53.839503)
			(xy 240.518111 -53.861315) (xy 240.565717 -53.890369) (xy 240.608585 -53.926044) (xy 240.645802 -53.967581)
			(xy 240.676575 -54.014094) (xy 240.700247 -54.064591) (xy 240.716315 -54.117998) (xy 240.724435 -54.173174)
			(xy 240.724944 -54.20106) (xy 240.724435 -54.228946) (xy 240.716315 -54.284122) (xy 240.700247 -54.337529)
			(xy 240.676575 -54.388026) (xy 240.645802 -54.434539) (xy 240.608585 -54.476076) (xy 240.565717 -54.511751)
			(xy 240.518111 -54.540805) (xy 240.466782 -54.562617) (xy 240.412825 -54.576723) (xy 240.357388 -54.582823)
			(xy 240.301654 -54.580786) (xy 240.246811 -54.570656) (xy 240.194027 -54.552649) (xy 240.144427 -54.527148)
			(xy 240.099069 -54.494697) (xy 240.05892 -54.455988) (xy 240.024834 -54.411845) (xy 239.997538 -54.36321)
			(xy 239.977615 -54.311119) (xy 239.965489 -54.256682) (xy 239.961418 -54.20106) (xy 238.47449 -54.20106)
			(xy 238.482131 -54.226456) (xy 238.490251 -54.281632) (xy 238.49076 -54.309518) (xy 238.490251 -54.337404)
			(xy 238.482131 -54.39258) (xy 238.466063 -54.445987) (xy 238.442391 -54.496484) (xy 238.411618 -54.542997)
			(xy 238.374401 -54.584534) (xy 238.331533 -54.620209) (xy 238.283927 -54.649263) (xy 238.232598 -54.671075)
			(xy 238.178641 -54.685181) (xy 238.123204 -54.691281) (xy 238.06747 -54.689244) (xy 238.012627 -54.679114)
			(xy 237.959843 -54.661107) (xy 237.910243 -54.635606) (xy 237.864885 -54.603155) (xy 237.824736 -54.564446)
			(xy 237.79065 -54.520303) (xy 237.763354 -54.471668) (xy 237.743431 -54.419577) (xy 237.731305 -54.36514)
			(xy 237.727234 -54.309518) (xy 233.11104 -54.309518) (xy 233.11104 -54.794658) (xy 238.931448 -54.794658)
			(xy 238.935519 -54.739036) (xy 238.947645 -54.684599) (xy 238.967568 -54.632508) (xy 238.994864 -54.583873)
			(xy 239.02895 -54.53973) (xy 239.069099 -54.501021) (xy 239.114457 -54.46857) (xy 239.164057 -54.443069)
			(xy 239.216841 -54.425062) (xy 239.271684 -54.414932) (xy 239.327418 -54.412895) (xy 239.382855 -54.418995)
			(xy 239.436812 -54.433101) (xy 239.488141 -54.454913) (xy 239.535747 -54.483967) (xy 239.578615 -54.519642)
			(xy 239.615832 -54.561179) (xy 239.646605 -54.607692) (xy 239.670277 -54.658189) (xy 239.686345 -54.711596)
			(xy 239.694465 -54.766772) (xy 239.694974 -54.794658) (xy 239.694465 -54.822544) (xy 239.686345 -54.87772)
			(xy 239.670277 -54.931127) (xy 239.646605 -54.981624) (xy 239.615832 -55.028137) (xy 239.578615 -55.069674)
			(xy 239.535747 -55.105349) (xy 239.488141 -55.134403) (xy 239.436812 -55.156215) (xy 239.382855 -55.170321)
			(xy 239.327418 -55.176421) (xy 239.271684 -55.174384) (xy 239.216841 -55.164254) (xy 239.164057 -55.146247)
			(xy 239.114457 -55.120746) (xy 239.069099 -55.088295) (xy 239.02895 -55.049586) (xy 238.994864 -55.005443)
			(xy 238.967568 -54.956808) (xy 238.947645 -54.904717) (xy 238.935519 -54.85028) (xy 238.931448 -54.794658)
			(xy 233.11104 -54.794658) (xy 233.11104 -55.408068) (xy 237.462312 -55.408068) (xy 237.466383 -55.352446)
			(xy 237.478509 -55.298009) (xy 237.498432 -55.245918) (xy 237.525728 -55.197283) (xy 237.559814 -55.15314)
			(xy 237.599963 -55.114431) (xy 237.645321 -55.08198) (xy 237.694921 -55.056479) (xy 237.747705 -55.038472)
			(xy 237.802548 -55.028342) (xy 237.858282 -55.026305) (xy 237.913719 -55.032405) (xy 237.967676 -55.046511)
			(xy 238.019005 -55.068323) (xy 238.066611 -55.097377) (xy 238.109479 -55.133052) (xy 238.146696 -55.174589)
			(xy 238.177469 -55.221102) (xy 238.201141 -55.271599) (xy 238.217209 -55.325006) (xy 238.225329 -55.380182)
			(xy 238.225838 -55.408068) (xy 238.225329 -55.435954) (xy 238.217209 -55.49113) (xy 238.201141 -55.544537)
			(xy 238.177469 -55.595034) (xy 238.146696 -55.641547) (xy 238.109479 -55.683084) (xy 238.066611 -55.718759)
			(xy 238.019005 -55.747813) (xy 237.967676 -55.769625) (xy 237.913719 -55.783731) (xy 237.858282 -55.789831)
			(xy 237.802548 -55.787794) (xy 237.747705 -55.777664) (xy 237.694921 -55.759657) (xy 237.645321 -55.734156)
			(xy 237.599963 -55.701705) (xy 237.559814 -55.662996) (xy 237.525728 -55.618853) (xy 237.498432 -55.570218)
			(xy 237.478509 -55.518127) (xy 237.466383 -55.46369) (xy 237.462312 -55.408068) (xy 233.11104 -55.408068)
			(xy 233.11104 -56.86679) (xy 240.166142 -56.86679) (xy 240.170213 -56.811168) (xy 240.182339 -56.756731)
			(xy 240.202262 -56.70464) (xy 240.229558 -56.656005) (xy 240.263644 -56.611862) (xy 240.303793 -56.573153)
			(xy 240.349151 -56.540702) (xy 240.398751 -56.515201) (xy 240.451535 -56.497194) (xy 240.506378 -56.487064)
			(xy 240.562112 -56.485027) (xy 240.617549 -56.491127) (xy 240.671506 -56.505233) (xy 240.722835 -56.527045)
			(xy 240.770441 -56.556099) (xy 240.813309 -56.591774) (xy 240.850526 -56.633311) (xy 240.881299 -56.679824)
			(xy 240.904971 -56.730321) (xy 240.921039 -56.783728) (xy 240.929159 -56.838904) (xy 240.929668 -56.86679)
			(xy 240.929159 -56.894676) (xy 240.921039 -56.949852) (xy 240.904971 -57.003259) (xy 240.881299 -57.053756)
			(xy 240.850526 -57.100269) (xy 240.813309 -57.141806) (xy 240.770441 -57.177481) (xy 240.722835 -57.206535)
			(xy 240.671506 -57.228347) (xy 240.617549 -57.242453) (xy 240.562112 -57.248553) (xy 240.506378 -57.246516)
			(xy 240.451535 -57.236386) (xy 240.398751 -57.218379) (xy 240.349151 -57.192878) (xy 240.303793 -57.160427)
			(xy 240.263644 -57.121718) (xy 240.229558 -57.077575) (xy 240.202262 -57.02894) (xy 240.182339 -56.976849)
			(xy 240.170213 -56.922412) (xy 240.166142 -56.86679) (xy 233.11104 -56.86679) (xy 233.11104 -60.918852)
			(xy 233.114541 -60.923276) (xy 233.123126 -60.930592) (xy 233.128058 -60.93333) (xy 233.13136 -60.934854)
			(xy 233.156252 -60.944252) (xy 233.15676 -60.944252) (xy 233.206036 -60.962794) (xy 233.212132 -60.965588)
			(xy 233.218736 -60.969398) (xy 233.223816 -60.970668) (xy 233.227619 -60.971581) (xy 233.235402 -60.972348)
			(xy 233.23931 -60.972192) (xy 233.246676 -60.971938) (xy 233.255472 -60.970536) (xy 233.271336 -60.96246)
			(xy 233.277664 -60.95619) (xy 233.28122 -60.95238) (xy 233.28376 -60.94984) (xy 233.286808 -60.945776)
			(xy 233.304996 -60.926138) (xy 233.345915 -60.891632) (xy 233.391246 -60.86317) (xy 233.440103 -60.841306)
			(xy 233.491531 -60.826469) (xy 233.544526 -60.818948) (xy 233.571288 -60.818522) (xy 233.571542 -60.818522)
			(xy 233.572812 -60.818522) (xy 233.59999 -60.819538) (xy 233.600498 -60.819538) (xy 233.606086 -60.820046)
			(xy 233.61015 -60.8203) (xy 233.612182 -60.8203) (xy 233.646472 -60.818522) (xy 233.647996 -60.818522)
			(xy 233.675231 -60.819028) (xy 233.729143 -60.826818) (xy 233.781398 -60.842198) (xy 233.830934 -60.864854)
			(xy 233.876743 -60.894326) (xy 233.906781 -60.920376) (xy 239.456974 -60.920376) (xy 239.461045 -60.864754)
			(xy 239.473171 -60.810317) (xy 239.493094 -60.758226) (xy 239.52039 -60.709591) (xy 239.554476 -60.665448)
			(xy 239.594625 -60.626739) (xy 239.639983 -60.594288) (xy 239.689583 -60.568787) (xy 239.742367 -60.55078)
			(xy 239.79721 -60.54065) (xy 239.852944 -60.538613) (xy 239.908381 -60.544713) (xy 239.962338 -60.558819)
			(xy 240.013667 -60.580631) (xy 240.061273 -60.609685) (xy 240.104141 -60.64536) (xy 240.141358 -60.686897)
			(xy 240.172131 -60.73341) (xy 240.195803 -60.783907) (xy 240.211871 -60.837314) (xy 240.219991 -60.89249)
			(xy 240.2205 -60.920376) (xy 240.219991 -60.948262) (xy 240.211871 -61.003438) (xy 240.195803 -61.056845)
			(xy 240.172131 -61.107342) (xy 240.141358 -61.153855) (xy 240.104141 -61.195392) (xy 240.061273 -61.231067)
			(xy 240.013667 -61.260121) (xy 239.962338 -61.281933) (xy 239.908381 -61.296039) (xy 239.852944 -61.302139)
			(xy 239.79721 -61.300102) (xy 239.742367 -61.289972) (xy 239.689583 -61.271965) (xy 239.639983 -61.246464)
			(xy 239.594625 -61.214013) (xy 239.554476 -61.175304) (xy 239.52039 -61.131161) (xy 239.493094 -61.082526)
			(xy 239.473171 -61.030435) (xy 239.461045 -60.975998) (xy 239.456974 -60.920376) (xy 233.906781 -60.920376)
			(xy 233.917895 -60.930015) (xy 233.953551 -60.971194) (xy 233.982988 -61.017026) (xy 234.005606 -61.06658)
			(xy 234.020945 -61.118847) (xy 234.028693 -61.172764) (xy 234.028693 -61.227236) (xy 234.020945 -61.281153)
			(xy 234.005606 -61.33342) (xy 233.982988 -61.382974) (xy 233.953551 -61.428806) (xy 233.917895 -61.469985)
			(xy 233.876743 -61.505674) (xy 233.830934 -61.535146) (xy 233.781398 -61.557802) (xy 233.729143 -61.573182)
			(xy 233.675231 -61.580972) (xy 233.647996 -61.581538) (xy 233.646472 -61.581538) (xy 233.61015 -61.57976)
			(xy 233.609388 -61.57976) (xy 233.571288 -61.581538) (xy 233.551476 -61.581538) (xy 233.54538 -61.581284)
			(xy 233.533696 -61.57976) (xy 233.532934 -61.57976) (xy 233.499562 -61.575605) (xy 233.43492 -61.557077)
			(xy 233.40441 -61.54293) (xy 233.382167 -61.531637) (xy 233.340557 -61.504121) (xy 233.302889 -61.471415)
			(xy 233.286046 -61.453014) (xy 233.284776 -61.451744) (xy 233.278934 -61.44514) (xy 233.276648 -61.442854)
			(xy 233.269922 -61.436721) (xy 233.253345 -61.429233) (xy 233.235199 -61.427986) (xy 233.226356 -61.430154)
			(xy 233.156506 -61.455808) (xy 233.137964 -61.462666) (xy 233.137456 -61.46292) (xy 233.134916 -61.463682)
			(xy 233.13009 -61.46546) (xy 233.12882 -61.466222) (xy 233.128312 -61.466222) (xy 233.123409 -61.468923)
			(xy 233.114824 -61.476102) (xy 233.111294 -61.480446) (xy 233.11104 -61.4807) (xy 233.11104 -62.358778)
			(xy 236.702344 -62.358778) (xy 236.706415 -62.303156) (xy 236.718541 -62.248719) (xy 236.738464 -62.196628)
			(xy 236.76576 -62.147993) (xy 236.799846 -62.10385) (xy 236.839995 -62.065141) (xy 236.885353 -62.03269)
			(xy 236.934953 -62.007189) (xy 236.987737 -61.989182) (xy 237.04258 -61.979052) (xy 237.098314 -61.977015)
			(xy 237.153751 -61.983115) (xy 237.207708 -61.997221) (xy 237.259037 -62.019033) (xy 237.306643 -62.048087)
			(xy 237.349511 -62.083762) (xy 237.386728 -62.125299) (xy 237.417501 -62.171812) (xy 237.441173 -62.222309)
			(xy 237.457241 -62.275716) (xy 237.465361 -62.330892) (xy 237.46587 -62.358778) (xy 237.465361 -62.386664)
			(xy 237.457241 -62.44184) (xy 237.441173 -62.495247) (xy 237.417501 -62.545744) (xy 237.386728 -62.592257)
			(xy 237.349511 -62.633794) (xy 237.306643 -62.669469) (xy 237.259037 -62.698523) (xy 237.207708 -62.720335)
			(xy 237.153751 -62.734441) (xy 237.098314 -62.740541) (xy 237.04258 -62.738504) (xy 236.987737 -62.728374)
			(xy 236.934953 -62.710367) (xy 236.885353 -62.684866) (xy 236.839995 -62.652415) (xy 236.799846 -62.613706)
			(xy 236.76576 -62.569563) (xy 236.738464 -62.520928) (xy 236.718541 -62.468837) (xy 236.706415 -62.4144)
			(xy 236.702344 -62.358778) (xy 233.11104 -62.358778) (xy 233.11104 -63.318898) (xy 233.114544 -63.323319)
			(xy 233.123131 -63.330629) (xy 233.128058 -63.333376) (xy 233.13136 -63.3349) (xy 233.156252 -63.344298)
			(xy 233.15676 -63.344298) (xy 233.206036 -63.36284) (xy 233.212132 -63.365634) (xy 233.218736 -63.369444)
			(xy 233.223816 -63.370714) (xy 233.227619 -63.371626) (xy 233.235402 -63.372393) (xy 233.23931 -63.372238)
			(xy 233.246676 -63.371984) (xy 233.255474 -63.370584) (xy 233.271342 -63.362513) (xy 233.277664 -63.356236)
			(xy 233.28122 -63.352426) (xy 233.28376 -63.349886) (xy 233.286808 -63.345822) (xy 233.304997 -63.326186)
			(xy 233.345918 -63.291685) (xy 233.391249 -63.263227) (xy 233.440106 -63.241367) (xy 233.491533 -63.226532)
			(xy 233.544526 -63.219012) (xy 233.571288 -63.218568) (xy 233.571542 -63.218568) (xy 233.572812 -63.218568)
			(xy 233.59999 -63.219584) (xy 233.600498 -63.219584) (xy 233.606086 -63.220092) (xy 233.61015 -63.220346)
			(xy 233.612182 -63.220346) (xy 233.646472 -63.218568) (xy 233.647996 -63.218568) (xy 233.675235 -63.219074)
			(xy 233.729154 -63.226865) (xy 233.781417 -63.242247) (xy 233.83096 -63.264906) (xy 233.876776 -63.294383)
			(xy 233.917933 -63.330076) (xy 233.953595 -63.371261) (xy 233.983036 -63.4171) (xy 233.998499 -63.450978)
			(xy 237.60633 -63.450978) (xy 237.610401 -63.395356) (xy 237.622527 -63.340919) (xy 237.64245 -63.288828)
			(xy 237.669746 -63.240193) (xy 237.703832 -63.19605) (xy 237.743981 -63.157341) (xy 237.789339 -63.12489)
			(xy 237.838939 -63.099389) (xy 237.891723 -63.081382) (xy 237.946566 -63.071252) (xy 238.0023 -63.069215)
			(xy 238.057737 -63.075315) (xy 238.111694 -63.089421) (xy 238.163023 -63.111233) (xy 238.210629 -63.140287)
			(xy 238.253497 -63.175962) (xy 238.290714 -63.217499) (xy 238.321487 -63.264012) (xy 238.345159 -63.314509)
			(xy 238.361227 -63.367916) (xy 238.369347 -63.423092) (xy 238.369856 -63.450978) (xy 238.369347 -63.478864)
			(xy 238.361227 -63.53404) (xy 238.345159 -63.587447) (xy 238.321487 -63.637944) (xy 238.290714 -63.684457)
			(xy 238.253497 -63.725994) (xy 238.210629 -63.761669) (xy 238.163023 -63.790723) (xy 238.111694 -63.812535)
			(xy 238.057737 -63.826641) (xy 238.0023 -63.832741) (xy 237.946566 -63.830704) (xy 237.891723 -63.820574)
			(xy 237.838939 -63.802567) (xy 237.789339 -63.777066) (xy 237.743981 -63.744615) (xy 237.703832 -63.705906)
			(xy 237.669746 -63.661763) (xy 237.64245 -63.613128) (xy 237.622527 -63.561037) (xy 237.610401 -63.5066)
			(xy 237.60633 -63.450978) (xy 233.998499 -63.450978) (xy 234.005657 -63.466661) (xy 234.020998 -63.518935)
			(xy 234.028747 -63.57286) (xy 234.028747 -63.62734) (xy 234.020998 -63.681265) (xy 234.005657 -63.733539)
			(xy 233.983036 -63.7831) (xy 233.953595 -63.828939) (xy 233.917933 -63.870124) (xy 233.876776 -63.905817)
			(xy 233.83096 -63.935294) (xy 233.781417 -63.957953) (xy 233.729154 -63.973335) (xy 233.675235 -63.981126)
			(xy 233.647996 -63.981584) (xy 233.646472 -63.981584) (xy 233.61015 -63.979806) (xy 233.609388 -63.979806)
			(xy 233.571288 -63.981584) (xy 233.551476 -63.981584) (xy 233.54538 -63.98133) (xy 233.533696 -63.979806)
			(xy 233.532934 -63.979806) (xy 233.499561 -63.975652) (xy 233.434919 -63.957125) (xy 233.40441 -63.942976)
			(xy 233.382168 -63.931681) (xy 233.340561 -63.904163) (xy 233.302897 -63.871454) (xy 233.286046 -63.85306)
			(xy 233.284776 -63.85179) (xy 233.27868 -63.844932) (xy 233.276648 -63.8429) (xy 233.272511 -63.839017)
			(xy 233.262895 -63.832997) (xy 233.257598 -63.830962) (xy 233.232452 -63.830962) (xy 233.223562 -63.831724)
			(xy 233.21518 -63.83401) (xy 233.133138 -63.86449) (xy 233.121962 -63.870586) (xy 233.11888 -63.87294)
			(xy 233.113399 -63.878428) (xy 233.11104 -63.881508) (xy 233.11104 -65.00876) (xy 240.02441 -65.00876)
			(xy 240.028481 -64.953138) (xy 240.040607 -64.898701) (xy 240.06053 -64.84661) (xy 240.087826 -64.797975)
			(xy 240.121912 -64.753832) (xy 240.162061 -64.715123) (xy 240.207419 -64.682672) (xy 240.257019 -64.657171)
			(xy 240.309803 -64.639164) (xy 240.364646 -64.629034) (xy 240.42038 -64.626997) (xy 240.475817 -64.633097)
			(xy 240.529774 -64.647203) (xy 240.581103 -64.669015) (xy 240.628709 -64.698069) (xy 240.671577 -64.733744)
			(xy 240.708794 -64.775281) (xy 240.739567 -64.821794) (xy 240.763239 -64.872291) (xy 240.779307 -64.925698)
			(xy 240.787427 -64.980874) (xy 240.787936 -65.00876) (xy 240.787427 -65.036646) (xy 240.779307 -65.091822)
			(xy 240.763239 -65.145229) (xy 240.739567 -65.195726) (xy 240.708794 -65.242239) (xy 240.671577 -65.283776)
			(xy 240.628709 -65.319451) (xy 240.581103 -65.348505) (xy 240.529774 -65.370317) (xy 240.475817 -65.384423)
			(xy 240.42038 -65.390523) (xy 240.364646 -65.388486) (xy 240.309803 -65.378356) (xy 240.257019 -65.360349)
			(xy 240.207419 -65.334848) (xy 240.162061 -65.302397) (xy 240.121912 -65.263688) (xy 240.087826 -65.219545)
			(xy 240.06053 -65.17091) (xy 240.040607 -65.118819) (xy 240.028481 -65.064382) (xy 240.02441 -65.00876)
			(xy 233.11104 -65.00876) (xy 233.11104 -66.91884) (xy 233.11454 -66.923265) (xy 233.123125 -66.930582)
			(xy 233.128058 -66.933318) (xy 233.13136 -66.934842) (xy 233.156252 -66.94424) (xy 233.15676 -66.94424)
			(xy 233.206036 -66.962782) (xy 233.212132 -66.965576) (xy 233.218736 -66.969386) (xy 233.223816 -66.970656)
			(xy 233.227619 -66.971569) (xy 233.235402 -66.972337) (xy 233.23931 -66.97218) (xy 233.246676 -66.971926)
			(xy 233.255475 -66.970527) (xy 233.271348 -66.962461) (xy 233.277664 -66.956178) (xy 233.28122 -66.952368)
			(xy 233.28376 -66.949828) (xy 233.286808 -66.945764) (xy 233.304996 -66.926126) (xy 233.345915 -66.891622)
			(xy 233.391246 -66.86316) (xy 233.440103 -66.841297) (xy 233.491531 -66.826461) (xy 233.544526 -66.81894)
			(xy 233.571288 -66.81851) (xy 233.571542 -66.81851) (xy 233.572812 -66.81851) (xy 233.59999 -66.819526)
			(xy 233.600498 -66.819526) (xy 233.606086 -66.820034) (xy 233.61015 -66.820288) (xy 233.612182 -66.820288)
			(xy 233.646472 -66.81851) (xy 233.647996 -66.81851) (xy 233.675233 -66.819016) (xy 233.729148 -66.826807)
			(xy 233.781406 -66.842188) (xy 233.830945 -66.864846) (xy 233.876756 -66.894321) (xy 233.91791 -66.930013)
			(xy 233.953567 -66.971195) (xy 233.983004 -67.017031) (xy 234.005622 -67.066589) (xy 234.02096 -67.11886)
			(xy 234.028706 -67.172781) (xy 234.02925 -67.200018) (xy 234.028763 -67.227269) (xy 234.021005 -67.281218)
			(xy 234.005648 -67.333513) (xy 233.983007 -67.38309) (xy 233.953541 -67.428941) (xy 233.91785 -67.470133)
			(xy 233.876661 -67.505826) (xy 233.830811 -67.535295) (xy 233.781235 -67.55794) (xy 233.728941 -67.5733)
			(xy 233.674993 -67.581061) (xy 233.647742 -67.581526) (xy 233.614722 -67.580002) (xy 233.609896 -67.579748)
			(xy 233.60253 -67.58051) (xy 233.576872 -67.582182) (xy 233.525527 -67.579442) (xy 233.475016 -67.569828)
			(xy 233.426254 -67.553515) (xy 233.380127 -67.530798) (xy 233.33747 -67.502089) (xy 233.299057 -67.467909)
			(xy 233.281982 -67.448684) (xy 233.280712 -67.44716) (xy 233.276648 -67.443096) (xy 233.271401 -67.438133)
			(xy 233.258753 -67.431172) (xy 233.251756 -67.42938) (xy 233.244626 -67.42812) (xy 233.230191 -67.429164)
			(xy 233.223308 -67.431412) (xy 233.156506 -67.455796) (xy 233.137964 -67.462654) (xy 233.137456 -67.462908)
			(xy 233.134916 -67.46367) (xy 233.13009 -67.465448) (xy 233.12882 -67.46621) (xy 233.128312 -67.46621)
			(xy 233.123409 -67.46891) (xy 233.114822 -67.476088) (xy 233.111294 -67.480434) (xy 233.11104 -67.480688)
			(xy 233.11104 -67.921632) (xy 233.116628 -67.927982) (xy 233.120179 -67.93117) (xy 233.128233 -67.936288)
			(xy 233.13263 -67.938142) (xy 233.226356 -67.970654) (xy 233.230173 -67.97191) (xy 233.238087 -67.973308)
			(xy 233.242104 -67.973448) (xy 233.24947 -67.973448) (xy 233.256836 -67.971416) (xy 233.264202 -67.96913)
			(xy 233.277156 -67.960494) (xy 233.28249 -67.953636) (xy 233.284268 -67.95135) (xy 233.285284 -67.95008)
			(xy 233.296223 -67.936771) (xy 233.320135 -67.911967) (xy 233.333036 -67.90055) (xy 233.339894 -67.894454)
			(xy 233.344466 -67.891152) (xy 233.370374 -67.872102) (xy 233.370628 -67.871848) (xy 233.395323 -67.855195)
			(xy 233.448711 -67.828795) (xy 233.505503 -67.810852) (xy 233.564368 -67.801785) (xy 233.594148 -67.801236)
			(xy 233.594402 -67.801236) (xy 233.610158 -67.801381) (xy 233.641566 -67.803928) (xy 233.65714 -67.806316)
			(xy 233.662474 -67.807078) (xy 233.668062 -67.80784) (xy 233.670348 -67.80784) (xy 233.696998 -67.809189)
			(xy 233.749556 -67.818408) (xy 233.800319 -67.834855) (xy 233.848297 -67.85821) (xy 233.892555 -67.888019)
			(xy 233.932231 -67.923701) (xy 233.966552 -67.96456) (xy 233.994849 -68.009799) (xy 234.016571 -68.058539)
			(xy 234.031294 -68.109828) (xy 234.038731 -68.162668) (xy 234.039156 -68.189348) (xy 234.03863 -68.217757)
			(xy 234.030197 -68.273945) (xy 234.013526 -68.328262) (xy 233.988984 -68.379506) (xy 233.957115 -68.426544)
			(xy 233.918622 -68.468336) (xy 233.874358 -68.503958) (xy 233.825301 -68.532622) (xy 233.799126 -68.543678)
			(xy 233.795316 -68.545202) (xy 233.787084 -68.549788) (xy 233.774403 -68.563702) (xy 233.767598 -68.581255)
			(xy 233.767122 -68.590668) (xy 233.767122 -68.593208) (xy 233.767122 -68.594478) (xy 233.766868 -68.60032)
			(xy 233.766835 -68.607563) (xy 233.770315 -68.621616) (xy 233.773726 -68.628006) (xy 233.776012 -68.631308)
			(xy 233.77652 -68.63207) (xy 233.776774 -68.632324) (xy 233.778298 -68.63461) (xy 233.785156 -68.641722)
			(xy 233.789982 -68.645786) (xy 233.794554 -68.647818) (xy 233.79811 -68.649342) (xy 233.823472 -68.660776)
			(xy 233.870868 -68.689907) (xy 233.913534 -68.725608) (xy 233.950567 -68.767123) (xy 233.981184 -68.813572)
			(xy 234.004735 -68.863973) (xy 234.020723 -68.917259) (xy 234.028809 -68.9723) (xy 234.02925 -69.000116)
			(xy 234.028763 -69.027368) (xy 234.021005 -69.081316) (xy 234.005649 -69.133611) (xy 233.983007 -69.183189)
			(xy 233.953541 -69.22904) (xy 233.917851 -69.270232) (xy 233.876661 -69.305926) (xy 233.830812 -69.335395)
			(xy 233.781235 -69.35804) (xy 233.728941 -69.373399) (xy 233.674994 -69.381161) (xy 233.647742 -69.381624)
			(xy 233.614722 -69.3801) (xy 233.609896 -69.379846) (xy 233.60253 -69.380608) (xy 233.576871 -69.38228)
			(xy 233.525525 -69.37954) (xy 233.475012 -69.369928) (xy 233.426248 -69.353618) (xy 233.380117 -69.330905)
			(xy 233.337455 -69.302201) (xy 233.299035 -69.268027) (xy 233.281982 -69.248782) (xy 233.280712 -69.247258)
			(xy 233.276648 -69.243194) (xy 233.271401 -69.238231) (xy 233.258753 -69.23127) (xy 233.251756 -69.229478)
			(xy 233.244626 -69.228218) (xy 233.230191 -69.229262) (xy 233.223308 -69.23151) (xy 233.156506 -69.255894)
			(xy 233.137964 -69.262752) (xy 233.137456 -69.263006) (xy 233.134916 -69.263768) (xy 233.13009 -69.265546)
			(xy 233.12882 -69.266308) (xy 233.128312 -69.266308) (xy 233.123409 -69.269008) (xy 233.114822 -69.276186)
			(xy 233.111294 -69.280532) (xy 233.11104 -69.280786) (xy 233.11104 -70.116954) (xy 239.652554 -70.116954)
			(xy 239.656625 -70.061332) (xy 239.668751 -70.006895) (xy 239.688674 -69.954804) (xy 239.71597 -69.906169)
			(xy 239.750056 -69.862026) (xy 239.790205 -69.823317) (xy 239.835563 -69.790866) (xy 239.885163 -69.765365)
			(xy 239.937947 -69.747358) (xy 239.99279 -69.737228) (xy 240.048524 -69.735191) (xy 240.103961 -69.741291)
			(xy 240.157918 -69.755397) (xy 240.209247 -69.777209) (xy 240.256853 -69.806263) (xy 240.299721 -69.841938)
			(xy 240.336938 -69.883475) (xy 240.367711 -69.929988) (xy 240.391383 -69.980485) (xy 240.407451 -70.033892)
			(xy 240.415571 -70.089068) (xy 240.41608 -70.116954) (xy 240.415571 -70.14484) (xy 240.407451 -70.200016)
			(xy 240.391383 -70.253423) (xy 240.367711 -70.30392) (xy 240.336938 -70.350433) (xy 240.299721 -70.39197)
			(xy 240.256853 -70.427645) (xy 240.209247 -70.456699) (xy 240.157918 -70.478511) (xy 240.103961 -70.492617)
			(xy 240.048524 -70.498717) (xy 239.99279 -70.49668) (xy 239.937947 -70.48655) (xy 239.885163 -70.468543)
			(xy 239.835563 -70.443042) (xy 239.790205 -70.410591) (xy 239.750056 -70.371882) (xy 239.71597 -70.327739)
			(xy 239.688674 -70.279104) (xy 239.668751 -70.227013) (xy 239.656625 -70.172576) (xy 239.652554 -70.116954)
			(xy 233.11104 -70.116954) (xy 233.11104 -70.569074) (xy 233.109516 -70.599554) (xy 233.108357 -70.610895)
			(xy 233.10467 -70.633394) (xy 233.10215 -70.644512) (xy 233.10088 -70.650354) (xy 233.10088 -71.539608)
			(xy 239.186464 -71.539608) (xy 239.190535 -71.483986) (xy 239.202661 -71.429549) (xy 239.222584 -71.377458)
			(xy 239.24988 -71.328823) (xy 239.283966 -71.28468) (xy 239.324115 -71.245971) (xy 239.369473 -71.21352)
			(xy 239.419073 -71.188019) (xy 239.471857 -71.170012) (xy 239.5267 -71.159882) (xy 239.582434 -71.157845)
			(xy 239.637871 -71.163945) (xy 239.691828 -71.178051) (xy 239.743157 -71.199863) (xy 239.790763 -71.228917)
			(xy 239.833631 -71.264592) (xy 239.870848 -71.306129) (xy 239.901621 -71.352642) (xy 239.925293 -71.403139)
			(xy 239.941361 -71.456546) (xy 239.949481 -71.511722) (xy 239.94999 -71.539608) (xy 239.949481 -71.567494)
			(xy 239.941361 -71.62267) (xy 239.925293 -71.676077) (xy 239.901621 -71.726574) (xy 239.870848 -71.773087)
			(xy 239.833631 -71.814624) (xy 239.790763 -71.850299) (xy 239.743157 -71.879353) (xy 239.691828 -71.901165)
			(xy 239.637871 -71.915271) (xy 239.582434 -71.921371) (xy 239.5267 -71.919334) (xy 239.471857 -71.909204)
			(xy 239.419073 -71.891197) (xy 239.369473 -71.865696) (xy 239.324115 -71.833245) (xy 239.283966 -71.794536)
			(xy 239.24988 -71.750393) (xy 239.222584 -71.701758) (xy 239.202661 -71.649667) (xy 239.190535 -71.59523)
			(xy 239.186464 -71.539608) (xy 233.10088 -71.539608) (xy 233.10088 -76.853034) (xy 236.02264 -76.853034)
			(xy 236.026711 -76.797412) (xy 236.038837 -76.742975) (xy 236.05876 -76.690884) (xy 236.086056 -76.642249)
			(xy 236.120142 -76.598106) (xy 236.160291 -76.559397) (xy 236.205649 -76.526946) (xy 236.255249 -76.501445)
			(xy 236.308033 -76.483438) (xy 236.362876 -76.473308) (xy 236.41861 -76.471271) (xy 236.474047 -76.477371)
			(xy 236.528004 -76.491477) (xy 236.579333 -76.513289) (xy 236.626939 -76.542343) (xy 236.669807 -76.578018)
			(xy 236.707024 -76.619555) (xy 236.737797 -76.666068) (xy 236.761469 -76.716565) (xy 236.777537 -76.769972)
			(xy 236.785657 -76.825148) (xy 236.786166 -76.853034) (xy 236.785657 -76.88092) (xy 236.777537 -76.936096)
			(xy 236.761469 -76.989503) (xy 236.737797 -77.04) (xy 236.707024 -77.086513) (xy 236.669807 -77.12805)
			(xy 236.626939 -77.163725) (xy 236.579333 -77.192779) (xy 236.528004 -77.214591) (xy 236.474047 -77.228697)
			(xy 236.41861 -77.234797) (xy 236.362876 -77.23276) (xy 236.308033 -77.22263) (xy 236.255249 -77.204623)
			(xy 236.205649 -77.179122) (xy 236.160291 -77.146671) (xy 236.120142 -77.107962) (xy 236.086056 -77.063819)
			(xy 236.05876 -77.015184) (xy 236.038837 -76.963093) (xy 236.026711 -76.908656) (xy 236.02264 -76.853034)
			(xy 233.10088 -76.853034) (xy 233.10088 -77.36459) (xy 234.24591 -77.36459) (xy 234.249981 -77.308968)
			(xy 234.262107 -77.254531) (xy 234.28203 -77.20244) (xy 234.309326 -77.153805) (xy 234.343412 -77.109662)
			(xy 234.383561 -77.070953) (xy 234.428919 -77.038502) (xy 234.478519 -77.013001) (xy 234.531303 -76.994994)
			(xy 234.586146 -76.984864) (xy 234.64188 -76.982827) (xy 234.697317 -76.988927) (xy 234.751274 -77.003033)
			(xy 234.802603 -77.024845) (xy 234.850209 -77.053899) (xy 234.893077 -77.089574) (xy 234.930294 -77.131111)
			(xy 234.961067 -77.177624) (xy 234.984739 -77.228121) (xy 235.000807 -77.281528) (xy 235.008927 -77.336704)
			(xy 235.009436 -77.36459) (xy 235.008927 -77.392476) (xy 235.000807 -77.447652) (xy 234.984739 -77.501059)
			(xy 234.961067 -77.551556) (xy 234.930294 -77.598069) (xy 234.893077 -77.639606) (xy 234.850209 -77.675281)
			(xy 234.802603 -77.704335) (xy 234.751274 -77.726147) (xy 234.697317 -77.740253) (xy 234.64188 -77.746353)
			(xy 234.586146 -77.744316) (xy 234.531303 -77.734186) (xy 234.478519 -77.716179) (xy 234.428919 -77.690678)
			(xy 234.383561 -77.658227) (xy 234.343412 -77.619518) (xy 234.309326 -77.575375) (xy 234.28203 -77.52674)
			(xy 234.262107 -77.474649) (xy 234.249981 -77.420212) (xy 234.24591 -77.36459) (xy 233.10088 -77.36459)
			(xy 233.10088 -78.84668) (xy 233.101642 -78.854808) (xy 233.101642 -78.855316) (xy 233.103242 -78.862835)
			(xy 233.11022 -78.876522) (xy 233.115358 -78.88224) (xy 233.988864 -79.755746) (xy 234.005148 -79.772657)
			(xy 234.033146 -79.81034) (xy 234.055385 -79.851683) (xy 234.063794 -79.873602) (xy 234.066334 -79.881222)
			(xy 234.070144 -79.891636) (xy 234.071922 -79.897224) (xy 234.072176 -79.898494) (xy 234.075075 -79.909965)
			(xy 234.0794 -79.933229) (xy 234.080812 -79.944976) (xy 234.080812 -79.945484) (xy 234.082336 -79.961994)
			(xy 234.082336 -79.962502) (xy 234.08259 -79.966566) (xy 234.08259 -79.967328) (xy 234.082844 -79.982568)
			(xy 234.082844 -80.183482) (xy 237.540292 -80.183482) (xy 237.540292 -79.319882) (xy 237.540782 -79.289914)
			(xy 237.548605 -79.230492) (xy 237.564118 -79.172599) (xy 237.587054 -79.117226) (xy 237.617021 -79.06532)
			(xy 237.653508 -79.01777) (xy 237.695888 -78.97539) (xy 237.743438 -78.938903) (xy 237.795344 -78.908936)
			(xy 237.850717 -78.886) (xy 237.90861 -78.870487) (xy 237.968032 -78.862664) (xy 238.027968 -78.862664)
			(xy 238.08739 -78.870487) (xy 238.145283 -78.886) (xy 238.200656 -78.908936) (xy 238.252562 -78.938903)
			(xy 238.300112 -78.97539) (xy 238.342492 -79.01777) (xy 238.378979 -79.06532) (xy 238.408946 -79.117226)
			(xy 238.431882 -79.172599) (xy 238.447395 -79.230492) (xy 238.455218 -79.289914) (xy 238.455708 -79.319882)
			(xy 238.455708 -80.183482) (xy 238.455218 -80.21345) (xy 238.447395 -80.272872) (xy 238.431882 -80.330765)
			(xy 238.408946 -80.386138) (xy 238.378979 -80.438044) (xy 238.342492 -80.485594) (xy 238.300112 -80.527974)
			(xy 238.252562 -80.564461) (xy 238.200656 -80.594428) (xy 238.145283 -80.617364) (xy 238.08739 -80.632877)
			(xy 238.027968 -80.6407) (xy 237.968032 -80.6407) (xy 237.90861 -80.632877) (xy 237.850717 -80.617364)
			(xy 237.795344 -80.594428) (xy 237.743438 -80.564461) (xy 237.695888 -80.527974) (xy 237.653508 -80.485594)
			(xy 237.617021 -80.438044) (xy 237.587054 -80.386138) (xy 237.564118 -80.330765) (xy 237.548605 -80.272872)
			(xy 237.540782 -80.21345) (xy 237.540292 -80.183482) (xy 234.082844 -80.183482) (xy 234.082844 -82.132678)
			(xy 234.081828 -82.158078) (xy 234.079182 -82.184737) (xy 234.066161 -82.236701) (xy 234.05592 -82.261456)
			(xy 234.05211 -82.270092) (xy 234.049824 -82.274664) (xy 234.047538 -82.27949) (xy 234.047284 -82.280252)
			(xy 234.04576 -82.2833) (xy 234.038648 -82.295238) (xy 234.038394 -82.295492) (xy 234.036108 -82.299302)
			(xy 234.035854 -82.299556) (xy 234.035092 -82.300572) (xy 234.034076 -82.30235) (xy 234.028961 -82.310443)
			(xy 234.017907 -82.326076) (xy 234.011978 -82.333592) (xy 234.008785 -82.337171) (xy 238.132537 -82.337171)
			(xy 238.132537 -82.277229) (xy 238.140362 -82.217799) (xy 238.155876 -82.159898) (xy 238.178816 -82.104519)
			(xy 238.208788 -82.052607) (xy 238.24528 -82.005052) (xy 238.287667 -81.962667) (xy 238.335224 -81.926177)
			(xy 238.387137 -81.896207) (xy 238.442517 -81.87327) (xy 238.500418 -81.857758) (xy 238.559849 -81.849936)
			(xy 238.58982 -81.849468) (xy 239.45342 -81.849468) (xy 239.483385 -81.850007) (xy 239.542803 -81.857832)
			(xy 239.600691 -81.873345) (xy 239.656058 -81.896282) (xy 239.707959 -81.926248) (xy 239.755504 -81.962733)
			(xy 239.79788 -82.005111) (xy 239.834363 -82.052658) (xy 239.864327 -82.10456) (xy 239.887261 -82.159928)
			(xy 239.902772 -82.217817) (xy 239.910594 -82.277235) (xy 239.910594 -82.337165) (xy 239.902772 -82.396583)
			(xy 239.887261 -82.454472) (xy 239.864327 -82.50984) (xy 239.834363 -82.561742) (xy 239.79788 -82.609289)
			(xy 239.755504 -82.651667) (xy 239.707959 -82.688152) (xy 239.656058 -82.718118) (xy 239.600691 -82.741055)
			(xy 239.542803 -82.756568) (xy 239.483385 -82.764393) (xy 239.45342 -82.764884) (xy 238.58982 -82.764884)
			(xy 238.559849 -82.764464) (xy 238.500418 -82.756642) (xy 238.442517 -82.74113) (xy 238.387137 -82.718193)
			(xy 238.335224 -82.688223) (xy 238.287667 -82.651733) (xy 238.24528 -82.609348) (xy 238.208788 -82.561793)
			(xy 238.178816 -82.509881) (xy 238.155876 -82.454502) (xy 238.140362 -82.396601) (xy 238.132537 -82.337171)
			(xy 234.008785 -82.337171) (xy 233.988864 -82.3595) (xy 233.614468 -82.733896) (xy 233.611761 -82.736746)
			(xy 233.607164 -82.743123) (xy 233.605324 -82.746596) (xy 233.602745 -82.752024) (xy 233.599932 -82.763703)
			(xy 233.599736 -82.76971) (xy 233.599736 -83.068414) (xy 233.59999 -83.367118) (xy 233.599517 -83.397146)
			(xy 233.591665 -83.456686) (xy 233.576099 -83.514689) (xy 233.553085 -83.570161) (xy 233.523018 -83.622148)
			(xy 233.486415 -83.66976) (xy 233.443902 -83.712179) (xy 233.39621 -83.748678) (xy 233.344157 -83.77863)
			(xy 233.288636 -83.801522) (xy 233.230598 -83.816961) (xy 233.171041 -83.824682) (xy 233.141012 -83.82508)
			(xy 233.111144 -83.824527) (xy 233.05193 -83.816622) (xy 232.994246 -83.801089) (xy 232.939069 -83.77819)
			(xy 232.887337 -83.748314) (xy 232.839927 -83.711968) (xy 232.818432 -83.691222) (xy 232.816654 -83.689444)
			(xy 232.812844 -83.68538) (xy 232.811574 -83.68411) (xy 232.811066 -83.683602) (xy 232.803776 -83.676653)
			(xy 232.785308 -83.668655) (xy 232.775252 -83.668108) (xy 232.774998 -83.668108) (xy 232.702608 -83.667346)
			(xy 232.692498 -83.667677) (xy 232.673763 -83.675266) (xy 232.666286 -83.682078) (xy 232.057194 -84.29117)
			(xy 232.052169 -84.296595) (xy 232.045214 -84.309635) (xy 232.043478 -84.316824) (xy 232.043478 -84.337144)
			(xy 232.044494 -84.341716) (xy 232.047546 -84.359018) (xy 232.05085 -84.393999) (xy 232.051098 -84.411566)
			(xy 232.051098 -84.414106) (xy 232.050543 -84.44131) (xy 232.042671 -84.495148) (xy 232.027228 -84.547322)
			(xy 232.00453 -84.596772) (xy 231.975036 -84.642495) (xy 231.939345 -84.683565) (xy 231.898181 -84.719146)
			(xy 231.852379 -84.748518) (xy 231.802869 -84.771085) (xy 231.750654 -84.786388) (xy 231.696795 -84.794117)
			(xy 231.66959 -84.794598) (xy 231.669336 -84.794598) (xy 231.645087 -84.794221) (xy 231.596979 -84.788073)
			(xy 231.55004 -84.77587) (xy 231.505029 -84.757811) (xy 231.483662 -84.746338) (xy 231.478836 -84.743544)
			(xy 231.463088 -84.738718) (xy 231.459547 -84.737755) (xy 231.452279 -84.736741) (xy 231.44861 -84.736686)
			(xy 230.5812 -84.736686) (xy 230.563674 -84.743544) (xy 230.559864 -84.7471) (xy 230.557578 -84.749386)
			(xy 230.550179 -84.75623) (xy 230.531581 -84.763959) (xy 230.52151 -84.764372) (xy 230.304086 -84.764372)
			(xy 230.294078 -84.764862) (xy 230.275586 -84.772523) (xy 230.261431 -84.786675) (xy 230.253765 -84.805164)
			(xy 230.253286 -84.815172) (xy 230.253286 -85.458587) (xy 232.264389 -85.458587) (xy 232.264389 -85.398613)
			(xy 232.272218 -85.339151) (xy 232.28774 -85.28122) (xy 232.310692 -85.225811) (xy 232.34068 -85.173871)
			(xy 232.377191 -85.126291) (xy 232.4196 -85.083883) (xy 232.467181 -85.047373) (xy 232.519122 -85.017387)
			(xy 232.574531 -84.994437) (xy 232.632463 -84.978915) (xy 232.691925 -84.971088) (xy 232.721912 -84.97062)
			(xy 233.585512 -84.97062) (xy 233.615495 -84.971147) (xy 233.674947 -84.978975) (xy 233.732868 -84.994497)
			(xy 233.788268 -85.017445) (xy 233.840199 -85.047429) (xy 233.887772 -85.083934) (xy 233.930174 -85.126337)
			(xy 233.963295 -85.169502) (xy 238.555276 -85.169502) (xy 238.555276 -84.305902) (xy 238.555766 -84.275918)
			(xy 238.563594 -84.216462) (xy 238.579115 -84.158537) (xy 238.602064 -84.103133) (xy 238.632048 -84.051199)
			(xy 238.668554 -84.003623) (xy 238.710959 -83.961218) (xy 238.758535 -83.924712) (xy 238.810469 -83.894728)
			(xy 238.865873 -83.871779) (xy 238.923798 -83.856258) (xy 238.983254 -83.84843) (xy 239.043222 -83.84843)
			(xy 239.102678 -83.856258) (xy 239.160603 -83.871779) (xy 239.216007 -83.894728) (xy 239.267941 -83.924712)
			(xy 239.315517 -83.961218) (xy 239.357922 -84.003623) (xy 239.394428 -84.051199) (xy 239.424412 -84.103133)
			(xy 239.447361 -84.158537) (xy 239.462882 -84.216462) (xy 239.47071 -84.275918) (xy 239.4712 -84.305902)
			(xy 239.4712 -85.169502) (xy 239.47071 -85.199486) (xy 239.462882 -85.258942) (xy 239.447361 -85.316867)
			(xy 239.424412 -85.372271) (xy 239.394428 -85.424205) (xy 239.357922 -85.471781) (xy 239.315517 -85.514186)
			(xy 239.267941 -85.550692) (xy 239.216007 -85.580676) (xy 239.160603 -85.603625) (xy 239.102678 -85.619146)
			(xy 239.043222 -85.626974) (xy 238.983254 -85.626974) (xy 238.923798 -85.619146) (xy 238.865873 -85.603625)
			(xy 238.810469 -85.580676) (xy 238.758535 -85.550692) (xy 238.710959 -85.514186) (xy 238.668554 -85.471781)
			(xy 238.632048 -85.424205) (xy 238.602064 -85.372271) (xy 238.579115 -85.316867) (xy 238.563594 -85.258942)
			(xy 238.555766 -85.199486) (xy 238.555276 -85.169502) (xy 233.963295 -85.169502) (xy 233.966678 -85.173911)
			(xy 233.99666 -85.225842) (xy 234.019607 -85.281243) (xy 234.035127 -85.339165) (xy 234.042954 -85.398617)
			(xy 234.042954 -85.458583) (xy 234.035127 -85.518035) (xy 234.019607 -85.575957) (xy 233.99666 -85.631358)
			(xy 233.966678 -85.683289) (xy 233.930174 -85.730863) (xy 233.887772 -85.773266) (xy 233.840199 -85.809771)
			(xy 233.788268 -85.839755) (xy 233.732868 -85.862703) (xy 233.674947 -85.878225) (xy 233.615495 -85.886053)
			(xy 233.585512 -85.886544) (xy 232.721912 -85.886544) (xy 232.691925 -85.886112) (xy 232.632463 -85.878285)
			(xy 232.574531 -85.862763) (xy 232.519122 -85.839813) (xy 232.467181 -85.809827) (xy 232.4196 -85.773317)
			(xy 232.377191 -85.730909) (xy 232.34068 -85.683329) (xy 232.310692 -85.631389) (xy 232.28774 -85.57598)
			(xy 232.272218 -85.518049) (xy 232.264389 -85.458587) (xy 230.253286 -85.458587) (xy 230.253286 -86.906608)
			(xy 230.252653 -86.917931) (xy 230.242883 -86.938362) (xy 230.225285 -86.952618) (xy 230.214424 -86.955884)
			(xy 230.207742 -86.957791) (xy 230.195648 -86.964624) (xy 230.190548 -86.969346) (xy 230.186992 -86.972902)
			(xy 230.179372 -86.991444) (xy 230.179372 -87.444066) (xy 232.194882 -87.444066) (xy 232.194882 -87.384134)
			(xy 232.202704 -87.324714) (xy 232.218215 -87.266824) (xy 232.241149 -87.211454) (xy 232.271114 -87.15955)
			(xy 232.307596 -87.112002) (xy 232.349973 -87.069621) (xy 232.397519 -87.033135) (xy 232.44942 -87.003166)
			(xy 232.504788 -86.980227) (xy 232.562677 -86.964712) (xy 232.622096 -86.956884) (xy 232.652062 -86.956392)
			(xy 233.515662 -86.956392) (xy 233.545633 -86.956859) (xy 233.605062 -86.964678) (xy 233.662961 -86.980188)
			(xy 233.718341 -87.003123) (xy 233.770254 -87.033091) (xy 233.81781 -87.069578) (xy 233.860197 -87.111961)
			(xy 233.896688 -87.159515) (xy 233.92666 -87.211425) (xy 233.9496 -87.266803) (xy 233.965115 -87.324701)
			(xy 233.972939 -87.384129) (xy 233.972939 -87.416385) (xy 234.381521 -87.416385) (xy 234.381521 -87.356415)
			(xy 234.389349 -87.296959) (xy 234.40487 -87.239032) (xy 234.42782 -87.183628) (xy 234.457804 -87.131692)
			(xy 234.494312 -87.084115) (xy 234.536717 -87.04171) (xy 234.584294 -87.005203) (xy 234.636229 -86.975219)
			(xy 234.691634 -86.952269) (xy 234.749561 -86.936748) (xy 234.809017 -86.928921) (xy 234.839002 -86.928452)
			(xy 235.702602 -86.928452) (xy 235.732587 -86.928914) (xy 235.792044 -86.936742) (xy 235.849971 -86.952264)
			(xy 235.905376 -86.975214) (xy 235.957312 -87.005199) (xy 236.004889 -87.041707) (xy 236.047295 -87.084112)
			(xy 236.083802 -87.13169) (xy 236.113787 -87.183626) (xy 236.136737 -87.239031) (xy 236.152258 -87.296958)
			(xy 236.160086 -87.356415) (xy 236.160086 -87.416385) (xy 236.152258 -87.475842) (xy 236.136737 -87.533769)
			(xy 236.113787 -87.589174) (xy 236.083802 -87.64111) (xy 236.047295 -87.688688) (xy 236.004889 -87.731093)
			(xy 235.957312 -87.767601) (xy 235.905376 -87.797586) (xy 235.849971 -87.820536) (xy 235.792044 -87.836058)
			(xy 235.732587 -87.843886) (xy 235.702602 -87.844376) (xy 234.839002 -87.844376) (xy 234.809017 -87.843879)
			(xy 234.749561 -87.836052) (xy 234.691634 -87.820531) (xy 234.636229 -87.797581) (xy 234.584294 -87.767597)
			(xy 234.536717 -87.73109) (xy 234.494312 -87.688685) (xy 234.457804 -87.641108) (xy 234.42782 -87.589172)
			(xy 234.40487 -87.533768) (xy 234.389349 -87.475841) (xy 234.381521 -87.416385) (xy 233.972939 -87.416385)
			(xy 233.972939 -87.444071) (xy 233.965115 -87.503499) (xy 233.9496 -87.561397) (xy 233.92666 -87.616775)
			(xy 233.896688 -87.668685) (xy 233.860197 -87.716239) (xy 233.81781 -87.758622) (xy 233.770254 -87.795109)
			(xy 233.718341 -87.825077) (xy 233.662961 -87.848012) (xy 233.605062 -87.863522) (xy 233.545633 -87.871341)
			(xy 233.515662 -87.871808) (xy 232.652062 -87.871808) (xy 232.622096 -87.871316) (xy 232.562677 -87.863488)
			(xy 232.504788 -87.847973) (xy 232.44942 -87.825034) (xy 232.397519 -87.795065) (xy 232.349973 -87.758579)
			(xy 232.307596 -87.716198) (xy 232.271114 -87.66865) (xy 232.241149 -87.616746) (xy 232.218215 -87.561376)
			(xy 232.202704 -87.503486) (xy 232.194882 -87.444066) (xy 230.179372 -87.444066) (xy 230.179372 -88.006187)
			(xy 238.124409 -88.006187) (xy 238.124409 -87.946213) (xy 238.132238 -87.886751) (xy 238.147762 -87.82882)
			(xy 238.170714 -87.773411) (xy 238.200704 -87.721472) (xy 238.237216 -87.673892) (xy 238.279627 -87.631486)
			(xy 238.32721 -87.594978) (xy 238.379152 -87.564994) (xy 238.434563 -87.542047) (xy 238.492496 -87.526529)
			(xy 238.551959 -87.518706) (xy 238.581946 -87.51824) (xy 239.445546 -87.51824) (xy 239.475528 -87.518729)
			(xy 239.53498 -87.526561) (xy 239.5929 -87.542086) (xy 239.648299 -87.565038) (xy 239.700228 -87.595024)
			(xy 239.747799 -87.631531) (xy 239.790199 -87.673935) (xy 239.826701 -87.72151) (xy 239.856682 -87.773442)
			(xy 239.879628 -87.828843) (xy 239.895148 -87.886765) (xy 239.902974 -87.946217) (xy 239.902974 -88.006183)
			(xy 239.895148 -88.065635) (xy 239.879628 -88.123557) (xy 239.856682 -88.178958) (xy 239.826701 -88.23089)
			(xy 239.790199 -88.278465) (xy 239.747799 -88.320869) (xy 239.700228 -88.357376) (xy 239.648299 -88.387362)
			(xy 239.5929 -88.410314) (xy 239.53498 -88.425839) (xy 239.475528 -88.433671) (xy 239.445546 -88.434164)
			(xy 238.581946 -88.434164) (xy 238.551959 -88.433694) (xy 238.492496 -88.425871) (xy 238.434563 -88.410353)
			(xy 238.379152 -88.387406) (xy 238.32721 -88.357422) (xy 238.279627 -88.320914) (xy 238.237216 -88.278508)
			(xy 238.200704 -88.230928) (xy 238.170714 -88.178989) (xy 238.147762 -88.12358) (xy 238.132238 -88.065649)
			(xy 238.124409 -88.006187) (xy 230.179372 -88.006187) (xy 230.179372 -88.007444) (xy 230.178883 -88.03353)
			(xy 230.17071 -88.085058) (xy 230.154573 -88.134672) (xy 230.13087 -88.181149) (xy 230.100185 -88.223344)
			(xy 230.08209 -88.24214) (xy 229.743254 -88.580722) (xy 229.737753 -88.586639) (xy 229.730366 -88.600996)
			(xy 229.728776 -88.608916) (xy 229.728268 -88.61679) (xy 229.728268 -88.889586) (xy 234.138976 -88.889586)
			(xy 234.143047 -88.833964) (xy 234.155173 -88.779527) (xy 234.175096 -88.727436) (xy 234.202392 -88.678801)
			(xy 234.236478 -88.634658) (xy 234.276627 -88.595949) (xy 234.321985 -88.563498) (xy 234.371585 -88.537997)
			(xy 234.424369 -88.51999) (xy 234.479212 -88.50986) (xy 234.534946 -88.507823) (xy 234.590383 -88.513923)
			(xy 234.64434 -88.528029) (xy 234.695669 -88.549841) (xy 234.743275 -88.578895) (xy 234.786143 -88.61457)
			(xy 234.82336 -88.656107) (xy 234.854133 -88.70262) (xy 234.877805 -88.753117) (xy 234.893873 -88.806524)
			(xy 234.901993 -88.8617) (xy 234.902502 -88.889586) (xy 234.901993 -88.917472) (xy 234.893873 -88.972648)
			(xy 234.877805 -89.026055) (xy 234.854133 -89.076552) (xy 234.82336 -89.123065) (xy 234.786143 -89.164602)
			(xy 234.743275 -89.200277) (xy 234.695669 -89.229331) (xy 234.64434 -89.251143) (xy 234.590383 -89.265249)
			(xy 234.534946 -89.271349) (xy 234.479212 -89.269312) (xy 234.424369 -89.259182) (xy 234.371585 -89.241175)
			(xy 234.321985 -89.215674) (xy 234.276627 -89.183223) (xy 234.236478 -89.144514) (xy 234.202392 -89.100371)
			(xy 234.175096 -89.051736) (xy 234.155173 -88.999645) (xy 234.143047 -88.945208) (xy 234.138976 -88.889586)
			(xy 229.728268 -88.889586) (xy 229.728268 -89.781634) (xy 229.728313 -89.785304) (xy 229.729333 -89.792572)
			(xy 229.7303 -89.796112) (xy 229.73305 -89.804219) (xy 229.743048 -89.818102) (xy 229.749858 -89.82329)
			(xy 229.817676 -89.871042) (xy 229.82426 -89.875375) (xy 229.839264 -89.880172) (xy 229.84714 -89.88044)
			(xy 229.86365 -89.877392) (xy 229.867714 -89.876122) (xy 229.898017 -89.866292) (xy 229.960831 -89.855691)
			(xy 229.992682 -89.85504) (xy 230.019217 -89.855502) (xy 230.071773 -89.862866) (xy 230.122802 -89.87744)
			(xy 230.17132 -89.898944) (xy 230.216391 -89.926962) (xy 230.257145 -89.960954) (xy 230.292797 -90.000264)
			(xy 230.322659 -90.044135) (xy 230.346155 -90.09172) (xy 230.362832 -90.142102) (xy 230.372367 -90.194308)
			(xy 230.373455 -90.212672) (xy 236.886494 -90.212672) (xy 236.890565 -90.15705) (xy 236.902691 -90.102613)
			(xy 236.922614 -90.050522) (xy 236.94991 -90.001887) (xy 236.983996 -89.957744) (xy 237.024145 -89.919035)
			(xy 237.069503 -89.886584) (xy 237.119103 -89.861083) (xy 237.171887 -89.843076) (xy 237.22673 -89.832946)
			(xy 237.282464 -89.830909) (xy 237.337901 -89.837009) (xy 237.391858 -89.851115) (xy 237.443187 -89.872927)
			(xy 237.490793 -89.901981) (xy 237.533661 -89.937656) (xy 237.570878 -89.979193) (xy 237.601651 -90.025706)
			(xy 237.625323 -90.076203) (xy 237.641391 -90.12961) (xy 237.649511 -90.184786) (xy 237.65002 -90.212672)
			(xy 237.649511 -90.240558) (xy 237.641391 -90.295734) (xy 237.625323 -90.349141) (xy 237.601651 -90.399638)
			(xy 237.570878 -90.446151) (xy 237.533661 -90.487688) (xy 237.490793 -90.523363) (xy 237.443187 -90.552417)
			(xy 237.391858 -90.574229) (xy 237.337901 -90.588335) (xy 237.282464 -90.594435) (xy 237.22673 -90.592398)
			(xy 237.171887 -90.582268) (xy 237.119103 -90.564261) (xy 237.069503 -90.53876) (xy 237.024145 -90.506309)
			(xy 236.983996 -90.4676) (xy 236.94991 -90.423457) (xy 236.922614 -90.374822) (xy 236.902691 -90.322731)
			(xy 236.890565 -90.268294) (xy 236.886494 -90.212672) (xy 230.373455 -90.212672) (xy 230.373936 -90.2208)
			(xy 230.374395 -90.227466) (xy 230.378378 -90.240214) (xy 230.38181 -90.245946) (xy 230.38308 -90.247978)
			(xy 230.38663 -90.252701) (xy 230.395488 -90.260518) (xy 230.400606 -90.263472) (xy 230.462836 -90.29319)
			(xy 230.468011 -90.295451) (xy 230.479035 -90.297887) (xy 230.48468 -90.298016) (xy 230.52786 -90.298016)
			(xy 230.542338 -90.293444) (xy 230.546402 -90.29065) (xy 230.570527 -90.274534) (xy 230.622622 -90.249002)
			(xy 230.67798 -90.231644) (xy 230.735326 -90.222859) (xy 230.764334 -90.222324) (xy 230.791583 -90.222813)
			(xy 230.845525 -90.230573) (xy 230.897814 -90.245932) (xy 230.947385 -90.268575) (xy 230.993228 -90.298043)
			(xy 231.034412 -90.333735) (xy 231.070097 -90.374924) (xy 231.099557 -90.420773) (xy 231.122191 -90.470348)
			(xy 231.137541 -90.522639) (xy 231.145292 -90.576583) (xy 231.145842 -90.603832) (xy 231.145842 -90.60434)
			(xy 231.145357 -90.631649) (xy 231.137533 -90.685703) (xy 231.122079 -90.738089) (xy 231.099311 -90.787735)
			(xy 231.069695 -90.833626) (xy 231.052116 -90.85453) (xy 231.045512 -90.86215) (xy 231.042464 -90.87104)
			(xy 231.040993 -90.875592) (xy 231.039595 -90.885053) (xy 231.03967 -90.889836) (xy 231.042464 -90.959686)
			(xy 231.043239 -90.969221) (xy 231.050932 -90.986721) (xy 231.05745 -90.993722) (xy 231.057704 -90.993976)
			(xy 231.078989 -91.015653) (xy 231.115096 -91.064506) (xy 231.127751 -91.088972) (xy 236.971838 -91.088972)
			(xy 236.975909 -91.03335) (xy 236.988035 -90.978913) (xy 237.007958 -90.926822) (xy 237.035254 -90.878187)
			(xy 237.06934 -90.834044) (xy 237.109489 -90.795335) (xy 237.154847 -90.762884) (xy 237.204447 -90.737383)
			(xy 237.257231 -90.719376) (xy 237.312074 -90.709246) (xy 237.367808 -90.707209) (xy 237.423245 -90.713309)
			(xy 237.477202 -90.727415) (xy 237.528531 -90.749227) (xy 237.576137 -90.778281) (xy 237.619005 -90.813956)
			(xy 237.656222 -90.855493) (xy 237.686995 -90.902006) (xy 237.710667 -90.952503) (xy 237.726735 -91.00591)
			(xy 237.734855 -91.061086) (xy 237.735364 -91.088972) (xy 237.734855 -91.116858) (xy 237.726735 -91.172034)
			(xy 237.710667 -91.225441) (xy 237.686995 -91.275938) (xy 237.656222 -91.322451) (xy 237.619005 -91.363988)
			(xy 237.576137 -91.399663) (xy 237.528531 -91.428717) (xy 237.477202 -91.450529) (xy 237.423245 -91.464635)
			(xy 237.367808 -91.470735) (xy 237.312074 -91.468698) (xy 237.257231 -91.458568) (xy 237.204447 -91.440561)
			(xy 237.154847 -91.41506) (xy 237.109489 -91.382609) (xy 237.06934 -91.3439) (xy 237.035254 -91.299757)
			(xy 237.007958 -91.251122) (xy 236.988035 -91.199031) (xy 236.975909 -91.144594) (xy 236.971838 -91.088972)
			(xy 231.127751 -91.088972) (xy 231.143006 -91.118464) (xy 231.162013 -91.176162) (xy 231.171637 -91.236144)
			(xy 231.172258 -91.266518) (xy 231.171708 -91.29638) (xy 231.162452 -91.355381) (xy 231.144108 -91.412216)
			(xy 231.117124 -91.465495) (xy 231.08216 -91.513913) (xy 231.040073 -91.556285) (xy 231.016302 -91.574366)
			(xy 231.015794 -91.574366) (xy 231.015794 -91.57462) (xy 231.011608 -91.577884) (xy 231.004563 -91.585821)
			(xy 231.001824 -91.590368) (xy 230.99922 -91.595279) (xy 230.996014 -91.605918) (xy 230.995474 -91.61145)
			(xy 230.992446 -91.650312) (xy 239.454434 -91.650312) (xy 239.458505 -91.59469) (xy 239.470631 -91.540253)
			(xy 239.490554 -91.488162) (xy 239.51785 -91.439527) (xy 239.551936 -91.395384) (xy 239.592085 -91.356675)
			(xy 239.637443 -91.324224) (xy 239.687043 -91.298723) (xy 239.739827 -91.280716) (xy 239.79467 -91.270586)
			(xy 239.850404 -91.268549) (xy 239.905841 -91.274649) (xy 239.959798 -91.288755) (xy 240.011127 -91.310567)
			(xy 240.058733 -91.339621) (xy 240.101601 -91.375296) (xy 240.138818 -91.416833) (xy 240.169591 -91.463346)
			(xy 240.193263 -91.513843) (xy 240.209331 -91.56725) (xy 240.217451 -91.622426) (xy 240.21796 -91.650312)
			(xy 240.217451 -91.678198) (xy 240.209331 -91.733374) (xy 240.193263 -91.786781) (xy 240.169591 -91.837278)
			(xy 240.138818 -91.883791) (xy 240.101601 -91.925328) (xy 240.058733 -91.961003) (xy 240.011127 -91.990057)
			(xy 239.959798 -92.011869) (xy 239.905841 -92.025975) (xy 239.850404 -92.032075) (xy 239.79467 -92.030038)
			(xy 239.739827 -92.019908) (xy 239.687043 -92.001901) (xy 239.637443 -91.9764) (xy 239.592085 -91.943949)
			(xy 239.551936 -91.90524) (xy 239.51785 -91.861097) (xy 239.490554 -91.812462) (xy 239.470631 -91.760371)
			(xy 239.458505 -91.705934) (xy 239.454434 -91.650312) (xy 230.992446 -91.650312) (xy 230.989378 -91.689682)
			(xy 230.989263 -91.699333) (xy 230.995402 -91.717614) (xy 231.001316 -91.725242) (xy 231.202484 -91.92641)
			(xy 231.220514 -91.945181) (xy 231.25109 -91.987299) (xy 231.274713 -92.033676) (xy 231.290801 -92.083173)
			(xy 231.298962 -92.134575) (xy 231.299512 -92.160598) (xy 231.299512 -92.665042) (xy 237.406432 -92.665042)
			(xy 237.410503 -92.60942) (xy 237.422629 -92.554983) (xy 237.442552 -92.502892) (xy 237.469848 -92.454257)
			(xy 237.503934 -92.410114) (xy 237.544083 -92.371405) (xy 237.589441 -92.338954) (xy 237.639041 -92.313453)
			(xy 237.691825 -92.295446) (xy 237.746668 -92.285316) (xy 237.802402 -92.283279) (xy 237.857839 -92.289379)
			(xy 237.911796 -92.303485) (xy 237.963125 -92.325297) (xy 238.010731 -92.354351) (xy 238.053599 -92.390026)
			(xy 238.090816 -92.431563) (xy 238.121589 -92.478076) (xy 238.145261 -92.528573) (xy 238.161329 -92.58198)
			(xy 238.169449 -92.637156) (xy 238.169958 -92.665042) (xy 238.169449 -92.692928) (xy 238.161329 -92.748104)
			(xy 238.145261 -92.801511) (xy 238.121589 -92.852008) (xy 238.090816 -92.898521) (xy 238.053599 -92.940058)
			(xy 238.010731 -92.975733) (xy 237.963125 -93.004787) (xy 237.911796 -93.026599) (xy 237.857839 -93.040705)
			(xy 237.802402 -93.046805) (xy 237.746668 -93.044768) (xy 237.691825 -93.034638) (xy 237.639041 -93.016631)
			(xy 237.589441 -92.99113) (xy 237.544083 -92.958679) (xy 237.503934 -92.91997) (xy 237.469848 -92.875827)
			(xy 237.442552 -92.827192) (xy 237.422629 -92.775101) (xy 237.410503 -92.720664) (xy 237.406432 -92.665042)
			(xy 231.299512 -92.665042) (xy 231.299512 -93.76664) (xy 236.86592 -93.76664) (xy 236.869991 -93.711018)
			(xy 236.882117 -93.656581) (xy 236.90204 -93.60449) (xy 236.929336 -93.555855) (xy 236.963422 -93.511712)
			(xy 237.003571 -93.473003) (xy 237.048929 -93.440552) (xy 237.098529 -93.415051) (xy 237.151313 -93.397044)
			(xy 237.206156 -93.386914) (xy 237.26189 -93.384877) (xy 237.317327 -93.390977) (xy 237.371284 -93.405083)
			(xy 237.422613 -93.426895) (xy 237.470219 -93.455949) (xy 237.513087 -93.491624) (xy 237.550304 -93.533161)
			(xy 237.581077 -93.579674) (xy 237.604749 -93.630171) (xy 237.620817 -93.683578) (xy 237.628937 -93.738754)
			(xy 237.629446 -93.76664) (xy 237.628937 -93.794526) (xy 237.620817 -93.849702) (xy 237.604749 -93.903109)
			(xy 237.581077 -93.953606) (xy 237.550304 -94.000119) (xy 237.513087 -94.041656) (xy 237.470219 -94.077331)
			(xy 237.422613 -94.106385) (xy 237.371284 -94.128197) (xy 237.317327 -94.142303) (xy 237.26189 -94.148403)
			(xy 237.206156 -94.146366) (xy 237.151313 -94.136236) (xy 237.098529 -94.118229) (xy 237.048929 -94.092728)
			(xy 237.003571 -94.060277) (xy 236.963422 -94.021568) (xy 236.929336 -93.977425) (xy 236.90204 -93.92879)
			(xy 236.882117 -93.876699) (xy 236.869991 -93.822262) (xy 236.86592 -93.76664) (xy 231.299512 -93.76664)
			(xy 231.299512 -94.679008) (xy 231.593134 -94.679008) (xy 231.597205 -94.623386) (xy 231.609331 -94.568949)
			(xy 231.629254 -94.516858) (xy 231.65655 -94.468223) (xy 231.690636 -94.42408) (xy 231.730785 -94.385371)
			(xy 231.776143 -94.35292) (xy 231.825743 -94.327419) (xy 231.878527 -94.309412) (xy 231.93337 -94.299282)
			(xy 231.989104 -94.297245) (xy 232.044541 -94.303345) (xy 232.098498 -94.317451) (xy 232.149827 -94.339263)
			(xy 232.197433 -94.368317) (xy 232.240301 -94.403992) (xy 232.277518 -94.445529) (xy 232.308291 -94.492042)
			(xy 232.331963 -94.542539) (xy 232.348031 -94.595946) (xy 232.354573 -94.6404) (xy 235.823504 -94.6404)
			(xy 235.827575 -94.584778) (xy 235.839701 -94.530341) (xy 235.859624 -94.47825) (xy 235.88692 -94.429615)
			(xy 235.921006 -94.385472) (xy 235.961155 -94.346763) (xy 236.006513 -94.314312) (xy 236.056113 -94.288811)
			(xy 236.108897 -94.270804) (xy 236.16374 -94.260674) (xy 236.219474 -94.258637) (xy 236.274911 -94.264737)
			(xy 236.328868 -94.278843) (xy 236.380197 -94.300655) (xy 236.427803 -94.329709) (xy 236.470671 -94.365384)
			(xy 236.507888 -94.406921) (xy 236.538661 -94.453434) (xy 236.562333 -94.503931) (xy 236.578401 -94.557338)
			(xy 236.586521 -94.612514) (xy 236.58703 -94.6404) (xy 236.586521 -94.668286) (xy 236.578401 -94.723462)
			(xy 236.562333 -94.776869) (xy 236.538661 -94.827366) (xy 236.507888 -94.873879) (xy 236.470671 -94.915416)
			(xy 236.427803 -94.951091) (xy 236.380197 -94.980145) (xy 236.328868 -95.001957) (xy 236.274911 -95.016063)
			(xy 236.219474 -95.022163) (xy 236.16374 -95.020126) (xy 236.108897 -95.009996) (xy 236.056113 -94.991989)
			(xy 236.006513 -94.966488) (xy 235.961155 -94.934037) (xy 235.921006 -94.895328) (xy 235.88692 -94.851185)
			(xy 235.859624 -94.80255) (xy 235.839701 -94.750459) (xy 235.827575 -94.696022) (xy 235.823504 -94.6404)
			(xy 232.354573 -94.6404) (xy 232.356151 -94.651122) (xy 232.35666 -94.679008) (xy 232.356151 -94.706894)
			(xy 232.348031 -94.76207) (xy 232.331963 -94.815477) (xy 232.308291 -94.865974) (xy 232.277518 -94.912487)
			(xy 232.240301 -94.954024) (xy 232.197433 -94.989699) (xy 232.149827 -95.018753) (xy 232.098498 -95.040565)
			(xy 232.044541 -95.054671) (xy 231.989104 -95.060771) (xy 231.93337 -95.058734) (xy 231.878527 -95.048604)
			(xy 231.825743 -95.030597) (xy 231.776143 -95.005096) (xy 231.730785 -94.972645) (xy 231.690636 -94.933936)
			(xy 231.65655 -94.889793) (xy 231.629254 -94.841158) (xy 231.609331 -94.789067) (xy 231.597205 -94.73463)
			(xy 231.593134 -94.679008) (xy 231.299512 -94.679008) (xy 231.299512 -94.975426) (xy 231.299332 -94.989853)
			(xy 231.296785 -95.018595) (xy 231.294432 -95.03283) (xy 231.294432 -95.033084) (xy 231.293212 -95.04276)
			(xy 231.297261 -95.061822) (xy 231.302306 -95.070168) (xy 231.32288 -95.10014) (xy 231.3432 -95.129604)
			(xy 231.34877 -95.137108) (xy 231.364168 -95.147675) (xy 231.373172 -95.150178) (xy 231.375458 -95.150686)
			(xy 231.401295 -95.156044) (xy 231.451285 -95.172936) (xy 231.498466 -95.196561) (xy 231.541939 -95.226469)
			(xy 231.580871 -95.262086) (xy 231.614518 -95.302732) (xy 231.642238 -95.347631) (xy 231.6635 -95.395924)
			(xy 231.677898 -95.446688) (xy 231.685157 -95.498953) (xy 231.685592 -95.525336) (xy 231.685103 -95.552585)
			(xy 231.677343 -95.606528) (xy 231.661984 -95.658817) (xy 231.639341 -95.708389) (xy 231.609873 -95.754234)
			(xy 231.574182 -95.795418) (xy 231.532992 -95.831104) (xy 231.487143 -95.860566) (xy 231.437569 -95.883202)
			(xy 231.385277 -95.898554) (xy 231.331333 -95.906307) (xy 231.304084 -95.906844) (xy 231.2755 -95.906334)
			(xy 231.218971 -95.897805) (xy 231.164347 -95.880939) (xy 231.11285 -95.856115) (xy 231.065631 -95.823887)
			(xy 231.023748 -95.784976) (xy 230.988137 -95.740254) (xy 230.959595 -95.69072) (xy 230.948738 -95.664274)
			(xy 230.947722 -95.661734) (xy 230.942327 -95.651326) (xy 230.924196 -95.636507) (xy 230.912924 -95.633286)
			(xy 230.911908 -95.633032) (xy 230.833168 -95.616522) (xy 230.828088 -95.615506) (xy 230.816567 -95.6138)
			(xy 230.794078 -95.619757) (xy 230.784908 -95.626936) (xy 230.753412 -95.658178) (xy 230.748021 -95.664168)
			(xy 230.741029 -95.678678) (xy 230.739696 -95.686626) (xy 230.739188 -95.693484) (xy 230.739188 -95.77832)
			(xy 230.739442 -95.783146) (xy 230.740586 -95.791641) (xy 230.74772 -95.807217) (xy 230.753412 -95.813626)
			(xy 230.979472 -96.039432) (xy 231.090724 -96.150684) (xy 231.098134 -96.157366) (xy 231.116571 -96.164942)
			(xy 231.126538 -96.165416) (xy 232.278936 -96.165416) (xy 232.290493 -96.164801) (xy 232.311252 -96.154619)
			(xy 232.318814 -96.145858) (xy 232.36809 -96.082866) (xy 232.37136 -96.078474) (xy 232.376103 -96.068606)
			(xy 232.377488 -96.063308) (xy 232.377488 -96.03994) (xy 232.376472 -96.034606) (xy 232.371778 -96.013259)
			(xy 232.366688 -95.969846) (xy 232.366312 -95.947992) (xy 232.366776 -95.92074) (xy 232.374534 -95.866791)
			(xy 232.389891 -95.814495) (xy 232.412534 -95.764917) (xy 232.442003 -95.719067) (xy 232.477697 -95.677877)
			(xy 232.518889 -95.642186) (xy 232.564742 -95.612721) (xy 232.614322 -95.590081) (xy 232.666618 -95.574728)
			(xy 232.720568 -95.566974) (xy 232.74782 -95.566484) (xy 232.774336 -95.56694) (xy 232.826857 -95.574284)
			(xy 232.877855 -95.588827) (xy 232.926349 -95.61029) (xy 232.971406 -95.638259) (xy 233.012157 -95.672196)
			(xy 233.047818 -95.711447) (xy 233.077703 -95.755256) (xy 233.101235 -95.802781) (xy 233.117962 -95.853105)
			(xy 233.127562 -95.905261) (xy 233.129074 -95.931736) (xy 233.129582 -95.944182) (xy 233.129582 -95.947992)
			(xy 233.129242 -95.97115) (xy 233.123639 -96.017125) (xy 233.118406 -96.039686) (xy 233.117136 -96.044512)
			(xy 233.116258 -96.054084) (xy 233.120844 -96.072736) (xy 233.126026 -96.080834) (xy 233.164888 -96.130618)
			(xy 233.176826 -96.145858) (xy 233.184367 -96.154648) (xy 233.205137 -96.164838) (xy 233.216704 -96.165416)
			(xy 233.67238 -96.165416) (xy 233.674412 -96.165416) (xy 233.686983 -96.164256) (xy 233.708716 -96.151471)
			(xy 233.715814 -96.141032) (xy 233.719116 -96.134428) (xy 233.755692 -96.04883) (xy 233.758406 -96.041863)
			(xy 233.760098 -96.027014) (xy 233.758994 -96.01962) (xy 233.758994 -96.019366) (xy 233.757409 -96.012202)
			(xy 233.7507 -95.999161) (xy 233.745786 -95.993712) (xy 233.725991 -95.972255) (xy 233.692486 -95.924451)
			(xy 233.666648 -95.872104) (xy 233.649078 -95.816435) (xy 233.640185 -95.75874) (xy 233.639614 -95.729552)
			(xy 233.6401 -95.702301) (xy 233.647856 -95.648353) (xy 233.663211 -95.596058) (xy 233.685853 -95.546481)
			(xy 233.715319 -95.500631) (xy 233.75101 -95.45944) (xy 233.792201 -95.423749) (xy 233.838051 -95.394283)
			(xy 233.887628 -95.371641) (xy 233.939923 -95.356286) (xy 233.993871 -95.34853) (xy 234.048373 -95.34853)
			(xy 234.102321 -95.356286) (xy 234.154616 -95.371641) (xy 234.204193 -95.394283) (xy 234.250043 -95.423749)
			(xy 234.291234 -95.45944) (xy 234.326925 -95.500631) (xy 234.356391 -95.546481) (xy 234.379033 -95.596058)
			(xy 234.394388 -95.648353) (xy 234.402144 -95.702301) (xy 234.40263 -95.729552) (xy 234.402079 -95.758742)
			(xy 234.393195 -95.816442) (xy 234.375626 -95.872116) (xy 234.349783 -95.924465) (xy 234.316268 -95.972266)
			(xy 234.296458 -95.993712) (xy 234.291378 -95.999046) (xy 234.284774 -96.012) (xy 234.28325 -96.01962)
			(xy 234.282158 -96.027017) (xy 234.283827 -96.041868) (xy 234.286552 -96.04883) (xy 234.323128 -96.134428)
			(xy 234.32643 -96.141032) (xy 234.333544 -96.15146) (xy 234.355263 -96.164261) (xy 234.367832 -96.165416)
			(xy 234.792774 -96.165416) (xy 234.802724 -96.164875) (xy 234.821095 -96.157207) (xy 234.835198 -96.143158)
			(xy 234.83951 -96.134174) (xy 234.845352 -96.11995) (xy 234.84332 -96.110044) (xy 234.839256 -96.089724)
			(xy 234.837478 -96.087946) (xy 235.80852 -96.087946) (xy 235.817749 -96.087543) (xy 235.835003 -96.08099)
			(xy 235.848812 -96.068742) (xy 235.853478 -96.060768) (xy 235.895388 -95.981012) (xy 235.900736 -95.969578)
			(xy 235.900621 -95.944371) (xy 235.895134 -95.933006) (xy 235.892086 -95.928688) (xy 235.876247 -95.904741)
			(xy 235.85118 -95.853089) (xy 235.834153 -95.798259) (xy 235.82555 -95.741495) (xy 235.82503 -95.712788)
			(xy 235.82503 -95.712534) (xy 235.825516 -95.685283) (xy 235.833272 -95.631335) (xy 235.848627 -95.57904)
			(xy 235.871269 -95.529463) (xy 235.900735 -95.483613) (xy 235.936426 -95.442422) (xy 235.977617 -95.406731)
			(xy 236.023467 -95.377265) (xy 236.073044 -95.354623) (xy 236.125339 -95.339268) (xy 236.179287 -95.331512)
			(xy 236.233789 -95.331512) (xy 236.287737 -95.339268) (xy 236.340032 -95.354623) (xy 236.389609 -95.377265)
			(xy 236.435459 -95.406731) (xy 236.47665 -95.442422) (xy 236.512341 -95.483613) (xy 236.541807 -95.529463)
			(xy 236.564449 -95.57904) (xy 236.579804 -95.631335) (xy 236.58756 -95.685283) (xy 236.588046 -95.712534)
			(xy 236.588046 -95.712788) (xy 236.587502 -95.74149) (xy 236.57886 -95.798242) (xy 236.561829 -95.853063)
			(xy 236.536791 -95.90472) (xy 236.52099 -95.928688) (xy 236.517942 -95.933006) (xy 236.512563 -95.944395)
			(xy 236.512451 -95.969554) (xy 236.517688 -95.981012) (xy 236.559598 -96.060768) (xy 236.564246 -96.068753)
			(xy 236.578067 -96.08099) (xy 236.595326 -96.087541) (xy 236.604556 -96.087946) (xy 237.038388 -96.087946)
			(xy 237.048408 -96.088364) (xy 237.066921 -96.096034) (xy 237.081085 -96.110208) (xy 237.088743 -96.128726)
			(xy 237.089188 -96.138746) (xy 237.089188 -96.264984) (xy 237.090204 -96.274636) (xy 237.091829 -96.281882)
			(xy 237.098664 -96.295056) (xy 237.103666 -96.300544) (xy 240.575338 -99.772216) (xy 240.582958 -99.772978)
			(xy 243.510054 -99.772978) (xy 243.518312 -99.772035) (xy 243.533605 -99.765555) (xy 243.540026 -99.760278)
			(xy 243.546884 -99.754182) (xy 243.555266 -99.737926) (xy 243.556536 -99.728274) (xy 243.556536 -99.72802)
			(xy 243.560316 -99.70055) (xy 243.574785 -99.647022) (xy 243.596844 -99.596149) (xy 243.626029 -99.549002)
			(xy 243.661726 -99.506571) (xy 243.703185 -99.46975) (xy 243.749533 -99.439313) (xy 243.799796 -99.415898)
			(xy 243.852918 -99.4) (xy 243.90778 -99.391952) (xy 243.935504 -99.39147) (xy 243.962756 -99.391956)
			(xy 244.016704 -99.399713) (xy 244.069 -99.415068) (xy 244.118578 -99.437709) (xy 244.164429 -99.467175)
			(xy 244.205621 -99.502866) (xy 244.241314 -99.544056) (xy 244.270782 -99.589906) (xy 244.293426 -99.639483)
			(xy 244.308783 -99.691778) (xy 244.316543 -99.745726) (xy 244.317012 -99.772978) (xy 244.316449 -99.804003)
			(xy 244.306499 -99.86525) (xy 244.286777 -99.924081) (xy 244.272816 -99.951794) (xy 244.267736 -99.961446)
			(xy 244.267736 -108.610146) (xy 245.158768 -108.610146) (xy 245.159298 -108.582895) (xy 245.167048 -108.528948)
			(xy 245.182397 -108.476653) (xy 245.205032 -108.427075) (xy 245.234493 -108.381222) (xy 245.27018 -108.34003)
			(xy 245.311366 -108.304335) (xy 245.357213 -108.274866) (xy 245.406787 -108.252222) (xy 245.45908 -108.236863)
			(xy 245.513025 -108.229103) (xy 245.540276 -108.228638) (xy 245.568957 -108.229202) (xy 245.625669 -108.237809)
			(xy 245.680456 -108.254802) (xy 245.732084 -108.2798) (xy 245.779392 -108.312239) (xy 245.821316 -108.351389)
			(xy 245.856911 -108.396371) (xy 245.885378 -108.446171) (xy 245.906074 -108.499669) (xy 245.918535 -108.55566)
			(xy 245.921022 -108.584238) (xy 245.922507 -108.59876) (xy 245.93262 -108.626129) (xy 245.950059 -108.649522)
			(xy 245.973399 -108.667031) (xy 246.000737 -108.677228) (xy 246.015256 -108.678726) (xy 246.043842 -108.681195)
			(xy 246.099854 -108.693625) (xy 246.153373 -108.7143) (xy 246.203194 -108.742756) (xy 246.248193 -108.778351)
			(xy 246.287354 -108.820282) (xy 246.319797 -108.867604) (xy 246.344788 -108.91925) (xy 246.361765 -108.974055)
			(xy 246.370345 -109.030785) (xy 246.370856 -109.059472) (xy 246.370296 -109.08672) (xy 246.362544 -109.140663)
			(xy 246.347195 -109.192953) (xy 246.324561 -109.242527) (xy 246.308516 -109.267498) (xy 246.461786 -109.267498)
			(xy 246.465857 -109.211876) (xy 246.477983 -109.157439) (xy 246.497906 -109.105348) (xy 246.525202 -109.056713)
			(xy 246.559288 -109.01257) (xy 246.599437 -108.973861) (xy 246.644795 -108.94141) (xy 246.694395 -108.915909)
			(xy 246.747179 -108.897902) (xy 246.802022 -108.887772) (xy 246.857756 -108.885735) (xy 246.913193 -108.891835)
			(xy 246.96715 -108.905941) (xy 247.018479 -108.927753) (xy 247.066085 -108.956807) (xy 247.108953 -108.992482)
			(xy 247.14617 -109.034019) (xy 247.176943 -109.080532) (xy 247.200615 -109.131029) (xy 247.216683 -109.184436)
			(xy 247.224803 -109.239612) (xy 247.225312 -109.267498) (xy 247.224803 -109.295384) (xy 247.216683 -109.35056)
			(xy 247.200615 -109.403967) (xy 247.176943 -109.454464) (xy 247.14617 -109.500977) (xy 247.108953 -109.542514)
			(xy 247.066085 -109.578189) (xy 247.018479 -109.607243) (xy 246.96715 -109.629055) (xy 246.913193 -109.643161)
			(xy 246.857756 -109.649261) (xy 246.802022 -109.647224) (xy 246.747179 -109.637094) (xy 246.694395 -109.619087)
			(xy 246.644795 -109.593586) (xy 246.599437 -109.561135) (xy 246.559288 -109.522426) (xy 246.525202 -109.478283)
			(xy 246.497906 -109.429648) (xy 246.477983 -109.377557) (xy 246.465857 -109.32312) (xy 246.461786 -109.267498)
			(xy 246.308516 -109.267498) (xy 246.295102 -109.288375) (xy 246.259418 -109.329565) (xy 246.218236 -109.365256)
			(xy 246.172394 -109.394724) (xy 246.122825 -109.417369) (xy 246.070537 -109.432728) (xy 246.016596 -109.44049)
			(xy 245.989348 -109.44098) (xy 245.960666 -109.440469) (xy 245.903953 -109.431852) (xy 245.849166 -109.41485)
			(xy 245.797538 -109.389845) (xy 245.750231 -109.357399) (xy 245.708309 -109.318243) (xy 245.672714 -109.273257)
			(xy 245.644249 -109.223454) (xy 245.623552 -109.169953) (xy 245.611089 -109.113959) (xy 245.608602 -109.08538)
			(xy 245.607171 -109.070849) (xy 245.597053 -109.043471) (xy 245.579603 -109.020073) (xy 245.556247 -109.002566)
			(xy 245.528894 -108.992381) (xy 245.514368 -108.990892) (xy 245.485786 -108.988385) (xy 245.429776 -108.975959)
			(xy 245.376258 -108.955288) (xy 245.326438 -108.926836) (xy 245.28144 -108.891246) (xy 245.242278 -108.849319)
			(xy 245.209834 -108.802002) (xy 245.184842 -108.75036) (xy 245.167863 -108.695558) (xy 245.159281 -108.638832)
			(xy 245.158768 -108.610146) (xy 244.267736 -108.610146) (xy 244.267736 -112.089946) (xy 244.270066 -112.093162)
			(xy 244.275551 -112.098903) (xy 244.278658 -112.101376) (xy 244.354096 -112.150398) (xy 244.359109 -112.153149)
			(xy 244.370005 -112.156607) (xy 244.375686 -112.157256) (xy 244.388132 -112.158272) (xy 244.40007 -112.152938)
			(xy 244.424594 -112.142493) (xy 244.475829 -112.127785) (xy 244.528612 -112.120356) (xy 244.555264 -112.119918)
			(xy 244.582517 -112.120379) (xy 244.636468 -112.128131) (xy 244.688766 -112.143483) (xy 244.738348 -112.166122)
			(xy 244.784202 -112.195587) (xy 244.825396 -112.231278) (xy 244.861092 -112.272469) (xy 244.890561 -112.318321)
			(xy 244.913204 -112.3679) (xy 244.928561 -112.420197) (xy 244.936319 -112.474147) (xy 244.936319 -112.528653)
			(xy 244.928561 -112.582603) (xy 244.913204 -112.6349) (xy 244.890561 -112.684479) (xy 244.861092 -112.730331)
			(xy 244.825396 -112.771522) (xy 244.784202 -112.807213) (xy 244.738348 -112.836678) (xy 244.688766 -112.859317)
			(xy 244.636468 -112.874669) (xy 244.582517 -112.882421) (xy 244.555264 -112.882934) (xy 244.528613 -112.882487)
			(xy 244.475831 -112.875057) (xy 244.424598 -112.860347) (xy 244.40007 -112.849914) (xy 244.398292 -112.849152)
			(xy 244.392754 -112.847089) (xy 244.381079 -112.845287) (xy 244.375178 -112.845596) (xy 244.362732 -112.846612)
			(xy 244.29593 -112.890046) (xy 244.279166 -112.900968) (xy 244.269768 -112.90935) (xy 244.267736 -112.91189)
			(xy 244.267736 -113.302034) (xy 246.513602 -113.302034) (xy 246.517673 -113.246412) (xy 246.529799 -113.191975)
			(xy 246.549722 -113.139884) (xy 246.577018 -113.091249) (xy 246.611104 -113.047106) (xy 246.651253 -113.008397)
			(xy 246.696611 -112.975946) (xy 246.746211 -112.950445) (xy 246.798995 -112.932438) (xy 246.853838 -112.922308)
			(xy 246.909572 -112.920271) (xy 246.965009 -112.926371) (xy 247.018966 -112.940477) (xy 247.070295 -112.962289)
			(xy 247.117901 -112.991343) (xy 247.160769 -113.027018) (xy 247.197986 -113.068555) (xy 247.228759 -113.115068)
			(xy 247.252431 -113.165565) (xy 247.268499 -113.218972) (xy 247.276619 -113.274148) (xy 247.277128 -113.302034)
			(xy 247.276619 -113.32992) (xy 247.268499 -113.385096) (xy 247.252431 -113.438503) (xy 247.228759 -113.489)
			(xy 247.197986 -113.535513) (xy 247.160769 -113.57705) (xy 247.117901 -113.612725) (xy 247.070295 -113.641779)
			(xy 247.018966 -113.663591) (xy 246.965009 -113.677697) (xy 246.909572 -113.683797) (xy 246.853838 -113.68176)
			(xy 246.798995 -113.67163) (xy 246.746211 -113.653623) (xy 246.696611 -113.628122) (xy 246.651253 -113.595671)
			(xy 246.611104 -113.556962) (xy 246.577018 -113.512819) (xy 246.549722 -113.464184) (xy 246.529799 -113.412093)
			(xy 246.517673 -113.357656) (xy 246.513602 -113.302034) (xy 244.267736 -113.302034) (xy 244.267736 -114.244628)
			(xy 244.276118 -114.253264) (xy 244.278658 -114.255296) (xy 244.309138 -114.27587) (xy 244.318282 -114.281712)
			(xy 244.346984 -114.300254) (xy 244.353041 -114.303709) (xy 244.366434 -114.307569) (xy 244.3734 -114.307874)
			(xy 244.396768 -114.307874) (xy 244.406928 -114.30381) (xy 244.414802 -114.301016) (xy 244.445002 -114.290932)
			(xy 244.50769 -114.279818) (xy 244.539516 -114.278918) (xy 244.544596 -114.278918) (xy 244.572255 -114.279511)
			(xy 244.626969 -114.287696) (xy 244.679929 -114.303692) (xy 244.730025 -114.327165) (xy 244.776209 -114.357622)
			(xy 244.817513 -114.394426) (xy 244.853073 -114.436807) (xy 244.882143 -114.483876) (xy 244.904116 -114.534648)
			(xy 244.91853 -114.58806) (xy 244.922294 -114.615468) (xy 244.922294 -114.615722) (xy 244.923056 -114.622326)
			(xy 244.92458 -114.6429) (xy 244.92458 -114.643408) (xy 244.924834 -114.660172) (xy 244.924834 -114.66068)
			(xy 244.924351 -114.687622) (xy 244.916732 -114.740964) (xy 244.901686 -114.792705) (xy 244.879512 -114.841815)
			(xy 244.85065 -114.887317) (xy 244.815675 -114.928307) (xy 244.775282 -114.963971) (xy 244.730273 -114.993597)
			(xy 244.681545 -115.016599) (xy 244.630067 -115.032517) (xy 244.57686 -115.041036) (xy 244.54993 -115.041934)
			(xy 244.542818 -115.041934) (xy 244.518654 -115.041558) (xy 244.470714 -115.035455) (xy 244.423925 -115.023355)
			(xy 244.40134 -115.014756) (xy 244.397022 -115.012978) (xy 244.387116 -115.010946) (xy 244.377711 -115.009568)
			(xy 244.359045 -115.013085) (xy 244.350794 -115.017804) (xy 244.318282 -115.03914) (xy 244.317774 -115.03914)
			(xy 244.276372 -115.06708) (xy 244.267736 -115.075716) (xy 244.267736 -117.434106) (xy 245.576852 -117.434106)
			(xy 245.577309 -117.406735) (xy 245.585127 -117.352555) (xy 245.600618 -117.300052) (xy 245.623462 -117.250305)
			(xy 245.653189 -117.204339) (xy 245.670832 -117.183408) (xy 245.671086 -117.183154) (xy 245.676655 -117.176055)
			(xy 245.682913 -117.159148) (xy 245.683278 -117.150134) (xy 245.683278 -117.083078) (xy 245.682936 -117.074059)
			(xy 245.676679 -117.057142) (xy 245.671086 -117.050058) (xy 245.670832 -117.050058) (xy 245.670832 -117.049804)
			(xy 245.653197 -117.028867) (xy 245.623472 -116.9829) (xy 245.600626 -116.933154) (xy 245.585129 -116.880653)
			(xy 245.577299 -116.826475) (xy 245.577299 -116.771734) (xy 245.585127 -116.717556) (xy 245.600622 -116.665054)
			(xy 245.623467 -116.615308) (xy 245.653192 -116.569341) (xy 245.670832 -116.548408) (xy 245.671086 -116.548154)
			(xy 245.676655 -116.541055) (xy 245.682913 -116.524148) (xy 245.683278 -116.515134) (xy 245.683278 -116.448078)
			(xy 245.682936 -116.439059) (xy 245.676679 -116.422142) (xy 245.671086 -116.415058) (xy 245.670832 -116.415058)
			(xy 245.670832 -116.414804) (xy 245.653186 -116.393877) (xy 245.623474 -116.347903) (xy 245.600639 -116.298155)
			(xy 245.58515 -116.245653) (xy 245.577324 -116.191476) (xy 245.576852 -116.164106) (xy 245.577383 -116.136857)
			(xy 245.585138 -116.082913) (xy 245.60049 -116.030621) (xy 245.623128 -115.981047) (xy 245.65259 -115.935198)
			(xy 245.688276 -115.894009) (xy 245.729461 -115.858317) (xy 245.775306 -115.82885) (xy 245.824878 -115.806206)
			(xy 245.877168 -115.790848) (xy 245.931111 -115.783087) (xy 245.95836 -115.782598) (xy 245.985729 -115.783088)
			(xy 246.039907 -115.7909) (xy 246.09241 -115.806384) (xy 246.142157 -115.82922) (xy 246.188125 -115.858939)
			(xy 246.209058 -115.876578) (xy 246.209312 -115.876832) (xy 246.216388 -115.882433) (xy 246.233313 -115.88867)
			(xy 246.242332 -115.889024) (xy 246.309388 -115.889024) (xy 246.318404 -115.888656) (xy 246.33532 -115.882415)
			(xy 246.342408 -115.876832) (xy 246.342408 -115.876578) (xy 246.342662 -115.876578) (xy 246.363595 -115.85894)
			(xy 246.409568 -115.829229) (xy 246.459315 -115.806393) (xy 246.511815 -115.790901) (xy 246.565991 -115.783073)
			(xy 246.59336 -115.782598) (xy 246.620612 -115.783093) (xy 246.674562 -115.790844) (xy 246.72686 -115.806195)
			(xy 246.77644 -115.828834) (xy 246.822294 -115.858298) (xy 246.863487 -115.893989) (xy 246.899181 -115.935179)
			(xy 246.92865 -115.98103) (xy 246.951293 -116.030608) (xy 246.966649 -116.082904) (xy 246.974405 -116.136854)
			(xy 246.974868 -116.164106) (xy 246.974413 -116.191477) (xy 246.966594 -116.245657) (xy 246.951103 -116.29816)
			(xy 246.928258 -116.347907) (xy 246.898531 -116.393873) (xy 246.880888 -116.414804) (xy 246.880634 -116.415058)
			(xy 246.875051 -116.422147) (xy 246.868804 -116.439062) (xy 246.868442 -116.448078) (xy 246.868442 -116.515134)
			(xy 246.868774 -116.524154) (xy 246.875038 -116.541071) (xy 246.880634 -116.548154) (xy 246.880888 -116.548154)
			(xy 246.880888 -116.548408) (xy 246.898534 -116.569336) (xy 246.928257 -116.615305) (xy 246.951101 -116.665052)
			(xy 246.966597 -116.717555) (xy 246.974424 -116.771734) (xy 246.974424 -116.826475) (xy 246.966595 -116.880654)
			(xy 246.951098 -116.933156) (xy 246.928253 -116.982903) (xy 246.898528 -117.028871) (xy 246.880888 -117.049804)
			(xy 246.880634 -117.050058) (xy 246.875051 -117.057147) (xy 246.868804 -117.074062) (xy 246.868442 -117.083078)
			(xy 246.868442 -117.150134) (xy 246.868774 -117.159154) (xy 246.875038 -117.176071) (xy 246.880634 -117.183154)
			(xy 246.880888 -117.183154) (xy 246.880888 -117.183408) (xy 246.898542 -117.204328) (xy 246.928252 -117.250304)
			(xy 246.951086 -117.300054) (xy 246.966573 -117.352558) (xy 246.974397 -117.406736) (xy 246.974868 -117.434106)
			(xy 246.97473 -117.442234) (xy 247.85904 -117.442234) (xy 247.863111 -117.386612) (xy 247.875237 -117.332175)
			(xy 247.89516 -117.280084) (xy 247.922456 -117.231449) (xy 247.956542 -117.187306) (xy 247.996691 -117.148597)
			(xy 248.042049 -117.116146) (xy 248.091649 -117.090645) (xy 248.144433 -117.072638) (xy 248.199276 -117.062508)
			(xy 248.25501 -117.060471) (xy 248.310447 -117.066571) (xy 248.364404 -117.080677) (xy 248.415733 -117.102489)
			(xy 248.463339 -117.131543) (xy 248.506207 -117.167218) (xy 248.543424 -117.208755) (xy 248.574197 -117.255268)
			(xy 248.597869 -117.305765) (xy 248.613937 -117.359172) (xy 248.622057 -117.414348) (xy 248.622566 -117.442234)
			(xy 248.622057 -117.47012) (xy 248.613937 -117.525296) (xy 248.597869 -117.578703) (xy 248.574197 -117.6292)
			(xy 248.543424 -117.675713) (xy 248.506207 -117.71725) (xy 248.463339 -117.752925) (xy 248.415733 -117.781979)
			(xy 248.364404 -117.803791) (xy 248.310447 -117.817897) (xy 248.25501 -117.823997) (xy 248.199276 -117.82196)
			(xy 248.144433 -117.81183) (xy 248.091649 -117.793823) (xy 248.042049 -117.768322) (xy 247.996691 -117.735871)
			(xy 247.956542 -117.697162) (xy 247.922456 -117.653019) (xy 247.89516 -117.604384) (xy 247.875237 -117.552293)
			(xy 247.863111 -117.497856) (xy 247.85904 -117.442234) (xy 246.97473 -117.442234) (xy 246.974416 -117.460663)
			(xy 246.967047 -117.513262) (xy 246.952452 -117.564331) (xy 246.942102 -117.588792) (xy 246.937753 -117.60016)
			(xy 246.939101 -117.624434) (xy 246.944642 -117.635274) (xy 246.986044 -117.706394) (xy 246.99276 -117.716478)
			(xy 247.013181 -117.729461) (xy 247.02516 -117.731286) (xy 247.053143 -117.73446) (xy 247.107807 -117.747998)
			(xy 247.159886 -117.769425) (xy 247.208249 -117.798277) (xy 247.251844 -117.833926) (xy 247.289724 -117.875598)
			(xy 247.321066 -117.922386) (xy 247.345188 -117.973274) (xy 247.361565 -118.027155) (xy 247.367007 -118.063772)
			(xy 249.006104 -118.063772) (xy 249.010175 -118.00815) (xy 249.022301 -117.953713) (xy 249.042224 -117.901622)
			(xy 249.06952 -117.852987) (xy 249.103606 -117.808844) (xy 249.143755 -117.770135) (xy 249.189113 -117.737684)
			(xy 249.238713 -117.712183) (xy 249.291497 -117.694176) (xy 249.34634 -117.684046) (xy 249.402074 -117.682009)
			(xy 249.457511 -117.688109) (xy 249.511468 -117.702215) (xy 249.562797 -117.724027) (xy 249.610403 -117.753081)
			(xy 249.653271 -117.788756) (xy 249.690488 -117.830293) (xy 249.721261 -117.876806) (xy 249.744933 -117.927303)
			(xy 249.761001 -117.98071) (xy 249.769121 -118.035886) (xy 249.76963 -118.063772) (xy 249.769121 -118.091658)
			(xy 249.761001 -118.146834) (xy 249.744933 -118.200241) (xy 249.721261 -118.250738) (xy 249.690488 -118.297251)
			(xy 249.653271 -118.338788) (xy 249.610403 -118.374463) (xy 249.562797 -118.403517) (xy 249.511468 -118.425329)
			(xy 249.457511 -118.439435) (xy 249.402074 -118.445535) (xy 249.34634 -118.443498) (xy 249.291497 -118.433368)
			(xy 249.238713 -118.415361) (xy 249.189113 -118.38986) (xy 249.143755 -118.357409) (xy 249.103606 -118.3187)
			(xy 249.06952 -118.274557) (xy 249.042224 -118.225922) (xy 249.022301 -118.173831) (xy 249.010175 -118.119394)
			(xy 249.006104 -118.063772) (xy 247.367007 -118.063772) (xy 247.369843 -118.082858) (xy 247.370346 -118.111016)
			(xy 247.36986 -118.138267) (xy 247.362104 -118.192215) (xy 247.346749 -118.24451) (xy 247.324107 -118.294087)
			(xy 247.294641 -118.339937) (xy 247.25895 -118.381128) (xy 247.217759 -118.416819) (xy 247.171909 -118.446285)
			(xy 247.122332 -118.468927) (xy 247.070037 -118.484282) (xy 247.016089 -118.492038) (xy 246.961587 -118.492038)
			(xy 246.907639 -118.484282) (xy 246.855344 -118.468927) (xy 246.805767 -118.446285) (xy 246.759917 -118.416819)
			(xy 246.718726 -118.381128) (xy 246.683035 -118.339937) (xy 246.653569 -118.294087) (xy 246.630927 -118.24451)
			(xy 246.615572 -118.192215) (xy 246.607816 -118.138267) (xy 246.60733 -118.111016) (xy 246.60779 -118.08446)
			(xy 246.615156 -118.03186) (xy 246.629747 -117.980791) (xy 246.640096 -117.95633) (xy 246.644431 -117.944957)
			(xy 246.643093 -117.920688) (xy 246.637556 -117.909848) (xy 246.596154 -117.838728) (xy 246.58941 -117.828667)
			(xy 246.569009 -117.815676) (xy 246.557038 -117.813836) (xy 246.527564 -117.810453) (xy 246.470096 -117.795736)
			(xy 246.415599 -117.772298) (xy 246.365389 -117.740703) (xy 246.342662 -117.721634) (xy 246.342408 -117.72138)
			(xy 246.335325 -117.715788) (xy 246.318405 -117.709545) (xy 246.309388 -117.709188) (xy 246.242332 -117.709188)
			(xy 246.233317 -117.709563) (xy 246.2164 -117.715798) (xy 246.209312 -117.72138) (xy 246.209312 -117.721634)
			(xy 246.209058 -117.721634) (xy 246.188119 -117.739265) (xy 246.142148 -117.768977) (xy 246.092402 -117.791814)
			(xy 246.039903 -117.807307) (xy 245.985729 -117.815138) (xy 245.95836 -117.815614) (xy 245.931108 -117.815159)
			(xy 245.87716 -117.807398) (xy 245.824865 -117.792038) (xy 245.775288 -117.769392) (xy 245.729438 -117.739922)
			(xy 245.688248 -117.704228) (xy 245.652557 -117.663035) (xy 245.623091 -117.617183) (xy 245.60045 -117.567604)
			(xy 245.585095 -117.515307) (xy 245.577338 -117.461358) (xy 245.576852 -117.434106) (xy 244.267736 -117.434106)
			(xy 244.267736 -117.962426) (xy 244.427246 -117.962426) (xy 244.431317 -117.906804) (xy 244.443443 -117.852367)
			(xy 244.463366 -117.800276) (xy 244.490662 -117.751641) (xy 244.524748 -117.707498) (xy 244.564897 -117.668789)
			(xy 244.610255 -117.636338) (xy 244.659855 -117.610837) (xy 244.712639 -117.59283) (xy 244.767482 -117.5827)
			(xy 244.823216 -117.580663) (xy 244.878653 -117.586763) (xy 244.93261 -117.600869) (xy 244.983939 -117.622681)
			(xy 245.031545 -117.651735) (xy 245.074413 -117.68741) (xy 245.11163 -117.728947) (xy 245.142403 -117.77546)
			(xy 245.166075 -117.825957) (xy 245.182143 -117.879364) (xy 245.190263 -117.93454) (xy 245.190772 -117.962426)
			(xy 245.190263 -117.990312) (xy 245.182143 -118.045488) (xy 245.166075 -118.098895) (xy 245.142403 -118.149392)
			(xy 245.11163 -118.195905) (xy 245.074413 -118.237442) (xy 245.031545 -118.273117) (xy 244.983939 -118.302171)
			(xy 244.93261 -118.323983) (xy 244.878653 -118.338089) (xy 244.823216 -118.344189) (xy 244.767482 -118.342152)
			(xy 244.712639 -118.332022) (xy 244.659855 -118.314015) (xy 244.610255 -118.288514) (xy 244.564897 -118.256063)
			(xy 244.524748 -118.217354) (xy 244.490662 -118.173211) (xy 244.463366 -118.124576) (xy 244.443443 -118.072485)
			(xy 244.431317 -118.018048) (xy 244.427246 -117.962426) (xy 244.267736 -117.962426) (xy 244.267736 -118.649496)
			(xy 244.267181 -118.676531) (xy 244.258378 -118.72988) (xy 244.241052 -118.7811) (xy 244.215661 -118.828837)
			(xy 244.182874 -118.871834) (xy 244.163596 -118.890796) (xy 244.16258 -118.891812) (xy 243.439696 -119.614696)
			(xy 243.420924 -119.632726) (xy 243.378806 -119.663302) (xy 243.33243 -119.686924) (xy 243.282933 -119.703013)
			(xy 243.231531 -119.711174) (xy 243.205508 -119.711724) (xy 242.880896 -119.711724) (xy 242.874888 -119.711898)
			(xy 242.863212 -119.714734) (xy 242.857782 -119.717312) (xy 242.854308 -119.719152) (xy 242.84793 -119.723746)
			(xy 242.845082 -119.726456) (xy 242.82146 -119.750078) (xy 242.821968 -119.757698) (xy 242.845336 -119.846344)
			(xy 242.846894 -119.850894) (xy 242.851494 -119.859339) (xy 242.85448 -119.863108) (xy 242.861084 -119.871236)
			(xy 242.880642 -119.881142) (xy 242.88496 -119.882412) (xy 242.910957 -119.890566) (xy 242.960506 -119.91322)
			(xy 243.006328 -119.942694) (xy 243.04749 -119.978387) (xy 243.083156 -120.019573) (xy 243.1126 -120.065414)
			(xy 243.135222 -120.114978) (xy 243.136071 -120.11787) (xy 243.411246 -120.11787) (xy 243.415317 -120.062248)
			(xy 243.427443 -120.007811) (xy 243.447366 -119.95572) (xy 243.474662 -119.907085) (xy 243.508748 -119.862942)
			(xy 243.548897 -119.824233) (xy 243.594255 -119.791782) (xy 243.643855 -119.766281) (xy 243.696639 -119.748274)
			(xy 243.751482 -119.738144) (xy 243.807216 -119.736107) (xy 243.862653 -119.742207) (xy 243.91661 -119.756313)
			(xy 243.967939 -119.778125) (xy 244.015545 -119.807179) (xy 244.058413 -119.842854) (xy 244.09563 -119.884391)
			(xy 244.126403 -119.930904) (xy 244.150075 -119.981401) (xy 244.166143 -120.034808) (xy 244.174263 -120.089984)
			(xy 244.174772 -120.11787) (xy 244.427246 -120.11787) (xy 244.431317 -120.062248) (xy 244.443443 -120.007811)
			(xy 244.463366 -119.95572) (xy 244.490662 -119.907085) (xy 244.524748 -119.862942) (xy 244.564897 -119.824233)
			(xy 244.610255 -119.791782) (xy 244.659855 -119.766281) (xy 244.712639 -119.748274) (xy 244.767482 -119.738144)
			(xy 244.823216 -119.736107) (xy 244.878653 -119.742207) (xy 244.93261 -119.756313) (xy 244.983939 -119.778125)
			(xy 245.031545 -119.807179) (xy 245.074413 -119.842854) (xy 245.11163 -119.884391) (xy 245.142403 -119.930904)
			(xy 245.166075 -119.981401) (xy 245.182143 -120.034808) (xy 245.190263 -120.089984) (xy 245.190772 -120.11787)
			(xy 245.190263 -120.145756) (xy 245.189134 -120.15343) (xy 247.62282 -120.15343) (xy 247.626891 -120.097808)
			(xy 247.639017 -120.043371) (xy 247.65894 -119.99128) (xy 247.686236 -119.942645) (xy 247.720322 -119.898502)
			(xy 247.760471 -119.859793) (xy 247.805829 -119.827342) (xy 247.855429 -119.801841) (xy 247.908213 -119.783834)
			(xy 247.963056 -119.773704) (xy 248.01879 -119.771667) (xy 248.074227 -119.777767) (xy 248.128184 -119.791873)
			(xy 248.179513 -119.813685) (xy 248.227119 -119.842739) (xy 248.269987 -119.878414) (xy 248.307204 -119.919951)
			(xy 248.337977 -119.966464) (xy 248.361649 -120.016961) (xy 248.377717 -120.070368) (xy 248.385837 -120.125544)
			(xy 248.386346 -120.15343) (xy 248.385837 -120.181316) (xy 248.377717 -120.236492) (xy 248.361649 -120.289899)
			(xy 248.337977 -120.340396) (xy 248.307204 -120.386909) (xy 248.269987 -120.428446) (xy 248.227119 -120.464121)
			(xy 248.179513 -120.493175) (xy 248.128184 -120.514987) (xy 248.074227 -120.529093) (xy 248.01879 -120.535193)
			(xy 247.963056 -120.533156) (xy 247.908213 -120.523026) (xy 247.855429 -120.505019) (xy 247.805829 -120.479518)
			(xy 247.760471 -120.447067) (xy 247.720322 -120.408358) (xy 247.686236 -120.364215) (xy 247.65894 -120.31558)
			(xy 247.639017 -120.263489) (xy 247.626891 -120.209052) (xy 247.62282 -120.15343) (xy 245.189134 -120.15343)
			(xy 245.182143 -120.200932) (xy 245.166075 -120.254339) (xy 245.142403 -120.304836) (xy 245.11163 -120.351349)
			(xy 245.074413 -120.392886) (xy 245.031545 -120.428561) (xy 244.983939 -120.457615) (xy 244.93261 -120.479427)
			(xy 244.878653 -120.493533) (xy 244.823216 -120.499633) (xy 244.767482 -120.497596) (xy 244.712639 -120.487466)
			(xy 244.659855 -120.469459) (xy 244.610255 -120.443958) (xy 244.564897 -120.411507) (xy 244.524748 -120.372798)
			(xy 244.490662 -120.328655) (xy 244.463366 -120.28002) (xy 244.443443 -120.227929) (xy 244.431317 -120.173492)
			(xy 244.427246 -120.11787) (xy 244.174772 -120.11787) (xy 244.174263 -120.145756) (xy 244.166143 -120.200932)
			(xy 244.150075 -120.254339) (xy 244.126403 -120.304836) (xy 244.09563 -120.351349) (xy 244.058413 -120.392886)
			(xy 244.015545 -120.428561) (xy 243.967939 -120.457615) (xy 243.91661 -120.479427) (xy 243.862653 -120.493533)
			(xy 243.807216 -120.499633) (xy 243.751482 -120.497596) (xy 243.696639 -120.487466) (xy 243.643855 -120.469459)
			(xy 243.594255 -120.443958) (xy 243.548897 -120.411507) (xy 243.508748 -120.372798) (xy 243.474662 -120.328655)
			(xy 243.447366 -120.28002) (xy 243.427443 -120.227929) (xy 243.415317 -120.173492) (xy 243.411246 -120.11787)
			(xy 243.136071 -120.11787) (xy 243.150563 -120.167256) (xy 243.158311 -120.221185) (xy 243.158772 -120.248426)
			(xy 243.158307 -120.275677) (xy 243.150547 -120.329623) (xy 243.135188 -120.381916) (xy 243.112544 -120.43149)
			(xy 243.083074 -120.477337) (xy 243.04738 -120.518524) (xy 243.006188 -120.554211) (xy 242.960336 -120.583673)
			(xy 242.910757 -120.60631) (xy 242.858462 -120.62166) (xy 242.804515 -120.629411) (xy 242.777264 -120.629934)
			(xy 242.74975 -120.629459) (xy 242.695288 -120.621577) (xy 242.64252 -120.605967) (xy 242.592536 -120.582951)
			(xy 242.546369 -120.553004) (xy 242.504973 -120.516747) (xy 242.469205 -120.474929) (xy 242.439803 -120.428413)
			(xy 242.417376 -120.378162) (xy 242.409472 -120.351804) (xy 242.409472 -120.351296) (xy 242.407948 -120.346216)
			(xy 242.405217 -120.339824) (xy 242.39685 -120.328731) (xy 242.391438 -120.324372) (xy 242.387761 -120.321803)
			(xy 242.379715 -120.317841) (xy 242.375436 -120.316498) (xy 242.348004 -120.309132) (xy 242.346734 -120.308878)
			(xy 242.293648 -120.295162) (xy 242.282218 -120.293638) (xy 242.2779 -120.293638) (xy 241.000788 -121.57075)
			(xy 245.81993 -121.57075) (xy 245.820355 -121.544434) (xy 245.827597 -121.492304) (xy 245.841924 -121.44166)
			(xy 245.863064 -121.393461) (xy 245.890618 -121.348618) (xy 245.924065 -121.307981) (xy 245.94312 -121.289826)
			(xy 245.950515 -121.282299) (xy 245.959043 -121.263023) (xy 245.95963 -121.252488) (xy 245.95963 -121.177812)
			(xy 245.959099 -121.167263) (xy 245.950564 -121.147968) (xy 245.94312 -121.140474) (xy 245.924063 -121.12232)
			(xy 245.890605 -121.081691) (xy 245.863046 -121.03685) (xy 245.841907 -120.988649) (xy 245.827591 -120.938001)
			(xy 245.820368 -120.885866) (xy 245.81993 -120.85955) (xy 245.820416 -120.832299) (xy 245.828172 -120.778351)
			(xy 245.843527 -120.726056) (xy 245.866169 -120.676479) (xy 245.895635 -120.630629) (xy 245.931326 -120.589438)
			(xy 245.972517 -120.553747) (xy 246.018367 -120.524281) (xy 246.067944 -120.501639) (xy 246.120239 -120.486284)
			(xy 246.174187 -120.478528) (xy 246.228689 -120.478528) (xy 246.282637 -120.486284) (xy 246.334932 -120.501639)
			(xy 246.384509 -120.524281) (xy 246.430359 -120.553747) (xy 246.47155 -120.589438) (xy 246.507241 -120.630629)
			(xy 246.536707 -120.676479) (xy 246.559349 -120.726056) (xy 246.574704 -120.778351) (xy 246.58246 -120.832299)
			(xy 246.582946 -120.85955) (xy 246.582529 -120.885866) (xy 246.575286 -120.937997) (xy 246.560959 -120.988642)
			(xy 246.539817 -121.036841) (xy 246.512261 -121.081683) (xy 246.478812 -121.12232) (xy 246.459756 -121.140474)
			(xy 246.452372 -121.148011) (xy 246.443836 -121.167279) (xy 246.443246 -121.177812) (xy 246.443246 -121.252488)
			(xy 246.443754 -121.26304) (xy 246.452303 -121.282337) (xy 246.459756 -121.289826) (xy 246.478828 -121.307965)
			(xy 246.512281 -121.348599) (xy 246.539837 -121.393444) (xy 246.560972 -121.441647) (xy 246.575286 -121.492297)
			(xy 246.582509 -121.544433) (xy 246.582946 -121.57075) (xy 246.58246 -121.598001) (xy 246.574704 -121.651949)
			(xy 246.559349 -121.704244) (xy 246.536707 -121.753821) (xy 246.507241 -121.799671) (xy 246.47155 -121.840862)
			(xy 246.430359 -121.876553) (xy 246.384509 -121.906019) (xy 246.334932 -121.928661) (xy 246.282637 -121.944016)
			(xy 246.228689 -121.951772) (xy 246.174187 -121.951772) (xy 246.120239 -121.944016) (xy 246.067944 -121.928661)
			(xy 246.018367 -121.906019) (xy 245.972517 -121.876553) (xy 245.931326 -121.840862) (xy 245.895635 -121.799671)
			(xy 245.866169 -121.753821) (xy 245.843527 -121.704244) (xy 245.828172 -121.651949) (xy 245.820416 -121.598001)
			(xy 245.81993 -121.57075) (xy 241.000788 -121.57075) (xy 240.27892 -122.292618) (xy 241.98021 -122.292618)
			(xy 241.984281 -122.236996) (xy 241.996407 -122.182559) (xy 242.01633 -122.130468) (xy 242.043626 -122.081833)
			(xy 242.077712 -122.03769) (xy 242.117861 -121.998981) (xy 242.163219 -121.96653) (xy 242.212819 -121.941029)
			(xy 242.265603 -121.923022) (xy 242.320446 -121.912892) (xy 242.37618 -121.910855) (xy 242.431617 -121.916955)
			(xy 242.485574 -121.931061) (xy 242.536903 -121.952873) (xy 242.584509 -121.981927) (xy 242.627377 -122.017602)
			(xy 242.664594 -122.059139) (xy 242.695367 -122.105652) (xy 242.719039 -122.156149) (xy 242.735107 -122.209556)
			(xy 242.743227 -122.264732) (xy 242.743736 -122.292618) (xy 242.743227 -122.320504) (xy 242.735107 -122.37568)
			(xy 242.719039 -122.429087) (xy 242.699902 -122.46991) (xy 243.136926 -122.46991) (xy 243.140997 -122.414288)
			(xy 243.153123 -122.359851) (xy 243.173046 -122.30776) (xy 243.200342 -122.259125) (xy 243.234428 -122.214982)
			(xy 243.274577 -122.176273) (xy 243.319935 -122.143822) (xy 243.369535 -122.118321) (xy 243.422319 -122.100314)
			(xy 243.477162 -122.090184) (xy 243.532896 -122.088147) (xy 243.588333 -122.094247) (xy 243.64229 -122.108353)
			(xy 243.693619 -122.130165) (xy 243.741225 -122.159219) (xy 243.784093 -122.194894) (xy 243.82131 -122.236431)
			(xy 243.852083 -122.282944) (xy 243.875755 -122.333441) (xy 243.891823 -122.386848) (xy 243.899943 -122.442024)
			(xy 243.900452 -122.46991) (xy 243.899943 -122.497796) (xy 243.891823 -122.552972) (xy 243.875755 -122.606379)
			(xy 243.852083 -122.656876) (xy 243.82131 -122.703389) (xy 243.784093 -122.744926) (xy 243.741225 -122.780601)
			(xy 243.693619 -122.809655) (xy 243.64229 -122.831467) (xy 243.588333 -122.845573) (xy 243.532896 -122.851673)
			(xy 243.477162 -122.849636) (xy 243.422319 -122.839506) (xy 243.369535 -122.821499) (xy 243.319935 -122.795998)
			(xy 243.274577 -122.763547) (xy 243.234428 -122.724838) (xy 243.200342 -122.680695) (xy 243.173046 -122.63206)
			(xy 243.153123 -122.579969) (xy 243.140997 -122.525532) (xy 243.136926 -122.46991) (xy 242.699902 -122.46991)
			(xy 242.695367 -122.479584) (xy 242.664594 -122.526097) (xy 242.627377 -122.567634) (xy 242.584509 -122.603309)
			(xy 242.536903 -122.632363) (xy 242.485574 -122.654175) (xy 242.431617 -122.668281) (xy 242.37618 -122.674381)
			(xy 242.320446 -122.672344) (xy 242.265603 -122.662214) (xy 242.212819 -122.644207) (xy 242.163219 -122.618706)
			(xy 242.117861 -122.586255) (xy 242.077712 -122.547546) (xy 242.043626 -122.503403) (xy 242.01633 -122.454768)
			(xy 241.996407 -122.402677) (xy 241.984281 -122.34824) (xy 241.98021 -122.292618) (xy 240.27892 -122.292618)
			(xy 239.321786 -123.249752) (xy 244.109967 -123.249752) (xy 244.109967 -123.195248) (xy 244.117724 -123.141299)
			(xy 244.13308 -123.089002) (xy 244.155722 -123.039423) (xy 244.185189 -122.993572) (xy 244.220882 -122.95238)
			(xy 244.262073 -122.916688) (xy 244.307925 -122.887221) (xy 244.357504 -122.864579) (xy 244.4098 -122.849224)
			(xy 244.46375 -122.841467) (xy 244.491002 -122.841004) (xy 244.518032 -122.841498) (xy 244.571549 -122.849136)
			(xy 244.623451 -122.864259) (xy 244.672695 -122.886564) (xy 244.718294 -122.915602) (xy 244.759332 -122.950791)
			(xy 244.777514 -122.970798) (xy 244.777768 -122.971052) (xy 244.785208 -122.978703) (xy 244.804695 -122.987369)
			(xy 244.81536 -122.987816) (xy 244.90299 -122.988324) (xy 244.922548 -122.979688) (xy 244.929914 -122.971306)
			(xy 244.948074 -122.951582) (xy 244.988975 -122.916918) (xy 245.034331 -122.88833) (xy 245.083246 -122.866381)
			(xy 245.134755 -122.851505) (xy 245.187841 -122.843997) (xy 245.214648 -122.843544) (xy 245.242018 -122.84403)
			(xy 245.296196 -122.851841) (xy 245.3487 -122.867325) (xy 245.398447 -122.890163) (xy 245.444414 -122.919884)
			(xy 245.465346 -122.937524) (xy 245.4656 -122.937778) (xy 245.472676 -122.94338) (xy 245.489601 -122.949615)
			(xy 245.49862 -122.94997) (xy 245.565676 -122.94997) (xy 245.574692 -122.949608) (xy 245.59161 -122.943364)
			(xy 245.598696 -122.937778) (xy 245.598696 -122.937524) (xy 245.59895 -122.937524) (xy 245.619883 -122.919883)
			(xy 245.665851 -122.890159) (xy 245.715597 -122.867313) (xy 245.768099 -122.851817) (xy 245.822277 -122.843988)
			(xy 245.877019 -122.843988) (xy 245.931197 -122.851817) (xy 245.983699 -122.867313) (xy 246.033445 -122.890159)
			(xy 246.079413 -122.919883) (xy 246.100346 -122.937524) (xy 246.1006 -122.937778) (xy 246.107676 -122.94338)
			(xy 246.124601 -122.949615) (xy 246.13362 -122.94997) (xy 246.200676 -122.94997) (xy 246.209692 -122.949608)
			(xy 246.22661 -122.943364) (xy 246.233696 -122.937778) (xy 246.234204 -122.937524) (xy 246.246938 -122.926579)
			(xy 246.274029 -122.906738) (xy 246.288306 -122.8979) (xy 246.297196 -122.892566) (xy 246.309388 -122.875548)
			(xy 246.329708 -122.78233) (xy 246.32539 -122.761756) (xy 246.319548 -122.75312) (xy 246.303548 -122.729056)
			(xy 246.278207 -122.677124) (xy 246.260982 -122.621966) (xy 246.252266 -122.564842) (xy 246.25173 -122.53595)
			(xy 246.252216 -122.508699) (xy 246.259972 -122.454751) (xy 246.275327 -122.402456) (xy 246.297969 -122.352879)
			(xy 246.327435 -122.307029) (xy 246.363126 -122.265838) (xy 246.404317 -122.230147) (xy 246.450167 -122.200681)
			(xy 246.499744 -122.178039) (xy 246.552039 -122.162684) (xy 246.605987 -122.154928) (xy 246.660489 -122.154928)
			(xy 246.714437 -122.162684) (xy 246.766732 -122.178039) (xy 246.816309 -122.200681) (xy 246.862159 -122.230147)
			(xy 246.90335 -122.265838) (xy 246.939041 -122.307029) (xy 246.968507 -122.352879) (xy 246.991149 -122.402456)
			(xy 247.006504 -122.454751) (xy 247.01426 -122.508699) (xy 247.014746 -122.53595) (xy 247.014198 -122.56404)
			(xy 247.005979 -122.619614) (xy 246.989696 -122.673381) (xy 246.965702 -122.724178) (xy 246.934515 -122.770905)
			(xy 246.896812 -122.812552) (xy 246.853407 -122.848217) (xy 246.82958 -122.863102) (xy 246.82069 -122.868436)
			(xy 246.808498 -122.885454) (xy 246.788178 -122.978672) (xy 246.792496 -122.999246) (xy 246.798338 -123.007882)
			(xy 246.814337 -123.031946) (xy 246.839679 -123.083878) (xy 246.856905 -123.139036) (xy 246.865621 -123.19616)
			(xy 246.866156 -123.225052) (xy 246.865577 -123.2523) (xy 246.857829 -123.306242) (xy 246.842482 -123.358532)
			(xy 246.81985 -123.408106) (xy 246.790393 -123.453954) (xy 246.754711 -123.495143) (xy 246.713531 -123.530836)
			(xy 246.66769 -123.560304) (xy 246.618122 -123.582948) (xy 246.565836 -123.598308) (xy 246.511896 -123.60607)
			(xy 246.484648 -123.60656) (xy 246.457278 -123.606076) (xy 246.4031 -123.598264) (xy 246.350596 -123.582779)
			(xy 246.300849 -123.559942) (xy 246.254882 -123.53022) (xy 246.23395 -123.51258) (xy 246.233696 -123.512326)
			(xy 246.226621 -123.506723) (xy 246.209695 -123.500488) (xy 246.200676 -123.500134) (xy 246.13362 -123.500134)
			(xy 246.124603 -123.500493) (xy 246.107686 -123.506739) (xy 246.1006 -123.512326) (xy 246.100346 -123.51258)
			(xy 246.079413 -123.530221) (xy 246.033445 -123.559945) (xy 245.983699 -123.582791) (xy 245.931197 -123.598287)
			(xy 245.877019 -123.606116) (xy 245.822277 -123.606116) (xy 245.768099 -123.598287) (xy 245.715597 -123.582791)
			(xy 245.665851 -123.559945) (xy 245.619883 -123.530221) (xy 245.59895 -123.51258) (xy 245.598696 -123.512326)
			(xy 245.591621 -123.506723) (xy 245.574695 -123.500488) (xy 245.565676 -123.500134) (xy 245.49862 -123.500134)
			(xy 245.489603 -123.500493) (xy 245.472686 -123.506739) (xy 245.4656 -123.512326) (xy 245.4656 -123.51258)
			(xy 245.465346 -123.51258) (xy 245.444405 -123.530208) (xy 245.398435 -123.559922) (xy 245.34869 -123.582761)
			(xy 245.296191 -123.598254) (xy 245.242017 -123.606085) (xy 245.214648 -123.60656) (xy 245.187618 -123.606078)
			(xy 245.134101 -123.598435) (xy 245.0822 -123.583308) (xy 245.032957 -123.561001) (xy 244.987358 -123.531961)
			(xy 244.946319 -123.496772) (xy 244.928136 -123.476766) (xy 244.927882 -123.476512) (xy 244.920414 -123.468893)
			(xy 244.900949 -123.460207) (xy 244.89029 -123.459748) (xy 244.80266 -123.45924) (xy 244.783102 -123.467876)
			(xy 244.775736 -123.476258) (xy 244.757564 -123.49597) (xy 244.716664 -123.530633) (xy 244.67131 -123.559221)
			(xy 244.622398 -123.581172) (xy 244.570891 -123.59605) (xy 244.517808 -123.603564) (xy 244.491002 -123.60402)
			(xy 244.46375 -123.603533) (xy 244.4098 -123.595776) (xy 244.357504 -123.580421) (xy 244.307925 -123.557779)
			(xy 244.262073 -123.528312) (xy 244.220882 -123.49262) (xy 244.185189 -123.451428) (xy 244.155722 -123.405577)
			(xy 244.13308 -123.355998) (xy 244.117724 -123.303701) (xy 244.109967 -123.249752) (xy 239.321786 -123.249752)
			(xy 237.60811 -124.963428) (xy 240.873024 -124.963428) (xy 240.877095 -124.907806) (xy 240.889221 -124.853369)
			(xy 240.909144 -124.801278) (xy 240.93644 -124.752643) (xy 240.970526 -124.7085) (xy 241.010675 -124.669791)
			(xy 241.056033 -124.63734) (xy 241.105633 -124.611839) (xy 241.158417 -124.593832) (xy 241.21326 -124.583702)
			(xy 241.268994 -124.581665) (xy 241.324431 -124.587765) (xy 241.378388 -124.601871) (xy 241.429717 -124.623683)
			(xy 241.477323 -124.652737) (xy 241.520191 -124.688412) (xy 241.557408 -124.729949) (xy 241.588181 -124.776462)
			(xy 241.611853 -124.826959) (xy 241.627921 -124.880366) (xy 241.636041 -124.935542) (xy 241.63655 -124.963428)
			(xy 241.636041 -124.991314) (xy 241.627921 -125.04649) (xy 241.624483 -125.057916) (xy 242.981478 -125.057916)
			(xy 242.985549 -125.002294) (xy 242.997675 -124.947857) (xy 243.017598 -124.895766) (xy 243.044894 -124.847131)
			(xy 243.07898 -124.802988) (xy 243.119129 -124.764279) (xy 243.164487 -124.731828) (xy 243.214087 -124.706327)
			(xy 243.266871 -124.68832) (xy 243.321714 -124.67819) (xy 243.377448 -124.676153) (xy 243.432885 -124.682253)
			(xy 243.486842 -124.696359) (xy 243.538171 -124.718171) (xy 243.585777 -124.747225) (xy 243.628645 -124.7829)
			(xy 243.665862 -124.824437) (xy 243.696635 -124.87095) (xy 243.720307 -124.921447) (xy 243.736375 -124.974854)
			(xy 243.744495 -125.03003) (xy 243.745004 -125.057916) (xy 243.744495 -125.085802) (xy 243.736375 -125.140978)
			(xy 243.720307 -125.194385) (xy 243.696635 -125.244882) (xy 243.665862 -125.291395) (xy 243.628645 -125.332932)
			(xy 243.585777 -125.368607) (xy 243.538171 -125.397661) (xy 243.524769 -125.403356) (xy 247.744234 -125.403356)
			(xy 247.744725 -125.375987) (xy 247.752535 -125.321808) (xy 247.768018 -125.269305) (xy 247.790855 -125.219558)
			(xy 247.820575 -125.17359) (xy 247.838214 -125.152658) (xy 247.838468 -125.152404) (xy 247.844067 -125.145326)
			(xy 247.850304 -125.128402) (xy 247.85066 -125.119384) (xy 247.85066 -125.052328) (xy 247.850298 -125.043311)
			(xy 247.844055 -125.026394) (xy 247.838468 -125.019308) (xy 247.838214 -125.019308) (xy 247.838214 -125.019054)
			(xy 247.820589 -124.998111) (xy 247.790875 -124.952141) (xy 247.768036 -124.902397) (xy 247.752541 -124.849898)
			(xy 247.74471 -124.795724) (xy 247.744234 -124.768356) (xy 247.74472 -124.741105) (xy 247.752476 -124.687157)
			(xy 247.767831 -124.634862) (xy 247.790473 -124.585285) (xy 247.819939 -124.539435) (xy 247.85563 -124.498244)
			(xy 247.896821 -124.462553) (xy 247.942671 -124.433087) (xy 247.992248 -124.410445) (xy 248.044543 -124.39509)
			(xy 248.098491 -124.387334) (xy 248.152993 -124.387334) (xy 248.206941 -124.39509) (xy 248.259236 -124.410445)
			(xy 248.308813 -124.433087) (xy 248.354663 -124.462553) (xy 248.395854 -124.498244) (xy 248.431545 -124.539435)
			(xy 248.461011 -124.585285) (xy 248.483653 -124.634862) (xy 248.499008 -124.687157) (xy 248.506764 -124.741105)
			(xy 248.50725 -124.768356) (xy 248.50677 -124.795726) (xy 248.498958 -124.849905) (xy 248.483472 -124.902408)
			(xy 248.460633 -124.952155) (xy 248.430911 -124.998122) (xy 248.41327 -125.019054) (xy 248.413016 -125.019308)
			(xy 248.407422 -125.026389) (xy 248.401179 -125.04331) (xy 248.400824 -125.052328) (xy 248.400824 -125.119384)
			(xy 248.401184 -125.128401) (xy 248.407429 -125.145318) (xy 248.413016 -125.152404) (xy 248.41327 -125.152404)
			(xy 248.41327 -125.152658) (xy 248.430898 -125.173599) (xy 248.460613 -125.219569) (xy 248.483451 -125.269314)
			(xy 248.498945 -125.321813) (xy 248.506775 -125.375987) (xy 248.50725 -125.403356) (xy 248.506764 -125.430607)
			(xy 248.499008 -125.484555) (xy 248.483653 -125.53685) (xy 248.461011 -125.586427) (xy 248.431545 -125.632277)
			(xy 248.395854 -125.673468) (xy 248.354663 -125.709159) (xy 248.308813 -125.738625) (xy 248.259236 -125.761267)
			(xy 248.206941 -125.776622) (xy 248.152993 -125.784378) (xy 248.098491 -125.784378) (xy 248.044543 -125.776622)
			(xy 247.992248 -125.761267) (xy 247.942671 -125.738625) (xy 247.896821 -125.709159) (xy 247.85563 -125.673468)
			(xy 247.819939 -125.632277) (xy 247.790473 -125.586427) (xy 247.767831 -125.53685) (xy 247.752476 -125.484555)
			(xy 247.74472 -125.430607) (xy 247.744234 -125.403356) (xy 243.524769 -125.403356) (xy 243.486842 -125.419473)
			(xy 243.432885 -125.433579) (xy 243.377448 -125.439679) (xy 243.321714 -125.437642) (xy 243.266871 -125.427512)
			(xy 243.214087 -125.409505) (xy 243.164487 -125.384004) (xy 243.119129 -125.351553) (xy 243.07898 -125.312844)
			(xy 243.044894 -125.268701) (xy 243.017598 -125.220066) (xy 242.997675 -125.167975) (xy 242.985549 -125.113538)
			(xy 242.981478 -125.057916) (xy 241.624483 -125.057916) (xy 241.611853 -125.099897) (xy 241.588181 -125.150394)
			(xy 241.557408 -125.196907) (xy 241.520191 -125.238444) (xy 241.477323 -125.274119) (xy 241.429717 -125.303173)
			(xy 241.378388 -125.324985) (xy 241.324431 -125.339091) (xy 241.268994 -125.345191) (xy 241.21326 -125.343154)
			(xy 241.158417 -125.333024) (xy 241.105633 -125.315017) (xy 241.056033 -125.289516) (xy 241.010675 -125.257065)
			(xy 240.970526 -125.218356) (xy 240.93644 -125.174213) (xy 240.909144 -125.125578) (xy 240.889221 -125.073487)
			(xy 240.877095 -125.01905) (xy 240.873024 -124.963428) (xy 237.60811 -124.963428) (xy 236.59211 -125.979428)
			(xy 240.873024 -125.979428) (xy 240.877095 -125.923806) (xy 240.889221 -125.869369) (xy 240.909144 -125.817278)
			(xy 240.93644 -125.768643) (xy 240.970526 -125.7245) (xy 241.010675 -125.685791) (xy 241.056033 -125.65334)
			(xy 241.105633 -125.627839) (xy 241.158417 -125.609832) (xy 241.21326 -125.599702) (xy 241.268994 -125.597665)
			(xy 241.324431 -125.603765) (xy 241.378388 -125.617871) (xy 241.429717 -125.639683) (xy 241.477323 -125.668737)
			(xy 241.520191 -125.704412) (xy 241.557408 -125.745949) (xy 241.588181 -125.792462) (xy 241.611853 -125.842959)
			(xy 241.627921 -125.896366) (xy 241.636041 -125.951542) (xy 241.63655 -125.979428) (xy 241.636041 -126.007314)
			(xy 241.627921 -126.06249) (xy 241.614396 -126.107444) (xy 243.356382 -126.107444) (xy 243.360453 -126.051822)
			(xy 243.372579 -125.997385) (xy 243.392502 -125.945294) (xy 243.419798 -125.896659) (xy 243.453884 -125.852516)
			(xy 243.494033 -125.813807) (xy 243.539391 -125.781356) (xy 243.588991 -125.755855) (xy 243.641775 -125.737848)
			(xy 243.696618 -125.727718) (xy 243.752352 -125.725681) (xy 243.807789 -125.731781) (xy 243.861746 -125.745887)
			(xy 243.913075 -125.767699) (xy 243.960681 -125.796753) (xy 244.003549 -125.832428) (xy 244.022607 -125.853698)
			(xy 248.684796 -125.853698) (xy 248.685262 -125.826328) (xy 248.69308 -125.772149) (xy 248.708569 -125.719646)
			(xy 248.731411 -125.669899) (xy 248.761135 -125.623932) (xy 248.778776 -125.603) (xy 248.77903 -125.602746)
			(xy 248.784607 -125.595653) (xy 248.790858 -125.578741) (xy 248.791222 -125.569726) (xy 248.791222 -125.50267)
			(xy 248.790875 -125.493652) (xy 248.78462 -125.476736) (xy 248.77903 -125.46965) (xy 248.778776 -125.46965)
			(xy 248.778776 -125.469396) (xy 248.761118 -125.448479) (xy 248.73141 -125.402502) (xy 248.708578 -125.35275)
			(xy 248.693091 -125.300247) (xy 248.685268 -125.246068) (xy 248.684796 -125.218698) (xy 248.685282 -125.191447)
			(xy 248.693038 -125.137499) (xy 248.708393 -125.085204) (xy 248.731035 -125.035627) (xy 248.760501 -124.989777)
			(xy 248.796192 -124.948586) (xy 248.837383 -124.912895) (xy 248.883233 -124.883429) (xy 248.93281 -124.860787)
			(xy 248.985105 -124.845432) (xy 249.039053 -124.837676) (xy 249.093555 -124.837676) (xy 249.147503 -124.845432)
			(xy 249.199798 -124.860787) (xy 249.249375 -124.883429) (xy 249.295225 -124.912895) (xy 249.336416 -124.948586)
			(xy 249.372107 -124.989777) (xy 249.401573 -125.035627) (xy 249.424215 -125.085204) (xy 249.43957 -125.137499)
			(xy 249.447326 -125.191447) (xy 249.447812 -125.218698) (xy 249.447342 -125.246068) (xy 249.439525 -125.300247)
			(xy 249.424036 -125.35275) (xy 249.401196 -125.402497) (xy 249.371472 -125.448464) (xy 249.353832 -125.469396)
			(xy 249.353578 -125.46965) (xy 249.348004 -125.476745) (xy 249.34175 -125.493655) (xy 249.341386 -125.50267)
			(xy 249.341386 -125.569726) (xy 249.341734 -125.578744) (xy 249.347988 -125.59566) (xy 249.353578 -125.602746)
			(xy 249.353832 -125.602746) (xy 249.353832 -125.603) (xy 249.37149 -125.623917) (xy 249.401198 -125.669895)
			(xy 249.424029 -125.719646) (xy 249.439516 -125.77215) (xy 249.44734 -125.826328) (xy 249.447812 -125.853698)
			(xy 249.447326 -125.880949) (xy 249.43957 -125.934897) (xy 249.424215 -125.987192) (xy 249.401573 -126.036769)
			(xy 249.372107 -126.082619) (xy 249.336416 -126.12381) (xy 249.295225 -126.159501) (xy 249.249375 -126.188967)
			(xy 249.199798 -126.211609) (xy 249.147503 -126.226964) (xy 249.093555 -126.23472) (xy 249.039053 -126.23472)
			(xy 248.985105 -126.226964) (xy 248.93281 -126.211609) (xy 248.883233 -126.188967) (xy 248.837383 -126.159501)
			(xy 248.796192 -126.12381) (xy 248.760501 -126.082619) (xy 248.731035 -126.036769) (xy 248.708393 -125.987192)
			(xy 248.693038 -125.934897) (xy 248.685282 -125.880949) (xy 248.684796 -125.853698) (xy 244.022607 -125.853698)
			(xy 244.040766 -125.873965) (xy 244.071539 -125.920478) (xy 244.095211 -125.970975) (xy 244.111279 -126.024382)
			(xy 244.119399 -126.079558) (xy 244.119908 -126.107444) (xy 244.119399 -126.13533) (xy 244.111279 -126.190506)
			(xy 244.095211 -126.243913) (xy 244.071539 -126.29441) (xy 244.040766 -126.340923) (xy 244.003549 -126.38246)
			(xy 243.960681 -126.418135) (xy 243.913075 -126.447189) (xy 243.861746 -126.469001) (xy 243.807789 -126.483107)
			(xy 243.752352 -126.489207) (xy 243.696618 -126.48717) (xy 243.641775 -126.47704) (xy 243.588991 -126.459033)
			(xy 243.539391 -126.433532) (xy 243.494033 -126.401081) (xy 243.453884 -126.362372) (xy 243.419798 -126.318229)
			(xy 243.392502 -126.269594) (xy 243.372579 -126.217503) (xy 243.360453 -126.163066) (xy 243.356382 -126.107444)
			(xy 241.614396 -126.107444) (xy 241.611853 -126.115897) (xy 241.588181 -126.166394) (xy 241.557408 -126.212907)
			(xy 241.520191 -126.254444) (xy 241.477323 -126.290119) (xy 241.429717 -126.319173) (xy 241.378388 -126.340985)
			(xy 241.324431 -126.355091) (xy 241.268994 -126.361191) (xy 241.21326 -126.359154) (xy 241.158417 -126.349024)
			(xy 241.105633 -126.331017) (xy 241.056033 -126.305516) (xy 241.010675 -126.273065) (xy 240.970526 -126.234356)
			(xy 240.93644 -126.190213) (xy 240.909144 -126.141578) (xy 240.889221 -126.089487) (xy 240.877095 -126.03505)
			(xy 240.873024 -125.979428) (xy 236.59211 -125.979428) (xy 236.033056 -126.538482) (xy 236.030348 -126.541332)
			(xy 236.025752 -126.547708) (xy 236.023912 -126.551182) (xy 236.021332 -126.55661) (xy 236.018517 -126.568289)
			(xy 236.018324 -126.574296) (xy 236.018324 -127.051308) (xy 242.94414 -127.051308) (xy 242.948211 -126.995686)
			(xy 242.960337 -126.941249) (xy 242.98026 -126.889158) (xy 243.007556 -126.840523) (xy 243.041642 -126.79638)
			(xy 243.081791 -126.757671) (xy 243.127149 -126.72522) (xy 243.176749 -126.699719) (xy 243.229533 -126.681712)
			(xy 243.284376 -126.671582) (xy 243.34011 -126.669545) (xy 243.395547 -126.675645) (xy 243.449504 -126.689751)
			(xy 243.500833 -126.711563) (xy 243.548439 -126.740617) (xy 243.591307 -126.776292) (xy 243.628524 -126.817829)
			(xy 243.659297 -126.864342) (xy 243.682969 -126.914839) (xy 243.699037 -126.968246) (xy 243.707157 -127.023422)
			(xy 243.707666 -127.051308) (xy 243.707157 -127.079194) (xy 243.699037 -127.13437) (xy 243.682969 -127.187777)
			(xy 243.659297 -127.238274) (xy 243.628524 -127.284787) (xy 243.591307 -127.326324) (xy 243.548439 -127.361999)
			(xy 243.500833 -127.391053) (xy 243.449504 -127.412865) (xy 243.395547 -127.426971) (xy 243.34011 -127.433071)
			(xy 243.284376 -127.431034) (xy 243.229533 -127.420904) (xy 243.176749 -127.402897) (xy 243.127149 -127.377396)
			(xy 243.081791 -127.344945) (xy 243.041642 -127.306236) (xy 243.007556 -127.262093) (xy 242.98026 -127.213458)
			(xy 242.960337 -127.161367) (xy 242.948211 -127.10693) (xy 242.94414 -127.051308) (xy 236.018324 -127.051308)
			(xy 236.018324 -128.252747) (xy 241.928428 -128.252747) (xy 241.928428 -128.198253) (xy 241.936184 -128.144312)
			(xy 241.951536 -128.092025) (xy 241.974174 -128.042454) (xy 242.003636 -127.99661) (xy 242.039323 -127.955426)
			(xy 242.080507 -127.919739) (xy 242.126351 -127.890276) (xy 242.175921 -127.867638) (xy 242.228208 -127.852284)
			(xy 242.282149 -127.844528) (xy 242.309396 -127.844042) (xy 242.336767 -127.8445) (xy 242.390946 -127.852318)
			(xy 242.44345 -127.867809) (xy 242.493197 -127.890652) (xy 242.539163 -127.920379) (xy 242.560094 -127.938022)
			(xy 242.560348 -127.938276) (xy 242.567439 -127.943856) (xy 242.584353 -127.950105) (xy 242.593368 -127.950468)
			(xy 242.660424 -127.950468) (xy 242.669443 -127.950129) (xy 242.68636 -127.94387) (xy 242.693444 -127.938276)
			(xy 242.693444 -127.938022) (xy 242.693698 -127.938022) (xy 242.714631 -127.920381) (xy 242.760599 -127.890657)
			(xy 242.810345 -127.867811) (xy 242.862847 -127.852315) (xy 242.917025 -127.844486) (xy 242.971767 -127.844486)
			(xy 243.025945 -127.852315) (xy 243.078447 -127.867811) (xy 243.128193 -127.890657) (xy 243.174161 -127.920381)
			(xy 243.195094 -127.938022) (xy 243.195348 -127.938276) (xy 243.202439 -127.943856) (xy 243.219353 -127.950105)
			(xy 243.228368 -127.950468) (xy 243.295424 -127.950468) (xy 243.304443 -127.950129) (xy 243.32136 -127.94387)
			(xy 243.328444 -127.938276) (xy 243.328444 -127.938022) (xy 243.328698 -127.938022) (xy 243.349623 -127.920374)
			(xy 243.395597 -127.890663) (xy 243.445347 -127.867828) (xy 243.497849 -127.852339) (xy 243.552026 -127.844514)
			(xy 243.579396 -127.844042) (xy 243.606653 -127.844405) (xy 243.660611 -127.852162) (xy 243.712916 -127.86752)
			(xy 243.762504 -127.890165) (xy 243.808363 -127.919637) (xy 243.849562 -127.955335) (xy 243.885261 -127.996534)
			(xy 243.914733 -128.042393) (xy 243.937379 -128.09198) (xy 243.952737 -128.144285) (xy 243.960495 -128.198243)
			(xy 243.960495 -128.252757) (xy 243.952737 -128.306715) (xy 243.937379 -128.35902) (xy 243.914733 -128.408607)
			(xy 243.885261 -128.454466) (xy 243.849562 -128.495665) (xy 243.808363 -128.531363) (xy 243.762504 -128.560835)
			(xy 243.712916 -128.58348) (xy 243.660611 -128.598838) (xy 243.606653 -128.606595) (xy 243.579396 -128.607058)
			(xy 243.552025 -128.606605) (xy 243.497845 -128.598785) (xy 243.445342 -128.583294) (xy 243.395595 -128.560449)
			(xy 243.349629 -128.530721) (xy 243.328698 -128.513078) (xy 243.328444 -128.512824) (xy 243.321355 -128.507241)
			(xy 243.30444 -128.500994) (xy 243.295424 -128.500632) (xy 243.228368 -128.500632) (xy 243.219349 -128.500967)
			(xy 243.202432 -128.507229) (xy 243.195348 -128.512824) (xy 243.195094 -128.513078) (xy 243.174161 -128.530719)
			(xy 243.128193 -128.560443) (xy 243.078447 -128.583289) (xy 243.025945 -128.598785) (xy 242.971767 -128.606614)
			(xy 242.917025 -128.606614) (xy 242.862847 -128.598785) (xy 242.810345 -128.583289) (xy 242.760599 -128.560443)
			(xy 242.714631 -128.530719) (xy 242.693698 -128.513078) (xy 242.693444 -128.512824) (xy 242.686355 -128.507241)
			(xy 242.66944 -128.500994) (xy 242.660424 -128.500632) (xy 242.593368 -128.500632) (xy 242.584349 -128.500967)
			(xy 242.567432 -128.507229) (xy 242.560348 -128.512824) (xy 242.560348 -128.513078) (xy 242.560094 -128.513078)
			(xy 242.539172 -128.53073) (xy 242.493197 -128.560441) (xy 242.443447 -128.583274) (xy 242.390944 -128.598762)
			(xy 242.336766 -128.606586) (xy 242.309396 -128.607058) (xy 242.282149 -128.606472) (xy 242.228208 -128.598716)
			(xy 242.175921 -128.583362) (xy 242.126351 -128.560724) (xy 242.080507 -128.531261) (xy 242.039323 -128.495574)
			(xy 242.003636 -128.45439) (xy 241.974174 -128.408546) (xy 241.951536 -128.358975) (xy 241.936184 -128.306688)
			(xy 241.928428 -128.252747) (xy 236.018324 -128.252747) (xy 236.018324 -131.447157) (xy 241.913309 -131.447157)
			(xy 241.913309 -131.392643) (xy 241.921067 -131.338685) (xy 241.936426 -131.28638) (xy 241.959072 -131.236793)
			(xy 241.988544 -131.190934) (xy 242.024243 -131.149736) (xy 242.065442 -131.114038) (xy 242.111302 -131.084567)
			(xy 242.160889 -131.061922) (xy 242.213195 -131.046565) (xy 242.267153 -131.038808) (xy 242.29441 -131.038346)
			(xy 242.321781 -131.038795) (xy 242.375961 -131.046615) (xy 242.428465 -131.062108) (xy 242.478212 -131.084953)
			(xy 242.524177 -131.114682) (xy 242.545108 -131.132326) (xy 242.545362 -131.13258) (xy 242.552448 -131.138166)
			(xy 242.569366 -131.144411) (xy 242.578382 -131.144772) (xy 242.645438 -131.144772) (xy 242.654457 -131.144439)
			(xy 242.671375 -131.138175) (xy 242.678458 -131.13258) (xy 242.678458 -131.132326) (xy 242.678712 -131.132326)
			(xy 242.699645 -131.114685) (xy 242.745613 -131.084961) (xy 242.795359 -131.062115) (xy 242.847861 -131.046619)
			(xy 242.902039 -131.03879) (xy 242.956781 -131.03879) (xy 243.010959 -131.046619) (xy 243.063461 -131.062115)
			(xy 243.113207 -131.084961) (xy 243.159175 -131.114685) (xy 243.180108 -131.132326) (xy 243.180362 -131.13258)
			(xy 243.187448 -131.138166) (xy 243.204366 -131.144411) (xy 243.213382 -131.144772) (xy 243.280438 -131.144772)
			(xy 243.289457 -131.144439) (xy 243.306375 -131.138175) (xy 243.313458 -131.13258) (xy 243.313458 -131.132326)
			(xy 243.313712 -131.132326) (xy 243.33467 -131.114719) (xy 243.380635 -131.085001) (xy 243.430376 -131.062159)
			(xy 243.482871 -131.04666) (xy 243.537043 -131.038824) (xy 243.56441 -131.038346) (xy 243.591657 -131.038925)
			(xy 243.645598 -131.046682) (xy 243.697885 -131.062036) (xy 243.747455 -131.084675) (xy 243.793298 -131.114138)
			(xy 243.834482 -131.149825) (xy 243.870168 -131.19101) (xy 243.89963 -131.236854) (xy 243.922268 -131.286425)
			(xy 243.937621 -131.338712) (xy 243.945376 -131.392653) (xy 243.945376 -131.447147) (xy 243.937621 -131.501088)
			(xy 243.922268 -131.553375) (xy 243.89963 -131.602946) (xy 243.870168 -131.64879) (xy 243.834482 -131.689975)
			(xy 243.793298 -131.725662) (xy 243.747455 -131.755125) (xy 243.697885 -131.777764) (xy 243.645598 -131.793118)
			(xy 243.591657 -131.800875) (xy 243.56441 -131.801362) (xy 243.53704 -131.800899) (xy 243.48286 -131.793082)
			(xy 243.430356 -131.777593) (xy 243.38061 -131.75475) (xy 243.334643 -131.725024) (xy 243.313712 -131.707382)
			(xy 243.313458 -131.707128) (xy 243.306365 -131.701551) (xy 243.289453 -131.695301) (xy 243.280438 -131.694936)
			(xy 243.213382 -131.694936) (xy 243.204363 -131.695276) (xy 243.187446 -131.701535) (xy 243.180362 -131.707128)
			(xy 243.180108 -131.707382) (xy 243.159175 -131.725023) (xy 243.113207 -131.754747) (xy 243.063461 -131.777593)
			(xy 243.010959 -131.793089) (xy 242.956781 -131.800918) (xy 242.902039 -131.800918) (xy 242.847861 -131.793089)
			(xy 242.795359 -131.777593) (xy 242.745613 -131.754747) (xy 242.699645 -131.725023) (xy 242.678712 -131.707382)
			(xy 242.678458 -131.707128) (xy 242.671365 -131.701551) (xy 242.654453 -131.695301) (xy 242.645438 -131.694936)
			(xy 242.578382 -131.694936) (xy 242.569363 -131.695276) (xy 242.552446 -131.701535) (xy 242.545362 -131.707128)
			(xy 242.545362 -131.707382) (xy 242.545108 -131.707382) (xy 242.524181 -131.725028) (xy 242.478207 -131.754739)
			(xy 242.428459 -131.777574) (xy 242.375957 -131.793064) (xy 242.32178 -131.800889) (xy 242.29441 -131.801362)
			(xy 242.267153 -131.800992) (xy 242.213195 -131.793235) (xy 242.160889 -131.777878) (xy 242.111302 -131.755233)
			(xy 242.065442 -131.725762) (xy 242.024243 -131.690064) (xy 241.988544 -131.648866) (xy 241.959072 -131.603007)
			(xy 241.936426 -131.55342) (xy 241.921067 -131.501115) (xy 241.913309 -131.447157) (xy 236.018324 -131.447157)
			(xy 236.018324 -133.816344) (xy 237.527844 -133.816344) (xy 237.531915 -133.760722) (xy 237.544041 -133.706285)
			(xy 237.563964 -133.654194) (xy 237.59126 -133.605559) (xy 237.625346 -133.561416) (xy 237.665495 -133.522707)
			(xy 237.710853 -133.490256) (xy 237.760453 -133.464755) (xy 237.813237 -133.446748) (xy 237.86808 -133.436618)
			(xy 237.923814 -133.434581) (xy 237.979251 -133.440681) (xy 237.990898 -133.443726) (xy 243.322856 -133.443726)
			(xy 243.323323 -133.417412) (xy 243.330555 -133.365283) (xy 243.344873 -133.314639) (xy 243.366006 -133.26644)
			(xy 243.393553 -133.221596) (xy 243.426993 -133.180958) (xy 243.446046 -133.162802) (xy 243.453441 -133.155274)
			(xy 243.461971 -133.135999) (xy 243.462556 -133.125464) (xy 243.462556 -133.050788) (xy 243.46206 -133.040234)
			(xy 243.453503 -133.020938) (xy 243.446046 -133.01345) (xy 243.426963 -132.995322) (xy 243.39351 -132.954685)
			(xy 243.365956 -132.909839) (xy 243.344823 -132.861633) (xy 243.330511 -132.810981) (xy 243.323292 -132.758844)
			(xy 243.322856 -132.732526) (xy 243.323342 -132.705275) (xy 243.331098 -132.651327) (xy 243.346453 -132.599032)
			(xy 243.369095 -132.549455) (xy 243.398561 -132.503605) (xy 243.434252 -132.462414) (xy 243.475443 -132.426723)
			(xy 243.521293 -132.397257) (xy 243.57087 -132.374615) (xy 243.623165 -132.35926) (xy 243.677113 -132.351504)
			(xy 243.731615 -132.351504) (xy 243.785563 -132.35926) (xy 243.837858 -132.374615) (xy 243.887435 -132.397257)
			(xy 243.933285 -132.426723) (xy 243.974476 -132.462414) (xy 244.010167 -132.503605) (xy 244.039633 -132.549455)
			(xy 244.062275 -132.599032) (xy 244.07763 -132.651327) (xy 244.085386 -132.705275) (xy 244.085872 -132.732526)
			(xy 244.085431 -132.758841) (xy 244.078192 -132.810971) (xy 244.063868 -132.861615) (xy 244.042731 -132.909814)
			(xy 244.01518 -132.954656) (xy 243.981736 -132.995295) (xy 243.962682 -133.01345) (xy 243.955254 -133.020949)
			(xy 243.946745 -133.040246) (xy 243.946172 -133.050788) (xy 243.946172 -133.125464) (xy 243.946716 -133.136012)
			(xy 243.955242 -133.155307) (xy 243.962682 -133.162802) (xy 243.981728 -133.180967) (xy 244.015187 -133.221594)
			(xy 244.042747 -133.266433) (xy 244.063888 -133.314631) (xy 244.078207 -133.365277) (xy 244.085433 -133.41741)
			(xy 244.085872 -133.443726) (xy 244.085386 -133.470977) (xy 244.07763 -133.524925) (xy 244.062275 -133.57722)
			(xy 244.039633 -133.626797) (xy 244.010167 -133.672647) (xy 243.974476 -133.713838) (xy 243.933285 -133.749529)
			(xy 243.887435 -133.778995) (xy 243.837858 -133.801637) (xy 243.785563 -133.816992) (xy 243.731615 -133.824748)
			(xy 243.677113 -133.824748) (xy 243.623165 -133.816992) (xy 243.57087 -133.801637) (xy 243.521293 -133.778995)
			(xy 243.475443 -133.749529) (xy 243.434252 -133.713838) (xy 243.398561 -133.672647) (xy 243.369095 -133.626797)
			(xy 243.346453 -133.57722) (xy 243.331098 -133.524925) (xy 243.323342 -133.470977) (xy 243.322856 -133.443726)
			(xy 237.990898 -133.443726) (xy 238.033208 -133.454787) (xy 238.084537 -133.476599) (xy 238.132143 -133.505653)
			(xy 238.175011 -133.541328) (xy 238.212228 -133.582865) (xy 238.243001 -133.629378) (xy 238.266673 -133.679875)
			(xy 238.282741 -133.733282) (xy 238.290861 -133.788458) (xy 238.29137 -133.816344) (xy 238.290861 -133.84423)
			(xy 238.282741 -133.899406) (xy 238.266673 -133.952813) (xy 238.243001 -134.00331) (xy 238.212228 -134.049823)
			(xy 238.175011 -134.09136) (xy 238.132143 -134.127035) (xy 238.084537 -134.156089) (xy 238.033208 -134.177901)
			(xy 237.979251 -134.192007) (xy 237.923814 -134.198107) (xy 237.86808 -134.19607) (xy 237.813237 -134.18594)
			(xy 237.760453 -134.167933) (xy 237.710853 -134.142432) (xy 237.665495 -134.109981) (xy 237.625346 -134.071272)
			(xy 237.59126 -134.027129) (xy 237.563964 -133.978494) (xy 237.544041 -133.926403) (xy 237.531915 -133.871966)
			(xy 237.527844 -133.816344) (xy 236.018324 -133.816344) (xy 236.018324 -141.640814) (xy 236.25124 -141.640814)
			(xy 236.255311 -141.585192) (xy 236.267437 -141.530755) (xy 236.28736 -141.478664) (xy 236.314656 -141.430029)
			(xy 236.348742 -141.385886) (xy 236.388891 -141.347177) (xy 236.434249 -141.314726) (xy 236.483849 -141.289225)
			(xy 236.536633 -141.271218) (xy 236.591476 -141.261088) (xy 236.64721 -141.259051) (xy 236.702647 -141.265151)
			(xy 236.756604 -141.279257) (xy 236.807933 -141.301069) (xy 236.855539 -141.330123) (xy 236.898407 -141.365798)
			(xy 236.935624 -141.407335) (xy 236.966397 -141.453848) (xy 236.990069 -141.504345) (xy 237.006137 -141.557752)
			(xy 237.014257 -141.612928) (xy 237.014766 -141.640814) (xy 237.014257 -141.6687) (xy 237.006137 -141.723876)
			(xy 236.990069 -141.777283) (xy 236.966397 -141.82778) (xy 236.935624 -141.874293) (xy 236.898407 -141.91583)
			(xy 236.855539 -141.951505) (xy 236.807933 -141.980559) (xy 236.756604 -142.002371) (xy 236.702647 -142.016477)
			(xy 236.64721 -142.022577) (xy 236.591476 -142.02054) (xy 236.536633 -142.01041) (xy 236.483849 -141.992403)
			(xy 236.434249 -141.966902) (xy 236.388891 -141.934451) (xy 236.348742 -141.895742) (xy 236.314656 -141.851599)
			(xy 236.28736 -141.802964) (xy 236.267437 -141.750873) (xy 236.255311 -141.696436) (xy 236.25124 -141.640814)
			(xy 236.018324 -141.640814) (xy 236.018324 -144.672812) (xy 236.25124 -144.672812) (xy 236.255311 -144.61719)
			(xy 236.267437 -144.562753) (xy 236.28736 -144.510662) (xy 236.314656 -144.462027) (xy 236.348742 -144.417884)
			(xy 236.388891 -144.379175) (xy 236.434249 -144.346724) (xy 236.483849 -144.321223) (xy 236.536633 -144.303216)
			(xy 236.591476 -144.293086) (xy 236.64721 -144.291049) (xy 236.702647 -144.297149) (xy 236.756604 -144.311255)
			(xy 236.807933 -144.333067) (xy 236.855539 -144.362121) (xy 236.898407 -144.397796) (xy 236.935624 -144.439333)
			(xy 236.966397 -144.485846) (xy 236.990069 -144.536343) (xy 237.006137 -144.58975) (xy 237.014257 -144.644926)
			(xy 237.014766 -144.672812) (xy 237.014257 -144.700698) (xy 237.006137 -144.755874) (xy 236.990069 -144.809281)
			(xy 236.966397 -144.859778) (xy 236.935624 -144.906291) (xy 236.898407 -144.947828) (xy 236.855539 -144.983503)
			(xy 236.807933 -145.012557) (xy 236.756604 -145.034369) (xy 236.702647 -145.048475) (xy 236.64721 -145.054575)
			(xy 236.591476 -145.052538) (xy 236.536633 -145.042408) (xy 236.483849 -145.024401) (xy 236.434249 -144.9989)
			(xy 236.388891 -144.966449) (xy 236.348742 -144.92774) (xy 236.314656 -144.883597) (xy 236.28736 -144.834962)
			(xy 236.267437 -144.782871) (xy 236.255311 -144.728434) (xy 236.25124 -144.672812) (xy 236.018324 -144.672812)
			(xy 236.018324 -145.688812) (xy 236.25124 -145.688812) (xy 236.255311 -145.63319) (xy 236.267437 -145.578753)
			(xy 236.28736 -145.526662) (xy 236.314656 -145.478027) (xy 236.348742 -145.433884) (xy 236.388891 -145.395175)
			(xy 236.434249 -145.362724) (xy 236.483849 -145.337223) (xy 236.536633 -145.319216) (xy 236.591476 -145.309086)
			(xy 236.64721 -145.307049) (xy 236.702647 -145.313149) (xy 236.756604 -145.327255) (xy 236.807933 -145.349067)
			(xy 236.855539 -145.378121) (xy 236.898407 -145.413796) (xy 236.935624 -145.455333) (xy 236.966397 -145.501846)
			(xy 236.990069 -145.552343) (xy 237.006137 -145.60575) (xy 237.014257 -145.660926) (xy 237.014766 -145.688812)
			(xy 237.014257 -145.716698) (xy 237.006137 -145.771874) (xy 236.990069 -145.825281) (xy 236.966397 -145.875778)
			(xy 236.935624 -145.922291) (xy 236.898407 -145.963828) (xy 236.855539 -145.999503) (xy 236.807933 -146.028557)
			(xy 236.756604 -146.050369) (xy 236.702647 -146.064475) (xy 236.64721 -146.070575) (xy 236.591476 -146.068538)
			(xy 236.536633 -146.058408) (xy 236.483849 -146.040401) (xy 236.434249 -146.0149) (xy 236.388891 -145.982449)
			(xy 236.348742 -145.94374) (xy 236.314656 -145.899597) (xy 236.28736 -145.850962) (xy 236.267437 -145.798871)
			(xy 236.255311 -145.744434) (xy 236.25124 -145.688812) (xy 236.018324 -145.688812) (xy 236.018324 -146.704812)
			(xy 236.25124 -146.704812) (xy 236.255311 -146.64919) (xy 236.267437 -146.594753) (xy 236.28736 -146.542662)
			(xy 236.314656 -146.494027) (xy 236.348742 -146.449884) (xy 236.388891 -146.411175) (xy 236.434249 -146.378724)
			(xy 236.483849 -146.353223) (xy 236.536633 -146.335216) (xy 236.591476 -146.325086) (xy 236.64721 -146.323049)
			(xy 236.702647 -146.329149) (xy 236.756604 -146.343255) (xy 236.807933 -146.365067) (xy 236.855539 -146.394121)
			(xy 236.898407 -146.429796) (xy 236.935624 -146.471333) (xy 236.966397 -146.517846) (xy 236.990069 -146.568343)
			(xy 237.006137 -146.62175) (xy 237.014257 -146.676926) (xy 237.014766 -146.704812) (xy 237.014257 -146.732698)
			(xy 237.006137 -146.787874) (xy 236.990069 -146.841281) (xy 236.966397 -146.891778) (xy 236.935624 -146.938291)
			(xy 236.898407 -146.979828) (xy 236.855539 -147.015503) (xy 236.807933 -147.044557) (xy 236.756604 -147.066369)
			(xy 236.702647 -147.080475) (xy 236.64721 -147.086575) (xy 236.591476 -147.084538) (xy 236.536633 -147.074408)
			(xy 236.483849 -147.056401) (xy 236.434249 -147.0309) (xy 236.388891 -146.998449) (xy 236.348742 -146.95974)
			(xy 236.314656 -146.915597) (xy 236.28736 -146.866962) (xy 236.267437 -146.814871) (xy 236.255311 -146.760434)
			(xy 236.25124 -146.704812) (xy 236.018324 -146.704812) (xy 236.018324 -147.720812) (xy 236.25124 -147.720812)
			(xy 236.255311 -147.66519) (xy 236.267437 -147.610753) (xy 236.28736 -147.558662) (xy 236.314656 -147.510027)
			(xy 236.348742 -147.465884) (xy 236.388891 -147.427175) (xy 236.434249 -147.394724) (xy 236.483849 -147.369223)
			(xy 236.536633 -147.351216) (xy 236.591476 -147.341086) (xy 236.64721 -147.339049) (xy 236.702647 -147.345149)
			(xy 236.756604 -147.359255) (xy 236.807933 -147.381067) (xy 236.855539 -147.410121) (xy 236.898407 -147.445796)
			(xy 236.935624 -147.487333) (xy 236.966397 -147.533846) (xy 236.990069 -147.584343) (xy 237.006137 -147.63775)
			(xy 237.014257 -147.692926) (xy 237.014766 -147.720812) (xy 237.014257 -147.748698) (xy 237.006137 -147.803874)
			(xy 236.990069 -147.857281) (xy 236.966397 -147.907778) (xy 236.935624 -147.954291) (xy 236.898407 -147.995828)
			(xy 236.855539 -148.031503) (xy 236.807933 -148.060557) (xy 236.756604 -148.082369) (xy 236.702647 -148.096475)
			(xy 236.64721 -148.102575) (xy 236.591476 -148.100538) (xy 236.536633 -148.090408) (xy 236.483849 -148.072401)
			(xy 236.434249 -148.0469) (xy 236.388891 -148.014449) (xy 236.348742 -147.97574) (xy 236.314656 -147.931597)
			(xy 236.28736 -147.882962) (xy 236.267437 -147.830871) (xy 236.255311 -147.776434) (xy 236.25124 -147.720812)
			(xy 236.018324 -147.720812) (xy 236.018324 -160.415478) (xy 236.018495 -160.421487) (xy 236.021325 -160.433165)
			(xy 236.023912 -160.438592) (xy 236.02575 -160.442067) (xy 236.030342 -160.448448) (xy 236.033056 -160.451292)
			(xy 236.212126 -160.630362) (xy 236.217808 -160.635549) (xy 236.231515 -160.642518) (xy 236.23905 -160.644078)
			(xy 236.239558 -160.644078) (xy 236.247686 -160.64484) (xy 236.94009 -160.64484) (xy 236.94771 -160.644078)
			(xy 238.755682 -158.836106) (xy 238.756122 -158.832563) (xy 238.756121 -158.825425) (xy 238.755682 -158.821882)
			(xy 237.662974 -157.729174) (xy 237.644861 -157.710393) (xy 237.614177 -157.668196) (xy 237.590477 -157.621715)
			(xy 237.574345 -157.572097) (xy 237.566181 -157.520565) (xy 237.565692 -157.494478) (xy 237.565692 -152.390094)
			(xy 237.565347 -152.381108) (xy 237.559137 -152.364245) (xy 237.547457 -152.350588) (xy 237.539784 -152.345898)
			(xy 237.450122 -152.29586) (xy 237.422436 -152.296368) (xy 237.410752 -152.303734) (xy 237.383519 -152.319911)
			(xy 237.325549 -152.345439) (xy 237.264618 -152.362747) (xy 237.201885 -152.371506) (xy 237.170214 -152.37206)
			(xy 237.140228 -152.371592) (xy 237.080768 -152.363765) (xy 237.022839 -152.348245) (xy 236.967431 -152.325296)
			(xy 236.915493 -152.29531) (xy 236.867913 -152.258802) (xy 236.825506 -152.216396) (xy 236.788996 -152.168817)
			(xy 236.75901 -152.11688) (xy 236.736059 -152.061472) (xy 236.720537 -152.003544) (xy 236.712709 -151.944084)
			(xy 236.712252 -151.914098) (xy 236.712252 -151.050498) (xy 236.712721 -151.020513) (xy 236.720549 -150.961055)
			(xy 236.736071 -150.903128) (xy 236.759022 -150.847723) (xy 236.789008 -150.795788) (xy 236.825516 -150.74821)
			(xy 236.867922 -150.705806) (xy 236.915501 -150.669299) (xy 236.967438 -150.639315) (xy 237.022844 -150.616366)
			(xy 237.080771 -150.600846) (xy 237.140229 -150.59302) (xy 237.170214 -150.592536) (xy 237.201887 -150.593069)
			(xy 237.264628 -150.601803) (xy 237.325562 -150.619115) (xy 237.383522 -150.644675) (xy 237.410752 -150.660862)
			(xy 237.422436 -150.668228) (xy 237.450122 -150.668736) (xy 237.539784 -150.618698) (xy 237.547429 -150.613979)
			(xy 237.559073 -150.600313) (xy 237.56531 -150.583478) (xy 237.565692 -150.574502) (xy 237.565692 -150.1648)
			(xy 237.565329 -150.155752) (xy 237.55905 -150.138781) (xy 237.547273 -150.125043) (xy 237.53953 -150.12035)
			(xy 237.461552 -150.077424) (xy 237.453443 -150.073411) (xy 237.435555 -150.070775) (xy 237.417858 -150.074478)
			(xy 237.40999 -150.078948) (xy 237.382566 -150.095557) (xy 237.324054 -150.121768) (xy 237.262451 -150.139538)
			(xy 237.198969 -150.14852) (xy 237.166912 -150.149052) (xy 237.16615 -150.149052) (xy 237.136179 -150.148559)
			(xy 237.076749 -150.140732) (xy 237.018849 -150.125218) (xy 236.963468 -150.102281) (xy 236.911553 -150.072315)
			(xy 236.863991 -150.035832) (xy 236.821596 -149.993455) (xy 236.785093 -149.945909) (xy 236.755105 -149.894006)
			(xy 236.732145 -149.838635) (xy 236.716606 -149.780741) (xy 236.708753 -149.721315) (xy 236.708188 -149.691344)
			(xy 236.708188 -148.827744) (xy 236.708655 -148.797762) (xy 236.716479 -148.738312) (xy 236.731999 -148.680392)
			(xy 236.75495 -148.624995) (xy 236.784938 -148.573069) (xy 236.821449 -148.525504) (xy 236.863859 -148.483113)
			(xy 236.911441 -148.446623) (xy 236.96338 -148.416659) (xy 237.018788 -148.393733) (xy 237.076714 -148.378239)
			(xy 237.136168 -148.370442) (xy 237.16615 -148.370036) (xy 237.198299 -148.370566) (xy 237.26197 -148.379523)
			(xy 237.323767 -148.397283) (xy 237.382478 -148.423498) (xy 237.40999 -148.44014) (xy 237.417832 -148.444692)
			(xy 237.435554 -148.448458) (xy 237.453473 -148.445775) (xy 237.461552 -148.441664) (xy 237.53953 -148.398738)
			(xy 237.547267 -148.394032) (xy 237.559059 -148.380306) (xy 237.565344 -148.363336) (xy 237.565692 -148.354288)
			(xy 237.565692 -139.241276) (xy 237.56618 -139.215189) (xy 237.574349 -139.163659) (xy 237.590482 -139.114042)
			(xy 237.614181 -139.067561) (xy 237.644863 -139.025362) (xy 237.662974 -139.00658) (xy 238.383318 -138.28649)
			(xy 238.385604 -138.276584) (xy 238.38662 -138.272266) (xy 238.389161 -138.261898) (xy 238.395258 -138.241438)
			(xy 238.398812 -138.231372) (xy 238.409089 -138.204363) (xy 238.43661 -138.153551) (xy 238.471468 -138.107462)
			(xy 238.512868 -138.067147) (xy 238.559866 -138.033524) (xy 238.611391 -138.007362) (xy 238.666268 -137.989255)
			(xy 238.723245 -137.979618) (xy 238.752126 -137.978642) (xy 238.764826 -137.978896) (xy 238.786713 -137.979566)
			(xy 238.830128 -137.985295) (xy 238.85144 -137.990326) (xy 238.855504 -137.991342) (xy 238.864394 -137.992104)
			(xy 238.870703 -137.992449) (xy 238.883166 -137.990389) (xy 238.889032 -137.98804) (xy 238.8997 -137.98169)
			(xy 238.939832 -137.950956) (xy 238.943896 -137.947654) (xy 238.963708 -137.932414) (xy 238.971582 -137.924286)
			(xy 238.972344 -137.92327) (xy 238.972344 -134.807706) (xy 238.97209 -134.802626) (xy 238.970919 -134.794196)
			(xy 238.963784 -134.778753) (xy 238.95812 -134.7724) (xy 238.680244 -134.494778) (xy 238.543846 -134.35838)
			(xy 238.542068 -134.35711) (xy 238.539528 -134.355332) (xy 238.518289 -134.339961) (xy 238.479829 -134.304334)
			(xy 238.446605 -134.263778) (xy 238.419243 -134.219058) (xy 238.398258 -134.171014) (xy 238.384045 -134.120551)
			(xy 238.37687 -134.068617) (xy 238.37646 -134.042404) (xy 238.376945 -134.015152) (xy 238.384701 -133.961202)
			(xy 238.400056 -133.908905) (xy 238.422696 -133.859325) (xy 238.452162 -133.813472) (xy 238.487853 -133.772279)
			(xy 238.529043 -133.736584) (xy 238.574893 -133.707114) (xy 238.624471 -133.684468) (xy 238.676767 -133.669109)
			(xy 238.730716 -133.661348) (xy 238.757968 -133.660896) (xy 238.785683 -133.66139) (xy 238.84053 -133.669404)
			(xy 238.893641 -133.68527) (xy 238.943897 -133.708653) (xy 238.990241 -133.739061) (xy 239.031699 -133.775854)
			(xy 239.067397 -133.818257) (xy 239.096585 -133.86538) (xy 239.118648 -133.916229) (xy 239.133122 -133.969736)
			(xy 239.136936 -133.997192) (xy 239.137952 -134.005828) (xy 239.145318 -134.021068) (xy 239.538764 -134.414514)
			(xy 239.556795 -134.433285) (xy 239.587372 -134.475402) (xy 239.610995 -134.521779) (xy 239.627085 -134.571276)
			(xy 239.635245 -134.622679) (xy 239.635792 -134.648702) (xy 239.635792 -135.142051) (xy 241.56187 -135.142051)
			(xy 241.56187 -135.087549) (xy 241.569626 -135.033603) (xy 241.58498 -134.981309) (xy 241.60762 -134.931732)
			(xy 241.637084 -134.885882) (xy 241.672774 -134.844692) (xy 241.713962 -134.809) (xy 241.75981 -134.779532)
			(xy 241.809385 -134.756889) (xy 241.861677 -134.741531) (xy 241.915623 -134.733772) (xy 241.942874 -134.733284)
			(xy 241.971792 -134.733789) (xy 242.028965 -134.742516) (xy 242.084166 -134.759775) (xy 242.136128 -134.785169)
			(xy 242.183661 -134.818116) (xy 242.225676 -134.857862) (xy 242.243864 -134.88035) (xy 242.251656 -134.889338)
			(xy 242.273122 -134.899526) (xy 242.285012 -134.899908) (xy 242.378484 -134.897876) (xy 242.39982 -134.8867)
			(xy 242.406678 -134.876794) (xy 242.422076 -134.855884) (xy 242.457654 -134.818057) (xy 242.498033 -134.785405)
			(xy 242.542468 -134.75853) (xy 242.590136 -134.73793) (xy 242.640158 -134.723985) (xy 242.691609 -134.716952)
			(xy 242.717574 -134.71652) (xy 242.744944 -134.716996) (xy 242.799123 -134.724811) (xy 242.851626 -134.740297)
			(xy 242.901373 -134.763137) (xy 242.94734 -134.79286) (xy 242.968272 -134.8105) (xy 242.968526 -134.810754)
			(xy 242.975625 -134.816322) (xy 242.992532 -134.822579) (xy 243.001546 -134.822946) (xy 243.068602 -134.822946)
			(xy 243.07762 -134.822601) (xy 243.094538 -134.816346) (xy 243.101622 -134.810754) (xy 243.101622 -134.8105)
			(xy 243.101876 -134.8105) (xy 243.122809 -134.792859) (xy 243.168777 -134.763135) (xy 243.218523 -134.740289)
			(xy 243.271025 -134.724793) (xy 243.325203 -134.716964) (xy 243.379945 -134.716964) (xy 243.434123 -134.724793)
			(xy 243.486625 -134.740289) (xy 243.536371 -134.763135) (xy 243.582339 -134.792859) (xy 243.603272 -134.8105)
			(xy 243.603526 -134.810754) (xy 243.610625 -134.816322) (xy 243.627532 -134.822579) (xy 243.636546 -134.822946)
			(xy 243.703602 -134.822946) (xy 243.71262 -134.822601) (xy 243.729538 -134.816346) (xy 243.736622 -134.810754)
			(xy 243.73713 -134.8105) (xy 243.749868 -134.79956) (xy 243.776957 -134.779716) (xy 243.791232 -134.770876)
			(xy 243.800122 -134.765542) (xy 243.812314 -134.748524) (xy 243.832634 -134.655306) (xy 243.828316 -134.634732)
			(xy 243.822474 -134.626096) (xy 243.806467 -134.602037) (xy 243.781127 -134.550103) (xy 243.763903 -134.494944)
			(xy 243.75519 -134.437819) (xy 243.754656 -134.408926) (xy 243.755142 -134.381675) (xy 243.762898 -134.327727)
			(xy 243.778253 -134.275432) (xy 243.800895 -134.225855) (xy 243.830361 -134.180005) (xy 243.866052 -134.138814)
			(xy 243.907243 -134.103123) (xy 243.953093 -134.073657) (xy 244.00267 -134.051015) (xy 244.054965 -134.03566)
			(xy 244.108913 -134.027904) (xy 244.163415 -134.027904) (xy 244.217363 -134.03566) (xy 244.269658 -134.051015)
			(xy 244.319235 -134.073657) (xy 244.365085 -134.103123) (xy 244.406276 -134.138814) (xy 244.441967 -134.180005)
			(xy 244.471433 -134.225855) (xy 244.494075 -134.275432) (xy 244.50943 -134.327727) (xy 244.517186 -134.381675)
			(xy 244.517672 -134.408926) (xy 244.51722 -134.437019) (xy 244.508988 -134.492599) (xy 244.492691 -134.546371)
			(xy 244.468682 -134.597169) (xy 244.43748 -134.643895) (xy 244.399761 -134.685539) (xy 244.35634 -134.721198)
			(xy 244.332506 -134.736078) (xy 244.323616 -134.741412) (xy 244.311424 -134.75843) (xy 244.291104 -134.851648)
			(xy 244.295422 -134.872222) (xy 244.301264 -134.880858) (xy 244.317244 -134.904934) (xy 244.342592 -134.956861)
			(xy 244.359824 -135.012015) (xy 244.368545 -135.069136) (xy 244.369082 -135.098028) (xy 244.368648 -135.125281)
			(xy 244.360887 -135.179232) (xy 244.345527 -135.231529) (xy 244.322881 -135.281108) (xy 244.293409 -135.32696)
			(xy 244.257712 -135.368151) (xy 244.216517 -135.403842) (xy 244.170661 -135.433307) (xy 244.121079 -135.455946)
			(xy 244.068779 -135.471299) (xy 244.014827 -135.479052) (xy 243.987574 -135.479536) (xy 243.960202 -135.479101)
			(xy 243.906021 -135.471278) (xy 243.853517 -135.455782) (xy 243.803771 -135.432933) (xy 243.757806 -135.403201)
			(xy 243.736876 -135.385556) (xy 243.736622 -135.385302) (xy 243.729533 -135.379719) (xy 243.712618 -135.37347)
			(xy 243.703602 -135.37311) (xy 243.636546 -135.37311) (xy 243.627531 -135.373487) (xy 243.610614 -135.379721)
			(xy 243.603526 -135.385302) (xy 243.603526 -135.385556) (xy 243.603272 -135.385556) (xy 243.582339 -135.403197)
			(xy 243.536371 -135.432921) (xy 243.486625 -135.455767) (xy 243.434123 -135.471263) (xy 243.379945 -135.479092)
			(xy 243.325203 -135.479092) (xy 243.271025 -135.471263) (xy 243.218523 -135.455767) (xy 243.168777 -135.432921)
			(xy 243.122809 -135.403197) (xy 243.101876 -135.385556) (xy 243.101622 -135.385302) (xy 243.094533 -135.379719)
			(xy 243.077618 -135.37347) (xy 243.068602 -135.37311) (xy 243.001546 -135.37311) (xy 242.992531 -135.373487)
			(xy 242.975614 -135.379721) (xy 242.968526 -135.385302) (xy 242.968526 -135.385556) (xy 242.968272 -135.385556)
			(xy 242.947318 -135.403168) (xy 242.901352 -135.432885) (xy 242.85161 -135.455727) (xy 242.799114 -135.471225)
			(xy 242.744942 -135.479059) (xy 242.717574 -135.479536) (xy 242.688658 -135.478989) (xy 242.631487 -135.470269)
			(xy 242.576288 -135.453018) (xy 242.524325 -135.427632) (xy 242.476791 -135.394693) (xy 242.434774 -135.354954)
			(xy 242.416584 -135.33247) (xy 242.408767 -135.323508) (xy 242.38732 -135.313305) (xy 242.375436 -135.312912)
			(xy 242.281964 -135.314944) (xy 242.260628 -135.32612) (xy 242.25377 -135.336026) (xy 242.238348 -135.356918)
			(xy 242.202774 -135.394744) (xy 242.162398 -135.427397) (xy 242.117968 -135.454274) (xy 242.070303 -135.474877)
			(xy 242.020285 -135.488827) (xy 241.968837 -135.495865) (xy 241.942874 -135.4963) (xy 241.915623 -135.495828)
			(xy 241.861677 -135.488069) (xy 241.809385 -135.472711) (xy 241.75981 -135.450068) (xy 241.713962 -135.4206)
			(xy 241.672774 -135.384908) (xy 241.637084 -135.343718) (xy 241.60762 -135.297868) (xy 241.58498 -135.248291)
			(xy 241.569626 -135.195997) (xy 241.56187 -135.142051) (xy 239.635792 -135.142051) (xy 239.635792 -135.257032)
			(xy 239.638053 -135.259957) (xy 239.643284 -135.265181) (xy 239.646206 -135.267446) (xy 239.692434 -135.301482)
			(xy 239.692942 -135.302244) (xy 239.708182 -135.313674) (xy 239.714922 -135.318345) (xy 239.730468 -135.323535)
			(xy 239.738662 -135.323834) (xy 239.756442 -135.323834) (xy 239.763046 -135.322056) (xy 239.787938 -135.31596)
			(xy 239.800712 -135.313417) (xy 239.826515 -135.309859) (xy 239.8395 -135.308848) (xy 239.840262 -135.308848)
			(xy 239.84331 -135.308594) (xy 239.846612 -135.308594) (xy 239.84839 -135.30834) (xy 239.849406 -135.30834)
			(xy 239.858042 -135.308086) (xy 239.867948 -135.308086) (xy 239.895071 -135.308758) (xy 239.948723 -135.316831)
			(xy 240.000689 -135.332423) (xy 240.049923 -135.35522) (xy 240.09543 -135.384761) (xy 240.136294 -135.420452)
			(xy 240.171689 -135.461571) (xy 240.200902 -135.50729) (xy 240.223344 -135.556687) (xy 240.238561 -135.608764)
			(xy 240.246247 -135.662472) (xy 240.246247 -135.716728) (xy 240.238561 -135.770436) (xy 240.223344 -135.822513)
			(xy 240.203184 -135.866886) (xy 240.639852 -135.866886) (xy 240.643923 -135.811264) (xy 240.656049 -135.756827)
			(xy 240.675972 -135.704736) (xy 240.703268 -135.656101) (xy 240.737354 -135.611958) (xy 240.777503 -135.573249)
			(xy 240.822861 -135.540798) (xy 240.872461 -135.515297) (xy 240.925245 -135.49729) (xy 240.980088 -135.48716)
			(xy 241.035822 -135.485123) (xy 241.091259 -135.491223) (xy 241.145216 -135.505329) (xy 241.196545 -135.527141)
			(xy 241.244151 -135.556195) (xy 241.287019 -135.59187) (xy 241.324236 -135.633407) (xy 241.355009 -135.67992)
			(xy 241.378681 -135.730417) (xy 241.394749 -135.783824) (xy 241.402869 -135.839) (xy 241.403378 -135.866886)
			(xy 241.402869 -135.894772) (xy 241.394749 -135.949948) (xy 241.378681 -136.003355) (xy 241.355009 -136.053852)
			(xy 241.324236 -136.100365) (xy 241.287019 -136.141902) (xy 241.244151 -136.177577) (xy 241.196545 -136.206631)
			(xy 241.145216 -136.228443) (xy 241.091259 -136.242549) (xy 241.035822 -136.248649) (xy 240.980088 -136.246612)
			(xy 240.925245 -136.236482) (xy 240.872461 -136.218475) (xy 240.822861 -136.192974) (xy 240.777503 -136.160523)
			(xy 240.737354 -136.121814) (xy 240.703268 -136.077671) (xy 240.675972 -136.029036) (xy 240.656049 -135.976945)
			(xy 240.643923 -135.922508) (xy 240.639852 -135.866886) (xy 240.203184 -135.866886) (xy 240.200902 -135.87191)
			(xy 240.171689 -135.917629) (xy 240.136294 -135.958748) (xy 240.09543 -135.994439) (xy 240.049923 -136.02398)
			(xy 240.000689 -136.046777) (xy 239.948723 -136.062369) (xy 239.895072 -136.070442) (xy 239.867948 -136.071102)
			(xy 239.864392 -136.071102) (xy 239.836885 -136.070619) (xy 239.782443 -136.06271) (xy 239.755934 -136.055354)
			(xy 239.75568 -136.055354) (xy 239.749841 -136.053796) (xy 239.737776 -136.053156) (xy 239.731804 -136.054084)
			(xy 239.720882 -136.056116) (xy 239.696752 -136.07415) (xy 239.645952 -136.11225) (xy 239.643104 -136.114462)
			(xy 239.638001 -136.119559) (xy 239.635792 -136.12241) (xy 239.635792 -137.44829) (xy 240.54511 -137.44829)
			(xy 240.549181 -137.392668) (xy 240.561307 -137.338231) (xy 240.58123 -137.28614) (xy 240.608526 -137.237505)
			(xy 240.642612 -137.193362) (xy 240.682761 -137.154653) (xy 240.728119 -137.122202) (xy 240.777719 -137.096701)
			(xy 240.830503 -137.078694) (xy 240.885346 -137.068564) (xy 240.94108 -137.066527) (xy 240.996517 -137.072627)
			(xy 241.050474 -137.086733) (xy 241.101803 -137.108545) (xy 241.149409 -137.137599) (xy 241.192277 -137.173274)
			(xy 241.229494 -137.214811) (xy 241.260267 -137.261324) (xy 241.267302 -137.276332) (xy 245.24716 -137.276332)
			(xy 245.247563 -137.250016) (xy 245.254808 -137.197884) (xy 245.269139 -137.147239) (xy 245.290283 -137.09904)
			(xy 245.317842 -137.054198) (xy 245.351292 -137.013562) (xy 245.37035 -136.995408) (xy 245.377743 -136.987879)
			(xy 245.386274 -136.968605) (xy 245.38686 -136.95807) (xy 245.38686 -136.883394) (xy 245.386359 -136.872841)
			(xy 245.377805 -136.853545) (xy 245.37035 -136.846056) (xy 245.351271 -136.827925) (xy 245.317818 -136.787289)
			(xy 245.290263 -136.742443) (xy 245.269129 -136.694238) (xy 245.254816 -136.643586) (xy 245.247596 -136.591449)
			(xy 245.24716 -136.565132) (xy 245.247646 -136.537881) (xy 245.255402 -136.483933) (xy 245.270757 -136.431638)
			(xy 245.293399 -136.382061) (xy 245.322865 -136.336211) (xy 245.358556 -136.29502) (xy 245.399747 -136.259329)
			(xy 245.445597 -136.229863) (xy 245.495174 -136.207221) (xy 245.547469 -136.191866) (xy 245.601417 -136.18411)
			(xy 245.655919 -136.18411) (xy 245.709867 -136.191866) (xy 245.762162 -136.207221) (xy 245.811739 -136.229863)
			(xy 245.857589 -136.259329) (xy 245.89878 -136.29502) (xy 245.934471 -136.336211) (xy 245.963937 -136.382061)
			(xy 245.986579 -136.431638) (xy 246.001934 -136.483933) (xy 246.00969 -136.537881) (xy 246.010176 -136.565132)
			(xy 246.009738 -136.591447) (xy 246.002498 -136.643577) (xy 245.988174 -136.694221) (xy 245.967036 -136.74242)
			(xy 245.939484 -136.787262) (xy 245.90604 -136.827901) (xy 245.886986 -136.846056) (xy 245.8796 -136.85359)
			(xy 245.871067 -136.872861) (xy 245.870476 -136.883394) (xy 245.870476 -136.95807) (xy 245.871015 -136.968618)
			(xy 245.879544 -136.987913) (xy 245.886986 -136.995408) (xy 245.906036 -137.013569) (xy 245.939494 -137.054198)
			(xy 245.967054 -137.099036) (xy 245.988194 -137.147236) (xy 246.002512 -137.197883) (xy 246.009737 -137.250016)
			(xy 246.010176 -137.276332) (xy 246.00969 -137.303583) (xy 246.001934 -137.357531) (xy 245.986579 -137.409826)
			(xy 245.963937 -137.459403) (xy 245.934471 -137.505253) (xy 245.89878 -137.546444) (xy 245.857589 -137.582135)
			(xy 245.811739 -137.611601) (xy 245.762162 -137.634243) (xy 245.709867 -137.649598) (xy 245.655919 -137.657354)
			(xy 245.601417 -137.657354) (xy 245.547469 -137.649598) (xy 245.495174 -137.634243) (xy 245.445597 -137.611601)
			(xy 245.399747 -137.582135) (xy 245.358556 -137.546444) (xy 245.322865 -137.505253) (xy 245.293399 -137.459403)
			(xy 245.270757 -137.409826) (xy 245.255402 -137.357531) (xy 245.247646 -137.303583) (xy 245.24716 -137.276332)
			(xy 241.267302 -137.276332) (xy 241.283939 -137.311821) (xy 241.300007 -137.365228) (xy 241.308127 -137.420404)
			(xy 241.308636 -137.44829) (xy 241.308127 -137.476176) (xy 241.300007 -137.531352) (xy 241.283939 -137.584759)
			(xy 241.260267 -137.635256) (xy 241.229494 -137.681769) (xy 241.192277 -137.723306) (xy 241.18823 -137.726674)
			(xy 246.187722 -137.726674) (xy 246.188167 -137.699303) (xy 246.195989 -137.645123) (xy 246.211483 -137.592619)
			(xy 246.234329 -137.542873) (xy 246.264059 -137.496907) (xy 246.281702 -137.475976) (xy 246.281956 -137.475722)
			(xy 246.287546 -137.468638) (xy 246.293789 -137.451719) (xy 246.294148 -137.442702) (xy 246.294148 -137.375646)
			(xy 246.29378 -137.36663) (xy 246.287541 -137.349712) (xy 246.281956 -137.342626) (xy 246.281702 -137.342626)
			(xy 246.281702 -137.342372) (xy 246.264084 -137.321423) (xy 246.234369 -137.275455) (xy 246.211529 -137.225712)
			(xy 246.196033 -137.173215) (xy 246.188199 -137.119042) (xy 246.187722 -137.091674) (xy 246.188208 -137.064423)
			(xy 246.195964 -137.010475) (xy 246.211319 -136.95818) (xy 246.233961 -136.908603) (xy 246.263427 -136.862753)
			(xy 246.299118 -136.821562) (xy 246.340309 -136.785871) (xy 246.386159 -136.756405) (xy 246.435736 -136.733763)
			(xy 246.488031 -136.718408) (xy 246.541979 -136.710652) (xy 246.596481 -136.710652) (xy 246.650429 -136.718408)
			(xy 246.702724 -136.733763) (xy 246.752301 -136.756405) (xy 246.798151 -136.785871) (xy 246.839342 -136.821562)
			(xy 246.875033 -136.862753) (xy 246.904499 -136.908603) (xy 246.927141 -136.95818) (xy 246.942496 -137.010475)
			(xy 246.950252 -137.064423) (xy 246.950738 -137.091674) (xy 246.950272 -137.119044) (xy 246.942456 -137.173224)
			(xy 246.926968 -137.225728) (xy 246.904126 -137.275475) (xy 246.8744 -137.321441) (xy 246.856758 -137.342372)
			(xy 246.856504 -137.342626) (xy 246.850943 -137.34973) (xy 246.844681 -137.366633) (xy 246.844312 -137.375646)
			(xy 246.844312 -137.442702) (xy 246.844665 -137.451719) (xy 246.850915 -137.468636) (xy 246.856504 -137.475722)
			(xy 246.856758 -137.475722) (xy 246.856758 -137.475976) (xy 246.874393 -137.496912) (xy 246.904107 -137.542883)
			(xy 246.926944 -137.592629) (xy 246.942436 -137.645129) (xy 246.950264 -137.699305) (xy 246.950738 -137.726674)
			(xy 246.950252 -137.753925) (xy 246.942496 -137.807873) (xy 246.927141 -137.860168) (xy 246.904499 -137.909745)
			(xy 246.875033 -137.955595) (xy 246.839342 -137.996786) (xy 246.798151 -138.032477) (xy 246.752301 -138.061943)
			(xy 246.702724 -138.084585) (xy 246.650429 -138.09994) (xy 246.596481 -138.107696) (xy 246.541979 -138.107696)
			(xy 246.488031 -138.09994) (xy 246.435736 -138.084585) (xy 246.386159 -138.061943) (xy 246.340309 -138.032477)
			(xy 246.299118 -137.996786) (xy 246.263427 -137.955595) (xy 246.233961 -137.909745) (xy 246.211319 -137.860168)
			(xy 246.195964 -137.807873) (xy 246.188208 -137.753925) (xy 246.187722 -137.726674) (xy 241.18823 -137.726674)
			(xy 241.149409 -137.758981) (xy 241.101803 -137.788035) (xy 241.050474 -137.809847) (xy 240.996517 -137.823953)
			(xy 240.94108 -137.830053) (xy 240.885346 -137.828016) (xy 240.830503 -137.817886) (xy 240.777719 -137.799879)
			(xy 240.728119 -137.774378) (xy 240.682761 -137.741927) (xy 240.642612 -137.703218) (xy 240.608526 -137.659075)
			(xy 240.58123 -137.61044) (xy 240.561307 -137.558349) (xy 240.549181 -137.503912) (xy 240.54511 -137.44829)
			(xy 239.635792 -137.44829) (xy 239.635792 -138.40333) (xy 247.396254 -138.40333) (xy 247.396765 -138.375665)
			(xy 247.404761 -138.320914) (xy 247.420576 -138.267891) (xy 247.443879 -138.217707) (xy 247.474181 -138.171411)
			(xy 247.510848 -138.129973) (xy 247.553112 -138.094262) (xy 247.57634 -138.079226) (xy 247.586005 -138.072575)
			(xy 247.598456 -138.052725) (xy 247.600216 -138.041126) (xy 247.60809 -137.961116) (xy 247.608693 -137.949479)
			(xy 247.600631 -137.927644) (xy 247.592596 -137.919206) (xy 247.592342 -137.918952) (xy 247.573763 -137.900868)
			(xy 247.541183 -137.860538) (xy 247.514369 -137.816164) (xy 247.493815 -137.768566) (xy 247.479902 -137.718622)
			(xy 247.472885 -137.667253) (xy 247.472454 -137.64133) (xy 247.473006 -137.614081) (xy 247.480757 -137.560138)
			(xy 247.496107 -137.507847) (xy 247.518742 -137.458272) (xy 247.548201 -137.412424) (xy 247.583886 -137.371234)
			(xy 247.625069 -137.335542) (xy 247.670913 -137.306074) (xy 247.720483 -137.283431) (xy 247.772771 -137.268072)
			(xy 247.826713 -137.260311) (xy 247.853962 -137.259822) (xy 247.881332 -137.260305) (xy 247.93551 -137.268118)
			(xy 247.988013 -137.283603) (xy 248.037761 -137.306441) (xy 248.083728 -137.336162) (xy 248.10466 -137.353802)
			(xy 248.104914 -137.354056) (xy 248.111988 -137.359661) (xy 248.128915 -137.365895) (xy 248.137934 -137.366248)
			(xy 248.20499 -137.366248) (xy 248.214008 -137.365897) (xy 248.230925 -137.359647) (xy 248.23801 -137.354056)
			(xy 248.23801 -137.353802) (xy 248.238264 -137.353802) (xy 248.259199 -137.336167) (xy 248.305171 -137.306454)
			(xy 248.354918 -137.283617) (xy 248.407418 -137.268126) (xy 248.461593 -137.260296) (xy 248.488962 -137.259822)
			(xy 248.516215 -137.260291) (xy 248.570168 -137.268043) (xy 248.622467 -137.283396) (xy 248.672049 -137.306036)
			(xy 248.717904 -137.335503) (xy 248.759098 -137.371197) (xy 248.794792 -137.41239) (xy 248.82426 -137.458244)
			(xy 248.846901 -137.507825) (xy 248.862255 -137.560125) (xy 248.870009 -137.614077) (xy 248.87047 -137.64133)
			(xy 248.869913 -137.670246) (xy 248.861194 -137.727416) (xy 248.843944 -137.782614) (xy 248.81856 -137.834576)
			(xy 248.785623 -137.882111) (xy 248.745887 -137.924129) (xy 248.723404 -137.94232) (xy 248.714598 -137.949929)
			(xy 248.704414 -137.970828) (xy 248.703846 -137.982452) (xy 248.703846 -138.062208) (xy 248.704379 -138.073841)
			(xy 248.71457 -138.094752) (xy 248.723404 -138.10234) (xy 248.745907 -138.120507) (xy 248.785641 -138.162532)
			(xy 248.818578 -138.210072) (xy 248.843963 -138.262038) (xy 248.861215 -138.31724) (xy 248.869938 -138.374413)
			(xy 248.87047 -138.40333) (xy 248.870073 -138.430585) (xy 248.862311 -138.484541) (xy 248.850205 -138.525758)
			(xy 249.141742 -138.525758) (xy 249.142232 -138.498389) (xy 249.150042 -138.44421) (xy 249.165525 -138.391707)
			(xy 249.188362 -138.341959) (xy 249.218082 -138.295992) (xy 249.235722 -138.27506) (xy 249.235976 -138.274806)
			(xy 249.241575 -138.267728) (xy 249.247812 -138.250804) (xy 249.248168 -138.241786) (xy 249.248168 -138.17473)
			(xy 249.247803 -138.165714) (xy 249.241562 -138.148796) (xy 249.235976 -138.14171) (xy 249.235722 -138.14171)
			(xy 249.235722 -138.141456) (xy 249.21804 -138.120556) (xy 249.188318 -138.074583) (xy 249.165475 -138.024831)
			(xy 249.149982 -137.972324) (xy 249.142158 -137.918141) (xy 249.142162 -137.863396) (xy 249.149996 -137.809214)
			(xy 249.165497 -137.75671) (xy 249.188348 -137.706962) (xy 249.218079 -137.660993) (xy 249.235722 -137.64006)
			(xy 249.235976 -137.639806) (xy 249.241575 -137.632728) (xy 249.247812 -137.615804) (xy 249.248168 -137.606786)
			(xy 249.248168 -137.53973) (xy 249.247803 -137.530714) (xy 249.241562 -137.513796) (xy 249.235976 -137.50671)
			(xy 249.235722 -137.50671) (xy 249.235722 -137.506456) (xy 249.21804 -137.485556) (xy 249.188318 -137.439583)
			(xy 249.165475 -137.389831) (xy 249.149982 -137.337324) (xy 249.142158 -137.283141) (xy 249.142162 -137.228396)
			(xy 249.149996 -137.174214) (xy 249.165497 -137.12171) (xy 249.188348 -137.071962) (xy 249.218079 -137.025993)
			(xy 249.235722 -137.00506) (xy 249.235976 -137.004806) (xy 249.241575 -136.997728) (xy 249.247812 -136.980804)
			(xy 249.248168 -136.971786) (xy 249.248168 -136.90473) (xy 249.247803 -136.895714) (xy 249.241562 -136.878796)
			(xy 249.235976 -136.87171) (xy 249.235722 -136.87171) (xy 249.235722 -136.871456) (xy 249.218099 -136.850511)
			(xy 249.188384 -136.804542) (xy 249.165545 -136.754798) (xy 249.15005 -136.7023) (xy 249.142218 -136.648126)
			(xy 249.141742 -136.620758) (xy 249.142228 -136.593507) (xy 249.149984 -136.539559) (xy 249.165339 -136.487264)
			(xy 249.187981 -136.437687) (xy 249.217447 -136.391837) (xy 249.253138 -136.350646) (xy 249.294329 -136.314955)
			(xy 249.340179 -136.285489) (xy 249.389756 -136.262847) (xy 249.442051 -136.247492) (xy 249.495999 -136.239736)
			(xy 249.550501 -136.239736) (xy 249.604449 -136.247492) (xy 249.656744 -136.262847) (xy 249.706321 -136.285489)
			(xy 249.752171 -136.314955) (xy 249.793362 -136.350646) (xy 249.829053 -136.391837) (xy 249.858519 -136.437687)
			(xy 249.881161 -136.487264) (xy 249.896516 -136.539559) (xy 249.904272 -136.593507) (xy 249.904758 -136.620758)
			(xy 249.904278 -136.648128) (xy 249.896465 -136.702307) (xy 249.88098 -136.75481) (xy 249.858141 -136.804557)
			(xy 249.828418 -136.850524) (xy 249.810778 -136.871456) (xy 249.810524 -136.87171) (xy 249.804918 -136.878783)
			(xy 249.798685 -136.895711) (xy 249.798332 -136.90473) (xy 249.798332 -136.971786) (xy 249.798689 -136.980803)
			(xy 249.804936 -136.99772) (xy 249.810524 -137.004806) (xy 249.810778 -137.004806) (xy 249.810778 -137.00506)
			(xy 249.828377 -137.026026) (xy 249.858103 -137.071988) (xy 249.880951 -137.121729) (xy 249.89645 -137.174226)
			(xy 249.904283 -137.2284) (xy 249.904287 -137.283137) (xy 249.896464 -137.337312) (xy 249.880973 -137.389812)
			(xy 249.858134 -137.439556) (xy 249.828415 -137.485523) (xy 249.810778 -137.506456) (xy 249.810524 -137.50671)
			(xy 249.804918 -137.513783) (xy 249.798685 -137.530711) (xy 249.798332 -137.53973) (xy 249.798332 -137.606786)
			(xy 249.798689 -137.615803) (xy 249.804936 -137.63272) (xy 249.810524 -137.639806) (xy 249.810778 -137.639806)
			(xy 249.810778 -137.64006) (xy 249.828377 -137.661026) (xy 249.858103 -137.706988) (xy 249.880951 -137.756729)
			(xy 249.89645 -137.809226) (xy 249.904283 -137.8634) (xy 249.904287 -137.918137) (xy 249.896464 -137.972312)
			(xy 249.880973 -138.024812) (xy 249.858134 -138.074556) (xy 249.828415 -138.120523) (xy 249.810778 -138.141456)
			(xy 249.810524 -138.14171) (xy 249.804918 -138.148783) (xy 249.798685 -138.165711) (xy 249.798332 -138.17473)
			(xy 249.798332 -138.241786) (xy 249.798689 -138.250803) (xy 249.804936 -138.26772) (xy 249.810524 -138.274806)
			(xy 249.810778 -138.274806) (xy 249.810778 -138.27506) (xy 249.828408 -138.295999) (xy 249.858122 -138.34197)
			(xy 249.88096 -138.391715) (xy 249.896453 -138.444215) (xy 249.904283 -138.498389) (xy 249.904758 -138.525758)
			(xy 249.904257 -138.554374) (xy 249.895719 -138.610964) (xy 249.878815 -138.665642) (xy 249.853924 -138.717177)
			(xy 249.821605 -138.764409) (xy 249.782587 -138.806278) (xy 249.760486 -138.824462) (xy 249.760232 -138.824716)
			(xy 249.751694 -138.832326) (xy 249.741807 -138.852918) (xy 249.741182 -138.86434) (xy 249.74169 -138.94435)
			(xy 249.742292 -138.955914) (xy 249.752465 -138.976685) (xy 249.761248 -138.984228) (xy 249.77725 -138.997436)
			(xy 249.777504 -138.99769) (xy 249.784586 -139.003283) (xy 249.801506 -139.009526) (xy 249.810524 -139.009882)
			(xy 249.87758 -139.009882) (xy 249.886596 -139.00952) (xy 249.903514 -139.003276) (xy 249.9106 -138.99769)
			(xy 249.9106 -138.997436) (xy 249.910854 -138.997436) (xy 249.931787 -138.979795) (xy 249.977755 -138.950071)
			(xy 250.027501 -138.927225) (xy 250.080003 -138.911729) (xy 250.134181 -138.9039) (xy 250.188923 -138.9039)
			(xy 250.243101 -138.911729) (xy 250.295603 -138.927225) (xy 250.345349 -138.950071) (xy 250.391317 -138.979795)
			(xy 250.41225 -138.997436) (xy 250.412504 -138.99769) (xy 250.419586 -139.003283) (xy 250.436506 -139.009526)
			(xy 250.445524 -139.009882) (xy 250.51258 -139.009882) (xy 250.521596 -139.00952) (xy 250.538514 -139.003276)
			(xy 250.5456 -138.99769) (xy 250.5456 -138.997436) (xy 250.545854 -138.997436) (xy 250.566787 -138.979795)
			(xy 250.612755 -138.950071) (xy 250.662501 -138.927225) (xy 250.715003 -138.911729) (xy 250.769181 -138.9039)
			(xy 250.823923 -138.9039) (xy 250.878101 -138.911729) (xy 250.930603 -138.927225) (xy 250.980349 -138.950071)
			(xy 251.026317 -138.979795) (xy 251.04725 -138.997436) (xy 251.047504 -138.99769) (xy 251.054586 -139.003283)
			(xy 251.071506 -139.009526) (xy 251.080524 -139.009882) (xy 251.14758 -139.009882) (xy 251.156596 -139.00952)
			(xy 251.173514 -139.003276) (xy 251.1806 -138.99769) (xy 251.1806 -138.997436) (xy 251.180854 -138.997436)
			(xy 251.201797 -138.979811) (xy 251.247766 -138.950095) (xy 251.297511 -138.927256) (xy 251.350009 -138.911762)
			(xy 251.404183 -138.903931) (xy 251.431552 -138.903456) (xy 251.458805 -138.903988) (xy 251.512756 -138.911739)
			(xy 251.565054 -138.927089) (xy 251.614636 -138.949727) (xy 251.660491 -138.979191) (xy 251.701685 -139.014881)
			(xy 251.737381 -139.056071) (xy 251.76685 -139.101922) (xy 251.789494 -139.151501) (xy 251.804851 -139.203797)
			(xy 251.812609 -139.257748) (xy 251.812609 -139.312252) (xy 251.804851 -139.366203) (xy 251.789494 -139.418499)
			(xy 251.76685 -139.468078) (xy 251.737381 -139.513929) (xy 251.701685 -139.555119) (xy 251.660491 -139.590809)
			(xy 251.614636 -139.620273) (xy 251.565054 -139.642911) (xy 251.512756 -139.658261) (xy 251.458805 -139.666012)
			(xy 251.431552 -139.666472) (xy 251.404183 -139.665982) (xy 251.350004 -139.658171) (xy 251.297501 -139.642688)
			(xy 251.247754 -139.619851) (xy 251.201786 -139.590131) (xy 251.180854 -139.572492) (xy 251.1806 -139.572238)
			(xy 251.173523 -139.566638) (xy 251.156599 -139.560401) (xy 251.14758 -139.560046) (xy 251.080524 -139.560046)
			(xy 251.071507 -139.560405) (xy 251.05459 -139.56665) (xy 251.047504 -139.572238) (xy 251.04725 -139.572492)
			(xy 251.026317 -139.590133) (xy 250.980349 -139.619857) (xy 250.930603 -139.642703) (xy 250.878101 -139.658199)
			(xy 250.823923 -139.666028) (xy 250.769181 -139.666028) (xy 250.715003 -139.658199) (xy 250.662501 -139.642703)
			(xy 250.612755 -139.619857) (xy 250.566787 -139.590133) (xy 250.545854 -139.572492) (xy 250.5456 -139.572238)
			(xy 250.538523 -139.566638) (xy 250.521599 -139.560401) (xy 250.51258 -139.560046) (xy 250.445524 -139.560046)
			(xy 250.436507 -139.560405) (xy 250.41959 -139.56665) (xy 250.412504 -139.572238) (xy 250.412504 -139.572492)
			(xy 250.41225 -139.572492) (xy 250.391317 -139.590133) (xy 250.345349 -139.619857) (xy 250.295603 -139.642703)
			(xy 250.243101 -139.658199) (xy 250.188923 -139.666028) (xy 250.134181 -139.666028) (xy 250.080003 -139.658199)
			(xy 250.027501 -139.642703) (xy 249.977755 -139.619857) (xy 249.931787 -139.590133) (xy 249.910854 -139.572492)
			(xy 249.9106 -139.572238) (xy 249.903523 -139.566638) (xy 249.886599 -139.560401) (xy 249.87758 -139.560046)
			(xy 249.810524 -139.560046) (xy 249.801507 -139.560405) (xy 249.78459 -139.56665) (xy 249.777504 -139.572238)
			(xy 249.777504 -139.572492) (xy 249.77725 -139.572492) (xy 249.756309 -139.59012) (xy 249.710339 -139.619834)
			(xy 249.660593 -139.642672) (xy 249.608095 -139.658166) (xy 249.553921 -139.665997) (xy 249.526552 -139.666472)
			(xy 249.499298 -139.666067) (xy 249.445345 -139.658303) (xy 249.393047 -139.64294) (xy 249.343467 -139.62029)
			(xy 249.297615 -139.590816) (xy 249.256425 -139.555116) (xy 249.220734 -139.513917) (xy 249.191269 -139.468059)
			(xy 249.168631 -139.418474) (xy 249.153279 -139.366172) (xy 249.145527 -139.312218) (xy 249.145044 -139.284964)
			(xy 249.14556 -139.256349) (xy 249.154094 -139.199759) (xy 249.170996 -139.145081) (xy 249.195884 -139.093547)
			(xy 249.2282 -139.046313) (xy 249.267216 -139.004444) (xy 249.289316 -138.98626) (xy 249.28957 -138.986006)
			(xy 249.298099 -138.978387) (xy 249.307991 -138.957802) (xy 249.30862 -138.946382) (xy 249.308112 -138.866372)
			(xy 249.307496 -138.85481) (xy 249.297333 -138.834039) (xy 249.288554 -138.826494) (xy 249.266101 -138.808313)
			(xy 249.226429 -138.766317) (xy 249.193545 -138.718817) (xy 249.168202 -138.666901) (xy 249.150979 -138.611756)
			(xy 249.142272 -138.554644) (xy 249.141742 -138.525758) (xy 248.850205 -138.525758) (xy 248.846949 -138.536842)
			(xy 248.8243 -138.586425) (xy 248.794826 -138.63228) (xy 248.759125 -138.673473) (xy 248.717925 -138.709166)
			(xy 248.672065 -138.738633) (xy 248.622478 -138.761273) (xy 248.570174 -138.776625) (xy 248.516217 -138.784378)
			(xy 248.488962 -138.784838) (xy 248.462646 -138.784416) (xy 248.410515 -138.777174) (xy 248.359871 -138.762848)
			(xy 248.311671 -138.741707) (xy 248.266829 -138.714152) (xy 248.226192 -138.680704) (xy 248.208038 -138.661648)
			(xy 248.200498 -138.654268) (xy 248.181232 -138.64573) (xy 248.1707 -138.645138) (xy 248.096024 -138.645138)
			(xy 248.085473 -138.645655) (xy 248.066177 -138.654197) (xy 248.058686 -138.661648) (xy 248.04054 -138.680712)
			(xy 247.999907 -138.714167) (xy 247.955064 -138.741724) (xy 247.906862 -138.76286) (xy 247.856213 -138.777176)
			(xy 247.804079 -138.7844) (xy 247.777762 -138.784838) (xy 247.750511 -138.784358) (xy 247.696565 -138.776597)
			(xy 247.644272 -138.761238) (xy 247.594696 -138.738595) (xy 247.548848 -138.709127) (xy 247.507659 -138.673436)
			(xy 247.471968 -138.632246) (xy 247.442501 -138.586397) (xy 247.419859 -138.536821) (xy 247.404502 -138.484527)
			(xy 247.396742 -138.430581) (xy 247.396254 -138.40333) (xy 239.635792 -138.40333) (xy 239.635792 -138.824462)
			(xy 240.561874 -138.824462) (xy 240.565945 -138.76884) (xy 240.578071 -138.714403) (xy 240.597994 -138.662312)
			(xy 240.62529 -138.613677) (xy 240.659376 -138.569534) (xy 240.699525 -138.530825) (xy 240.744883 -138.498374)
			(xy 240.794483 -138.472873) (xy 240.847267 -138.454866) (xy 240.90211 -138.444736) (xy 240.957844 -138.442699)
			(xy 241.013281 -138.448799) (xy 241.067238 -138.462905) (xy 241.118567 -138.484717) (xy 241.166173 -138.513771)
			(xy 241.209041 -138.549446) (xy 241.246258 -138.590983) (xy 241.277031 -138.637496) (xy 241.300703 -138.687993)
			(xy 241.316771 -138.7414) (xy 241.324891 -138.796576) (xy 241.3254 -138.824462) (xy 241.324891 -138.852348)
			(xy 241.316771 -138.907524) (xy 241.300703 -138.960931) (xy 241.277031 -139.011428) (xy 241.246258 -139.057941)
			(xy 241.209041 -139.099478) (xy 241.166173 -139.135153) (xy 241.118567 -139.164207) (xy 241.067238 -139.186019)
			(xy 241.013281 -139.200125) (xy 240.957844 -139.206225) (xy 240.90211 -139.204188) (xy 240.847267 -139.194058)
			(xy 240.794483 -139.176051) (xy 240.744883 -139.15055) (xy 240.699525 -139.118099) (xy 240.659376 -139.07939)
			(xy 240.62529 -139.035247) (xy 240.597994 -138.986612) (xy 240.578071 -138.934521) (xy 240.565945 -138.880084)
			(xy 240.561874 -138.824462) (xy 239.635792 -138.824462) (xy 239.635792 -140.392404) (xy 240.567716 -140.392404)
			(xy 240.571787 -140.336782) (xy 240.583913 -140.282345) (xy 240.603836 -140.230254) (xy 240.631132 -140.181619)
			(xy 240.665218 -140.137476) (xy 240.705367 -140.098767) (xy 240.750725 -140.066316) (xy 240.800325 -140.040815)
			(xy 240.853109 -140.022808) (xy 240.907952 -140.012678) (xy 240.963686 -140.010641) (xy 241.019123 -140.016741)
			(xy 241.07308 -140.030847) (xy 241.124409 -140.052659) (xy 241.172015 -140.081713) (xy 241.214883 -140.117388)
			(xy 241.2521 -140.158925) (xy 241.282873 -140.205438) (xy 241.306545 -140.255935) (xy 241.322613 -140.309342)
			(xy 241.330733 -140.364518) (xy 241.331242 -140.392404) (xy 241.330733 -140.42029) (xy 241.322613 -140.475466)
			(xy 241.306545 -140.528873) (xy 241.282873 -140.57937) (xy 241.2521 -140.625883) (xy 241.214883 -140.66742)
			(xy 241.172015 -140.703095) (xy 241.124409 -140.732149) (xy 241.07308 -140.753961) (xy 241.019123 -140.768067)
			(xy 240.963686 -140.774167) (xy 240.907952 -140.77213) (xy 240.853109 -140.762) (xy 240.800325 -140.743993)
			(xy 240.750725 -140.718492) (xy 240.705367 -140.686041) (xy 240.665218 -140.647332) (xy 240.631132 -140.603189)
			(xy 240.603836 -140.554554) (xy 240.583913 -140.502463) (xy 240.571787 -140.448026) (xy 240.567716 -140.392404)
			(xy 239.635792 -140.392404) (xy 239.635792 -141.046551) (xy 242.955054 -141.046551) (xy 242.955054 -140.992049)
			(xy 242.96281 -140.938101) (xy 242.978164 -140.885806) (xy 243.000804 -140.836228) (xy 243.030269 -140.790376)
			(xy 243.065959 -140.749184) (xy 243.107147 -140.71349) (xy 243.152996 -140.684021) (xy 243.202572 -140.661377)
			(xy 243.254865 -140.646017) (xy 243.308813 -140.638256) (xy 243.336064 -140.637768) (xy 243.362379 -140.638203)
			(xy 243.414508 -140.645446) (xy 243.465151 -140.659772) (xy 243.51335 -140.680911) (xy 243.558193 -140.708462)
			(xy 243.598832 -140.741905) (xy 243.616988 -140.760958) (xy 243.624518 -140.76835) (xy 243.643791 -140.776881)
			(xy 243.654326 -140.777468) (xy 243.729002 -140.777468) (xy 243.739555 -140.776963) (xy 243.75885 -140.768412)
			(xy 243.76634 -140.760958) (xy 243.784475 -140.741882) (xy 243.82511 -140.708428) (xy 243.869955 -140.680873)
			(xy 243.91816 -140.659738) (xy 243.96881 -140.645425) (xy 244.020947 -140.638204) (xy 244.047264 -140.637768)
			(xy 244.074517 -140.638277) (xy 244.128468 -140.646029) (xy 244.180767 -140.661381) (xy 244.230349 -140.68402)
			(xy 244.276203 -140.713485) (xy 244.317398 -140.749177) (xy 244.353093 -140.790368) (xy 244.382563 -140.83622)
			(xy 244.405206 -140.885799) (xy 244.420563 -140.938097) (xy 244.428321 -140.992047) (xy 244.428321 -141.046553)
			(xy 244.420563 -141.100503) (xy 244.405206 -141.152801) (xy 244.382563 -141.20238) (xy 244.353093 -141.248232)
			(xy 244.317398 -141.289423) (xy 244.276203 -141.325115) (xy 244.230349 -141.35458) (xy 244.180767 -141.377219)
			(xy 244.128468 -141.392571) (xy 244.074517 -141.400323) (xy 244.047264 -141.400784) (xy 244.020949 -141.400346)
			(xy 243.968819 -141.393106) (xy 243.918176 -141.378781) (xy 243.869977 -141.357643) (xy 243.825134 -141.330092)
			(xy 243.784496 -141.296648) (xy 243.76634 -141.277594) (xy 243.758806 -141.270207) (xy 243.739535 -141.261675)
			(xy 243.729002 -141.261084) (xy 243.654326 -141.261084) (xy 243.643777 -141.261619) (xy 243.624482 -141.270151)
			(xy 243.616988 -141.277594) (xy 243.59883 -141.296647) (xy 243.558201 -141.330105) (xy 243.513361 -141.357664)
			(xy 243.465161 -141.378803) (xy 243.414514 -141.393121) (xy 243.36238 -141.400346) (xy 243.336064 -141.400784)
			(xy 243.308813 -141.400344) (xy 243.254865 -141.392583) (xy 243.202572 -141.377223) (xy 243.152996 -141.354579)
			(xy 243.107147 -141.32511) (xy 243.065959 -141.289416) (xy 243.030269 -141.248224) (xy 243.000804 -141.202372)
			(xy 242.978164 -141.152794) (xy 242.96281 -141.100499) (xy 242.955054 -141.046551) (xy 239.635792 -141.046551)
			(xy 239.635792 -143.078551) (xy 242.955054 -143.078551) (xy 242.955054 -143.024049) (xy 242.96281 -142.970101)
			(xy 242.978164 -142.917806) (xy 243.000804 -142.868228) (xy 243.030269 -142.822376) (xy 243.065959 -142.781184)
			(xy 243.107147 -142.74549) (xy 243.152996 -142.716021) (xy 243.202572 -142.693377) (xy 243.254865 -142.678017)
			(xy 243.308813 -142.670256) (xy 243.336064 -142.669768) (xy 243.362379 -142.670203) (xy 243.414508 -142.677446)
			(xy 243.465151 -142.691772) (xy 243.51335 -142.712911) (xy 243.558193 -142.740462) (xy 243.598832 -142.773905)
			(xy 243.616988 -142.792958) (xy 243.624518 -142.80035) (xy 243.643791 -142.808881) (xy 243.654326 -142.809468)
			(xy 243.729002 -142.809468) (xy 243.739555 -142.808963) (xy 243.75885 -142.800412) (xy 243.76634 -142.792958)
			(xy 243.784475 -142.773882) (xy 243.82511 -142.740428) (xy 243.869955 -142.712873) (xy 243.91816 -142.691738)
			(xy 243.96881 -142.677425) (xy 244.020947 -142.670204) (xy 244.047264 -142.669768) (xy 244.074517 -142.670277)
			(xy 244.128468 -142.678029) (xy 244.180767 -142.693381) (xy 244.230349 -142.71602) (xy 244.276203 -142.745485)
			(xy 244.317398 -142.781177) (xy 244.353093 -142.822368) (xy 244.382563 -142.86822) (xy 244.405206 -142.917799)
			(xy 244.420563 -142.970097) (xy 244.428321 -143.024047) (xy 244.428321 -143.078553) (xy 244.420563 -143.132503)
			(xy 244.405206 -143.184801) (xy 244.382563 -143.23438) (xy 244.353093 -143.280232) (xy 244.317398 -143.321423)
			(xy 244.276203 -143.357115) (xy 244.230349 -143.38658) (xy 244.180767 -143.409219) (xy 244.128468 -143.424571)
			(xy 244.074517 -143.432323) (xy 244.047264 -143.432784) (xy 244.020949 -143.432346) (xy 243.968819 -143.425106)
			(xy 243.918176 -143.410781) (xy 243.869977 -143.389643) (xy 243.825134 -143.362092) (xy 243.784496 -143.328648)
			(xy 243.76634 -143.309594) (xy 243.758806 -143.302207) (xy 243.739535 -143.293675) (xy 243.729002 -143.293084)
			(xy 243.654326 -143.293084) (xy 243.643777 -143.293619) (xy 243.624482 -143.302151) (xy 243.616988 -143.309594)
			(xy 243.59883 -143.328647) (xy 243.558201 -143.362105) (xy 243.513361 -143.389664) (xy 243.465161 -143.410803)
			(xy 243.414514 -143.425121) (xy 243.36238 -143.432346) (xy 243.336064 -143.432784) (xy 243.308813 -143.432344)
			(xy 243.254865 -143.424583) (xy 243.202572 -143.409223) (xy 243.152996 -143.386579) (xy 243.107147 -143.35711)
			(xy 243.065959 -143.321416) (xy 243.030269 -143.280224) (xy 243.000804 -143.234372) (xy 242.978164 -143.184794)
			(xy 242.96281 -143.132499) (xy 242.955054 -143.078551) (xy 239.635792 -143.078551) (xy 239.635792 -143.966438)
			(xy 251.664216 -143.966438) (xy 251.664626 -143.940462) (xy 251.671676 -143.88899) (xy 251.685652 -143.838952)
			(xy 251.706293 -143.791276) (xy 251.733218 -143.746845) (xy 251.765928 -143.706483) (xy 251.803816 -143.670936)
			(xy 251.824744 -143.655542) (xy 251.834235 -143.64791) (xy 251.84538 -143.626298) (xy 251.84608 -143.61414)
			(xy 251.84608 -143.531336) (xy 251.845388 -143.519174) (xy 251.834248 -143.497553) (xy 251.824744 -143.489934)
			(xy 251.803825 -143.474531) (xy 251.765949 -143.438978) (xy 251.733248 -143.398614) (xy 251.70633 -143.354184)
			(xy 251.685691 -143.306511) (xy 251.671714 -143.256479) (xy 251.664658 -143.205012) (xy 251.664216 -143.179038)
			(xy 251.664724 -143.150299) (xy 251.673354 -143.093472) (xy 251.690409 -143.038582) (xy 251.715503 -142.98687)
			(xy 251.748069 -142.939507) (xy 251.76734 -142.91818) (xy 251.773944 -142.911322) (xy 251.781056 -142.893288)
			(xy 251.781056 -142.804388) (xy 251.773944 -142.786354) (xy 251.76734 -142.779496) (xy 251.748106 -142.758137)
			(xy 251.715538 -142.71078) (xy 251.690444 -142.659074) (xy 251.67339 -142.604188) (xy 251.664763 -142.547365)
			(xy 251.664759 -142.489891) (xy 251.673378 -142.433066) (xy 251.690423 -142.378178) (xy 251.71551 -142.326468)
			(xy 251.748071 -142.279106) (xy 251.76734 -142.25778) (xy 251.773944 -142.250922) (xy 251.781056 -142.232888)
			(xy 251.781056 -142.143988) (xy 251.773944 -142.125954) (xy 251.76734 -142.119096) (xy 251.748106 -142.097737)
			(xy 251.715538 -142.05038) (xy 251.690444 -141.998674) (xy 251.67339 -141.943788) (xy 251.664763 -141.886965)
			(xy 251.664759 -141.829491) (xy 251.673378 -141.772666) (xy 251.690423 -141.717778) (xy 251.71551 -141.666068)
			(xy 251.748071 -141.618706) (xy 251.76734 -141.59738) (xy 251.773944 -141.590522) (xy 251.781056 -141.572488)
			(xy 251.781056 -141.483588) (xy 251.773944 -141.465554) (xy 251.76734 -141.458696) (xy 251.748106 -141.437337)
			(xy 251.715538 -141.38998) (xy 251.690444 -141.338274) (xy 251.67339 -141.283388) (xy 251.664763 -141.226565)
			(xy 251.664759 -141.169091) (xy 251.673378 -141.112266) (xy 251.690423 -141.057378) (xy 251.71551 -141.005668)
			(xy 251.748071 -140.958306) (xy 251.76734 -140.93698) (xy 251.773944 -140.930122) (xy 251.781056 -140.912088)
			(xy 251.781056 -140.823188) (xy 251.773944 -140.805154) (xy 251.76734 -140.798296) (xy 251.748088 -140.776953)
			(xy 251.715519 -140.729595) (xy 251.690423 -140.677888) (xy 251.673368 -140.623001) (xy 251.66474 -140.566176)
			(xy 251.664216 -140.537438) (xy 251.664702 -140.510187) (xy 251.672458 -140.456239) (xy 251.687813 -140.403944)
			(xy 251.710455 -140.354367) (xy 251.739921 -140.308517) (xy 251.775612 -140.267326) (xy 251.816803 -140.231635)
			(xy 251.862653 -140.202169) (xy 251.91223 -140.179527) (xy 251.964525 -140.164172) (xy 252.018473 -140.156416)
			(xy 252.072975 -140.156416) (xy 252.126923 -140.164172) (xy 252.179218 -140.179527) (xy 252.228795 -140.202169)
			(xy 252.274645 -140.231635) (xy 252.315836 -140.267326) (xy 252.351527 -140.308517) (xy 252.380993 -140.354367)
			(xy 252.403635 -140.403944) (xy 252.41899 -140.456239) (xy 252.426746 -140.510187) (xy 252.427232 -140.537438)
			(xy 252.426723 -140.566177) (xy 252.418095 -140.623005) (xy 252.401041 -140.677896) (xy 252.375947 -140.729607)
			(xy 252.34338 -140.776969) (xy 252.324108 -140.798296) (xy 252.317504 -140.805154) (xy 252.310392 -140.823188)
			(xy 252.310392 -140.912088) (xy 252.317504 -140.930122) (xy 252.324108 -140.93698) (xy 252.343415 -140.958275)
			(xy 252.375976 -141.005644) (xy 252.401064 -141.057361) (xy 252.418109 -141.112256) (xy 252.426728 -141.169087)
			(xy 252.426724 -141.226568) (xy 252.418097 -141.283398) (xy 252.401043 -141.338291) (xy 252.375948 -141.390004)
			(xy 252.34338 -141.437368) (xy 252.324108 -141.458696) (xy 252.317504 -141.465554) (xy 252.310392 -141.483588)
			(xy 252.310392 -141.572488) (xy 252.317504 -141.590522) (xy 252.324108 -141.59738) (xy 252.343415 -141.618675)
			(xy 252.375976 -141.666044) (xy 252.401064 -141.717761) (xy 252.418109 -141.772656) (xy 252.426728 -141.829487)
			(xy 252.426724 -141.886968) (xy 252.418097 -141.943798) (xy 252.401043 -141.998691) (xy 252.375948 -142.050404)
			(xy 252.34338 -142.097768) (xy 252.324108 -142.119096) (xy 252.317504 -142.125954) (xy 252.310392 -142.143988)
			(xy 252.310392 -142.232888) (xy 252.317504 -142.250922) (xy 252.324108 -142.25778) (xy 252.343415 -142.279075)
			(xy 252.375976 -142.326444) (xy 252.401064 -142.378161) (xy 252.418109 -142.433056) (xy 252.426728 -142.489887)
			(xy 252.426724 -142.547368) (xy 252.418097 -142.604198) (xy 252.401043 -142.659091) (xy 252.375948 -142.710804)
			(xy 252.34338 -142.758168) (xy 252.324108 -142.779496) (xy 252.317504 -142.786354) (xy 252.310392 -142.804388)
			(xy 252.310392 -142.893288) (xy 252.317504 -142.911322) (xy 252.324108 -142.91818) (xy 252.343387 -142.9395)
			(xy 252.375954 -142.986863) (xy 252.401046 -143.038576) (xy 252.418094 -143.093469) (xy 252.426713 -143.150298)
			(xy 252.427232 -143.179038) (xy 252.426826 -143.205015) (xy 252.419777 -143.256488) (xy 252.405803 -143.306526)
			(xy 252.385161 -143.354203) (xy 252.358235 -143.398634) (xy 252.325524 -143.438996) (xy 252.287633 -143.474541)
			(xy 252.266704 -143.489934) (xy 252.257233 -143.497587) (xy 252.246075 -143.519183) (xy 252.245368 -143.531336)
			(xy 252.245368 -143.61414) (xy 252.246056 -143.626303) (xy 252.257197 -143.647925) (xy 252.266704 -143.655542)
			(xy 252.287622 -143.670946) (xy 252.325497 -143.7065) (xy 252.358195 -143.746865) (xy 252.385113 -143.791295)
			(xy 252.405752 -143.838966) (xy 252.41973 -143.888998) (xy 252.426789 -143.940464) (xy 252.427232 -143.966438)
			(xy 252.426746 -143.993689) (xy 252.41899 -144.047637) (xy 252.403635 -144.099932) (xy 252.380993 -144.149509)
			(xy 252.351527 -144.195359) (xy 252.315836 -144.23655) (xy 252.274645 -144.272241) (xy 252.228795 -144.301707)
			(xy 252.179218 -144.324349) (xy 252.126923 -144.339704) (xy 252.072975 -144.34746) (xy 252.018473 -144.34746)
			(xy 251.964525 -144.339704) (xy 251.91223 -144.324349) (xy 251.862653 -144.301707) (xy 251.816803 -144.272241)
			(xy 251.775612 -144.23655) (xy 251.739921 -144.195359) (xy 251.710455 -144.149509) (xy 251.687813 -144.099932)
			(xy 251.672458 -144.047637) (xy 251.664702 -143.993689) (xy 251.664216 -143.966438) (xy 239.635792 -143.966438)
			(xy 239.635792 -144.868392) (xy 239.635262 -144.894415) (xy 239.62709 -144.945815) (xy 239.610992 -144.99531)
			(xy 239.587364 -145.041684) (xy 239.556785 -145.083799) (xy 239.538764 -145.10258) (xy 239.530791 -145.110551)
			(xy 242.955054 -145.110551) (xy 242.955054 -145.056049) (xy 242.96281 -145.002101) (xy 242.978164 -144.949806)
			(xy 243.000804 -144.900228) (xy 243.030269 -144.854376) (xy 243.065959 -144.813184) (xy 243.107147 -144.77749)
			(xy 243.152996 -144.748021) (xy 243.202572 -144.725377) (xy 243.254865 -144.710017) (xy 243.308813 -144.702256)
			(xy 243.336064 -144.701768) (xy 243.362379 -144.702203) (xy 243.414508 -144.709446) (xy 243.465151 -144.723772)
			(xy 243.51335 -144.744911) (xy 243.558193 -144.772462) (xy 243.598832 -144.805905) (xy 243.616988 -144.824958)
			(xy 243.624518 -144.83235) (xy 243.643791 -144.840881) (xy 243.654326 -144.841468) (xy 243.729002 -144.841468)
			(xy 243.739555 -144.840963) (xy 243.75885 -144.832412) (xy 243.76634 -144.824958) (xy 243.784475 -144.805882)
			(xy 243.82511 -144.772428) (xy 243.869955 -144.744873) (xy 243.91816 -144.723738) (xy 243.96881 -144.709425)
			(xy 244.020947 -144.702204) (xy 244.047264 -144.701768) (xy 244.074517 -144.702277) (xy 244.128468 -144.710029)
			(xy 244.180767 -144.725381) (xy 244.230349 -144.74802) (xy 244.276203 -144.777485) (xy 244.317398 -144.813177)
			(xy 244.353093 -144.854368) (xy 244.382563 -144.90022) (xy 244.405206 -144.949799) (xy 244.406511 -144.954244)
			(xy 250.138946 -144.954244) (xy 250.139519 -144.926996) (xy 250.147268 -144.873054) (xy 250.162616 -144.820764)
			(xy 250.185248 -144.77119) (xy 250.214706 -144.725341) (xy 250.250388 -144.684152) (xy 250.291569 -144.64846)
			(xy 250.337411 -144.618991) (xy 250.386979 -144.596347) (xy 250.439266 -144.580988) (xy 250.493206 -144.573225)
			(xy 250.520454 -144.572736) (xy 250.549228 -144.573258) (xy 250.606123 -144.581908) (xy 250.661074 -144.599005)
			(xy 250.712834 -144.624159) (xy 250.76023 -144.656801) (xy 250.781566 -144.676114) (xy 250.78944 -144.68348)
			(xy 250.809252 -144.690592) (xy 250.905518 -144.683226) (xy 250.924314 -144.67332) (xy 250.930918 -144.664938)
			(xy 250.949154 -144.642763) (xy 250.991086 -144.603551) (xy 251.03842 -144.571064) (xy 251.090085 -144.546034)
			(xy 251.144918 -144.529026) (xy 251.201679 -144.520423) (xy 251.230384 -144.519904) (xy 251.257637 -144.52037)
			(xy 251.311588 -144.528125) (xy 251.363887 -144.54348) (xy 251.413468 -144.566121) (xy 251.459322 -144.595589)
			(xy 251.500515 -144.631282) (xy 251.536209 -144.672475) (xy 251.565677 -144.718329) (xy 251.588319 -144.767909)
			(xy 251.603674 -144.820208) (xy 251.611429 -144.874159) (xy 251.611892 -144.901412) (xy 251.611444 -144.928315)
			(xy 251.603871 -144.981586) (xy 251.588889 -145.033265) (xy 251.566797 -145.082327) (xy 251.538032 -145.127799)
			(xy 251.503165 -145.16878) (xy 251.462887 -145.204457) (xy 251.440696 -145.219674) (xy 251.429774 -145.226786)
			(xy 251.417836 -145.249646) (xy 251.419868 -145.361914) (xy 251.432822 -145.384266) (xy 251.443998 -145.391124)
			(xy 251.467599 -145.406047) (xy 251.510551 -145.441725) (xy 251.547844 -145.483283) (xy 251.578682 -145.529833)
			(xy 251.602406 -145.58038) (xy 251.618508 -145.633846) (xy 251.626646 -145.689087) (xy 251.627132 -145.717006)
			(xy 251.626677 -145.744) (xy 251.61907 -145.797448) (xy 251.604009 -145.849292) (xy 251.581793 -145.898496)
			(xy 251.552867 -145.94408) (xy 251.535692 -145.96491) (xy 251.52858 -145.973038) (xy 251.522484 -145.993612)
			(xy 251.533406 -146.078956) (xy 251.535196 -146.089497) (xy 251.546239 -146.107781) (xy 251.554742 -146.114262)
			(xy 251.575947 -146.129649) (xy 251.614401 -146.16523) (xy 251.647622 -146.205741) (xy 251.674984 -146.250418)
			(xy 251.695972 -146.298421) (xy 251.71019 -146.348845) (xy 251.717371 -146.400741) (xy 251.71781 -146.426936)
			(xy 251.717324 -146.454187) (xy 251.709568 -146.508135) (xy 251.694213 -146.56043) (xy 251.671571 -146.610007)
			(xy 251.642105 -146.655857) (xy 251.606414 -146.697048) (xy 251.565223 -146.732739) (xy 251.519373 -146.762205)
			(xy 251.469796 -146.784847) (xy 251.417501 -146.800202) (xy 251.363553 -146.807958) (xy 251.309051 -146.807958)
			(xy 251.255103 -146.800202) (xy 251.202808 -146.784847) (xy 251.153231 -146.762205) (xy 251.107381 -146.732739)
			(xy 251.06619 -146.697048) (xy 251.030499 -146.655857) (xy 251.001033 -146.610007) (xy 250.978391 -146.56043)
			(xy 250.963036 -146.508135) (xy 250.95528 -146.454187) (xy 250.954794 -146.426936) (xy 250.955291 -146.399944)
			(xy 250.96289 -146.346498) (xy 250.977943 -146.294656) (xy 251.000149 -146.245451) (xy 251.029064 -146.199864)
			(xy 251.046234 -146.179032) (xy 251.053346 -146.170904) (xy 251.059442 -146.15033) (xy 251.04852 -146.064986)
			(xy 251.046749 -146.054441) (xy 251.035691 -146.036159) (xy 251.027184 -146.02968) (xy 251.002883 -146.012068)
			(xy 250.959624 -145.970472) (xy 250.941078 -145.946876) (xy 250.935236 -145.939002) (xy 250.91771 -145.928588)
			(xy 250.827286 -145.91538) (xy 250.807982 -145.920206) (xy 250.800108 -145.926048) (xy 250.799854 -145.926048)
			(xy 250.775111 -145.943553) (xy 250.721258 -145.971356) (xy 250.663686 -145.990292) (xy 250.603843 -145.999883)
			(xy 250.57354 -146.00047) (xy 250.546286 -146.000007) (xy 250.492333 -145.992255) (xy 250.440033 -145.976902)
			(xy 250.390451 -145.954261) (xy 250.344596 -145.924794) (xy 250.303401 -145.8891) (xy 250.267707 -145.847906)
			(xy 250.23824 -145.802051) (xy 250.215599 -145.752469) (xy 250.200246 -145.700168) (xy 250.192493 -145.646216)
			(xy 250.192032 -145.618962) (xy 250.192467 -145.592928) (xy 250.199559 -145.541345) (xy 250.213591 -145.491203)
			(xy 250.234305 -145.443433) (xy 250.261315 -145.398918) (xy 250.277376 -145.378424) (xy 250.283116 -145.370666)
			(xy 250.288858 -145.352256) (xy 250.288552 -145.34261) (xy 250.282202 -145.262854) (xy 250.273566 -145.245074)
			(xy 250.2662 -145.238724) (xy 250.246561 -145.220536) (xy 250.212035 -145.179632) (xy 250.183562 -145.134305)
			(xy 250.161703 -145.085445) (xy 250.146885 -145.034009) (xy 250.1394 -144.981008) (xy 250.138946 -144.954244)
			(xy 244.406511 -144.954244) (xy 244.420563 -145.002097) (xy 244.428321 -145.056047) (xy 244.428321 -145.110553)
			(xy 244.420563 -145.164503) (xy 244.405206 -145.216801) (xy 244.382563 -145.26638) (xy 244.353093 -145.312232)
			(xy 244.317398 -145.353423) (xy 244.276203 -145.389115) (xy 244.230349 -145.41858) (xy 244.180767 -145.441219)
			(xy 244.128468 -145.456571) (xy 244.074517 -145.464323) (xy 244.047264 -145.464784) (xy 244.020949 -145.464346)
			(xy 243.968819 -145.457106) (xy 243.918176 -145.442781) (xy 243.869977 -145.421643) (xy 243.825134 -145.394092)
			(xy 243.784496 -145.360648) (xy 243.76634 -145.341594) (xy 243.758806 -145.334207) (xy 243.739535 -145.325675)
			(xy 243.729002 -145.325084) (xy 243.654326 -145.325084) (xy 243.643777 -145.325619) (xy 243.624482 -145.334151)
			(xy 243.616988 -145.341594) (xy 243.59883 -145.360647) (xy 243.558201 -145.394105) (xy 243.513361 -145.421664)
			(xy 243.465161 -145.442803) (xy 243.414514 -145.457121) (xy 243.36238 -145.464346) (xy 243.336064 -145.464784)
			(xy 243.308813 -145.464344) (xy 243.254865 -145.456583) (xy 243.202572 -145.441223) (xy 243.152996 -145.418579)
			(xy 243.107147 -145.38911) (xy 243.065959 -145.353416) (xy 243.030269 -145.312224) (xy 243.000804 -145.266372)
			(xy 242.978164 -145.216794) (xy 242.96281 -145.164499) (xy 242.955054 -145.110551) (xy 239.530791 -145.110551)
			(xy 238.69904 -145.94205) (xy 238.693747 -145.947835) (xy 238.686633 -145.961799) (xy 238.68507 -145.969482)
			(xy 238.684308 -145.977864) (xy 238.684308 -146.91487) (xy 251.816106 -146.91487) (xy 251.820177 -146.859248)
			(xy 251.832303 -146.804811) (xy 251.852226 -146.75272) (xy 251.879522 -146.704085) (xy 251.913608 -146.659942)
			(xy 251.953757 -146.621233) (xy 251.999115 -146.588782) (xy 252.048715 -146.563281) (xy 252.101499 -146.545274)
			(xy 252.156342 -146.535144) (xy 252.212076 -146.533107) (xy 252.267513 -146.539207) (xy 252.32147 -146.553313)
			(xy 252.372799 -146.575125) (xy 252.420405 -146.604179) (xy 252.463273 -146.639854) (xy 252.50049 -146.681391)
			(xy 252.531263 -146.727904) (xy 252.554935 -146.778401) (xy 252.571003 -146.831808) (xy 252.579123 -146.886984)
			(xy 252.579632 -146.91487) (xy 252.579123 -146.942756) (xy 252.571003 -146.997932) (xy 252.554935 -147.051339)
			(xy 252.549729 -147.062444) (xy 253.19431 -147.062444) (xy 253.198381 -147.006822) (xy 253.210507 -146.952385)
			(xy 253.23043 -146.900294) (xy 253.257726 -146.851659) (xy 253.291812 -146.807516) (xy 253.331961 -146.768807)
			(xy 253.377319 -146.736356) (xy 253.426919 -146.710855) (xy 253.479703 -146.692848) (xy 253.534546 -146.682718)
			(xy 253.59028 -146.680681) (xy 253.645717 -146.686781) (xy 253.699674 -146.700887) (xy 253.751003 -146.722699)
			(xy 253.798609 -146.751753) (xy 253.841477 -146.787428) (xy 253.878694 -146.828965) (xy 253.909467 -146.875478)
			(xy 253.933139 -146.925975) (xy 253.949207 -146.979382) (xy 253.957327 -147.034558) (xy 253.957836 -147.062444)
			(xy 253.957327 -147.09033) (xy 253.949207 -147.145506) (xy 253.933139 -147.198913) (xy 253.909467 -147.24941)
			(xy 253.878694 -147.295923) (xy 253.841477 -147.33746) (xy 253.798609 -147.373135) (xy 253.751003 -147.402189)
			(xy 253.699674 -147.424001) (xy 253.645717 -147.438107) (xy 253.59028 -147.444207) (xy 253.534546 -147.44217)
			(xy 253.479703 -147.43204) (xy 253.426919 -147.414033) (xy 253.377319 -147.388532) (xy 253.331961 -147.356081)
			(xy 253.291812 -147.317372) (xy 253.257726 -147.273229) (xy 253.23043 -147.224594) (xy 253.210507 -147.172503)
			(xy 253.198381 -147.118066) (xy 253.19431 -147.062444) (xy 252.549729 -147.062444) (xy 252.531263 -147.101836)
			(xy 252.50049 -147.148349) (xy 252.463273 -147.189886) (xy 252.420405 -147.225561) (xy 252.372799 -147.254615)
			(xy 252.32147 -147.276427) (xy 252.267513 -147.290533) (xy 252.212076 -147.296633) (xy 252.156342 -147.294596)
			(xy 252.101499 -147.284466) (xy 252.048715 -147.266459) (xy 251.999115 -147.240958) (xy 251.953757 -147.208507)
			(xy 251.913608 -147.169798) (xy 251.879522 -147.125655) (xy 251.852226 -147.07702) (xy 251.832303 -147.024929)
			(xy 251.820177 -146.970492) (xy 251.816106 -146.91487) (xy 238.684308 -146.91487) (xy 238.684308 -147.657656)
			(xy 243.350443 -147.657656) (xy 243.350443 -147.603144) (xy 243.358201 -147.549188) (xy 243.37356 -147.496885)
			(xy 243.396206 -147.447301) (xy 243.425679 -147.401444) (xy 243.461379 -147.360249) (xy 243.502578 -147.324554)
			(xy 243.548437 -147.295086) (xy 243.598024 -147.272445) (xy 243.650329 -147.257092) (xy 243.704286 -147.24934)
			(xy 243.731542 -147.24888) (xy 243.757857 -147.249326) (xy 243.809986 -147.256566) (xy 243.860629 -147.27089)
			(xy 243.908827 -147.292026) (xy 243.95367 -147.319576) (xy 243.99431 -147.353017) (xy 244.012466 -147.37207)
			(xy 244.020002 -147.379454) (xy 244.039271 -147.38799) (xy 244.049804 -147.38858) (xy 244.12448 -147.38858)
			(xy 244.135031 -147.38806) (xy 244.154327 -147.379519) (xy 244.161818 -147.37207) (xy 244.181638 -147.351282)
			(xy 244.22641 -147.315307) (xy 244.276068 -147.286447) (xy 244.32949 -147.265354) (xy 244.385469 -147.252505)
			(xy 244.442742 -147.24819) (xy 244.500015 -147.252505) (xy 244.555994 -147.265354) (xy 244.609416 -147.286447)
			(xy 244.659074 -147.315307) (xy 244.703846 -147.351282) (xy 244.723666 -147.37207) (xy 244.731202 -147.379454)
			(xy 244.750471 -147.38799) (xy 244.761004 -147.38858) (xy 244.83568 -147.38858) (xy 244.846231 -147.38806)
			(xy 244.865527 -147.379519) (xy 244.873018 -147.37207) (xy 244.891166 -147.353007) (xy 244.931798 -147.319552)
			(xy 244.97664 -147.291994) (xy 245.024842 -147.270857) (xy 245.075491 -147.256542) (xy 245.127626 -147.249318)
			(xy 245.153942 -147.24888) (xy 245.18119 -147.249393) (xy 245.235132 -147.257154) (xy 245.28742 -147.272512)
			(xy 245.33699 -147.295155) (xy 245.382834 -147.324622) (xy 245.424018 -147.360312) (xy 245.459703 -147.4015)
			(xy 245.489165 -147.447347) (xy 245.511802 -147.49692) (xy 245.527155 -147.549209) (xy 245.53491 -147.603152)
			(xy 245.53491 -147.657648) (xy 245.527155 -147.711591) (xy 245.511802 -147.76388) (xy 245.489165 -147.813453)
			(xy 245.459703 -147.8593) (xy 245.424018 -147.900488) (xy 245.382834 -147.936178) (xy 245.33699 -147.965645)
			(xy 245.28742 -147.988288) (xy 245.235132 -148.003646) (xy 245.18119 -148.011407) (xy 245.153942 -148.011896)
			(xy 245.127627 -148.011469) (xy 245.075496 -148.004226) (xy 245.024853 -147.989899) (xy 244.976654 -147.968759)
			(xy 244.931811 -147.941206) (xy 244.891174 -147.907761) (xy 244.873018 -147.888706) (xy 244.865491 -147.881311)
			(xy 244.846215 -147.872783) (xy 244.83568 -147.872196) (xy 244.761004 -147.872196) (xy 244.750453 -147.872715)
			(xy 244.731158 -147.881257) (xy 244.723666 -147.888706) (xy 244.703846 -147.909494) (xy 244.659074 -147.945469)
			(xy 244.609416 -147.974329) (xy 244.555994 -147.995422) (xy 244.500015 -148.008271) (xy 244.442742 -148.012586)
			(xy 244.385469 -148.008271) (xy 244.32949 -147.995422) (xy 244.276068 -147.974329) (xy 244.22641 -147.945469)
			(xy 244.181638 -147.909494) (xy 244.161818 -147.888706) (xy 244.154291 -147.881311) (xy 244.135015 -147.872783)
			(xy 244.12448 -147.872196) (xy 244.049804 -147.872196) (xy 244.039253 -147.872715) (xy 244.019958 -147.881257)
			(xy 244.012466 -147.888706) (xy 243.994321 -147.907772) (xy 243.953689 -147.941228) (xy 243.908846 -147.968786)
			(xy 243.860644 -147.989922) (xy 243.809994 -148.004237) (xy 243.757859 -148.011459) (xy 243.731542 -148.011896)
			(xy 243.704286 -148.01146) (xy 243.650329 -148.003708) (xy 243.598024 -147.988355) (xy 243.548437 -147.965714)
			(xy 243.502578 -147.936246) (xy 243.461379 -147.900551) (xy 243.425679 -147.859356) (xy 243.396206 -147.813499)
			(xy 243.37356 -147.763915) (xy 243.358201 -147.711612) (xy 243.350443 -147.657656) (xy 238.684308 -147.657656)
			(xy 238.684308 -148.017738) (xy 248.177556 -148.017738) (xy 248.181627 -147.962116) (xy 248.193753 -147.907679)
			(xy 248.213676 -147.855588) (xy 248.240972 -147.806953) (xy 248.275058 -147.76281) (xy 248.315207 -147.724101)
			(xy 248.360565 -147.69165) (xy 248.410165 -147.666149) (xy 248.462949 -147.648142) (xy 248.517792 -147.638012)
			(xy 248.573526 -147.635975) (xy 248.628963 -147.642075) (xy 248.68292 -147.656181) (xy 248.734249 -147.677993)
			(xy 248.781855 -147.707047) (xy 248.823118 -147.741386) (xy 254.081532 -147.741386) (xy 254.085603 -147.685764)
			(xy 254.097729 -147.631327) (xy 254.117652 -147.579236) (xy 254.144948 -147.530601) (xy 254.179034 -147.486458)
			(xy 254.219183 -147.447749) (xy 254.264541 -147.415298) (xy 254.314141 -147.389797) (xy 254.366925 -147.37179)
			(xy 254.421768 -147.36166) (xy 254.477502 -147.359623) (xy 254.532939 -147.365723) (xy 254.586896 -147.379829)
			(xy 254.638225 -147.401641) (xy 254.685831 -147.430695) (xy 254.728699 -147.46637) (xy 254.765916 -147.507907)
			(xy 254.796689 -147.55442) (xy 254.820361 -147.604917) (xy 254.836429 -147.658324) (xy 254.844549 -147.7135)
			(xy 254.845058 -147.741386) (xy 254.844549 -147.769272) (xy 254.836429 -147.824448) (xy 254.820361 -147.877855)
			(xy 254.796689 -147.928352) (xy 254.765916 -147.974865) (xy 254.728699 -148.016402) (xy 254.685831 -148.052077)
			(xy 254.638225 -148.081131) (xy 254.586896 -148.102943) (xy 254.532939 -148.117049) (xy 254.477502 -148.123149)
			(xy 254.421768 -148.121112) (xy 254.366925 -148.110982) (xy 254.314141 -148.092975) (xy 254.264541 -148.067474)
			(xy 254.219183 -148.035023) (xy 254.179034 -147.996314) (xy 254.144948 -147.952171) (xy 254.117652 -147.903536)
			(xy 254.097729 -147.851445) (xy 254.085603 -147.797008) (xy 254.081532 -147.741386) (xy 248.823118 -147.741386)
			(xy 248.824723 -147.742722) (xy 248.86194 -147.784259) (xy 248.892713 -147.830772) (xy 248.916385 -147.881269)
			(xy 248.932453 -147.934676) (xy 248.940573 -147.989852) (xy 248.941082 -148.017738) (xy 248.940573 -148.045624)
			(xy 248.932453 -148.1008) (xy 248.916385 -148.154207) (xy 248.892713 -148.204704) (xy 248.86194 -148.251217)
			(xy 248.824723 -148.292754) (xy 248.781855 -148.328429) (xy 248.734249 -148.357483) (xy 248.68292 -148.379295)
			(xy 248.628963 -148.393401) (xy 248.573526 -148.399501) (xy 248.517792 -148.397464) (xy 248.462949 -148.387334)
			(xy 248.410165 -148.369327) (xy 248.360565 -148.343826) (xy 248.315207 -148.311375) (xy 248.275058 -148.272666)
			(xy 248.240972 -148.228523) (xy 248.213676 -148.179888) (xy 248.193753 -148.127797) (xy 248.181627 -148.07336)
			(xy 248.177556 -148.017738) (xy 238.684308 -148.017738) (xy 238.684308 -150.195854) (xy 243.350465 -150.195854)
			(xy 243.350465 -150.141346) (xy 243.358223 -150.087393) (xy 243.373581 -150.035093) (xy 243.396226 -149.985511)
			(xy 243.425697 -149.939657) (xy 243.461394 -149.898465) (xy 243.502591 -149.862772) (xy 243.548448 -149.833306)
			(xy 243.598032 -149.810666) (xy 243.650334 -149.795314) (xy 243.704288 -149.787562) (xy 243.731542 -149.787102)
			(xy 243.757857 -149.787541) (xy 243.809987 -149.794781) (xy 243.86063 -149.809106) (xy 243.908829 -149.830244)
			(xy 243.953672 -149.857795) (xy 243.99431 -149.891238) (xy 244.012466 -149.910292) (xy 244.019999 -149.917679)
			(xy 244.03927 -149.926212) (xy 244.049804 -149.926802) (xy 244.12448 -149.926802) (xy 244.13503 -149.926275)
			(xy 244.154325 -149.917738) (xy 244.161818 -149.910292) (xy 244.181638 -149.889504) (xy 244.22641 -149.853529)
			(xy 244.276068 -149.824669) (xy 244.32949 -149.803576) (xy 244.385469 -149.790727) (xy 244.442742 -149.786412)
			(xy 244.500015 -149.790727) (xy 244.555994 -149.803576) (xy 244.609416 -149.824669) (xy 244.659074 -149.853529)
			(xy 244.703846 -149.889504) (xy 244.723666 -149.910292) (xy 244.731199 -149.917679) (xy 244.75047 -149.926212)
			(xy 244.761004 -149.926802) (xy 244.83568 -149.926802) (xy 244.84623 -149.926275) (xy 244.865525 -149.917738)
			(xy 244.873018 -149.910292) (xy 244.89117 -149.891233) (xy 244.931801 -149.857777) (xy 244.976642 -149.830218)
			(xy 245.024843 -149.80908) (xy 245.075491 -149.794764) (xy 245.127626 -149.78754) (xy 245.153942 -149.787102)
			(xy 245.181192 -149.787571) (xy 245.235137 -149.795332) (xy 245.287428 -149.810691) (xy 245.337001 -149.833336)
			(xy 245.382847 -149.862804) (xy 245.424034 -149.898496) (xy 245.459721 -149.939686) (xy 245.489185 -149.985536)
			(xy 245.511823 -150.035112) (xy 245.520145 -150.063454) (xy 248.03811 -150.063454) (xy 248.042181 -150.007832)
			(xy 248.054307 -149.953395) (xy 248.07423 -149.901304) (xy 248.101526 -149.852669) (xy 248.135612 -149.808526)
			(xy 248.175761 -149.769817) (xy 248.221119 -149.737366) (xy 248.270719 -149.711865) (xy 248.323503 -149.693858)
			(xy 248.378346 -149.683728) (xy 248.43408 -149.681691) (xy 248.489517 -149.687791) (xy 248.543474 -149.701897)
			(xy 248.594803 -149.723709) (xy 248.642409 -149.752763) (xy 248.685277 -149.788438) (xy 248.722494 -149.829975)
			(xy 248.753267 -149.876488) (xy 248.776939 -149.926985) (xy 248.793007 -149.980392) (xy 248.801127 -150.035568)
			(xy 248.801636 -150.063454) (xy 248.801127 -150.09134) (xy 248.793007 -150.146516) (xy 248.776939 -150.199923)
			(xy 248.753267 -150.25042) (xy 248.722494 -150.296933) (xy 248.685277 -150.33847) (xy 248.642409 -150.374145)
			(xy 248.594803 -150.403199) (xy 248.543474 -150.425011) (xy 248.489517 -150.439117) (xy 248.43408 -150.445217)
			(xy 248.378346 -150.44318) (xy 248.323503 -150.43305) (xy 248.270719 -150.415043) (xy 248.221119 -150.389542)
			(xy 248.175761 -150.357091) (xy 248.135612 -150.318382) (xy 248.101526 -150.274239) (xy 248.07423 -150.225604)
			(xy 248.054307 -150.173513) (xy 248.042181 -150.119076) (xy 248.03811 -150.063454) (xy 245.520145 -150.063454)
			(xy 245.527177 -150.087404) (xy 245.534932 -150.14135) (xy 245.534932 -150.19585) (xy 245.527177 -150.249796)
			(xy 245.511823 -150.302088) (xy 245.489185 -150.351664) (xy 245.459721 -150.397514) (xy 245.424034 -150.438704)
			(xy 245.382847 -150.474396) (xy 245.337001 -150.503864) (xy 245.287428 -150.526509) (xy 245.235137 -150.541868)
			(xy 245.181192 -150.549629) (xy 245.153942 -150.550118) (xy 245.127627 -150.549683) (xy 245.075497 -150.542441)
			(xy 245.024854 -150.528115) (xy 244.976655 -150.506976) (xy 244.931813 -150.479425) (xy 244.891174 -150.445982)
			(xy 244.873018 -150.426928) (xy 244.865488 -150.419536) (xy 244.846215 -150.411005) (xy 244.83568 -150.410418)
			(xy 244.761004 -150.410418) (xy 244.750452 -150.410931) (xy 244.731157 -150.419477) (xy 244.723666 -150.426928)
			(xy 244.703846 -150.447716) (xy 244.659074 -150.483691) (xy 244.609416 -150.512551) (xy 244.555994 -150.533644)
			(xy 244.500015 -150.546493) (xy 244.442742 -150.550808) (xy 244.385469 -150.546493) (xy 244.32949 -150.533644)
			(xy 244.276068 -150.512551) (xy 244.22641 -150.483691) (xy 244.181638 -150.447716) (xy 244.161818 -150.426928)
			(xy 244.154288 -150.419536) (xy 244.135015 -150.411005) (xy 244.12448 -150.410418) (xy 244.049804 -150.410418)
			(xy 244.039252 -150.410931) (xy 244.019957 -150.419477) (xy 244.012466 -150.426928) (xy 243.994325 -150.445998)
			(xy 243.953692 -150.479453) (xy 243.908848 -150.507009) (xy 243.860645 -150.528145) (xy 243.809995 -150.542459)
			(xy 243.757859 -150.549681) (xy 243.731542 -150.550118) (xy 243.704288 -150.549638) (xy 243.650334 -150.541886)
			(xy 243.598032 -150.526534) (xy 243.548448 -150.503894) (xy 243.502591 -150.474428) (xy 243.461394 -150.438735)
			(xy 243.425697 -150.397543) (xy 243.396226 -150.351689) (xy 243.373581 -150.302107) (xy 243.358223 -150.249807)
			(xy 243.350465 -150.195854) (xy 238.684308 -150.195854) (xy 238.684308 -151.67102) (xy 247.99366 -151.67102)
			(xy 247.997731 -151.615398) (xy 248.009857 -151.560961) (xy 248.02978 -151.50887) (xy 248.057076 -151.460235)
			(xy 248.091162 -151.416092) (xy 248.131311 -151.377383) (xy 248.176669 -151.344932) (xy 248.226269 -151.319431)
			(xy 248.279053 -151.301424) (xy 248.333896 -151.291294) (xy 248.38963 -151.289257) (xy 248.445067 -151.295357)
			(xy 248.499024 -151.309463) (xy 248.550353 -151.331275) (xy 248.597959 -151.360329) (xy 248.640827 -151.396004)
			(xy 248.678044 -151.437541) (xy 248.708817 -151.484054) (xy 248.732489 -151.534551) (xy 248.748557 -151.587958)
			(xy 248.756677 -151.643134) (xy 248.757186 -151.67102) (xy 248.756713 -151.696928) (xy 249.00966 -151.696928)
			(xy 249.013731 -151.641306) (xy 249.025857 -151.586869) (xy 249.04578 -151.534778) (xy 249.073076 -151.486143)
			(xy 249.107162 -151.442) (xy 249.147311 -151.403291) (xy 249.192669 -151.37084) (xy 249.242269 -151.345339)
			(xy 249.295053 -151.327332) (xy 249.349896 -151.317202) (xy 249.40563 -151.315165) (xy 249.461067 -151.321265)
			(xy 249.515024 -151.335371) (xy 249.566353 -151.357183) (xy 249.613959 -151.386237) (xy 249.638435 -151.406606)
			(xy 250.236734 -151.406606) (xy 250.240805 -151.350984) (xy 250.252931 -151.296547) (xy 250.272854 -151.244456)
			(xy 250.30015 -151.195821) (xy 250.334236 -151.151678) (xy 250.374385 -151.112969) (xy 250.419743 -151.080518)
			(xy 250.469343 -151.055017) (xy 250.522127 -151.03701) (xy 250.57697 -151.02688) (xy 250.632704 -151.024843)
			(xy 250.688141 -151.030943) (xy 250.742098 -151.045049) (xy 250.793427 -151.066861) (xy 250.841033 -151.095915)
			(xy 250.883901 -151.13159) (xy 250.921118 -151.173127) (xy 250.951891 -151.21964) (xy 250.975563 -151.270137)
			(xy 250.991631 -151.323544) (xy 250.999751 -151.37872) (xy 251.00026 -151.406606) (xy 250.999751 -151.434492)
			(xy 250.991631 -151.489668) (xy 250.975563 -151.543075) (xy 250.957021 -151.582628) (xy 251.56236 -151.582628)
			(xy 251.566431 -151.527006) (xy 251.578557 -151.472569) (xy 251.59848 -151.420478) (xy 251.625776 -151.371843)
			(xy 251.659862 -151.3277) (xy 251.700011 -151.288991) (xy 251.745369 -151.25654) (xy 251.794969 -151.231039)
			(xy 251.847753 -151.213032) (xy 251.902596 -151.202902) (xy 251.95833 -151.200865) (xy 252.013767 -151.206965)
			(xy 252.067724 -151.221071) (xy 252.119053 -151.242883) (xy 252.166659 -151.271937) (xy 252.209527 -151.307612)
			(xy 252.246744 -151.349149) (xy 252.277517 -151.395662) (xy 252.301189 -151.446159) (xy 252.317257 -151.499566)
			(xy 252.325377 -151.554742) (xy 252.32564 -151.569166) (xy 253.07366 -151.569166) (xy 253.077731 -151.513544)
			(xy 253.089857 -151.459107) (xy 253.10978 -151.407016) (xy 253.137076 -151.358381) (xy 253.171162 -151.314238)
			(xy 253.211311 -151.275529) (xy 253.256669 -151.243078) (xy 253.306269 -151.217577) (xy 253.359053 -151.19957)
			(xy 253.413896 -151.18944) (xy 253.46963 -151.187403) (xy 253.525067 -151.193503) (xy 253.579024 -151.207609)
			(xy 253.630353 -151.229421) (xy 253.677959 -151.258475) (xy 253.720827 -151.29415) (xy 253.758044 -151.335687)
			(xy 253.788817 -151.3822) (xy 253.812489 -151.432697) (xy 253.828557 -151.486104) (xy 253.836677 -151.54128)
			(xy 253.837186 -151.569166) (xy 253.836677 -151.597052) (xy 253.828557 -151.652228) (xy 253.812489 -151.705635)
			(xy 253.788817 -151.756132) (xy 253.758044 -151.802645) (xy 253.720827 -151.844182) (xy 253.677959 -151.879857)
			(xy 253.630353 -151.908911) (xy 253.579024 -151.930723) (xy 253.525067 -151.944829) (xy 253.46963 -151.950929)
			(xy 253.413896 -151.948892) (xy 253.359053 -151.938762) (xy 253.306269 -151.920755) (xy 253.256669 -151.895254)
			(xy 253.211311 -151.862803) (xy 253.171162 -151.824094) (xy 253.137076 -151.779951) (xy 253.10978 -151.731316)
			(xy 253.089857 -151.679225) (xy 253.077731 -151.624788) (xy 253.07366 -151.569166) (xy 252.32564 -151.569166)
			(xy 252.325886 -151.582628) (xy 252.325377 -151.610514) (xy 252.317257 -151.66569) (xy 252.301189 -151.719097)
			(xy 252.277517 -151.769594) (xy 252.246744 -151.816107) (xy 252.209527 -151.857644) (xy 252.166659 -151.893319)
			(xy 252.119053 -151.922373) (xy 252.067724 -151.944185) (xy 252.013767 -151.958291) (xy 251.95833 -151.964391)
			(xy 251.902596 -151.962354) (xy 251.847753 -151.952224) (xy 251.794969 -151.934217) (xy 251.745369 -151.908716)
			(xy 251.700011 -151.876265) (xy 251.659862 -151.837556) (xy 251.625776 -151.793413) (xy 251.59848 -151.744778)
			(xy 251.578557 -151.692687) (xy 251.566431 -151.63825) (xy 251.56236 -151.582628) (xy 250.957021 -151.582628)
			(xy 250.951891 -151.593572) (xy 250.921118 -151.640085) (xy 250.883901 -151.681622) (xy 250.841033 -151.717297)
			(xy 250.793427 -151.746351) (xy 250.742098 -151.768163) (xy 250.688141 -151.782269) (xy 250.632704 -151.788369)
			(xy 250.57697 -151.786332) (xy 250.522127 -151.776202) (xy 250.469343 -151.758195) (xy 250.419743 -151.732694)
			(xy 250.374385 -151.700243) (xy 250.334236 -151.661534) (xy 250.30015 -151.617391) (xy 250.272854 -151.568756)
			(xy 250.252931 -151.516665) (xy 250.240805 -151.462228) (xy 250.236734 -151.406606) (xy 249.638435 -151.406606)
			(xy 249.656827 -151.421912) (xy 249.694044 -151.463449) (xy 249.724817 -151.509962) (xy 249.748489 -151.560459)
			(xy 249.764557 -151.613866) (xy 249.772677 -151.669042) (xy 249.773186 -151.696928) (xy 249.772677 -151.724814)
			(xy 249.764557 -151.77999) (xy 249.748489 -151.833397) (xy 249.724817 -151.883894) (xy 249.694044 -151.930407)
			(xy 249.656827 -151.971944) (xy 249.613959 -152.007619) (xy 249.566353 -152.036673) (xy 249.515024 -152.058485)
			(xy 249.461067 -152.072591) (xy 249.40563 -152.078691) (xy 249.349896 -152.076654) (xy 249.295053 -152.066524)
			(xy 249.242269 -152.048517) (xy 249.192669 -152.023016) (xy 249.147311 -151.990565) (xy 249.107162 -151.951856)
			(xy 249.073076 -151.907713) (xy 249.04578 -151.859078) (xy 249.025857 -151.806987) (xy 249.013731 -151.75255)
			(xy 249.00966 -151.696928) (xy 248.756713 -151.696928) (xy 248.756677 -151.698906) (xy 248.748557 -151.754082)
			(xy 248.732489 -151.807489) (xy 248.708817 -151.857986) (xy 248.678044 -151.904499) (xy 248.640827 -151.946036)
			(xy 248.597959 -151.981711) (xy 248.550353 -152.010765) (xy 248.499024 -152.032577) (xy 248.445067 -152.046683)
			(xy 248.38963 -152.052783) (xy 248.333896 -152.050746) (xy 248.279053 -152.040616) (xy 248.226269 -152.022609)
			(xy 248.176669 -151.997108) (xy 248.131311 -151.964657) (xy 248.091162 -151.925948) (xy 248.057076 -151.881805)
			(xy 248.02978 -151.83317) (xy 248.009857 -151.781079) (xy 247.997731 -151.726642) (xy 247.99366 -151.67102)
			(xy 238.684308 -151.67102) (xy 238.684308 -153.782522) (xy 246.97766 -153.782522) (xy 246.981731 -153.7269)
			(xy 246.993857 -153.672463) (xy 247.01378 -153.620372) (xy 247.041076 -153.571737) (xy 247.075162 -153.527594)
			(xy 247.115311 -153.488885) (xy 247.160669 -153.456434) (xy 247.210269 -153.430933) (xy 247.263053 -153.412926)
			(xy 247.317896 -153.402796) (xy 247.37363 -153.400759) (xy 247.429067 -153.406859) (xy 247.483024 -153.420965)
			(xy 247.534353 -153.442777) (xy 247.581959 -153.471831) (xy 247.624827 -153.507506) (xy 247.662044 -153.549043)
			(xy 247.692817 -153.595556) (xy 247.716489 -153.646053) (xy 247.732557 -153.69946) (xy 247.740677 -153.754636)
			(xy 247.741186 -153.782522) (xy 247.99366 -153.782522) (xy 247.997731 -153.7269) (xy 248.009857 -153.672463)
			(xy 248.02978 -153.620372) (xy 248.057076 -153.571737) (xy 248.091162 -153.527594) (xy 248.131311 -153.488885)
			(xy 248.176669 -153.456434) (xy 248.226269 -153.430933) (xy 248.279053 -153.412926) (xy 248.333896 -153.402796)
			(xy 248.38963 -153.400759) (xy 248.445067 -153.406859) (xy 248.499024 -153.420965) (xy 248.550353 -153.442777)
			(xy 248.597959 -153.471831) (xy 248.640827 -153.507506) (xy 248.678044 -153.549043) (xy 248.708817 -153.595556)
			(xy 248.732489 -153.646053) (xy 248.748557 -153.69946) (xy 248.756677 -153.754636) (xy 248.757186 -153.782522)
			(xy 248.756677 -153.810408) (xy 248.748557 -153.865584) (xy 248.732489 -153.918991) (xy 248.708817 -153.969488)
			(xy 248.678044 -154.016001) (xy 248.640827 -154.057538) (xy 248.597959 -154.093213) (xy 248.550353 -154.122267)
			(xy 248.499024 -154.144079) (xy 248.445067 -154.158185) (xy 248.38963 -154.164285) (xy 248.333896 -154.162248)
			(xy 248.279053 -154.152118) (xy 248.226269 -154.134111) (xy 248.176669 -154.10861) (xy 248.131311 -154.076159)
			(xy 248.091162 -154.03745) (xy 248.057076 -153.993307) (xy 248.02978 -153.944672) (xy 248.009857 -153.892581)
			(xy 247.997731 -153.838144) (xy 247.99366 -153.782522) (xy 247.741186 -153.782522) (xy 247.740677 -153.810408)
			(xy 247.732557 -153.865584) (xy 247.716489 -153.918991) (xy 247.692817 -153.969488) (xy 247.662044 -154.016001)
			(xy 247.624827 -154.057538) (xy 247.581959 -154.093213) (xy 247.534353 -154.122267) (xy 247.483024 -154.144079)
			(xy 247.429067 -154.158185) (xy 247.37363 -154.164285) (xy 247.317896 -154.162248) (xy 247.263053 -154.152118)
			(xy 247.210269 -154.134111) (xy 247.160669 -154.10861) (xy 247.115311 -154.076159) (xy 247.075162 -154.03745)
			(xy 247.041076 -153.993307) (xy 247.01378 -153.944672) (xy 246.993857 -153.892581) (xy 246.981731 -153.838144)
			(xy 246.97766 -153.782522) (xy 238.684308 -153.782522) (xy 238.684308 -155.093162) (xy 238.685832 -155.105608)
			(xy 238.687711 -155.112149) (xy 238.694409 -155.123989) (xy 238.69904 -155.128976) (xy 238.782107 -155.212034)
			(xy 239.469166 -155.212034) (xy 239.473237 -155.156412) (xy 239.485363 -155.101975) (xy 239.505286 -155.049884)
			(xy 239.532582 -155.001249) (xy 239.566668 -154.957106) (xy 239.606817 -154.918397) (xy 239.652175 -154.885946)
			(xy 239.701775 -154.860445) (xy 239.754559 -154.842438) (xy 239.809402 -154.832308) (xy 239.865136 -154.830271)
			(xy 239.920573 -154.836371) (xy 239.97453 -154.850477) (xy 240.025859 -154.872289) (xy 240.073465 -154.901343)
			(xy 240.116333 -154.937018) (xy 240.15355 -154.978555) (xy 240.184323 -155.025068) (xy 240.207995 -155.075565)
			(xy 240.209086 -155.079192) (xy 242.069872 -155.079192) (xy 242.073943 -155.02357) (xy 242.086069 -154.969133)
			(xy 242.105992 -154.917042) (xy 242.133288 -154.868407) (xy 242.167374 -154.824264) (xy 242.207523 -154.785555)
			(xy 242.252881 -154.753104) (xy 242.302481 -154.727603) (xy 242.355265 -154.709596) (xy 242.410108 -154.699466)
			(xy 242.465842 -154.697429) (xy 242.521279 -154.703529) (xy 242.575236 -154.717635) (xy 242.626565 -154.739447)
			(xy 242.674171 -154.768501) (xy 242.717039 -154.804176) (xy 242.754256 -154.845713) (xy 242.785029 -154.892226)
			(xy 242.808701 -154.942723) (xy 242.824769 -154.99613) (xy 242.832889 -155.051306) (xy 242.833398 -155.079192)
			(xy 242.833333 -155.082748) (xy 243.393722 -155.082748) (xy 243.394148 -155.056433) (xy 243.40139 -155.004302)
			(xy 243.415717 -154.953658) (xy 243.436857 -154.905459) (xy 243.464411 -154.860617) (xy 243.497857 -154.819979)
			(xy 243.516912 -154.801824) (xy 243.524307 -154.794297) (xy 243.532835 -154.775021) (xy 243.533422 -154.764486)
			(xy 243.533422 -154.68981) (xy 243.532895 -154.67926) (xy 243.524358 -154.659965) (xy 243.516912 -154.652472)
			(xy 243.497852 -154.634321) (xy 243.464395 -154.59369) (xy 243.436836 -154.548849) (xy 243.415698 -154.500648)
			(xy 243.401382 -154.449999) (xy 243.394159 -154.397864) (xy 243.393722 -154.371548) (xy 243.3942 -154.344295)
			(xy 243.401951 -154.290343) (xy 243.417303 -154.238044) (xy 243.439942 -154.188462) (xy 243.469408 -154.142607)
			(xy 243.5051 -154.101413) (xy 243.546292 -154.065718) (xy 243.592146 -154.03625) (xy 243.641727 -154.013609)
			(xy 243.694025 -153.998255) (xy 243.747977 -153.990501) (xy 243.77523 -153.99004) (xy 243.801545 -153.990475)
			(xy 243.853676 -153.997714) (xy 243.90432 -154.012039) (xy 243.952519 -154.033178) (xy 243.997361 -154.06073)
			(xy 244.037999 -154.094175) (xy 244.056154 -154.11323) (xy 244.063663 -154.120647) (xy 244.082952 -154.129165)
			(xy 244.093492 -154.12974) (xy 244.168168 -154.12974) (xy 244.178716 -154.129195) (xy 244.19801 -154.12067)
			(xy 244.205506 -154.11323) (xy 244.225326 -154.092442) (xy 244.270098 -154.056467) (xy 244.319756 -154.027607)
			(xy 244.373178 -154.006514) (xy 244.429157 -153.993665) (xy 244.48643 -153.98935) (xy 244.543703 -153.993665)
			(xy 244.599682 -154.006514) (xy 244.653104 -154.027607) (xy 244.702762 -154.056467) (xy 244.747534 -154.092442)
			(xy 244.767354 -154.11323) (xy 244.774863 -154.120647) (xy 244.794152 -154.129165) (xy 244.804692 -154.12974)
			(xy 244.879368 -154.12974) (xy 244.889916 -154.129195) (xy 244.90921 -154.12067) (xy 244.916706 -154.11323)
			(xy 244.936526 -154.092442) (xy 244.981298 -154.056467) (xy 245.030956 -154.027607) (xy 245.084378 -154.006514)
			(xy 245.140357 -153.993665) (xy 245.19763 -153.98935) (xy 245.254903 -153.993665) (xy 245.310882 -154.006514)
			(xy 245.364304 -154.027607) (xy 245.413962 -154.056467) (xy 245.458734 -154.092442) (xy 245.478554 -154.11323)
			(xy 245.486063 -154.120647) (xy 245.505352 -154.129165) (xy 245.515892 -154.12974) (xy 245.590568 -154.12974)
			(xy 245.601116 -154.129195) (xy 245.62041 -154.12067) (xy 245.627906 -154.11323) (xy 245.646072 -154.094184)
			(xy 245.686698 -154.060725) (xy 245.731536 -154.033164) (xy 245.779735 -154.012024) (xy 245.830381 -153.997705)
			(xy 245.882514 -153.990479) (xy 245.90883 -153.99004) (xy 245.936086 -153.990427) (xy 245.990042 -153.998189)
			(xy 246.042344 -154.013552) (xy 246.091928 -154.036201) (xy 246.137783 -154.065677) (xy 246.178977 -154.101379)
			(xy 246.21467 -154.142579) (xy 246.244136 -154.188441) (xy 246.266776 -154.238029) (xy 246.282127 -154.290334)
			(xy 246.289878 -154.344292) (xy 246.290338 -154.371548) (xy 246.289922 -154.397864) (xy 246.28268 -154.449996)
			(xy 246.268352 -154.50064) (xy 246.24721 -154.548839) (xy 246.219654 -154.593681) (xy 246.186205 -154.634318)
			(xy 246.167148 -154.652472) (xy 246.159764 -154.660009) (xy 246.151228 -154.679277) (xy 246.150638 -154.68981)
			(xy 246.150638 -154.764486) (xy 246.15115 -154.775038) (xy 246.159696 -154.794334) (xy 246.167148 -154.801824)
			(xy 246.186217 -154.819965) (xy 246.219671 -154.860599) (xy 246.247227 -154.905443) (xy 246.268363 -154.953646)
			(xy 246.282678 -155.004296) (xy 246.2899 -155.056431) (xy 246.290338 -155.082748) (xy 246.289867 -155.109999)
			(xy 246.282105 -155.163946) (xy 246.266745 -155.216239) (xy 246.2441 -155.265814) (xy 246.214632 -155.311663)
			(xy 246.178939 -155.352852) (xy 246.137749 -155.388543) (xy 246.091899 -155.418009) (xy 246.042322 -155.440651)
			(xy 245.990028 -155.456008) (xy 245.936081 -155.463768) (xy 245.90883 -155.464256) (xy 245.882514 -155.463849)
			(xy 245.830382 -155.456604) (xy 245.779738 -155.442274) (xy 245.731539 -155.42113) (xy 245.686697 -155.393573)
			(xy 245.64606 -155.360123) (xy 245.627906 -155.341066) (xy 245.620375 -155.333675) (xy 245.601103 -155.325142)
			(xy 245.590568 -155.324556) (xy 245.515892 -155.324556) (xy 245.505342 -155.32508) (xy 245.486048 -155.33362)
			(xy 245.478554 -155.341066) (xy 245.458734 -155.361854) (xy 245.413962 -155.397829) (xy 245.364304 -155.426689)
			(xy 245.310882 -155.447782) (xy 245.254903 -155.460631) (xy 245.19763 -155.464946) (xy 245.140357 -155.460631)
			(xy 245.084378 -155.447782) (xy 245.030956 -155.426689) (xy 244.981298 -155.397829) (xy 244.936526 -155.361854)
			(xy 244.916706 -155.341066) (xy 244.909175 -155.333675) (xy 244.889903 -155.325142) (xy 244.879368 -155.324556)
			(xy 244.804692 -155.324556) (xy 244.794142 -155.32508) (xy 244.774848 -155.33362) (xy 244.767354 -155.341066)
			(xy 244.747534 -155.361854) (xy 244.702762 -155.397829) (xy 244.653104 -155.426689) (xy 244.599682 -155.447782)
			(xy 244.543703 -155.460631) (xy 244.48643 -155.464946) (xy 244.429157 -155.460631) (xy 244.373178 -155.447782)
			(xy 244.319756 -155.426689) (xy 244.270098 -155.397829) (xy 244.225326 -155.361854) (xy 244.205506 -155.341066)
			(xy 244.197975 -155.333675) (xy 244.178703 -155.325142) (xy 244.168168 -155.324556) (xy 244.093492 -155.324556)
			(xy 244.082942 -155.32508) (xy 244.063648 -155.33362) (xy 244.056154 -155.341066) (xy 244.038027 -155.360149)
			(xy 243.997389 -155.393602) (xy 243.952543 -155.421155) (xy 243.904337 -155.442288) (xy 243.853685 -155.4566)
			(xy 243.801548 -155.46382) (xy 243.77523 -155.464256) (xy 243.747982 -155.463694) (xy 243.694039 -155.455943)
			(xy 243.641749 -155.440594) (xy 243.592175 -155.41796) (xy 243.546327 -155.388501) (xy 243.505138 -155.352818)
			(xy 243.469446 -155.311636) (xy 243.439978 -155.265793) (xy 243.417333 -155.216224) (xy 243.401974 -155.163937)
			(xy 243.394212 -155.109996) (xy 243.393722 -155.082748) (xy 242.833333 -155.082748) (xy 242.832889 -155.107078)
			(xy 242.824769 -155.162254) (xy 242.808701 -155.215661) (xy 242.785029 -155.266158) (xy 242.754256 -155.312671)
			(xy 242.717039 -155.354208) (xy 242.674171 -155.389883) (xy 242.626565 -155.418937) (xy 242.575236 -155.440749)
			(xy 242.521279 -155.454855) (xy 242.465842 -155.460955) (xy 242.410108 -155.458918) (xy 242.355265 -155.448788)
			(xy 242.302481 -155.430781) (xy 242.252881 -155.40528) (xy 242.207523 -155.372829) (xy 242.167374 -155.33412)
			(xy 242.133288 -155.289977) (xy 242.105992 -155.241342) (xy 242.086069 -155.189251) (xy 242.073943 -155.134814)
			(xy 242.069872 -155.079192) (xy 240.209086 -155.079192) (xy 240.224063 -155.128972) (xy 240.232183 -155.184148)
			(xy 240.232692 -155.212034) (xy 240.232183 -155.23992) (xy 240.224063 -155.295096) (xy 240.207995 -155.348503)
			(xy 240.184323 -155.399) (xy 240.15355 -155.445513) (xy 240.116333 -155.48705) (xy 240.073465 -155.522725)
			(xy 240.025859 -155.551779) (xy 239.97453 -155.573591) (xy 239.920573 -155.587697) (xy 239.865136 -155.593797)
			(xy 239.809402 -155.59176) (xy 239.754559 -155.58163) (xy 239.701775 -155.563623) (xy 239.652175 -155.538122)
			(xy 239.606817 -155.505671) (xy 239.566668 -155.466962) (xy 239.532582 -155.422819) (xy 239.505286 -155.374184)
			(xy 239.485363 -155.322093) (xy 239.473237 -155.267656) (xy 239.469166 -155.212034) (xy 238.782107 -155.212034)
			(xy 240.264109 -156.69387) (xy 241.0874 -156.69387) (xy 241.091471 -156.638248) (xy 241.103597 -156.583811)
			(xy 241.12352 -156.53172) (xy 241.150816 -156.483085) (xy 241.184902 -156.438942) (xy 241.225051 -156.400233)
			(xy 241.270409 -156.367782) (xy 241.320009 -156.342281) (xy 241.372793 -156.324274) (xy 241.427636 -156.314144)
			(xy 241.48337 -156.312107) (xy 241.538807 -156.318207) (xy 241.592764 -156.332313) (xy 241.644093 -156.354125)
			(xy 241.691699 -156.383179) (xy 241.734567 -156.418854) (xy 241.771784 -156.460391) (xy 241.802557 -156.506904)
			(xy 241.826229 -156.557401) (xy 241.842297 -156.610808) (xy 241.850417 -156.665984) (xy 241.850926 -156.69387)
			(xy 241.850417 -156.721756) (xy 241.842297 -156.776932) (xy 241.826229 -156.830339) (xy 241.802557 -156.880836)
			(xy 241.771784 -156.927349) (xy 241.734567 -156.968886) (xy 241.691699 -157.004561) (xy 241.644093 -157.033615)
			(xy 241.592764 -157.055427) (xy 241.538807 -157.069533) (xy 241.48337 -157.075633) (xy 241.427636 -157.073596)
			(xy 241.372793 -157.063466) (xy 241.320009 -157.045459) (xy 241.270409 -157.019958) (xy 241.225051 -156.987507)
			(xy 241.184902 -156.948798) (xy 241.150816 -156.904655) (xy 241.12352 -156.85602) (xy 241.103597 -156.803929)
			(xy 241.091471 -156.749492) (xy 241.0874 -156.69387) (xy 240.264109 -156.69387) (xy 240.974372 -157.404054)
			(xy 240.992406 -157.422824) (xy 241.02299 -157.46494) (xy 241.046621 -157.511316) (xy 241.062719 -157.560813)
			(xy 241.070888 -157.612218) (xy 241.0714 -157.638242) (xy 241.0714 -157.647894) (xy 243.21389 -157.647894)
			(xy 243.214426 -157.621251) (xy 243.222949 -157.568653) (xy 243.239806 -157.518105) (xy 243.264559 -157.470919)
			(xy 243.296567 -157.428318) (xy 243.334998 -157.391409) (xy 243.356638 -157.37586) (xy 243.367927 -157.367502)
			(xy 243.385779 -157.345826) (xy 243.397058 -157.320111) (xy 243.400914 -157.292297) (xy 243.397056 -157.264483)
			(xy 243.385775 -157.238768) (xy 243.367922 -157.217094) (xy 243.356638 -157.208728) (xy 243.335036 -157.193131)
			(xy 243.296621 -157.156218) (xy 243.264621 -157.113623) (xy 243.239863 -157.066449) (xy 243.222988 -157.015916)
			(xy 243.214432 -156.963332) (xy 243.21389 -156.936694) (xy 243.2144 -156.910707) (xy 243.22253 -156.859372)
			(xy 243.238591 -156.809942) (xy 243.262187 -156.763632) (xy 243.292737 -156.721584) (xy 243.329488 -156.684833)
			(xy 243.371536 -156.654283) (xy 243.417846 -156.630687) (xy 243.467276 -156.614626) (xy 243.518611 -156.606496)
			(xy 243.570585 -156.606496) (xy 243.62192 -156.614626) (xy 243.67135 -156.630687) (xy 243.71766 -156.654283)
			(xy 243.759708 -156.684833) (xy 243.796459 -156.721584) (xy 243.827009 -156.763632) (xy 243.850605 -156.809942)
			(xy 243.866666 -156.859372) (xy 243.874796 -156.910707) (xy 243.875306 -156.936694) (xy 243.874763 -156.963336)
			(xy 243.866242 -157.015935) (xy 243.849386 -157.066483) (xy 243.824634 -157.113669) (xy 243.792628 -157.156269)
			(xy 243.754198 -157.193179) (xy 243.732558 -157.208728) (xy 243.721281 -157.217101) (xy 243.70343 -157.238774)
			(xy 243.692151 -157.264486) (xy 243.688293 -157.292297) (xy 243.692149 -157.320108) (xy 243.703427 -157.34582)
			(xy 243.721276 -157.367494) (xy 243.732558 -157.37586) (xy 243.754153 -157.391465) (xy 243.792569 -157.428377)
			(xy 243.82457 -157.47097) (xy 243.849329 -157.518142) (xy 243.866205 -157.568673) (xy 243.874763 -157.621257)
			(xy 243.875306 -157.647894) (xy 244.113812 -157.647894) (xy 244.114338 -157.621251) (xy 244.122862 -157.568651)
			(xy 244.13972 -157.518103) (xy 244.164475 -157.470916) (xy 244.196485 -157.428316) (xy 244.234919 -157.391408)
			(xy 244.25656 -157.37586) (xy 244.267847 -157.3675) (xy 244.285695 -157.345824) (xy 244.296971 -157.320109)
			(xy 244.300827 -157.292297) (xy 244.29697 -157.264484) (xy 244.285691 -157.23877) (xy 244.267842 -157.217095)
			(xy 244.25656 -157.208728) (xy 244.234963 -157.193125) (xy 244.196547 -157.156213) (xy 244.164545 -157.11362)
			(xy 244.139786 -157.066447) (xy 244.122911 -157.015915) (xy 244.114354 -156.963332) (xy 244.113812 -156.936694)
			(xy 244.114322 -156.910707) (xy 244.122452 -156.859372) (xy 244.138513 -156.809942) (xy 244.162109 -156.763632)
			(xy 244.192659 -156.721584) (xy 244.22941 -156.684833) (xy 244.271458 -156.654283) (xy 244.317768 -156.630687)
			(xy 244.367198 -156.614626) (xy 244.418533 -156.606496) (xy 244.470507 -156.606496) (xy 244.521842 -156.614626)
			(xy 244.571272 -156.630687) (xy 244.617582 -156.654283) (xy 244.65963 -156.684833) (xy 244.696381 -156.721584)
			(xy 244.726931 -156.763632) (xy 244.750527 -156.809942) (xy 244.766588 -156.859372) (xy 244.774718 -156.910707)
			(xy 244.775228 -156.936694) (xy 244.774719 -156.963338) (xy 244.766195 -157.01594) (xy 244.749335 -157.06649)
			(xy 244.724577 -157.113677) (xy 244.692563 -157.156276) (xy 244.654124 -157.193182) (xy 244.63248 -157.208728)
			(xy 244.621201 -157.2171) (xy 244.603346 -157.238771) (xy 244.592064 -157.264484) (xy 244.588206 -157.292297)
			(xy 244.592063 -157.320109) (xy 244.603343 -157.345823) (xy 244.621196 -157.367495) (xy 244.63248 -157.37586)
			(xy 244.65408 -157.391459) (xy 244.692494 -157.428373) (xy 244.724494 -157.470967) (xy 244.749252 -157.518141)
			(xy 244.766128 -157.568673) (xy 244.774685 -157.621256) (xy 244.775228 -157.647894) (xy 245.013734 -157.647894)
			(xy 245.014251 -157.62125) (xy 245.022775 -157.56865) (xy 245.039635 -157.518101) (xy 245.064392 -157.470914)
			(xy 245.096403 -157.428315) (xy 245.134839 -157.391407) (xy 245.156482 -157.37586) (xy 245.167776 -157.367505)
			(xy 245.185637 -157.345832) (xy 245.196923 -157.320115) (xy 245.200782 -157.292297) (xy 245.196921 -157.264479)
			(xy 245.185634 -157.238763) (xy 245.167771 -157.217091) (xy 245.156482 -157.208728) (xy 245.13489 -157.193118)
			(xy 245.096472 -157.156209) (xy 245.06447 -157.113617) (xy 245.03971 -157.066446) (xy 245.022833 -157.015915)
			(xy 245.014276 -156.963331) (xy 245.013734 -156.936694) (xy 245.014244 -156.910707) (xy 245.022374 -156.859372)
			(xy 245.038435 -156.809942) (xy 245.062031 -156.763632) (xy 245.092581 -156.721584) (xy 245.129332 -156.684833)
			(xy 245.17138 -156.654283) (xy 245.21769 -156.630687) (xy 245.26712 -156.614626) (xy 245.318455 -156.606496)
			(xy 245.370429 -156.606496) (xy 245.421764 -156.614626) (xy 245.471194 -156.630687) (xy 245.517504 -156.654283)
			(xy 245.559552 -156.684833) (xy 245.596303 -156.721584) (xy 245.626853 -156.763632) (xy 245.650449 -156.809942)
			(xy 245.66651 -156.859372) (xy 245.67464 -156.910707) (xy 245.67515 -156.936694) (xy 245.674631 -156.963338)
			(xy 245.666108 -157.015938) (xy 245.649249 -157.066488) (xy 245.624493 -157.113675) (xy 245.592481 -157.156274)
			(xy 245.554045 -157.193181) (xy 245.532402 -157.208728) (xy 245.521121 -157.217099) (xy 245.503263 -157.238769)
			(xy 245.491978 -157.264483) (xy 245.488119 -157.292297) (xy 245.491976 -157.320111) (xy 245.503259 -157.345825)
			(xy 245.521116 -157.367496) (xy 245.532402 -157.37586) (xy 245.553985 -157.391482) (xy 245.592404 -157.428388)
			(xy 245.624408 -157.470977) (xy 245.64917 -157.518146) (xy 245.666048 -157.568676) (xy 245.674607 -157.621257)
			(xy 245.67515 -157.647894) (xy 245.91391 -157.647894) (xy 245.914437 -157.621251) (xy 245.922961 -157.568652)
			(xy 245.939819 -157.518103) (xy 245.964574 -157.470917) (xy 245.996583 -157.428317) (xy 246.035017 -157.391408)
			(xy 246.056658 -157.37586) (xy 246.067946 -157.3675) (xy 246.085793 -157.345824) (xy 246.09707 -157.320109)
			(xy 246.100926 -157.292297) (xy 246.097068 -157.264484) (xy 246.08579 -157.23877) (xy 246.067941 -157.217095)
			(xy 246.056658 -157.208728) (xy 246.035061 -157.193125) (xy 245.996645 -157.156214) (xy 245.964643 -157.11362)
			(xy 245.939884 -157.066447) (xy 245.923009 -157.015915) (xy 245.914452 -156.963332) (xy 245.91391 -156.936694)
			(xy 245.91442 -156.910707) (xy 245.92255 -156.859372) (xy 245.938611 -156.809942) (xy 245.962207 -156.763632)
			(xy 245.992757 -156.721584) (xy 246.029508 -156.684833) (xy 246.071556 -156.654283) (xy 246.117866 -156.630687)
			(xy 246.167296 -156.614626) (xy 246.218631 -156.606496) (xy 246.270605 -156.606496) (xy 246.32194 -156.614626)
			(xy 246.37137 -156.630687) (xy 246.41768 -156.654283) (xy 246.459728 -156.684833) (xy 246.496479 -156.721584)
			(xy 246.527029 -156.763632) (xy 246.550625 -156.809942) (xy 246.566686 -156.859372) (xy 246.574816 -156.910707)
			(xy 246.575326 -156.936694) (xy 246.574817 -156.963338) (xy 246.566294 -157.01594) (xy 246.549434 -157.06649)
			(xy 246.524675 -157.113677) (xy 246.492661 -157.156276) (xy 246.454222 -157.193182) (xy 246.432578 -157.208728)
			(xy 246.421299 -157.2171) (xy 246.403445 -157.238772) (xy 246.392163 -157.264484) (xy 246.388305 -157.292297)
			(xy 246.392161 -157.320109) (xy 246.403441 -157.345823) (xy 246.421294 -157.367495) (xy 246.432578 -157.37586)
			(xy 246.454178 -157.391459) (xy 246.492592 -157.428373) (xy 246.524592 -157.470967) (xy 246.54935 -157.518141)
			(xy 246.566226 -157.568673) (xy 246.574783 -157.621256) (xy 246.575285 -157.645862) (xy 247.52935 -157.645862)
			(xy 247.529776 -157.619546) (xy 247.537017 -157.567416) (xy 247.551343 -157.516771) (xy 247.572483 -157.468572)
			(xy 247.600038 -157.42373) (xy 247.633484 -157.383093) (xy 247.65254 -157.364938) (xy 247.659918 -157.357396)
			(xy 247.668458 -157.338132) (xy 247.66905 -157.3276) (xy 247.66905 -157.252924) (xy 247.668507 -157.242376)
			(xy 247.65998 -157.223082) (xy 247.65254 -157.215586) (xy 247.633473 -157.197442) (xy 247.600019 -157.156808)
			(xy 247.572463 -157.111965) (xy 247.551327 -157.063763) (xy 247.537012 -157.013114) (xy 247.529788 -156.960979)
			(xy 247.52935 -156.934662) (xy 247.529836 -156.907411) (xy 247.537592 -156.853463) (xy 247.552947 -156.801168)
			(xy 247.575589 -156.751591) (xy 247.605055 -156.705741) (xy 247.640746 -156.66455) (xy 247.681937 -156.628859)
			(xy 247.727787 -156.599393) (xy 247.777364 -156.576751) (xy 247.829659 -156.561396) (xy 247.883607 -156.55364)
			(xy 247.938109 -156.55364) (xy 247.992057 -156.561396) (xy 248.044352 -156.576751) (xy 248.093929 -156.599393)
			(xy 248.139779 -156.628859) (xy 248.158524 -156.645101) (xy 249.513918 -156.645101) (xy 249.518234 -156.587828)
			(xy 249.531084 -156.531849) (xy 249.552177 -156.478427) (xy 249.581038 -156.428769) (xy 249.617015 -156.383997)
			(xy 249.637804 -156.364178) (xy 249.645218 -156.356667) (xy 249.653735 -156.337379) (xy 249.654314 -156.32684)
			(xy 249.654314 -156.252164) (xy 249.65376 -156.241617) (xy 249.645242 -156.222322) (xy 249.637804 -156.214826)
			(xy 249.618769 -156.19665) (xy 249.58531 -156.156025) (xy 249.557748 -156.111189) (xy 249.536606 -156.062992)
			(xy 249.522284 -156.012348) (xy 249.515055 -155.960217) (xy 249.514614 -155.933902) (xy 249.5151 -155.906651)
			(xy 249.522856 -155.852703) (xy 249.538211 -155.800408) (xy 249.560853 -155.750831) (xy 249.590319 -155.704981)
			(xy 249.62601 -155.66379) (xy 249.667201 -155.628099) (xy 249.713051 -155.598633) (xy 249.762628 -155.575991)
			(xy 249.814923 -155.560636) (xy 249.868871 -155.55288) (xy 249.923373 -155.55288) (xy 249.977321 -155.560636)
			(xy 250.029616 -155.575991) (xy 250.079193 -155.598633) (xy 250.125043 -155.628099) (xy 250.166234 -155.66379)
			(xy 250.201925 -155.704981) (xy 250.231391 -155.750831) (xy 250.254033 -155.800408) (xy 250.269388 -155.852703)
			(xy 250.277144 -155.906651) (xy 250.27763 -155.933902) (xy 250.277154 -155.960216) (xy 250.26992 -156.012343)
			(xy 250.255602 -156.062986) (xy 250.234471 -156.111184) (xy 250.206927 -156.156028) (xy 250.17349 -156.196669)
			(xy 250.15444 -156.214826) (xy 250.147031 -156.222341) (xy 250.13851 -156.241626) (xy 250.13793 -156.252164)
			(xy 250.13793 -156.32684) (xy 250.138469 -156.337389) (xy 250.146996 -156.356685) (xy 250.15444 -156.364178)
			(xy 250.175229 -156.383997) (xy 250.211202 -156.42877) (xy 250.24006 -156.478428) (xy 250.261151 -156.53185)
			(xy 250.273999 -156.587829) (xy 250.278314 -156.645101) (xy 250.273999 -156.702374) (xy 250.272863 -156.707322)
			(xy 252.579727 -156.707322) (xy 252.584039 -156.650052) (xy 252.596884 -156.594076) (xy 252.617973 -156.540656)
			(xy 252.646828 -156.491) (xy 252.682798 -156.446228) (xy 252.703584 -156.426408) (xy 252.710982 -156.418883)
			(xy 252.719509 -156.399606) (xy 252.720094 -156.38907) (xy 252.720094 -156.314394) (xy 252.719584 -156.303842)
			(xy 252.711036 -156.284547) (xy 252.703584 -156.277056) (xy 252.684511 -156.258918) (xy 252.651056 -156.218284)
			(xy 252.6235 -156.17344) (xy 252.602364 -156.125236) (xy 252.588051 -156.074586) (xy 252.58083 -156.022449)
			(xy 252.580394 -155.996132) (xy 252.58088 -155.968881) (xy 252.588636 -155.914933) (xy 252.603991 -155.862638)
			(xy 252.626633 -155.813061) (xy 252.656099 -155.767211) (xy 252.69179 -155.72602) (xy 252.732981 -155.690329)
			(xy 252.778831 -155.660863) (xy 252.828408 -155.638221) (xy 252.880703 -155.622866) (xy 252.934651 -155.61511)
			(xy 252.989153 -155.61511) (xy 253.043101 -155.622866) (xy 253.095396 -155.638221) (xy 253.144973 -155.660863)
			(xy 253.190823 -155.690329) (xy 253.232014 -155.72602) (xy 253.267705 -155.767211) (xy 253.297171 -155.813061)
			(xy 253.319813 -155.862638) (xy 253.335168 -155.914933) (xy 253.342924 -155.968881) (xy 253.34341 -155.996132)
			(xy 253.342961 -156.022447) (xy 253.335722 -156.074576) (xy 253.321399 -156.125219) (xy 253.300263 -156.173417)
			(xy 253.272714 -156.218261) (xy 253.239273 -156.2589) (xy 253.22022 -156.277056) (xy 253.212839 -156.284595)
			(xy 253.204302 -156.303862) (xy 253.20371 -156.314394) (xy 253.20371 -156.38907) (xy 253.204239 -156.39962)
			(xy 253.212774 -156.418915) (xy 253.22022 -156.426408) (xy 253.24104 -156.446196) (xy 253.277014 -156.490973)
			(xy 253.305873 -156.540636) (xy 253.326964 -156.594062) (xy 253.33981 -156.650045) (xy 253.344123 -156.707322)
			(xy 253.339804 -156.764598) (xy 253.326951 -156.82058) (xy 253.305854 -156.874003) (xy 253.27699 -156.923663)
			(xy 253.24101 -156.968436) (xy 253.22022 -156.988256) (xy 253.212839 -156.995795) (xy 253.204302 -157.015062)
			(xy 253.20371 -157.025594) (xy 253.20371 -157.10027) (xy 253.204239 -157.11082) (xy 253.212774 -157.130115)
			(xy 253.22022 -157.137608) (xy 253.239276 -157.155763) (xy 253.272733 -157.196393) (xy 253.300291 -157.241234)
			(xy 253.321429 -157.289435) (xy 253.335746 -157.340082) (xy 253.342971 -157.392216) (xy 253.34341 -157.418532)
			(xy 253.342924 -157.445783) (xy 253.335168 -157.499731) (xy 253.319813 -157.552026) (xy 253.297171 -157.601603)
			(xy 253.267705 -157.647453) (xy 253.232014 -157.688644) (xy 253.190823 -157.724335) (xy 253.144973 -157.753801)
			(xy 253.095396 -157.776443) (xy 253.043101 -157.791798) (xy 252.989153 -157.799554) (xy 252.934651 -157.799554)
			(xy 252.880703 -157.791798) (xy 252.828408 -157.776443) (xy 252.778831 -157.753801) (xy 252.732981 -157.724335)
			(xy 252.69179 -157.688644) (xy 252.656099 -157.647453) (xy 252.626633 -157.601603) (xy 252.603991 -157.552026)
			(xy 252.588636 -157.499731) (xy 252.58088 -157.445783) (xy 252.580394 -157.418532) (xy 252.580818 -157.392217)
			(xy 252.588062 -157.340086) (xy 252.60239 -157.289443) (xy 252.62353 -157.241244) (xy 252.651084 -157.196402)
			(xy 252.684529 -157.155764) (xy 252.703584 -157.137608) (xy 252.710982 -157.130083) (xy 252.719509 -157.110806)
			(xy 252.720094 -157.10027) (xy 252.720094 -157.025594) (xy 252.719584 -157.015042) (xy 252.711036 -156.995747)
			(xy 252.703584 -156.988256) (xy 252.682828 -156.968404) (xy 252.646852 -156.923636) (xy 252.617991 -156.873983)
			(xy 252.596897 -156.820566) (xy 252.584045 -156.764591) (xy 252.579727 -156.707322) (xy 250.272863 -156.707322)
			(xy 250.26115 -156.758353) (xy 250.240059 -156.811774) (xy 250.2112 -156.861432) (xy 250.175227 -156.906205)
			(xy 250.15444 -156.926026) (xy 250.147031 -156.933541) (xy 250.13851 -156.952826) (xy 250.13793 -156.963364)
			(xy 250.13793 -157.03804) (xy 250.138469 -157.048589) (xy 250.146996 -157.067885) (xy 250.15444 -157.075378)
			(xy 250.173486 -157.093543) (xy 250.206942 -157.134172) (xy 250.234501 -157.17901) (xy 250.255641 -157.227209)
			(xy 250.269961 -157.277854) (xy 250.277189 -157.329987) (xy 250.27763 -157.356302) (xy 250.277144 -157.383553)
			(xy 250.269388 -157.437501) (xy 250.254033 -157.489796) (xy 250.231391 -157.539373) (xy 250.201925 -157.585223)
			(xy 250.166234 -157.626414) (xy 250.125043 -157.662105) (xy 250.079193 -157.691571) (xy 250.029616 -157.714213)
			(xy 249.977321 -157.729568) (xy 249.923373 -157.737324) (xy 249.868871 -157.737324) (xy 249.814923 -157.729568)
			(xy 249.762628 -157.714213) (xy 249.713051 -157.691571) (xy 249.667201 -157.662105) (xy 249.62601 -157.626414)
			(xy 249.590319 -157.585223) (xy 249.560853 -157.539373) (xy 249.538211 -157.489796) (xy 249.522856 -157.437501)
			(xy 249.5151 -157.383553) (xy 249.514614 -157.356302) (xy 249.515078 -157.329988) (xy 249.522313 -157.277859)
			(xy 249.536633 -157.227216) (xy 249.557766 -157.179017) (xy 249.585312 -157.134174) (xy 249.618752 -157.093534)
			(xy 249.637804 -157.075378) (xy 249.645218 -157.067867) (xy 249.653735 -157.048579) (xy 249.654314 -157.03804)
			(xy 249.654314 -156.963364) (xy 249.65376 -156.952817) (xy 249.645242 -156.933522) (xy 249.637804 -156.926026)
			(xy 249.617017 -156.906205) (xy 249.58104 -156.861433) (xy 249.552178 -156.811776) (xy 249.531084 -156.758354)
			(xy 249.518234 -156.702374) (xy 249.513918 -156.645101) (xy 248.158524 -156.645101) (xy 248.18097 -156.66455)
			(xy 248.216661 -156.705741) (xy 248.246127 -156.751591) (xy 248.268769 -156.801168) (xy 248.284124 -156.853463)
			(xy 248.29188 -156.907411) (xy 248.292366 -156.934662) (xy 248.291951 -156.960978) (xy 248.284707 -157.013109)
			(xy 248.270378 -157.063753) (xy 248.249236 -157.111952) (xy 248.22168 -157.156794) (xy 248.188232 -157.197431)
			(xy 248.169176 -157.215586) (xy 248.16179 -157.223121) (xy 248.153254 -157.24239) (xy 248.152666 -157.252924)
			(xy 248.152666 -157.3276) (xy 248.153192 -157.33815) (xy 248.16173 -157.357444) (xy 248.169176 -157.364938)
			(xy 248.188238 -157.383087) (xy 248.221696 -157.423717) (xy 248.249255 -157.468559) (xy 248.270392 -157.516761)
			(xy 248.284707 -157.56741) (xy 248.291929 -157.619545) (xy 248.292366 -157.645862) (xy 248.29188 -157.673113)
			(xy 248.284124 -157.727061) (xy 248.268769 -157.779356) (xy 248.246127 -157.828933) (xy 248.216661 -157.874783)
			(xy 248.18097 -157.915974) (xy 248.139779 -157.951665) (xy 248.093929 -157.981131) (xy 248.044352 -158.003773)
			(xy 247.992057 -158.019128) (xy 247.938109 -158.026884) (xy 247.883607 -158.026884) (xy 247.829659 -158.019128)
			(xy 247.777364 -158.003773) (xy 247.727787 -157.981131) (xy 247.681937 -157.951665) (xy 247.640746 -157.915974)
			(xy 247.605055 -157.874783) (xy 247.575589 -157.828933) (xy 247.552947 -157.779356) (xy 247.537592 -157.727061)
			(xy 247.529836 -157.673113) (xy 247.52935 -157.645862) (xy 246.575285 -157.645862) (xy 246.575326 -157.647894)
			(xy 246.574816 -157.673881) (xy 246.566686 -157.725216) (xy 246.550625 -157.774646) (xy 246.527029 -157.820956)
			(xy 246.496479 -157.863004) (xy 246.459728 -157.899755) (xy 246.41768 -157.930305) (xy 246.37137 -157.953901)
			(xy 246.32194 -157.969962) (xy 246.270605 -157.978092) (xy 246.218631 -157.978092) (xy 246.167296 -157.969962)
			(xy 246.117866 -157.953901) (xy 246.071556 -157.930305) (xy 246.029508 -157.899755) (xy 245.992757 -157.863004)
			(xy 245.962207 -157.820956) (xy 245.938611 -157.774646) (xy 245.92255 -157.725216) (xy 245.91442 -157.673881)
			(xy 245.91391 -157.647894) (xy 245.67515 -157.647894) (xy 245.67464 -157.673881) (xy 245.66651 -157.725216)
			(xy 245.650449 -157.774646) (xy 245.626853 -157.820956) (xy 245.596303 -157.863004) (xy 245.559552 -157.899755)
			(xy 245.517504 -157.930305) (xy 245.471194 -157.953901) (xy 245.421764 -157.969962) (xy 245.370429 -157.978092)
			(xy 245.318455 -157.978092) (xy 245.26712 -157.969962) (xy 245.21769 -157.953901) (xy 245.17138 -157.930305)
			(xy 245.129332 -157.899755) (xy 245.092581 -157.863004) (xy 245.062031 -157.820956) (xy 245.038435 -157.774646)
			(xy 245.022374 -157.725216) (xy 245.014244 -157.673881) (xy 245.013734 -157.647894) (xy 244.775228 -157.647894)
			(xy 244.774718 -157.673881) (xy 244.766588 -157.725216) (xy 244.750527 -157.774646) (xy 244.726931 -157.820956)
			(xy 244.696381 -157.863004) (xy 244.65963 -157.899755) (xy 244.617582 -157.930305) (xy 244.571272 -157.953901)
			(xy 244.521842 -157.969962) (xy 244.470507 -157.978092) (xy 244.418533 -157.978092) (xy 244.367198 -157.969962)
			(xy 244.317768 -157.953901) (xy 244.271458 -157.930305) (xy 244.22941 -157.899755) (xy 244.192659 -157.863004)
			(xy 244.162109 -157.820956) (xy 244.138513 -157.774646) (xy 244.122452 -157.725216) (xy 244.114322 -157.673881)
			(xy 244.113812 -157.647894) (xy 243.875306 -157.647894) (xy 243.874796 -157.673881) (xy 243.866666 -157.725216)
			(xy 243.850605 -157.774646) (xy 243.827009 -157.820956) (xy 243.796459 -157.863004) (xy 243.759708 -157.899755)
			(xy 243.71766 -157.930305) (xy 243.67135 -157.953901) (xy 243.62192 -157.969962) (xy 243.570585 -157.978092)
			(xy 243.518611 -157.978092) (xy 243.467276 -157.969962) (xy 243.417846 -157.953901) (xy 243.371536 -157.930305)
			(xy 243.329488 -157.899755) (xy 243.292737 -157.863004) (xy 243.262187 -157.820956) (xy 243.238591 -157.774646)
			(xy 243.22253 -157.725216) (xy 243.2144 -157.673881) (xy 243.21389 -157.647894) (xy 241.0714 -157.647894)
			(xy 241.0714 -157.682438) (xy 241.08029 -157.691582) (xy 241.085878 -157.696154) (xy 241.164364 -157.73908)
			(xy 241.167666 -157.74035) (xy 241.17427 -157.743398) (xy 241.189764 -157.74543) (xy 241.20221 -157.743398)
			(xy 241.216688 -157.738572) (xy 241.22253 -157.735016) (xy 241.245101 -157.721704) (xy 241.293117 -157.700717)
			(xy 241.343556 -157.686506) (xy 241.395465 -157.679337) (xy 241.421666 -157.678882) (xy 241.448921 -157.679343)
			(xy 241.502877 -157.687096) (xy 241.555181 -157.702449) (xy 241.604766 -157.72509) (xy 241.650625 -157.754558)
			(xy 241.691823 -157.790253) (xy 241.727521 -157.831448) (xy 241.756993 -157.877304) (xy 241.779639 -157.926887)
			(xy 241.794997 -157.979189) (xy 241.802755 -158.033145) (xy 241.802755 -158.087655) (xy 241.798056 -158.120334)
			(xy 254.350264 -158.120334) (xy 254.354335 -158.064712) (xy 254.366461 -158.010275) (xy 254.386384 -157.958184)
			(xy 254.41368 -157.909549) (xy 254.447766 -157.865406) (xy 254.487915 -157.826697) (xy 254.533273 -157.794246)
			(xy 254.582873 -157.768745) (xy 254.635657 -157.750738) (xy 254.6905 -157.740608) (xy 254.746234 -157.738571)
			(xy 254.801671 -157.744671) (xy 254.855628 -157.758777) (xy 254.906957 -157.780589) (xy 254.954563 -157.809643)
			(xy 254.997431 -157.845318) (xy 255.034648 -157.886855) (xy 255.065421 -157.933368) (xy 255.089093 -157.983865)
			(xy 255.105161 -158.037272) (xy 255.113281 -158.092448) (xy 255.11379 -158.120334) (xy 255.113281 -158.14822)
			(xy 255.105161 -158.203396) (xy 255.089093 -158.256803) (xy 255.065421 -158.3073) (xy 255.034648 -158.353813)
			(xy 254.997431 -158.39535) (xy 254.954563 -158.431025) (xy 254.906957 -158.460079) (xy 254.855628 -158.481891)
			(xy 254.801671 -158.495997) (xy 254.746234 -158.502097) (xy 254.6905 -158.50006) (xy 254.635657 -158.48993)
			(xy 254.582873 -158.471923) (xy 254.533273 -158.446422) (xy 254.487915 -158.413971) (xy 254.447766 -158.375262)
			(xy 254.41368 -158.331119) (xy 254.386384 -158.282484) (xy 254.366461 -158.230393) (xy 254.354335 -158.175956)
			(xy 254.350264 -158.120334) (xy 241.798056 -158.120334) (xy 241.794997 -158.141611) (xy 241.779639 -158.193913)
			(xy 241.756993 -158.243496) (xy 241.727521 -158.289352) (xy 241.691823 -158.330547) (xy 241.650625 -158.366242)
			(xy 241.604766 -158.39571) (xy 241.555181 -158.418351) (xy 241.502877 -158.433704) (xy 241.448921 -158.441457)
			(xy 241.421666 -158.441898) (xy 241.421412 -158.441898) (xy 241.395067 -158.441451) (xy 241.342877 -158.434205)
			(xy 241.292176 -158.419862) (xy 241.243924 -158.398694) (xy 241.22126 -158.385256) (xy 241.216434 -158.382208)
			(xy 241.20094 -158.376874) (xy 241.192304 -158.376366) (xy 241.191542 -158.376366) (xy 241.18443 -158.375858)
			(xy 241.17808 -158.377128) (xy 241.174436 -158.377937) (xy 241.16742 -158.380484) (xy 241.16411 -158.382208)
			(xy 241.128804 -158.401258) (xy 241.128296 -158.401258) (xy 241.08664 -158.424372) (xy 241.079274 -158.429452)
			(xy 241.0714 -158.437834) (xy 241.0714 -158.753302) (xy 248.716544 -158.753302) (xy 248.720615 -158.69768)
			(xy 248.732741 -158.643243) (xy 248.752664 -158.591152) (xy 248.77996 -158.542517) (xy 248.814046 -158.498374)
			(xy 248.854195 -158.459665) (xy 248.899553 -158.427214) (xy 248.949153 -158.401713) (xy 249.001937 -158.383706)
			(xy 249.05678 -158.373576) (xy 249.112514 -158.371539) (xy 249.167951 -158.377639) (xy 249.221908 -158.391745)
			(xy 249.273237 -158.413557) (xy 249.320843 -158.442611) (xy 249.363711 -158.478286) (xy 249.400928 -158.519823)
			(xy 249.431701 -158.566336) (xy 249.455373 -158.616833) (xy 249.471441 -158.67024) (xy 249.479561 -158.725416)
			(xy 249.48007 -158.753302) (xy 249.479561 -158.781188) (xy 249.471441 -158.836364) (xy 249.455373 -158.889771)
			(xy 249.431701 -158.940268) (xy 249.400928 -158.986781) (xy 249.363711 -159.028318) (xy 249.320843 -159.063993)
			(xy 249.273237 -159.093047) (xy 249.221908 -159.114859) (xy 249.167951 -159.128965) (xy 249.112514 -159.135065)
			(xy 249.05678 -159.133028) (xy 249.001937 -159.122898) (xy 248.949153 -159.104891) (xy 248.899553 -159.07939)
			(xy 248.854195 -159.046939) (xy 248.814046 -159.00823) (xy 248.77996 -158.964087) (xy 248.752664 -158.915452)
			(xy 248.732741 -158.863361) (xy 248.720615 -158.808924) (xy 248.716544 -158.753302) (xy 241.0714 -158.753302)
			(xy 241.0714 -159.113728) (xy 241.075266 -159.118591) (xy 241.084901 -159.126429) (xy 241.09045 -159.129222)
			(xy 241.14125 -159.151828) (xy 241.176048 -159.167322) (xy 241.187478 -159.170116) (xy 241.192558 -159.17037)
			(xy 241.203988 -159.169354) (xy 241.212878 -159.16656) (xy 241.221514 -159.16402) (xy 241.22634 -159.16148)
			(xy 241.230658 -159.15894) (xy 241.23142 -159.158432) (xy 241.234976 -159.15513) (xy 241.255951 -159.136982)
			(xy 241.302164 -159.106313) (xy 241.352329 -159.082657) (xy 241.405391 -159.066512) (xy 241.460231 -159.058219)
			(xy 241.48796 -159.057594) (xy 241.493294 -159.057594) (xy 241.520392 -159.058303) (xy 241.573983 -159.066438)
			(xy 241.625883 -159.082077) (xy 241.675048 -159.104904) (xy 241.720487 -159.13446) (xy 241.761285 -159.170149)
			(xy 241.79662 -159.211254) (xy 241.825782 -159.256946) (xy 241.848184 -159.306306) (xy 241.863373 -159.35834)
			(xy 241.871045 -159.411999) (xy 241.8715 -159.439102) (xy 241.870997 -159.466899) (xy 241.862926 -159.521903)
			(xy 241.859954 -159.531812) (xy 244.312692 -159.531812) (xy 244.316763 -159.47619) (xy 244.328889 -159.421753)
			(xy 244.348812 -159.369662) (xy 244.376108 -159.321027) (xy 244.410194 -159.276884) (xy 244.450343 -159.238175)
			(xy 244.495701 -159.205724) (xy 244.545301 -159.180223) (xy 244.598085 -159.162216) (xy 244.652928 -159.152086)
			(xy 244.708662 -159.150049) (xy 244.764099 -159.156149) (xy 244.818056 -159.170255) (xy 244.869385 -159.192067)
			(xy 244.916991 -159.221121) (xy 244.959859 -159.256796) (xy 244.997076 -159.298333) (xy 245.027849 -159.344846)
			(xy 245.051521 -159.395343) (xy 245.067589 -159.44875) (xy 245.073458 -159.488632) (xy 246.595898 -159.488632)
			(xy 246.599969 -159.43301) (xy 246.612095 -159.378573) (xy 246.632018 -159.326482) (xy 246.659314 -159.277847)
			(xy 246.6934 -159.233704) (xy 246.733549 -159.194995) (xy 246.778907 -159.162544) (xy 246.828507 -159.137043)
			(xy 246.881291 -159.119036) (xy 246.936134 -159.108906) (xy 246.991868 -159.106869) (xy 247.047305 -159.112969)
			(xy 247.101262 -159.127075) (xy 247.152591 -159.148887) (xy 247.200197 -159.177941) (xy 247.243065 -159.213616)
			(xy 247.280282 -159.255153) (xy 247.311055 -159.301666) (xy 247.334727 -159.352163) (xy 247.350795 -159.40557)
			(xy 247.355708 -159.438952) (xy 254.026648 -159.438952) (xy 254.026648 -159.384448) (xy 254.034404 -159.330499)
			(xy 254.049759 -159.278202) (xy 254.0724 -159.228623) (xy 254.101865 -159.18277) (xy 254.137557 -159.141578)
			(xy 254.178746 -159.105883) (xy 254.224597 -159.076414) (xy 254.274174 -159.053769) (xy 254.326469 -159.03841)
			(xy 254.380418 -159.03065) (xy 254.40767 -159.030162) (xy 254.435751 -159.030658) (xy 254.491306 -159.038901)
			(xy 254.545052 -159.0552) (xy 254.595828 -159.079201) (xy 254.642537 -159.110386) (xy 254.68417 -159.148082)
			(xy 254.719827 -159.191473) (xy 254.748738 -159.239623) (xy 254.759968 -159.265366) (xy 254.759968 -159.26562)
			(xy 254.763928 -159.273997) (xy 254.776689 -159.287413) (xy 254.78486 -159.291782) (xy 254.846328 -159.320992)
			(xy 254.854941 -159.324636) (xy 254.873575 -159.326052) (xy 254.88265 -159.323786) (xy 254.908861 -159.316581)
			(xy 254.96266 -159.308809) (xy 254.989838 -159.308292) (xy 254.9906 -159.308292) (xy 255.017851 -159.308778)
			(xy 255.071799 -159.316534) (xy 255.124094 -159.331889) (xy 255.173671 -159.354531) (xy 255.219521 -159.383997)
			(xy 255.260712 -159.419688) (xy 255.296403 -159.460879) (xy 255.325869 -159.506729) (xy 255.348511 -159.556306)
			(xy 255.363866 -159.608601) (xy 255.371622 -159.662549) (xy 255.371622 -159.717051) (xy 255.363866 -159.770999)
			(xy 255.348511 -159.823294) (xy 255.325869 -159.872871) (xy 255.296403 -159.918721) (xy 255.260712 -159.959912)
			(xy 255.219521 -159.995603) (xy 255.173671 -160.025069) (xy 255.124094 -160.047711) (xy 255.071799 -160.063066)
			(xy 255.017851 -160.070822) (xy 254.9906 -160.071308) (xy 254.96252 -160.070794) (xy 254.906968 -160.062549)
			(xy 254.853225 -160.04625) (xy 254.802451 -160.02225) (xy 254.755743 -159.991067) (xy 254.71411 -159.953376)
			(xy 254.67845 -159.909989) (xy 254.649535 -159.861844) (xy 254.638302 -159.836104) (xy 254.638302 -159.83585)
			(xy 254.634361 -159.827462) (xy 254.621587 -159.814052) (xy 254.61341 -159.809688) (xy 254.551942 -159.780478)
			(xy 254.543317 -159.77687) (xy 254.524693 -159.775432) (xy 254.51562 -159.777684) (xy 254.489406 -159.784874)
			(xy 254.435609 -159.792656) (xy 254.408432 -159.793178) (xy 254.40767 -159.793178) (xy 254.380418 -159.79275)
			(xy 254.326469 -159.78499) (xy 254.274174 -159.769631) (xy 254.224597 -159.746986) (xy 254.178746 -159.717517)
			(xy 254.137557 -159.681822) (xy 254.101865 -159.64063) (xy 254.0724 -159.594777) (xy 254.049759 -159.545198)
			(xy 254.034404 -159.492901) (xy 254.026648 -159.438952) (xy 247.355708 -159.438952) (xy 247.358915 -159.460746)
			(xy 247.359424 -159.488632) (xy 247.358915 -159.516518) (xy 247.350795 -159.571694) (xy 247.334727 -159.625101)
			(xy 247.311055 -159.675598) (xy 247.280282 -159.722111) (xy 247.243065 -159.763648) (xy 247.200197 -159.799323)
			(xy 247.152591 -159.828377) (xy 247.101262 -159.850189) (xy 247.047305 -159.864295) (xy 246.991868 -159.870395)
			(xy 246.936134 -159.868358) (xy 246.881291 -159.858228) (xy 246.828507 -159.840221) (xy 246.778907 -159.81472)
			(xy 246.733549 -159.782269) (xy 246.6934 -159.74356) (xy 246.659314 -159.699417) (xy 246.632018 -159.650782)
			(xy 246.612095 -159.598691) (xy 246.599969 -159.544254) (xy 246.595898 -159.488632) (xy 245.073458 -159.488632)
			(xy 245.075709 -159.503926) (xy 245.076218 -159.531812) (xy 245.075709 -159.559698) (xy 245.067589 -159.614874)
			(xy 245.051521 -159.668281) (xy 245.027849 -159.718778) (xy 244.997076 -159.765291) (xy 244.959859 -159.806828)
			(xy 244.916991 -159.842503) (xy 244.869385 -159.871557) (xy 244.818056 -159.893369) (xy 244.764099 -159.907475)
			(xy 244.708662 -159.913575) (xy 244.652928 -159.911538) (xy 244.598085 -159.901408) (xy 244.545301 -159.883401)
			(xy 244.495701 -159.8579) (xy 244.450343 -159.825449) (xy 244.410194 -159.78674) (xy 244.376108 -159.742597)
			(xy 244.348812 -159.693962) (xy 244.328889 -159.641871) (xy 244.316763 -159.587434) (xy 244.312692 -159.531812)
			(xy 241.859954 -159.531812) (xy 241.846954 -159.575153) (xy 241.823421 -159.62552) (xy 241.792825 -159.671937)
			(xy 241.755814 -159.71342) (xy 241.713173 -159.74909) (xy 241.665804 -159.778192) (xy 241.614713 -159.800108)
			(xy 241.560981 -159.814375) (xy 241.533426 -159.81807) (xy 241.504978 -159.820356) (xy 241.502946 -159.820356)
			(xy 241.4905 -159.82061) (xy 241.48669 -159.82061) (xy 241.464338 -159.819848) (xy 241.439326 -159.817759)
			(xy 241.390124 -159.807843) (xy 241.342645 -159.791568) (xy 241.297706 -159.769213) (xy 241.256084 -159.741164)
			(xy 241.237008 -159.724852) (xy 241.23269 -159.721042) (xy 241.219228 -159.713676) (xy 241.208681 -159.708498)
			(xy 241.185238 -159.707433) (xy 241.17427 -159.711644) (xy 241.16792 -159.714438) (xy 241.167158 -159.714946)
			(xy 241.105436 -159.74187) (xy 241.09426 -159.749744) (xy 241.090958 -159.753046) (xy 241.086386 -159.758634)
			(xy 241.081052 -159.766254) (xy 241.076671 -159.772827) (xy 241.07175 -159.787827) (xy 241.0714 -159.795718)
			(xy 241.0714 -160.67024) (xy 241.073913 -160.673432) (xy 241.079784 -160.679047) (xy 241.083084 -160.681416)
			(xy 241.090196 -160.686242) (xy 241.169698 -160.716976) (xy 241.170206 -160.716976) (xy 241.17935 -160.720786)
			(xy 241.189265 -160.724806) (xy 241.21064 -160.724997) (xy 241.230225 -160.716434) (xy 241.23777 -160.708848)
			(xy 241.240564 -160.7058) (xy 241.257328 -160.688782) (xy 241.266218 -160.680654) (xy 241.266472 -160.6804)
			(xy 241.28638 -160.663319) (xy 241.330024 -160.634218) (xy 241.377248 -160.611383) (xy 241.42716 -160.595247)
			(xy 241.452908 -160.59023) (xy 241.469032 -160.58755) (xy 241.501589 -160.584625) (xy 241.517932 -160.584388)
			(xy 241.521234 -160.584388) (xy 241.548414 -160.584978) (xy 241.602196 -160.592911) (xy 241.654307 -160.608399)
			(xy 241.703692 -160.631127) (xy 241.74935 -160.660635) (xy 241.790358 -160.696326) (xy 241.825884 -160.737476)
			(xy 241.855208 -160.783252) (xy 241.877738 -160.832728) (xy 241.893016 -160.884901) (xy 241.900734 -160.938714)
			(xy 241.901182 -160.963864) (xy 242.529612 -160.963864) (xy 242.533683 -160.908242) (xy 242.545809 -160.853805)
			(xy 242.565732 -160.801714) (xy 242.593028 -160.753079) (xy 242.627114 -160.708936) (xy 242.667263 -160.670227)
			(xy 242.712621 -160.637776) (xy 242.762221 -160.612275) (xy 242.815005 -160.594268) (xy 242.869848 -160.584138)
			(xy 242.925582 -160.582101) (xy 242.981019 -160.588201) (xy 243.034976 -160.602307) (xy 243.086305 -160.624119)
			(xy 243.133911 -160.653173) (xy 243.176779 -160.688848) (xy 243.213996 -160.730385) (xy 243.244769 -160.776898)
			(xy 243.268441 -160.827395) (xy 243.284509 -160.880802) (xy 243.292629 -160.935978) (xy 243.293138 -160.963864)
			(xy 243.293045 -160.968944) (xy 243.80139 -160.968944) (xy 243.805461 -160.913322) (xy 243.817587 -160.858885)
			(xy 243.83751 -160.806794) (xy 243.864806 -160.758159) (xy 243.898892 -160.714016) (xy 243.939041 -160.675307)
			(xy 243.984399 -160.642856) (xy 244.033999 -160.617355) (xy 244.086783 -160.599348) (xy 244.141626 -160.589218)
			(xy 244.19736 -160.587181) (xy 244.252797 -160.593281) (xy 244.306754 -160.607387) (xy 244.358083 -160.629199)
			(xy 244.405689 -160.658253) (xy 244.448557 -160.693928) (xy 244.485774 -160.735465) (xy 244.516547 -160.781978)
			(xy 244.540219 -160.832475) (xy 244.556287 -160.885882) (xy 244.55868 -160.902142) (xy 245.582692 -160.902142)
			(xy 245.586763 -160.84652) (xy 245.598889 -160.792083) (xy 245.618812 -160.739992) (xy 245.646108 -160.691357)
			(xy 245.680194 -160.647214) (xy 245.720343 -160.608505) (xy 245.765701 -160.576054) (xy 245.815301 -160.550553)
			(xy 245.868085 -160.532546) (xy 245.922928 -160.522416) (xy 245.978662 -160.520379) (xy 246.034099 -160.526479)
			(xy 246.088056 -160.540585) (xy 246.139385 -160.562397) (xy 246.186991 -160.591451) (xy 246.229859 -160.627126)
			(xy 246.267076 -160.668663) (xy 246.297849 -160.715176) (xy 246.321521 -160.765673) (xy 246.337589 -160.81908)
			(xy 246.345709 -160.874256) (xy 246.346218 -160.902142) (xy 246.345709 -160.930028) (xy 246.337589 -160.985204)
			(xy 246.321521 -161.038611) (xy 246.297849 -161.089108) (xy 246.267076 -161.135621) (xy 246.229859 -161.177158)
			(xy 246.186991 -161.212833) (xy 246.139385 -161.241887) (xy 246.088056 -161.263699) (xy 246.034099 -161.277805)
			(xy 245.978662 -161.283905) (xy 245.922928 -161.281868) (xy 245.868085 -161.271738) (xy 245.815301 -161.253731)
			(xy 245.765701 -161.22823) (xy 245.720343 -161.195779) (xy 245.680194 -161.15707) (xy 245.646108 -161.112927)
			(xy 245.618812 -161.064292) (xy 245.598889 -161.012201) (xy 245.586763 -160.957764) (xy 245.582692 -160.902142)
			(xy 244.55868 -160.902142) (xy 244.564407 -160.941058) (xy 244.564916 -160.968944) (xy 244.564407 -160.99683)
			(xy 244.556287 -161.052006) (xy 244.540219 -161.105413) (xy 244.516547 -161.15591) (xy 244.485774 -161.202423)
			(xy 244.448557 -161.24396) (xy 244.405689 -161.279635) (xy 244.358083 -161.308689) (xy 244.306754 -161.330501)
			(xy 244.252797 -161.344607) (xy 244.19736 -161.350707) (xy 244.141626 -161.34867) (xy 244.086783 -161.33854)
			(xy 244.033999 -161.320533) (xy 243.984399 -161.295032) (xy 243.939041 -161.262581) (xy 243.898892 -161.223872)
			(xy 243.864806 -161.179729) (xy 243.83751 -161.131094) (xy 243.817587 -161.079003) (xy 243.805461 -161.024566)
			(xy 243.80139 -160.968944) (xy 243.293045 -160.968944) (xy 243.292629 -160.99175) (xy 243.284509 -161.046926)
			(xy 243.268441 -161.100333) (xy 243.244769 -161.15083) (xy 243.213996 -161.197343) (xy 243.176779 -161.23888)
			(xy 243.133911 -161.274555) (xy 243.086305 -161.303609) (xy 243.034976 -161.325421) (xy 242.981019 -161.339527)
			(xy 242.925582 -161.345627) (xy 242.869848 -161.34359) (xy 242.815005 -161.33346) (xy 242.762221 -161.315453)
			(xy 242.712621 -161.289952) (xy 242.667263 -161.257501) (xy 242.627114 -161.218792) (xy 242.593028 -161.174649)
			(xy 242.565732 -161.126014) (xy 242.545809 -161.073923) (xy 242.533683 -161.019486) (xy 242.529612 -160.963864)
			(xy 241.901182 -160.963864) (xy 241.901218 -160.965896) (xy 241.900732 -160.993148) (xy 241.892977 -161.047096)
			(xy 241.877622 -161.099392) (xy 241.854981 -161.148971) (xy 241.825515 -161.194822) (xy 241.789824 -161.236014)
			(xy 241.748633 -161.271707) (xy 241.702783 -161.301174) (xy 241.653205 -161.323817) (xy 241.60091 -161.339174)
			(xy 241.546962 -161.346931) (xy 241.51971 -161.347404) (xy 241.519202 -161.347404) (xy 241.490373 -161.346839)
			(xy 241.43338 -161.338092) (xy 241.378351 -161.320873) (xy 241.326538 -161.295572) (xy 241.30254 -161.279586)
			(xy 241.285803 -161.267695) (xy 241.254745 -161.240839) (xy 241.240564 -161.225992) (xy 241.23777 -161.222944)
			(xy 241.230148 -161.215481) (xy 241.210602 -161.206999) (xy 241.189296 -161.207147) (xy 241.17935 -161.211006)
			(xy 241.170206 -161.214816) (xy 241.169698 -161.214816) (xy 241.092482 -161.245042) (xy 241.087976 -161.247051)
			(xy 241.079785 -161.252548) (xy 241.076226 -161.255964) (xy 241.075718 -161.256472) (xy 241.0714 -161.261298)
			(xy 241.0714 -161.9504) (xy 255.091182 -161.9504) (xy 255.095253 -161.894778) (xy 255.107379 -161.840341)
			(xy 255.127302 -161.78825) (xy 255.154598 -161.739615) (xy 255.188684 -161.695472) (xy 255.228833 -161.656763)
			(xy 255.274191 -161.624312) (xy 255.323791 -161.598811) (xy 255.376575 -161.580804) (xy 255.431418 -161.570674)
			(xy 255.487152 -161.568637) (xy 255.542589 -161.574737) (xy 255.596546 -161.588843) (xy 255.647875 -161.610655)
			(xy 255.695481 -161.639709) (xy 255.738349 -161.675384) (xy 255.775566 -161.716921) (xy 255.806339 -161.763434)
			(xy 255.830011 -161.813931) (xy 255.846079 -161.867338) (xy 255.854199 -161.922514) (xy 255.854708 -161.9504)
			(xy 255.854199 -161.978286) (xy 255.846079 -162.033462) (xy 255.830011 -162.086869) (xy 255.806339 -162.137366)
			(xy 255.775566 -162.183879) (xy 255.738349 -162.225416) (xy 255.695481 -162.261091) (xy 255.647875 -162.290145)
			(xy 255.596546 -162.311957) (xy 255.542589 -162.326063) (xy 255.487152 -162.332163) (xy 255.431418 -162.330126)
			(xy 255.376575 -162.319996) (xy 255.323791 -162.301989) (xy 255.274191 -162.276488) (xy 255.228833 -162.244037)
			(xy 255.188684 -162.205328) (xy 255.154598 -162.161185) (xy 255.127302 -162.11255) (xy 255.107379 -162.060459)
			(xy 255.095253 -162.006022) (xy 255.091182 -161.9504) (xy 241.0714 -161.9504) (xy 241.0714 -163.0807)
			(xy 241.071908 -163.08832) (xy 241.073399 -163.096142) (xy 241.080513 -163.110377) (xy 241.085878 -163.11626)
			(xy 241.95405 -163.984178) (xy 242.381786 -164.411914) (xy 242.386029 -164.415849) (xy 242.395904 -164.421878)
			(xy 242.401344 -164.423852) (xy 242.40524 -164.42503) (xy 242.413277 -164.426301) (xy 242.417346 -164.426392)
			(xy 246.82958 -164.426392) (xy 246.839232 -164.425376) (xy 246.846478 -164.423751) (xy 246.859651 -164.416914)
			(xy 246.86514 -164.411914) (xy 248.250456 -163.026598) (xy 248.258076 -163.016946) (xy 248.266966 -163.00196)
			(xy 248.26722 -163.001452) (xy 248.275668 -162.975886) (xy 248.298748 -162.927239) (xy 248.328434 -162.882317)
			(xy 248.364138 -162.842013) (xy 248.405151 -162.807125) (xy 248.450659 -162.778347) (xy 248.499759 -162.756248)
			(xy 248.551478 -162.741268) (xy 248.604788 -162.733704) (xy 248.63171 -162.733228) (xy 248.658961 -162.733692)
			(xy 248.712909 -162.74145) (xy 248.765204 -162.756808) (xy 248.814781 -162.779451) (xy 248.86063 -162.80892)
			(xy 248.901818 -162.844614) (xy 248.937508 -162.885807) (xy 248.966971 -162.93166) (xy 248.989608 -162.981239)
			(xy 249.004959 -163.033536) (xy 249.012711 -163.087484) (xy 249.013218 -163.114736) (xy 249.01276 -163.141649)
			(xy 249.005199 -163.194942) (xy 248.99022 -163.246641) (xy 248.968118 -163.295721) (xy 248.939335 -163.341204)
			(xy 248.904441 -163.382188) (xy 248.86413 -163.417858) (xy 248.819204 -163.447504) (xy 248.770556 -163.470538)
			(xy 248.744994 -163.478972) (xy 248.741184 -163.480242) (xy 248.733818 -163.484052) (xy 248.72442 -163.491418)
			(xy 247.222772 -164.993066) (xy 247.203993 -165.011181) (xy 247.161797 -165.041871) (xy 247.115316 -165.065575)
			(xy 247.065697 -165.08171) (xy 247.014164 -165.089875) (xy 246.988076 -165.090348) (xy 242.25885 -165.090348)
			(xy 242.232764 -165.089858) (xy 242.181237 -165.081684) (xy 242.131624 -165.065546) (xy 242.085149 -165.041841)
			(xy 242.042957 -165.011154) (xy 242.024154 -164.993066) (xy 241.895122 -164.864034) (xy 241.890356 -164.8602)
			(xy 241.879445 -164.854679) (xy 241.873532 -164.853112) (xy 241.858785 -164.85086) (xy 241.829135 -164.854027)
			(xy 241.80166 -164.865615) (xy 241.778699 -164.88464) (xy 241.762205 -164.909481) (xy 241.753581 -164.938025)
			(xy 241.753136 -164.952934) (xy 241.753136 -169.334434) (xy 242.068096 -169.334434) (xy 242.06854 -169.307523)
			(xy 242.076125 -169.254238) (xy 242.091122 -169.202547) (xy 242.113233 -169.153476) (xy 242.142019 -169.107998)
			(xy 242.176909 -169.067016) (xy 242.217211 -169.031343) (xy 242.262125 -169.001686) (xy 242.310761 -168.978634)
			(xy 242.33632 -168.970198) (xy 242.336574 -168.970198) (xy 242.342267 -168.968218) (xy 242.352541 -168.961922)
			(xy 242.356894 -168.957752) (xy 244.42928 -166.885366) (xy 244.448077 -166.867271) (xy 244.49027 -166.836583)
			(xy 244.536747 -166.812879) (xy 244.586361 -166.796743) (xy 244.63789 -166.788572) (xy 244.663976 -166.788084)
			(xy 252.657102 -166.788084) (xy 252.667172 -166.787664) (xy 252.68577 -166.77994) (xy 252.69317 -166.773098)
			(xy 256.44475 -163.021518) (xy 256.451568 -163.0141) (xy 256.459302 -162.995515) (xy 256.459736 -162.98545)
			(xy 256.459736 -158.248604) (xy 256.459325 -158.238533) (xy 256.451596 -158.219934) (xy 256.44475 -158.212536)
			(xy 253.415292 -155.183078) (xy 253.407891 -155.176239) (xy 253.389292 -155.168519) (xy 253.379224 -155.168092)
			(xy 250.7361 -155.168092) (xy 250.710012 -155.167622) (xy 250.658479 -155.159453) (xy 250.608861 -155.143318)
			(xy 250.56238 -155.119614) (xy 250.520184 -155.088925) (xy 250.501404 -155.07081) (xy 249.594624 -154.163776)
			(xy 249.581162 -154.163776) (xy 249.557794 -154.175206) (xy 249.531773 -154.187234) (xy 249.477019 -154.204209)
			(xy 249.42034 -154.212791) (xy 249.391678 -154.213306) (xy 249.364428 -154.212823) (xy 249.310482 -154.205064)
			(xy 249.25819 -154.189707) (xy 249.208615 -154.167064) (xy 249.162767 -154.137597) (xy 249.121579 -154.101905)
			(xy 249.08589 -154.060715) (xy 249.056425 -154.014866) (xy 249.033786 -153.96529) (xy 249.018432 -153.912996)
			(xy 249.010676 -153.85905) (xy 249.010676 -153.80455) (xy 249.018432 -153.750604) (xy 249.033786 -153.69831)
			(xy 249.056425 -153.648734) (xy 249.08589 -153.602885) (xy 249.121579 -153.561695) (xy 249.162767 -153.526003)
			(xy 249.208615 -153.496536) (xy 249.25819 -153.473893) (xy 249.310482 -153.458536) (xy 249.364428 -153.450777)
			(xy 249.391678 -153.45029) (xy 249.422482 -153.450876) (xy 249.483284 -153.460811) (xy 249.541697 -153.480394)
			(xy 249.569224 -153.494232) (xy 249.574647 -153.496826) (xy 249.586329 -153.499651) (xy 249.592338 -153.49982)
			(xy 249.732038 -153.49982) (xy 249.759186 -153.500389) (xy 249.812758 -153.509212) (xy 249.864177 -153.526649)
			(xy 249.912066 -153.552233) (xy 249.955145 -153.58528) (xy 249.9741 -153.604722) (xy 249.975116 -153.605738)
			(xy 250.1519 -153.782522) (xy 252.05766 -153.782522) (xy 252.061731 -153.7269) (xy 252.073857 -153.672463)
			(xy 252.09378 -153.620372) (xy 252.121076 -153.571737) (xy 252.155162 -153.527594) (xy 252.195311 -153.488885)
			(xy 252.240669 -153.456434) (xy 252.290269 -153.430933) (xy 252.343053 -153.412926) (xy 252.397896 -153.402796)
			(xy 252.45363 -153.400759) (xy 252.509067 -153.406859) (xy 252.563024 -153.420965) (xy 252.614353 -153.442777)
			(xy 252.661959 -153.471831) (xy 252.704827 -153.507506) (xy 252.742044 -153.549043) (xy 252.772817 -153.595556)
			(xy 252.796489 -153.646053) (xy 252.812557 -153.69946) (xy 252.820677 -153.754636) (xy 252.821186 -153.782522)
			(xy 254.08966 -153.782522) (xy 254.093731 -153.7269) (xy 254.105857 -153.672463) (xy 254.12578 -153.620372)
			(xy 254.153076 -153.571737) (xy 254.187162 -153.527594) (xy 254.227311 -153.488885) (xy 254.272669 -153.456434)
			(xy 254.322269 -153.430933) (xy 254.375053 -153.412926) (xy 254.429896 -153.402796) (xy 254.48563 -153.400759)
			(xy 254.541067 -153.406859) (xy 254.595024 -153.420965) (xy 254.646353 -153.442777) (xy 254.693959 -153.471831)
			(xy 254.736827 -153.507506) (xy 254.774044 -153.549043) (xy 254.804817 -153.595556) (xy 254.828489 -153.646053)
			(xy 254.844557 -153.69946) (xy 254.852677 -153.754636) (xy 254.853186 -153.782522) (xy 254.852677 -153.810408)
			(xy 254.844557 -153.865584) (xy 254.828489 -153.918991) (xy 254.804817 -153.969488) (xy 254.774044 -154.016001)
			(xy 254.736827 -154.057538) (xy 254.693959 -154.093213) (xy 254.646353 -154.122267) (xy 254.595024 -154.144079)
			(xy 254.541067 -154.158185) (xy 254.48563 -154.164285) (xy 254.429896 -154.162248) (xy 254.375053 -154.152118)
			(xy 254.322269 -154.134111) (xy 254.272669 -154.10861) (xy 254.227311 -154.076159) (xy 254.187162 -154.03745)
			(xy 254.153076 -153.993307) (xy 254.12578 -153.944672) (xy 254.105857 -153.892581) (xy 254.093731 -153.838144)
			(xy 254.08966 -153.782522) (xy 252.821186 -153.782522) (xy 252.820677 -153.810408) (xy 252.812557 -153.865584)
			(xy 252.796489 -153.918991) (xy 252.772817 -153.969488) (xy 252.742044 -154.016001) (xy 252.704827 -154.057538)
			(xy 252.661959 -154.093213) (xy 252.614353 -154.122267) (xy 252.563024 -154.144079) (xy 252.509067 -154.158185)
			(xy 252.45363 -154.164285) (xy 252.397896 -154.162248) (xy 252.343053 -154.152118) (xy 252.290269 -154.134111)
			(xy 252.240669 -154.10861) (xy 252.195311 -154.076159) (xy 252.155162 -154.03745) (xy 252.121076 -153.993307)
			(xy 252.09378 -153.944672) (xy 252.073857 -153.892581) (xy 252.061731 -153.838144) (xy 252.05766 -153.782522)
			(xy 250.1519 -153.782522) (xy 250.858528 -154.48915) (xy 250.86593 -154.495988) (xy 250.884528 -154.50371)
			(xy 250.894596 -154.504136) (xy 253.53772 -154.504136) (xy 253.563809 -154.504586) (xy 253.615343 -154.512758)
			(xy 253.664962 -154.528898) (xy 253.711442 -154.552607) (xy 253.753637 -154.583301) (xy 253.772416 -154.601418)
			(xy 257.02641 -157.855412) (xy 257.044534 -157.874182) (xy 257.075214 -157.916384) (xy 257.098912 -157.962868)
			(xy 257.115042 -158.012487) (xy 257.123207 -158.06402) (xy 257.123692 -158.090108) (xy 257.123692 -163.143946)
			(xy 257.123188 -163.170033) (xy 257.115028 -163.221564) (xy 257.0989 -163.271182) (xy 257.075203 -163.317663)
			(xy 257.044521 -163.359861) (xy 257.02641 -163.378642) (xy 253.050294 -167.354758) (xy 253.031512 -167.37287)
			(xy 252.989315 -167.403554) (xy 252.942834 -167.427255) (xy 252.893217 -167.443387) (xy 252.841685 -167.451554)
			(xy 252.815598 -167.45204) (xy 244.822472 -167.45204) (xy 244.8124 -167.45244) (xy 244.793802 -167.460177)
			(xy 244.786404 -167.467026) (xy 242.826286 -169.427144) (xy 242.822166 -169.431534) (xy 242.815883 -169.441801)
			(xy 242.81384 -169.447464) (xy 242.81384 -169.447972) (xy 242.805399 -169.473518) (xy 242.782327 -169.522122)
			(xy 242.752656 -169.567002) (xy 242.716974 -169.60727) (xy 242.70919 -169.61389) (xy 245.108869 -169.61389)
			(xy 245.108869 -169.55391) (xy 245.116699 -169.494444) (xy 245.132223 -169.436508) (xy 245.155178 -169.381095)
			(xy 245.185169 -169.329152) (xy 245.221684 -169.281569) (xy 245.264097 -169.239158) (xy 245.311684 -169.202648)
			(xy 245.363629 -169.172661) (xy 245.419045 -169.149711) (xy 245.476981 -169.134191) (xy 245.536448 -169.126367)
			(xy 245.566438 -169.1259) (xy 246.430038 -169.1259) (xy 246.460018 -169.126468) (xy 246.519465 -169.134299)
			(xy 246.577381 -169.149822) (xy 246.632776 -169.172772) (xy 246.684702 -169.202755) (xy 246.73227 -169.239259)
			(xy 246.774667 -169.281659) (xy 246.811166 -169.32923) (xy 246.841145 -169.381158) (xy 246.86409 -169.436555)
			(xy 246.879608 -169.494472) (xy 246.887434 -169.55392) (xy 246.887434 -169.61388) (xy 246.879608 -169.673328)
			(xy 246.86409 -169.731245) (xy 246.841145 -169.786642) (xy 246.811166 -169.83857) (xy 246.774667 -169.886141)
			(xy 246.73227 -169.928541) (xy 246.684702 -169.965045) (xy 246.632776 -169.995028) (xy 246.577381 -170.017978)
			(xy 246.519465 -170.033501) (xy 246.460018 -170.041332) (xy 246.430038 -170.041824) (xy 245.566438 -170.041824)
			(xy 245.536448 -170.041433) (xy 245.476981 -170.033609) (xy 245.419045 -170.018089) (xy 245.363629 -169.995139)
			(xy 245.311684 -169.965152) (xy 245.264097 -169.928642) (xy 245.221684 -169.886231) (xy 245.185169 -169.838648)
			(xy 245.155178 -169.786705) (xy 245.132223 -169.731292) (xy 245.116699 -169.673356) (xy 245.108869 -169.61389)
			(xy 242.70919 -169.61389) (xy 242.675989 -169.642125) (xy 242.630514 -169.670877) (xy 242.581451 -169.692955)
			(xy 242.529773 -169.707922) (xy 242.476505 -169.715481) (xy 242.449604 -169.715942) (xy 242.422354 -169.715419)
			(xy 242.36841 -169.707664) (xy 242.316118 -169.692311) (xy 242.266543 -169.669672) (xy 242.220694 -169.64021)
			(xy 242.179505 -169.604522) (xy 242.143813 -169.563336) (xy 242.114346 -169.517491) (xy 242.091703 -169.467918)
			(xy 242.076345 -169.415627) (xy 242.068584 -169.361684) (xy 242.068096 -169.334434) (xy 241.753136 -169.334434)
			(xy 241.753136 -169.509948) (xy 241.74577 -169.51706) (xy 241.745516 -169.517568) (xy 241.74069 -169.522394)
			(xy 241.740182 -169.522902) (xy 241.618008 -169.645076) (xy 241.614842 -169.64875) (xy 241.609847 -169.657061)
			(xy 241.608102 -169.661586) (xy 241.606578 -169.66692) (xy 241.605229 -169.673006) (xy 241.605238 -169.685469)
			(xy 241.606578 -169.691558) (xy 241.606578 -169.691812) (xy 241.608864 -169.701718) (xy 241.62639 -169.77487)
			(xy 241.629438 -169.784014) (xy 241.63401 -169.792142) (xy 241.651028 -169.79773) (xy 241.652044 -169.798238)
			(xy 241.677603 -169.806647) (xy 241.725805 -169.830553) (xy 241.769521 -169.861919) (xy 241.78895 -169.880534)
			(xy 244.124226 -172.21581) (xy 254.043686 -172.21581) (xy 254.047757 -172.160188) (xy 254.059883 -172.105751)
			(xy 254.079806 -172.05366) (xy 254.107102 -172.005025) (xy 254.141188 -171.960882) (xy 254.181337 -171.922173)
			(xy 254.226695 -171.889722) (xy 254.276295 -171.864221) (xy 254.329079 -171.846214) (xy 254.383922 -171.836084)
			(xy 254.439656 -171.834047) (xy 254.495093 -171.840147) (xy 254.54905 -171.854253) (xy 254.600379 -171.876065)
			(xy 254.647985 -171.905119) (xy 254.690853 -171.940794) (xy 254.72807 -171.982331) (xy 254.758843 -172.028844)
			(xy 254.782515 -172.079341) (xy 254.798583 -172.132748) (xy 254.806703 -172.187924) (xy 254.807212 -172.21581)
			(xy 254.806703 -172.243696) (xy 254.798583 -172.298872) (xy 254.782515 -172.352279) (xy 254.758843 -172.402776)
			(xy 254.72807 -172.449289) (xy 254.690853 -172.490826) (xy 254.647985 -172.526501) (xy 254.600379 -172.555555)
			(xy 254.54905 -172.577367) (xy 254.495093 -172.591473) (xy 254.439656 -172.597573) (xy 254.383922 -172.595536)
			(xy 254.329079 -172.585406) (xy 254.276295 -172.567399) (xy 254.226695 -172.541898) (xy 254.181337 -172.509447)
			(xy 254.141188 -172.470738) (xy 254.107102 -172.426595) (xy 254.079806 -172.37796) (xy 254.059883 -172.325869)
			(xy 254.047757 -172.271432) (xy 254.043686 -172.21581) (xy 244.124226 -172.21581) (xy 245.404132 -173.495716)
			(xy 257.519424 -173.495716) (xy 257.519424 -172.632116) (xy 257.519914 -172.602132) (xy 257.527742 -172.542676)
			(xy 257.543263 -172.484751) (xy 257.566212 -172.429347) (xy 257.596196 -172.377413) (xy 257.632702 -172.329837)
			(xy 257.675107 -172.287432) (xy 257.722683 -172.250926) (xy 257.774617 -172.220942) (xy 257.830021 -172.197993)
			(xy 257.887946 -172.182472) (xy 257.947402 -172.174644) (xy 258.00737 -172.174644) (xy 258.066826 -172.182472)
			(xy 258.124751 -172.197993) (xy 258.180155 -172.220942) (xy 258.232089 -172.250926) (xy 258.279665 -172.287432)
			(xy 258.32207 -172.329837) (xy 258.358576 -172.377413) (xy 258.38856 -172.429347) (xy 258.411509 -172.484751)
			(xy 258.42703 -172.542676) (xy 258.434858 -172.602132) (xy 258.435348 -172.632116) (xy 258.435348 -173.495716)
			(xy 258.434858 -173.5257) (xy 258.42703 -173.585156) (xy 258.411509 -173.643081) (xy 258.38856 -173.698485)
			(xy 258.358576 -173.750419) (xy 258.32207 -173.797995) (xy 258.279665 -173.8404) (xy 258.232089 -173.876906)
			(xy 258.180155 -173.90689) (xy 258.124751 -173.929839) (xy 258.066826 -173.94536) (xy 258.00737 -173.953188)
			(xy 257.947402 -173.953188) (xy 257.887946 -173.94536) (xy 257.830021 -173.929839) (xy 257.774617 -173.90689)
			(xy 257.722683 -173.876906) (xy 257.675107 -173.8404) (xy 257.632702 -173.797995) (xy 257.596196 -173.750419)
			(xy 257.566212 -173.698485) (xy 257.543263 -173.643081) (xy 257.527742 -173.585156) (xy 257.519914 -173.5257)
			(xy 257.519424 -173.495716) (xy 245.404132 -173.495716) (xy 247.52935 -175.620934) (xy 259.44398 -175.620934)
			(xy 259.448051 -175.565312) (xy 259.460177 -175.510875) (xy 259.4801 -175.458784) (xy 259.507396 -175.410149)
			(xy 259.541482 -175.366006) (xy 259.581631 -175.327297) (xy 259.626989 -175.294846) (xy 259.676589 -175.269345)
			(xy 259.729373 -175.251338) (xy 259.784216 -175.241208) (xy 259.83995 -175.239171) (xy 259.895387 -175.245271)
			(xy 259.949344 -175.259377) (xy 260.000673 -175.281189) (xy 260.048279 -175.310243) (xy 260.091147 -175.345918)
			(xy 260.128364 -175.387455) (xy 260.159137 -175.433968) (xy 260.182809 -175.484465) (xy 260.198877 -175.537872)
			(xy 260.206997 -175.593048) (xy 260.207506 -175.620934) (xy 260.206997 -175.64882) (xy 260.198877 -175.703996)
			(xy 260.182809 -175.757403) (xy 260.159137 -175.8079) (xy 260.128364 -175.854413) (xy 260.091147 -175.89595)
			(xy 260.048279 -175.931625) (xy 260.000673 -175.960679) (xy 259.949344 -175.982491) (xy 259.895387 -175.996597)
			(xy 259.83995 -176.002697) (xy 259.784216 -176.00066) (xy 259.729373 -175.99053) (xy 259.676589 -175.972523)
			(xy 259.626989 -175.947022) (xy 259.581631 -175.914571) (xy 259.541482 -175.875862) (xy 259.507396 -175.831719)
			(xy 259.4801 -175.783084) (xy 259.460177 -175.730993) (xy 259.448051 -175.676556) (xy 259.44398 -175.620934)
			(xy 247.52935 -175.620934) (xy 252.786896 -180.87848) (xy 252.804927 -180.897251) (xy 252.835506 -180.939368)
			(xy 252.859132 -180.985745) (xy 252.875224 -181.035242) (xy 252.883389 -181.086645) (xy 252.883924 -181.112668)
			(xy 252.883924 -183.499252) (xy 256.04724 -183.499252) (xy 256.047633 -183.471997) (xy 256.055398 -183.418044)
			(xy 256.070761 -183.365744) (xy 256.093411 -183.316164) (xy 256.122887 -183.270311) (xy 256.158588 -183.22912)
			(xy 256.199788 -183.19343) (xy 256.245648 -183.163965) (xy 256.295235 -183.141328) (xy 256.347538 -183.125977)
			(xy 256.401493 -183.118226) (xy 256.428748 -183.117744) (xy 256.457052 -183.118254) (xy 256.51304 -183.126599)
			(xy 256.56718 -183.14313) (xy 256.618281 -183.167481) (xy 256.665221 -183.199119) (xy 256.706969 -183.237349)
			(xy 256.742607 -183.281329) (xy 256.757424 -183.30545) (xy 256.764282 -183.317134) (xy 256.78765 -183.330596)
			(xy 256.88925 -183.330088) (xy 256.898084 -183.329645) (xy 256.914666 -183.32353) (xy 256.928187 -183.312149)
			(xy 256.932938 -183.304688) (xy 256.933192 -183.304688) (xy 256.933192 -183.304434) (xy 256.947832 -183.279804)
			(xy 256.983393 -183.234877) (xy 257.025277 -183.195779) (xy 257.072541 -183.16339) (xy 257.12412 -183.138439)
			(xy 257.178853 -183.121489) (xy 257.235505 -183.112921) (xy 257.264154 -183.11241) (xy 257.291407 -183.112898)
			(xy 257.345358 -183.120649) (xy 257.397656 -183.136) (xy 257.447237 -183.158639) (xy 257.493091 -183.188104)
			(xy 257.534285 -183.223795) (xy 257.569979 -183.264986) (xy 257.599448 -183.310838) (xy 257.62209 -183.360418)
			(xy 257.637445 -183.412715) (xy 257.6452 -183.466666) (xy 257.645662 -183.493918) (xy 257.6449 -183.518048)
			(xy 257.644698 -183.528098) (xy 257.651248 -183.547087) (xy 257.6576 -183.554878) (xy 257.71221 -183.6166)
			(xy 257.730244 -183.625236) (xy 257.740404 -183.625744) (xy 257.76923 -183.627884) (xy 257.825782 -183.639849)
			(xy 257.879882 -183.660204) (xy 257.930295 -183.688483) (xy 257.975869 -183.72404) (xy 258.01556 -183.766061)
			(xy 258.048462 -183.813586) (xy 258.073823 -183.865529) (xy 258.091062 -183.920701) (xy 258.099785 -183.977843)
			(xy 258.100322 -184.006744) (xy 258.099836 -184.033995) (xy 258.09208 -184.087943) (xy 258.076725 -184.140238)
			(xy 258.054083 -184.189815) (xy 258.024617 -184.235665) (xy 257.988926 -184.276856) (xy 257.947735 -184.312547)
			(xy 257.901885 -184.342013) (xy 257.852308 -184.364655) (xy 257.800013 -184.38001) (xy 257.746065 -184.387766)
			(xy 257.691563 -184.387766) (xy 257.637615 -184.38001) (xy 257.58532 -184.364655) (xy 257.535743 -184.342013)
			(xy 257.489893 -184.312547) (xy 257.448702 -184.276856) (xy 257.413011 -184.235665) (xy 257.383545 -184.189815)
			(xy 257.360903 -184.140238) (xy 257.345548 -184.087943) (xy 257.337792 -184.033995) (xy 257.337306 -184.006744)
			(xy 257.337427 -183.994324) (xy 257.339079 -183.96954) (xy 257.340608 -183.957214) (xy 257.341583 -183.946312)
			(xy 257.335251 -183.925379) (xy 257.328416 -183.916828) (xy 257.306826 -183.892698) (xy 257.299155 -183.884756)
			(xy 257.279 -183.875798) (xy 257.267964 -183.875426) (xy 257.264154 -183.875426) (xy 257.261614 -183.875426)
			(xy 257.226562 -183.919368) (xy 257.220227 -183.928193) (xy 257.214952 -183.949243) (xy 257.216402 -183.960008)
			(xy 257.219253 -183.976753) (xy 257.222303 -184.010587) (xy 257.222498 -184.027572) (xy 257.222498 -184.027826)
			(xy 257.222012 -184.055077) (xy 257.214256 -184.109025) (xy 257.198901 -184.16132) (xy 257.176259 -184.210897)
			(xy 257.146793 -184.256747) (xy 257.111102 -184.297938) (xy 257.069911 -184.333629) (xy 257.024061 -184.363095)
			(xy 256.974484 -184.385737) (xy 256.922189 -184.401092) (xy 256.868241 -184.408848) (xy 256.813739 -184.408848)
			(xy 256.759791 -184.401092) (xy 256.707496 -184.385737) (xy 256.657919 -184.363095) (xy 256.612069 -184.333629)
			(xy 256.570878 -184.297938) (xy 256.535187 -184.256747) (xy 256.505721 -184.210897) (xy 256.483079 -184.16132)
			(xy 256.467724 -184.109025) (xy 256.459968 -184.055077) (xy 256.459482 -184.027826) (xy 256.459482 -184.027318)
			(xy 256.459549 -184.017521) (xy 256.460564 -183.997953) (xy 256.461514 -183.988202) (xy 256.462148 -183.978367)
			(xy 256.45679 -183.959419) (xy 256.4511 -183.951372) (xy 256.401824 -183.888126) (xy 256.384552 -183.87822)
			(xy 256.3749 -183.87695) (xy 256.347967 -183.872622) (xy 256.295613 -183.857305) (xy 256.245974 -183.834688)
			(xy 256.200061 -183.805233) (xy 256.158811 -183.76954) (xy 256.123064 -183.728336) (xy 256.09355 -183.682462)
			(xy 256.070869 -183.632852) (xy 256.055483 -183.580518) (xy 256.047708 -183.526526) (xy 256.04724 -183.499252)
			(xy 252.883924 -183.499252) (xy 252.883924 -190.696342) (xy 257.043426 -190.696342) (xy 257.047497 -190.64072)
			(xy 257.059623 -190.586283) (xy 257.079546 -190.534192) (xy 257.106842 -190.485557) (xy 257.140928 -190.441414)
			(xy 257.181077 -190.402705) (xy 257.226435 -190.370254) (xy 257.276035 -190.344753) (xy 257.328819 -190.326746)
			(xy 257.383662 -190.316616) (xy 257.439396 -190.314579) (xy 257.494833 -190.320679) (xy 257.54879 -190.334785)
			(xy 257.600119 -190.356597) (xy 257.647725 -190.385651) (xy 257.690593 -190.421326) (xy 257.72781 -190.462863)
			(xy 257.758583 -190.509376) (xy 257.782255 -190.559873) (xy 257.798323 -190.61328) (xy 257.806443 -190.668456)
			(xy 257.806952 -190.696342) (xy 257.806443 -190.724228) (xy 257.798323 -190.779404) (xy 257.782255 -190.832811)
			(xy 257.758583 -190.883308) (xy 257.749187 -190.89751) (xy 258.193792 -190.89751) (xy 258.197863 -190.841888)
			(xy 258.209989 -190.787451) (xy 258.229912 -190.73536) (xy 258.257208 -190.686725) (xy 258.291294 -190.642582)
			(xy 258.331443 -190.603873) (xy 258.376801 -190.571422) (xy 258.426401 -190.545921) (xy 258.479185 -190.527914)
			(xy 258.534028 -190.517784) (xy 258.589762 -190.515747) (xy 258.645199 -190.521847) (xy 258.699156 -190.535953)
			(xy 258.750485 -190.557765) (xy 258.798091 -190.586819) (xy 258.840959 -190.622494) (xy 258.878176 -190.664031)
			(xy 258.908949 -190.710544) (xy 258.932621 -190.761041) (xy 258.948689 -190.814448) (xy 258.956809 -190.869624)
			(xy 258.957318 -190.89751) (xy 258.956809 -190.925396) (xy 258.948689 -190.980572) (xy 258.932621 -191.033979)
			(xy 258.908949 -191.084476) (xy 258.878176 -191.130989) (xy 258.840959 -191.172526) (xy 258.798091 -191.208201)
			(xy 258.750485 -191.237255) (xy 258.699156 -191.259067) (xy 258.645199 -191.273173) (xy 258.589762 -191.279273)
			(xy 258.534028 -191.277236) (xy 258.479185 -191.267106) (xy 258.426401 -191.249099) (xy 258.376801 -191.223598)
			(xy 258.331443 -191.191147) (xy 258.291294 -191.152438) (xy 258.257208 -191.108295) (xy 258.229912 -191.05966)
			(xy 258.209989 -191.007569) (xy 258.197863 -190.953132) (xy 258.193792 -190.89751) (xy 257.749187 -190.89751)
			(xy 257.72781 -190.929821) (xy 257.690593 -190.971358) (xy 257.647725 -191.007033) (xy 257.600119 -191.036087)
			(xy 257.54879 -191.057899) (xy 257.494833 -191.072005) (xy 257.439396 -191.078105) (xy 257.383662 -191.076068)
			(xy 257.328819 -191.065938) (xy 257.276035 -191.047931) (xy 257.226435 -191.02243) (xy 257.181077 -190.989979)
			(xy 257.140928 -190.95127) (xy 257.106842 -190.907127) (xy 257.079546 -190.858492) (xy 257.059623 -190.806401)
			(xy 257.047497 -190.751964) (xy 257.043426 -190.696342) (xy 252.883924 -190.696342) (xy 252.883924 -190.98641)
			(xy 252.884087 -190.992421) (xy 252.886904 -191.004107) (xy 252.889512 -191.009524) (xy 252.891352 -191.012998)
			(xy 252.895947 -191.019375) (xy 252.898656 -191.022224) (xy 254.155448 -192.279016) (xy 254.161124 -192.284216)
			(xy 254.174827 -192.291211) (xy 254.182372 -192.292732) (xy 254.18288 -192.292732) (xy 254.191008 -192.293494)
			(xy 254.201168 -192.293494) (xy 254.213106 -192.29197) (xy 254.24892 -192.28181) (xy 254.249428 -192.28181)
			(xy 254.29464 -192.268602) (xy 254.300333 -192.26653) (xy 254.310602 -192.260111) (xy 254.31496 -192.255902)
			(xy 254.318845 -192.251584) (xy 254.324736 -192.241577) (xy 254.326644 -192.23609) (xy 254.32766 -192.23228)
			(xy 254.334747 -192.204837) (xy 254.355924 -192.152267) (xy 254.384646 -192.103408) (xy 254.420281 -192.059336)
			(xy 254.462045 -192.021022) (xy 254.509018 -191.989308) (xy 254.560165 -191.964893) (xy 254.614362 -191.948315)
			(xy 254.670416 -191.939937) (xy 254.698754 -191.939418) (xy 254.726008 -191.939878) (xy 254.779963 -191.94763)
			(xy 254.832265 -191.962982) (xy 254.881849 -191.985623) (xy 254.927706 -192.01509) (xy 254.968902 -192.050784)
			(xy 255.004598 -192.091978) (xy 255.034068 -192.137833) (xy 255.056711 -192.187417) (xy 255.072066 -192.239718)
			(xy 255.07982 -192.293672) (xy 255.080262 -192.320926) (xy 255.079743 -192.349263) (xy 255.071356 -192.405312)
			(xy 255.054772 -192.459504) (xy 255.030353 -192.510647) (xy 254.998639 -192.557616) (xy 254.960326 -192.599378)
			(xy 254.916258 -192.635012) (xy 254.867404 -192.663737) (xy 254.814838 -192.684919) (xy 254.7874 -192.69202)
			(xy 254.787146 -192.69202) (xy 254.784352 -192.692782) (xy 254.778635 -192.694649) (xy 254.768231 -192.700677)
			(xy 254.763778 -192.70472) (xy 254.759345 -192.709267) (xy 254.752656 -192.720058) (xy 254.75057 -192.726056)
			(xy 254.743204 -192.751964) (xy 254.725424 -192.814448) (xy 254.724455 -192.819148) (xy 254.724073 -192.828735)
			(xy 254.724662 -192.833498) (xy 254.72517 -192.836292) (xy 254.72517 -192.8368) (xy 254.725932 -192.839848)
			(xy 254.727508 -192.844971) (xy 254.732495 -192.854455) (xy 254.735838 -192.858644) (xy 254.7366 -192.859406)
			(xy 254.737362 -192.860422) (xy 254.737616 -192.860676) (xy 254.742696 -192.865502) (xy 254.742188 -192.86601)
			(xy 256.022856 -194.146678) (xy 256.030984 -194.151758) (xy 256.034286 -194.153282) (xy 256.044446 -194.156584)
			(xy 256.050796 -194.157346) (xy 256.052828 -194.1576) (xy 256.05359 -194.1576) (xy 256.072561 -194.159055)
			(xy 256.110098 -194.165287) (xy 256.12852 -194.170046) (xy 256.141676 -194.173681) (xy 256.167483 -194.182577)
			(xy 256.180082 -194.187826) (xy 256.208261 -194.200591) (xy 256.260404 -194.233871) (xy 256.306489 -194.275136)
			(xy 256.326386 -194.298824) (xy 256.344495 -194.322149) (xy 256.374041 -194.373274) (xy 256.395342 -194.428347)
			(xy 256.407889 -194.486047) (xy 256.410206 -194.515486) (xy 256.410206 -194.51574) (xy 256.41046 -194.51955)
			(xy 256.410968 -194.524884) (xy 256.41554 -194.535552) (xy 256.417472 -194.539238) (xy 256.422317 -194.546005)
			(xy 256.425192 -194.549014) (xy 256.845054 -194.968876) (xy 256.85572 -194.978755) (xy 256.881257 -194.992619)
			(xy 256.909663 -194.998743) (xy 256.938644 -194.996633) (xy 256.965863 -194.986458) (xy 256.989122 -194.969041)
			(xy 256.998216 -194.9577) (xy 257.002859 -194.951018) (xy 257.008049 -194.935604) (xy 257.008376 -194.927474)
			(xy 257.008376 -192.396872) (xy 257.006598 -192.39357) (xy 256.991663 -192.365282) (xy 256.97043 -192.304945)
			(xy 256.959575 -192.241908) (xy 256.958846 -192.209928) (xy 256.958846 -192.200784) (xy 256.959886 -192.173024)
			(xy 256.969006 -192.118228) (xy 256.985975 -192.065332) (xy 257.010433 -192.015456) (xy 257.041864 -191.969653)
			(xy 257.079603 -191.928891) (xy 257.122854 -191.894031) (xy 257.170701 -191.86581) (xy 257.222135 -191.844825)
			(xy 257.276068 -191.831517) (xy 257.33136 -191.82617) (xy 257.386843 -191.828896) (xy 257.441345 -191.839637)
			(xy 257.493714 -191.858167) (xy 257.542843 -191.884093) (xy 257.587694 -191.916868) (xy 257.627319 -191.9558)
			(xy 257.660881 -192.000065) (xy 257.687671 -192.048728) (xy 257.707122 -192.100761) (xy 257.718824 -192.155065)
			(xy 257.7211 -192.18275) (xy 257.721862 -192.205356) (xy 257.721862 -192.208658) (xy 257.721193 -192.240849)
			(xy 257.710397 -192.30432) (xy 257.689121 -192.365086) (xy 257.67411 -192.39357) (xy 257.672332 -192.396872)
			(xy 257.672332 -195.330064) (xy 257.672332 -195.331334) (xy 257.672744 -195.33842) (xy 257.677004 -195.351953)
			(xy 257.680714 -195.358004) (xy 257.689463 -195.369549) (xy 257.71211 -195.387587) (xy 257.738918 -195.398524)
			(xy 257.767721 -195.401476) (xy 257.78206 -195.399406) (xy 257.789191 -195.397672) (xy 257.802102 -195.390705)
			(xy 257.80746 -195.38569) (xy 259.21208 -193.98107) (xy 259.214784 -193.978218) (xy 259.219372 -193.971837)
			(xy 259.221224 -193.96837) (xy 259.223807 -193.962943) (xy 259.226633 -193.951264) (xy 259.226812 -193.945256)
			(xy 259.226812 -177.72761) (xy 259.22605 -177.726086) (xy 259.225796 -177.725832) (xy 259.210653 -177.697378)
			(xy 259.189092 -177.63664) (xy 259.178044 -177.573143) (xy 259.177282 -177.54092) (xy 259.177282 -177.531776)
			(xy 259.178315 -177.504014) (xy 259.187425 -177.449212) (xy 259.204384 -177.396311) (xy 259.228835 -177.346428)
			(xy 259.260261 -177.300617) (xy 259.297998 -177.259848) (xy 259.341247 -177.224982) (xy 259.389096 -177.196755)
			(xy 259.440531 -177.175765) (xy 259.494467 -177.162456) (xy 259.549762 -177.157108) (xy 259.605249 -177.159835)
			(xy 259.659754 -177.170579) (xy 259.712124 -177.189113) (xy 259.761254 -177.215045) (xy 259.806104 -177.247827)
			(xy 259.845727 -177.286766) (xy 259.879284 -177.331039) (xy 259.906067 -177.37971) (xy 259.925509 -177.43175)
			(xy 259.937199 -177.486059) (xy 259.939536 -177.513742) (xy 259.940298 -177.536348) (xy 259.940298 -177.53965)
			(xy 259.939912 -177.56397) (xy 259.933723 -177.612215) (xy 259.921452 -177.659281) (xy 259.903298 -177.704407)
			(xy 259.891784 -177.725832) (xy 259.89153 -177.726086) (xy 259.890768 -177.72761) (xy 259.890768 -191.789304)
			(xy 259.893911 -191.793234) (xy 259.901462 -191.799884) (xy 259.905754 -191.802512) (xy 259.931154 -191.81572)
			(xy 259.931662 -191.81572) (xy 259.97916 -191.840104) (xy 259.987288 -191.843152) (xy 259.987796 -191.843152)
			(xy 260.001258 -191.845184) (xy 260.020562 -191.845184) (xy 260.025388 -191.84493) (xy 260.035802 -191.842644)
			(xy 260.04647 -191.837564) (xy 260.049264 -191.835786) (xy 260.05028 -191.835024) (xy 260.074531 -191.818683)
			(xy 260.126952 -191.792775) (xy 260.182709 -191.775156) (xy 260.240499 -191.766238) (xy 260.269736 -191.765682)
			(xy 260.296986 -191.76617) (xy 260.350932 -191.773931) (xy 260.403223 -191.78929) (xy 260.452797 -191.811934)
			(xy 260.498644 -191.841402) (xy 260.539831 -191.877094) (xy 260.57552 -191.918284) (xy 260.604984 -191.964134)
			(xy 260.627623 -192.01371) (xy 260.642977 -192.066004) (xy 260.650732 -192.11995) (xy 260.650732 -192.17445)
			(xy 260.642977 -192.228396) (xy 260.627623 -192.28069) (xy 260.604984 -192.330266) (xy 260.57552 -192.376116)
			(xy 260.539831 -192.417306) (xy 260.498644 -192.452998) (xy 260.452797 -192.482466) (xy 260.403223 -192.50511)
			(xy 260.350932 -192.520469) (xy 260.296986 -192.52823) (xy 260.269736 -192.528698) (xy 260.239315 -192.528109)
			(xy 260.179244 -192.518461) (xy 260.121465 -192.499403) (xy 260.067442 -192.471419) (xy 260.04266 -192.453768)
			(xy 260.036818 -192.44945) (xy 260.024626 -192.444878) (xy 260.012942 -192.443608) (xy 260.009154 -192.443569)
			(xy 260.001632 -192.444469) (xy 259.997956 -192.445386) (xy 259.988304 -192.44945) (xy 259.941568 -192.47358)
			(xy 259.931662 -192.47866) (xy 259.931154 -192.47866) (xy 259.905754 -192.491614) (xy 259.901963 -192.49393)
			(xy 259.895191 -192.499678) (xy 259.892292 -192.503044) (xy 259.890768 -192.505076) (xy 259.890768 -194.104006)
			(xy 259.890198 -194.131149) (xy 259.881318 -194.184704) (xy 259.863861 -194.236107) (xy 259.838289 -194.283993)
			(xy 259.805282 -194.327092) (xy 259.785866 -194.346068) (xy 259.78485 -194.347084) (xy 258.018534 -196.1134)
			(xy 258.017421 -196.12522) (xy 258.024831 -196.147744) (xy 258.032758 -196.15658) (xy 258.610862 -196.734684)
			(xy 260.878586 -196.734684) (xy 260.882552 -196.650153) (xy 260.894417 -196.566366) (xy 260.914075 -196.484057)
			(xy 260.941355 -196.403951) (xy 260.976016 -196.326752) (xy 261.017754 -196.253137) (xy 261.066201 -196.183754)
			(xy 261.120933 -196.119213) (xy 261.181469 -196.060081) (xy 261.247275 -196.006877) (xy 261.317775 -195.960069)
			(xy 261.392347 -195.920068) (xy 261.470338 -195.887226) (xy 261.551062 -195.861832) (xy 261.633809 -195.844109)
			(xy 261.717851 -195.834211) (xy 261.802452 -195.832228) (xy 261.886866 -195.838175) (xy 261.970353 -195.852)
			(xy 262.052178 -195.873583) (xy 262.131622 -195.902733) (xy 262.207988 -195.939194) (xy 262.280604 -195.982646)
			(xy 262.348832 -196.032707) (xy 262.412072 -196.088937) (xy 262.469769 -196.150842) (xy 262.521416 -196.217878)
			(xy 262.566558 -196.289455) (xy 262.6048 -196.364945) (xy 262.635804 -196.443684) (xy 262.659299 -196.524981)
			(xy 262.675078 -196.60812) (xy 262.683002 -196.692372) (xy 262.683498 -196.734684) (xy 262.683002 -196.776996)
			(xy 262.675078 -196.861248) (xy 262.659299 -196.944387) (xy 262.635804 -197.025684) (xy 262.6048 -197.104423)
			(xy 262.566558 -197.179913) (xy 262.521416 -197.25149) (xy 262.48828 -197.2945) (xy 263.442194 -197.2945)
			(xy 263.446265 -197.238878) (xy 263.458391 -197.184441) (xy 263.478314 -197.13235) (xy 263.50561 -197.083715)
			(xy 263.539696 -197.039572) (xy 263.579845 -197.000863) (xy 263.625203 -196.968412) (xy 263.674803 -196.942911)
			(xy 263.727587 -196.924904) (xy 263.78243 -196.914774) (xy 263.838164 -196.912737) (xy 263.893601 -196.918837)
			(xy 263.947558 -196.932943) (xy 263.998887 -196.954755) (xy 264.046493 -196.983809) (xy 264.089361 -197.019484)
			(xy 264.126578 -197.061021) (xy 264.157351 -197.107534) (xy 264.181023 -197.158031) (xy 264.197091 -197.211438)
			(xy 264.205211 -197.266614) (xy 264.20572 -197.2945) (xy 264.205211 -197.322386) (xy 264.197091 -197.377562)
			(xy 264.181023 -197.430969) (xy 264.157351 -197.481466) (xy 264.126578 -197.527979) (xy 264.089361 -197.569516)
			(xy 264.046493 -197.605191) (xy 263.998887 -197.634245) (xy 263.947558 -197.656057) (xy 263.893601 -197.670163)
			(xy 263.838164 -197.676263) (xy 263.78243 -197.674226) (xy 263.727587 -197.664096) (xy 263.674803 -197.646089)
			(xy 263.625203 -197.620588) (xy 263.579845 -197.588137) (xy 263.539696 -197.549428) (xy 263.50561 -197.505285)
			(xy 263.478314 -197.45665) (xy 263.458391 -197.404559) (xy 263.446265 -197.350122) (xy 263.442194 -197.2945)
			(xy 262.48828 -197.2945) (xy 262.469769 -197.318526) (xy 262.412072 -197.380431) (xy 262.348832 -197.436661)
			(xy 262.280604 -197.486722) (xy 262.207988 -197.530174) (xy 262.131622 -197.566635) (xy 262.052178 -197.595785)
			(xy 261.970353 -197.617368) (xy 261.886866 -197.631193) (xy 261.802452 -197.63714) (xy 261.717851 -197.635157)
			(xy 261.633809 -197.625259) (xy 261.551062 -197.607536) (xy 261.470338 -197.582142) (xy 261.392347 -197.5493)
			(xy 261.317775 -197.509299) (xy 261.247275 -197.462491) (xy 261.181469 -197.409287) (xy 261.120933 -197.350155)
			(xy 261.066201 -197.285614) (xy 261.017754 -197.216231) (xy 260.976016 -197.142616) (xy 260.941355 -197.065417)
			(xy 260.914075 -196.985311) (xy 260.894417 -196.903002) (xy 260.882552 -196.819215) (xy 260.878586 -196.734684)
			(xy 258.610862 -196.734684) (xy 259.96392 -198.087742) (xy 259.969601 -198.092932) (xy 259.983308 -198.099904)
			(xy 259.990844 -198.101458) (xy 259.991352 -198.101458) (xy 259.99948 -198.10222) (xy 264.121392 -198.10222)
			(xy 264.12952 -198.101458) (xy 264.130028 -198.101458) (xy 264.137546 -198.099856) (xy 264.151231 -198.092876)
			(xy 264.156952 -198.087742) (xy 264.707878 -197.536816) (xy 264.713069 -197.531136) (xy 264.720046 -197.51743)
			(xy 264.721594 -197.509892) (xy 264.721594 -197.509384) (xy 264.722356 -197.501256) (xy 264.722356 -197.266052)
			(xy 264.721848 -197.260464) (xy 263.893046 -192.883282) (xy 263.832848 -192.565782) (xy 263.83079 -192.556913)
			(xy 263.821372 -192.541348) (xy 263.807102 -192.530063) (xy 263.798558 -192.52692) (xy 263.790684 -192.52438)
			(xy 263.778746 -192.52438) (xy 263.776206 -192.524634) (xy 263.759034 -192.526132) (xy 263.724564 -192.526386)
			(xy 263.707372 -192.525142) (xy 263.68113 -192.522485) (xy 263.629683 -192.510862) (xy 263.580327 -192.492263)
			(xy 263.534002 -192.467045) (xy 263.491592 -192.435687) (xy 263.453905 -192.398787) (xy 263.42166 -192.357048)
			(xy 263.40816 -192.334388) (xy 263.405112 -192.329816) (xy 263.400032 -192.32372) (xy 263.391904 -192.315592)
			(xy 263.388856 -192.312798) (xy 263.38498 -192.309666) (xy 263.376281 -192.30481) (xy 263.371584 -192.303146)
			(xy 263.368536 -192.302384) (xy 263.368282 -192.302384) (xy 263.356344 -192.299336) (xy 263.355836 -192.299336)
			(xy 263.29767 -192.285366) (xy 263.296654 -192.285112) (xy 263.287167 -192.283788) (xy 263.268375 -192.287438)
			(xy 263.260078 -192.292224) (xy 263.259062 -192.292986) (xy 263.235476 -192.308115) (xy 263.184805 -192.332038)
			(xy 263.131178 -192.348286) (xy 263.075751 -192.356508) (xy 263.047734 -192.356994) (xy 262.861298 -192.356994)
			(xy 262.851223 -192.356503) (xy 262.832665 -192.348637) (xy 262.818564 -192.334235) (xy 262.81109 -192.315516)
			(xy 262.810752 -192.305432) (xy 262.810752 -192.29832) (xy 262.81059 -192.293087) (xy 262.808406 -192.28285)
			(xy 262.806434 -192.278) (xy 262.802116 -192.268602) (xy 262.793988 -192.261236) (xy 262.79348 -192.260728)
			(xy 262.776112 -192.244811) (xy 262.745033 -192.209403) (xy 262.731504 -192.190116) (xy 262.720582 -192.173098)
			(xy 262.717534 -192.167764) (xy 262.712708 -192.159128) (xy 262.711946 -192.157604) (xy 262.70966 -192.153794)
			(xy 262.702675 -192.143688) (xy 262.681716 -192.130944) (xy 262.669528 -192.12941) (xy 262.668766 -192.12941)
			(xy 262.587232 -192.125346) (xy 262.579358 -192.125346) (xy 262.567518 -192.125975) (xy 262.546348 -192.136587)
			(xy 262.538718 -192.145666) (xy 262.534908 -192.150746) (xy 262.53186 -192.155572) (xy 262.506808 -192.192143)
			(xy 262.450589 -192.260687) (xy 262.387919 -192.323388) (xy 262.319402 -192.379642) (xy 262.2457 -192.428905)
			(xy 262.167521 -192.470703) (xy 262.085621 -192.504633) (xy 262.000788 -192.530369) (xy 261.91384 -192.547661)
			(xy 261.825615 -192.556344) (xy 261.78129 -192.556892) (xy 261.738338 -192.556381) (xy 261.652823 -192.548214)
			(xy 261.568471 -192.531956) (xy 261.486047 -192.507753) (xy 261.406297 -192.475825) (xy 261.329942 -192.436461)
			(xy 261.257676 -192.390017) (xy 261.190151 -192.336914) (xy 261.127979 -192.277633) (xy 261.071724 -192.212711)
			(xy 261.021896 -192.142735) (xy 260.978944 -192.06834) (xy 260.943258 -191.990199) (xy 260.915162 -191.909019)
			(xy 260.894909 -191.825537) (xy 260.882684 -191.740507) (xy 260.878596 -191.6547) (xy 260.882684 -191.568893)
			(xy 260.894909 -191.483863) (xy 260.915162 -191.400381) (xy 260.943258 -191.319201) (xy 260.978944 -191.24106)
			(xy 261.021896 -191.166665) (xy 261.071724 -191.096689) (xy 261.127979 -191.031767) (xy 261.190151 -190.972486)
			(xy 261.257676 -190.919383) (xy 261.329942 -190.872939) (xy 261.406297 -190.833575) (xy 261.486047 -190.801647)
			(xy 261.568471 -190.777444) (xy 261.652823 -190.761186) (xy 261.738338 -190.753019) (xy 261.78129 -190.752476)
			(xy 261.823226 -190.752958) (xy 261.906735 -190.760749) (xy 261.989161 -190.776255) (xy 262.069792 -190.799342)
			(xy 262.147934 -190.829811) (xy 262.222911 -190.8674) (xy 262.294077 -190.911783) (xy 262.360817 -190.962578)
			(xy 262.422556 -191.019347) (xy 262.478762 -191.0816) (xy 262.528948 -191.148799) (xy 262.572683 -191.220366)
			(xy 262.609588 -191.295681) (xy 262.639346 -191.374097) (xy 262.661699 -191.454935) (xy 262.676455 -191.537498)
			(xy 262.68045 -191.579246) (xy 262.68045 -191.580262) (xy 262.680704 -191.582294) (xy 262.68301 -191.594494)
			(xy 262.697209 -191.614813) (xy 262.707882 -191.621156) (xy 262.770366 -191.65189) (xy 262.770874 -191.65189)
			(xy 262.788146 -191.660272) (xy 262.793333 -191.66247) (xy 262.804357 -191.664775) (xy 262.80999 -191.664844)
			(xy 262.812022 -191.664844) (xy 262.819642 -191.664336) (xy 262.832088 -191.660272) (xy 262.83793 -191.656462)
			(xy 262.861336 -191.641692) (xy 262.911512 -191.618337) (xy 262.964538 -191.602488) (xy 263.0193 -191.594477)
			(xy 263.046972 -191.593978) (xy 263.047226 -191.593978) (xy 263.050782 -191.593978) (xy 263.054338 -191.593978)
			(xy 263.062974 -191.594232) (xy 263.082532 -191.595502) (xy 263.102869 -191.597604) (xy 263.142961 -191.605623)
			(xy 263.162542 -191.611504) (xy 263.16305 -191.611758) (xy 263.166606 -191.613028) (xy 263.19292 -191.622229)
			(xy 263.242768 -191.647182) (xy 263.288459 -191.679116) (xy 263.329023 -191.717352) (xy 263.363598 -191.761079)
			(xy 263.377934 -191.784986) (xy 263.378188 -191.785494) (xy 263.379712 -191.788034) (xy 263.382252 -191.792352)
			(xy 263.390126 -191.801496) (xy 263.395089 -191.806784) (xy 263.40735 -191.814519) (xy 263.414256 -191.816736)
			(xy 263.451086 -191.826134) (xy 263.451594 -191.826134) (xy 263.482074 -191.833754) (xy 263.483852 -191.834008)
			(xy 263.490456 -191.835532) (xy 263.50468 -191.83477) (xy 263.516872 -191.830706) (xy 263.520174 -191.82969)
			(xy 263.534398 -191.822832) (xy 263.537192 -191.821308) (xy 263.538462 -191.820546) (xy 263.551132 -191.812869)
			(xy 263.57745 -191.799265) (xy 263.59104 -191.793368) (xy 263.61136 -191.785494) (xy 263.629648 -191.779398)
			(xy 263.641332 -191.775842) (xy 263.6487 -191.772603) (xy 263.661121 -191.762383) (xy 263.665716 -191.755776)
			(xy 263.665716 -191.687958) (xy 263.664954 -191.67856) (xy 263.412986 -190.349378) (xy 262.83793 -187.312808)
			(xy 262.835537 -187.305951) (xy 262.82754 -187.293835) (xy 262.822182 -187.288932) (xy 262.815578 -187.283344)
			(xy 262.799576 -187.277248) (xy 262.79094 -187.276994) (xy 262.790178 -187.276994) (xy 262.763049 -187.275946)
			(xy 262.709479 -187.267128) (xy 262.657699 -187.250809) (xy 262.608753 -187.227319) (xy 262.563628 -187.197133)
			(xy 262.523234 -187.160858) (xy 262.488387 -187.119227) (xy 262.459789 -187.073079) (xy 262.438017 -187.023345)
			(xy 262.42351 -186.971028) (xy 262.416561 -186.917184) (xy 262.41731 -186.862898) (xy 262.425742 -186.809266)
			(xy 262.441686 -186.757369) (xy 262.464821 -186.708255) (xy 262.494681 -186.662913) (xy 262.530664 -186.622259)
			(xy 262.572042 -186.587112) (xy 262.617982 -186.558182) (xy 262.642604 -186.546744) (xy 262.65124 -186.542934)
			(xy 262.67918 -186.514994) (xy 262.68045 -186.512708) (xy 262.68172 -186.504072) (xy 262.682238 -186.500019)
			(xy 262.682114 -186.49185) (xy 262.681466 -186.487816) (xy 262.673846 -186.44743) (xy 262.645906 -186.299856)
			(xy 262.643366 -186.29249) (xy 262.641588 -186.288172) (xy 262.639556 -186.284616) (xy 262.636467 -186.280028)
			(xy 262.628656 -186.272201) (xy 262.624062 -186.269122) (xy 262.60425 -186.256422) (xy 262.562086 -186.229244)
			(xy 262.557758 -186.226566) (xy 262.548285 -186.22285) (xy 262.54329 -186.221878) (xy 262.533384 -186.2201)
			(xy 262.52297 -186.22264) (xy 262.500957 -186.227638) (xy 262.456133 -186.232991) (xy 262.433562 -186.233308)
			(xy 262.4328 -186.233308) (xy 262.405549 -186.232822) (xy 262.351601 -186.225066) (xy 262.299306 -186.209711)
			(xy 262.249729 -186.187069) (xy 262.203879 -186.157603) (xy 262.162688 -186.121912) (xy 262.126997 -186.080721)
			(xy 262.097531 -186.034871) (xy 262.074889 -185.985294) (xy 262.059534 -185.932999) (xy 262.051778 -185.879051)
			(xy 262.051292 -185.8518) (xy 262.051764 -185.824422) (xy 262.059592 -185.770229) (xy 262.075088 -185.717712)
			(xy 262.097932 -185.66795) (xy 262.127655 -185.621964) (xy 262.163648 -185.580701) (xy 262.20517 -185.545007)
			(xy 262.251368 -185.515615) (xy 262.301294 -185.49313) (xy 262.353921 -185.478014) (xy 262.380984 -185.473848)
			(xy 262.383016 -185.473594) (xy 262.386064 -185.472832) (xy 262.394725 -185.470356) (xy 262.409681 -185.460336)
			(xy 262.415274 -185.453274) (xy 262.426958 -185.437018) (xy 262.458454 -185.393838) (xy 262.46201 -185.387996)
			(xy 262.465842 -185.380133) (xy 262.468455 -185.362852) (xy 262.46709 -185.354214) (xy 262.002524 -182.900574)
			(xy 261.986014 -182.814214) (xy 261.985506 -182.81142) (xy 261.983134 -182.80312) (xy 261.973726 -182.788661)
			(xy 261.960059 -182.778133) (xy 261.951978 -182.775098) (xy 261.916164 -182.7657) (xy 261.910068 -182.763668)
			(xy 261.90575 -182.761636) (xy 261.902448 -182.759604) (xy 261.902194 -182.759604) (xy 261.887716 -182.750714)
			(xy 261.883906 -182.748428) (xy 261.878349 -182.745284) (xy 261.866141 -182.741561) (xy 261.859776 -182.741062)
			(xy 261.853426 -182.741316) (xy 261.846051 -182.742169) (xy 261.832241 -182.7476) (xy 261.826248 -182.751984)
			(xy 261.812532 -182.763414) (xy 261.80796 -182.767986) (xy 261.804912 -182.771542) (xy 261.786717 -182.792326)
			(xy 261.745357 -182.828939) (xy 261.699142 -182.859193) (xy 261.649041 -182.882454) (xy 261.596106 -182.898235)
			(xy 261.541447 -182.906203) (xy 261.513828 -182.90667) (xy 261.484652 -182.90612) (xy 261.426979 -182.897252)
			(xy 261.371325 -182.879717) (xy 261.344918 -182.8673) (xy 261.344664 -182.8673) (xy 261.335005 -182.863127)
			(xy 261.314007 -182.862201) (xy 261.304024 -182.865522) (xy 261.228586 -182.898542) (xy 261.220008 -182.903217)
			(xy 261.206942 -182.917718) (xy 261.203186 -182.926736) (xy 261.202424 -182.92953) (xy 261.202424 -182.929784)
			(xy 261.194229 -182.955717) (xy 261.171515 -183.005131) (xy 261.142013 -183.050818) (xy 261.106322 -183.091853)
			(xy 261.065164 -183.127402) (xy 261.019375 -183.156747) (xy 260.969883 -183.17929) (xy 260.917691 -183.194576)
			(xy 260.863856 -183.202295) (xy 260.836664 -183.202834) (xy 260.809414 -183.202346) (xy 260.755469 -183.194585)
			(xy 260.703177 -183.179227) (xy 260.653602 -183.156584) (xy 260.607755 -183.127118) (xy 260.566566 -183.091426)
			(xy 260.530876 -183.050237) (xy 260.501411 -183.004389) (xy 260.478769 -182.954814) (xy 260.463413 -182.902522)
			(xy 260.455654 -182.848576) (xy 260.455156 -182.821326) (xy 260.455711 -182.791743) (xy 260.46484 -182.733286)
			(xy 260.482883 -182.676938) (xy 260.509409 -182.624052) (xy 260.54378 -182.575894) (xy 260.585173 -182.533618)
			(xy 260.608572 -182.51551) (xy 260.615684 -182.510176) (xy 260.620256 -182.503572) (xy 260.622644 -182.499871)
			(xy 260.626212 -182.49182) (xy 260.627368 -182.48757) (xy 260.634734 -182.45836) (xy 260.63702 -182.449724)
			(xy 260.635496 -182.432452) (xy 260.634988 -182.431182) (xy 260.634226 -182.429658) (xy 260.622753 -182.404111)
			(xy 260.60657 -182.350499) (xy 260.598384 -182.295099) (xy 260.597904 -182.267098) (xy 260.598367 -182.239846)
			(xy 260.606125 -182.185895) (xy 260.621481 -182.133599) (xy 260.644124 -182.084019) (xy 260.673592 -182.038167)
			(xy 260.709286 -181.996976) (xy 260.750479 -181.961284) (xy 260.796332 -181.931817) (xy 260.845912 -181.909176)
			(xy 260.898209 -181.893822) (xy 260.95216 -181.886066) (xy 260.979412 -181.88559) (xy 261.00653 -181.88606)
			(xy 261.060223 -181.893727) (xy 261.112288 -181.908918) (xy 261.161678 -181.931329) (xy 261.207398 -181.960506)
			(xy 261.248526 -181.995863) (xy 261.284233 -182.036687) (xy 261.313801 -182.082156) (xy 261.325614 -182.10657)
			(xy 261.32917 -182.114444) (xy 261.34695 -182.132986) (xy 261.354062 -182.140098) (xy 261.372604 -182.148988)
			(xy 261.373112 -182.148988) (xy 261.38251 -182.15356) (xy 261.388749 -182.155997) (xy 261.401998 -182.157932)
			(xy 261.408672 -182.15737) (xy 261.415784 -182.156354) (xy 261.418578 -182.155592) (xy 261.44186 -182.149984)
			(xy 261.489375 -182.143995) (xy 261.51332 -182.143654) (xy 261.514844 -182.143654) (xy 261.546993 -182.144337)
			(xy 261.610378 -182.155141) (xy 261.67106 -182.176404) (xy 261.699502 -182.191406) (xy 261.706106 -182.194962)
			(xy 261.70636 -182.195216) (xy 261.713218 -182.19674) (xy 261.723373 -182.198443) (xy 261.743564 -182.194514)
			(xy 261.752334 -182.18912) (xy 261.790688 -182.16118) (xy 261.827772 -182.134256) (xy 261.833573 -182.129702)
			(xy 261.84249 -182.117961) (xy 261.845298 -182.111142) (xy 261.847257 -182.105452) (xy 261.848794 -182.093521)
			(xy 261.848346 -182.08752) (xy 261.754112 -181.589934) (xy 261.680706 -181.203854) (xy 261.676953 -181.193062)
			(xy 261.661604 -181.176164) (xy 261.651242 -181.171342) (xy 261.650734 -181.171088) (xy 261.631684 -181.167532)
			(xy 261.62508 -181.16804) (xy 261.5946 -181.169056) (xy 261.590536 -181.169056) (xy 261.563296 -181.168552)
			(xy 261.509374 -181.160766) (xy 261.457108 -181.145388) (xy 261.407561 -181.122733) (xy 261.361741 -181.09326)
			(xy 261.320578 -181.057569) (xy 261.284911 -181.016386) (xy 261.255464 -180.970549) (xy 261.232836 -180.920989)
			(xy 261.217488 -180.868715) (xy 261.209732 -180.814788) (xy 261.209282 -180.787548) (xy 261.209832 -180.758371)
			(xy 261.218711 -180.700697) (xy 261.236269 -180.645048) (xy 261.262096 -180.592722) (xy 261.29559 -180.544939)
			(xy 261.33597 -180.502813) (xy 261.382294 -180.467328) (xy 261.433482 -180.439311) (xy 261.460742 -180.4289)
			(xy 261.468616 -180.426106) (xy 261.495794 -180.404516) (xy 261.50062 -180.396642) (xy 261.511288 -180.379624)
			(xy 261.514425 -180.373745) (xy 261.517888 -180.360883) (xy 261.518146 -180.354224) (xy 261.518146 -180.343302)
			(xy 259.88518 -171.720256) (xy 258.23291 -162.99434) (xy 254.906272 -145.429478) (xy 254.897128 -145.372074)
			(xy 254.81407 -144.728692) (xy 253.763526 -136.740646) (xy 252.46965 -126.90348) (xy 252.467471 -126.893958)
			(xy 252.457039 -126.877464) (xy 252.44118 -126.86609) (xy 252.431804 -126.863348) (xy 252.419866 -126.8603)
			(xy 252.419358 -126.8603) (xy 252.39218 -126.853696) (xy 252.38452 -126.852538) (xy 252.369141 -126.854357)
			(xy 252.361954 -126.857252) (xy 252.348238 -126.863856) (xy 252.340364 -126.868174) (xy 252.333506 -126.873762)
			(xy 252.327156 -126.880112) (xy 252.325378 -126.882398) (xy 252.324362 -126.883668) (xy 252.323854 -126.88443)
			(xy 252.3236 -126.884684) (xy 252.320298 -126.889002) (xy 252.320044 -126.889256) (xy 252.318266 -126.891288)
			(xy 252.317758 -126.89205) (xy 252.299516 -126.913853) (xy 252.257679 -126.952337) (xy 252.210599 -126.984195)
			(xy 252.159317 -127.008722) (xy 252.104966 -127.025377) (xy 252.048747 -127.033792) (xy 252.020324 -127.03429)
			(xy 251.993289 -127.033822) (xy 251.939759 -127.026192) (xy 251.887842 -127.011083) (xy 251.838578 -126.988796)
			(xy 251.792954 -126.959778) (xy 251.751882 -126.92461) (xy 251.716187 -126.883997) (xy 251.686581 -126.838751)
			(xy 251.66366 -126.78978) (xy 251.64788 -126.738063) (xy 251.63956 -126.684636) (xy 251.638816 -126.657608)
			(xy 251.638816 -126.652782) (xy 251.639832 -126.623318) (xy 251.640594 -126.612396) (xy 251.636784 -126.601982)
			(xy 251.634776 -126.596886) (xy 251.628884 -126.587655) (xy 251.6251 -126.583694) (xy 251.622814 -126.581408)
			(xy 251.621798 -126.562358) (xy 251.621727 -126.553189) (xy 251.627337 -126.535747) (xy 251.63272 -126.528322)
			(xy 251.717302 -126.42088) (xy 251.717556 -126.420372) (xy 251.71781 -126.420118) (xy 251.719334 -126.41834)
			(xy 251.720604 -126.416562) (xy 251.720858 -126.416308) (xy 251.721874 -126.415038) (xy 251.722382 -126.414276)
			(xy 251.725684 -126.409704) (xy 251.72924 -126.40183) (xy 251.730868 -126.397367) (xy 251.732659 -126.388037)
			(xy 251.732796 -126.383288) (xy 251.732796 -126.361952) (xy 251.732941 -126.356513) (xy 251.735251 -126.345883)
			(xy 251.737368 -126.34087) (xy 251.743718 -126.3269) (xy 251.747386 -126.317735) (xy 251.748198 -126.298028)
			(xy 251.741542 -126.279462) (xy 251.735336 -126.271782) (xy 251.726192 -126.261368) (xy 251.71009 -126.241171)
			(xy 251.682891 -126.197259) (xy 251.661845 -126.150088) (xy 251.647334 -126.100515) (xy 251.639622 -126.049441)
			(xy 251.638816 -126.023624) (xy 251.638816 -126.017782) (xy 251.639832 -125.988318) (xy 251.640594 -125.977396)
			(xy 251.634498 -125.960886) (xy 251.63399 -125.959616) (xy 251.632974 -125.956568) (xy 251.6251 -125.948694)
			(xy 251.617666 -125.941978) (xy 251.599166 -125.934342) (xy 251.579152 -125.934342) (xy 251.560652 -125.941978)
			(xy 251.553218 -125.948694) (xy 251.282962 -126.21895) (xy 251.276692 -126.225868) (xy 251.26915 -126.242932)
			(xy 251.26823 -126.252224) (xy 251.267722 -126.261622) (xy 251.273818 -126.279656) (xy 251.279914 -126.287022)
			(xy 251.296397 -126.307645) (xy 251.324126 -126.35257) (xy 251.345404 -126.400885) (xy 251.359825 -126.45167)
			(xy 251.367116 -126.503958) (xy 251.367544 -126.530354) (xy 251.367084 -126.55761) (xy 251.359333 -126.611568)
			(xy 251.343981 -126.663873) (xy 251.321342 -126.713462) (xy 251.291876 -126.759323) (xy 251.256182 -126.800524)
			(xy 251.214989 -126.836226) (xy 251.169134 -126.865702) (xy 251.11955 -126.888352) (xy 251.067248 -126.903715)
			(xy 251.013292 -126.911478) (xy 250.986036 -126.911862) (xy 250.960155 -126.911433) (xy 250.908866 -126.904446)
			(xy 250.858991 -126.890594) (xy 250.811444 -126.870132) (xy 250.767097 -126.843434) (xy 250.726763 -126.810991)
			(xy 250.708668 -126.792482) (xy 250.704604 -126.788418) (xy 250.675902 -126.775972) (xy 250.671393 -126.774244)
			(xy 250.661931 -126.772329) (xy 250.657106 -126.772162) (xy 250.603766 -126.772162) (xy 250.598941 -126.772327)
			(xy 250.589481 -126.774251) (xy 250.58497 -126.775972) (xy 250.556268 -126.788418) (xy 250.552204 -126.792482)
			(xy 250.534097 -126.810978) (xy 250.49376 -126.843415) (xy 250.449414 -126.87011) (xy 250.401871 -126.890576)
			(xy 250.352001 -126.904438) (xy 250.300716 -126.911443) (xy 250.274836 -126.911862) (xy 250.247583 -126.911401)
			(xy 250.19363 -126.903648) (xy 250.141331 -126.888295) (xy 250.091749 -126.865654) (xy 250.045895 -126.836186)
			(xy 250.004701 -126.800491) (xy 249.969008 -126.759297) (xy 249.939542 -126.713442) (xy 249.916902 -126.66386)
			(xy 249.90155 -126.61156) (xy 249.893798 -126.557607) (xy 249.893328 -126.530354) (xy 249.893824 -126.50266)
			(xy 249.901831 -126.447854) (xy 249.917669 -126.394779) (xy 249.941006 -126.344548) (xy 249.971354 -126.298215)
			(xy 250.008076 -126.25675) (xy 250.050401 -126.221024) (xy 250.073668 -126.205996) (xy 250.075954 -126.204472)
			(xy 250.084593 -126.19778) (xy 250.095643 -126.178954) (xy 250.09729 -126.16815) (xy 250.105164 -126.08814)
			(xy 250.105756 -126.076507) (xy 250.097683 -126.054684) (xy 250.08967 -126.04623) (xy 250.089416 -126.045976)
			(xy 250.070849 -126.027882) (xy 250.03828 -125.987545) (xy 250.011471 -125.943172) (xy 249.990914 -125.895578)
			(xy 249.976989 -125.845639) (xy 249.969951 -125.794276) (xy 249.969528 -125.768354) (xy 249.970017 -125.741106)
			(xy 249.977779 -125.687165) (xy 249.993139 -125.634878) (xy 250.015783 -125.585309) (xy 250.045251 -125.539467)
			(xy 250.080943 -125.498285) (xy 250.122133 -125.462602) (xy 250.167981 -125.433144) (xy 250.217555 -125.41051)
			(xy 250.269845 -125.395162) (xy 250.323788 -125.387412) (xy 250.351036 -125.386846) (xy 250.376687 -125.387266)
			(xy 250.427524 -125.394152) (xy 250.476978 -125.407795) (xy 250.524156 -125.427948) (xy 250.568204 -125.454247)
			(xy 250.588526 -125.469904) (xy 250.58878 -125.470158) (xy 250.594953 -125.474601) (xy 250.609157 -125.480021)
			(xy 250.61672 -125.480826) (xy 250.652788 -125.480826) (xy 250.652788 -125.492002) (xy 250.71324 -125.492002)
			(xy 250.717541 -125.490911) (xy 250.725717 -125.487468) (xy 250.729496 -125.485144) (xy 250.733814 -125.482096)
			(xy 250.735338 -125.480826) (xy 250.75627 -125.463185) (xy 250.802236 -125.433462) (xy 250.851983 -125.410622)
			(xy 250.904487 -125.395136) (xy 250.958666 -125.387322) (xy 250.986036 -125.386846) (xy 251.013218 -125.38733)
			(xy 251.06703 -125.395053) (xy 251.119201 -125.410338) (xy 251.168673 -125.432875) (xy 251.214444 -125.462208)
			(xy 251.255587 -125.497742) (xy 251.273818 -125.51791) (xy 251.274072 -125.518164) (xy 251.276866 -125.521212)
			(xy 251.284002 -125.527559) (xy 251.301623 -125.534881) (xy 251.311156 -125.535436) (xy 251.352304 -125.53442)
			(xy 251.352812 -125.53442) (xy 251.393198 -125.533658) (xy 251.403158 -125.532631) (xy 251.421209 -125.524012)
			(xy 251.42825 -125.516894) (xy 251.717302 -125.15088) (xy 251.717556 -125.150372) (xy 251.71781 -125.150118)
			(xy 251.719334 -125.14834) (xy 251.720604 -125.146562) (xy 251.720858 -125.146308) (xy 251.721874 -125.145038)
			(xy 251.722382 -125.144276) (xy 251.725684 -125.139704) (xy 251.72924 -125.13183) (xy 251.730868 -125.127367)
			(xy 251.732659 -125.118037) (xy 251.732796 -125.113288) (xy 251.732796 -125.091952) (xy 251.732941 -125.086513)
			(xy 251.735251 -125.075883) (xy 251.737368 -125.07087) (xy 251.743718 -125.0569) (xy 251.747386 -125.047735)
			(xy 251.748198 -125.028028) (xy 251.741542 -125.009462) (xy 251.735336 -125.001782) (xy 251.726192 -124.991368)
			(xy 251.709763 -124.97075) (xy 251.682128 -124.925854) (xy 251.660923 -124.877587) (xy 251.64655 -124.826865)
			(xy 251.639282 -124.774649) (xy 251.638816 -124.74829) (xy 251.638816 -124.747782) (xy 251.639281 -124.720531)
			(xy 251.64704 -124.666583) (xy 251.662398 -124.614289) (xy 251.685041 -124.564712) (xy 251.71451 -124.518863)
			(xy 251.750204 -124.477675) (xy 251.791397 -124.441985) (xy 251.837249 -124.412521) (xy 251.886828 -124.389883)
			(xy 251.939124 -124.374531) (xy 251.993073 -124.366778) (xy 252.020324 -124.366274) (xy 252.05817 -124.368052)
			(xy 252.065282 -124.368814) (xy 252.076966 -124.366528) (xy 252.084125 -124.36493) (xy 252.097162 -124.358221)
			(xy 252.10262 -124.35332) (xy 252.113288 -124.342144) (xy 252.120315 -124.33414) (xy 252.127687 -124.314184)
			(xy 252.127512 -124.303536) (xy 251.999496 -123.326906) (xy 251.998065 -123.318801) (xy 251.990809 -123.304039)
			(xy 251.985272 -123.29795) (xy 251.979684 -123.292362) (xy 251.96546 -123.284742) (xy 251.957332 -123.283472)
			(xy 251.930961 -123.278581) (xy 251.879831 -123.26238) (xy 251.831472 -123.239184) (xy 251.786835 -123.209448)
			(xy 251.746797 -123.173759) (xy 251.712148 -123.132819) (xy 251.683569 -123.087433) (xy 251.661622 -123.038494)
			(xy 251.64674 -122.986965) (xy 251.639214 -122.933861) (xy 251.638816 -122.907044) (xy 251.639379 -122.876955)
			(xy 251.648823 -122.817521) (xy 251.667483 -122.760309) (xy 251.694897 -122.706737) (xy 251.730384 -122.658135)
			(xy 251.751338 -122.636534) (xy 251.754894 -122.632978) (xy 251.764038 -122.619262) (xy 251.764292 -122.619008)
			(xy 251.766324 -122.615706) (xy 251.76861 -122.611642) (xy 251.772928 -122.601228) (xy 251.775722 -122.594116)
			(xy 251.777754 -122.586496) (xy 251.778516 -122.57786) (xy 251.778516 -122.515884) (xy 251.778197 -122.507603)
			(xy 251.772883 -122.491919) (xy 251.768102 -122.48515) (xy 251.76607 -122.482864) (xy 251.764292 -122.481086)
			(xy 251.76099 -122.477276) (xy 251.757942 -122.474228) (xy 251.754894 -122.46991) (xy 251.751846 -122.466862)
			(xy 251.730824 -122.44523) (xy 251.695187 -122.396565) (xy 251.667651 -122.342899) (xy 251.648901 -122.285569)
			(xy 251.639405 -122.226003) (xy 251.638816 -122.195844) (xy 251.638893 -122.183106) (xy 251.640543 -122.157684)
			(xy 251.642118 -122.145044) (xy 251.645945 -122.119688) (xy 251.659513 -122.070236) (xy 251.679569 -122.023041)
			(xy 251.705755 -121.978951) (xy 251.721366 -121.958608) (xy 251.72543 -121.953528) (xy 251.728986 -121.945654)
			(xy 251.730755 -121.941025) (xy 251.732664 -121.931304) (xy 251.732796 -121.92635) (xy 251.732796 -121.905014)
			(xy 251.732934 -121.899573) (xy 251.735233 -121.888938) (xy 251.737368 -121.883932) (xy 251.743718 -121.869962)
			(xy 251.747398 -121.860794) (xy 251.748231 -121.841075) (xy 251.741589 -121.822491) (xy 251.735336 -121.814844)
			(xy 251.726192 -121.80443) (xy 251.710092 -121.784232) (xy 251.682897 -121.74032) (xy 251.661856 -121.693148)
			(xy 251.64735 -121.643576) (xy 251.639643 -121.592502) (xy 251.638816 -121.566686) (xy 251.638816 -121.560844)
			(xy 251.639832 -121.53138) (xy 251.640594 -121.520458) (xy 251.636784 -121.510044) (xy 251.634773 -121.50495)
			(xy 251.628876 -121.495724) (xy 251.6251 -121.491756) (xy 251.622814 -121.48947) (xy 251.621798 -121.47042)
			(xy 251.621716 -121.461247) (xy 251.62731 -121.443791) (xy 251.63272 -121.436384) (xy 251.714762 -121.332244)
			(xy 251.720604 -121.324116) (xy 251.726446 -121.31675) (xy 251.728986 -121.310654) (xy 251.732288 -121.298208)
			(xy 251.714762 -121.164858) (xy 251.711714 -121.153174) (xy 251.709682 -121.147586) (xy 251.706126 -121.142506)
			(xy 251.696943 -121.128911) (xy 251.68067 -121.100421) (xy 251.673614 -121.08561) (xy 251.670058 -121.077228)
			(xy 251.664671 -121.064511) (xy 251.655517 -121.038451) (xy 251.65177 -121.025158) (xy 251.65177 -121.024904)
			(xy 251.650246 -121.018808) (xy 251.648722 -121.012458) (xy 251.646182 -121.012204) (xy 251.642372 -120.979184)
			(xy 251.642372 -120.977914) (xy 251.63907 -120.9421) (xy 251.638816 -120.933718) (xy 251.638816 -120.923812)
			(xy 251.638926 -120.912543) (xy 251.640323 -120.890049) (xy 251.64161 -120.878854) (xy 251.644482 -120.85818)
			(xy 251.654153 -120.817575) (xy 251.660914 -120.797828) (xy 251.662946 -120.791986) (xy 251.664216 -120.780556)
			(xy 251.61748 -120.425718) (xy 251.586492 -120.189244) (xy 251.584714 -120.181116) (xy 251.477272 -119.826532)
			(xy 251.052838 -118.426992) (xy 251.049687 -118.417837) (xy 251.037666 -118.402683) (xy 251.02947 -118.397528)
			(xy 251.024644 -118.394734) (xy 251.011944 -118.391432) (xy 250.996704 -118.391432) (xy 250.994926 -118.39194)
			(xy 250.972302 -118.397186) (xy 250.9262 -118.402794) (xy 250.902978 -118.403116) (xy 250.894088 -118.403116)
			(xy 250.88469 -118.402862) (xy 250.884182 -118.402862) (xy 250.872888 -118.402233) (xy 250.850395 -118.399815)
			(xy 250.839224 -118.398036) (xy 250.825508 -118.395496) (xy 250.824238 -118.395242) (xy 250.821444 -118.394734)
			(xy 250.812046 -118.392702) (xy 250.810268 -118.392194) (xy 250.809506 -118.39194) (xy 250.784091 -118.385135)
			(xy 250.735278 -118.365498) (xy 250.689616 -118.339358) (xy 250.668536 -118.323614) (xy 250.666758 -118.322344)
			(xy 250.6599 -118.31828) (xy 250.645168 -118.310914) (xy 250.632468 -118.309136) (xy 250.611132 -118.309136)
			(xy 250.605694 -118.308988) (xy 250.595066 -118.306672) (xy 250.59005 -118.304564) (xy 250.57608 -118.298214)
			(xy 250.566912 -118.294529) (xy 250.54719 -118.293688) (xy 250.5286 -118.300331) (xy 250.520962 -118.306596)
			(xy 250.510548 -118.31574) (xy 250.490096 -118.332054) (xy 250.445577 -118.35953) (xy 250.397727 -118.380682)
			(xy 250.347441 -118.395114) (xy 250.295657 -118.402557) (xy 250.269502 -118.403116) (xy 250.266962 -118.403116)
			(xy 250.239931 -118.402643) (xy 250.186412 -118.395006) (xy 250.134507 -118.379891) (xy 250.085255 -118.357599)
			(xy 250.039644 -118.328579) (xy 249.998586 -118.29341) (xy 249.962903 -118.252797) (xy 249.933312 -118.207553)
			(xy 249.910403 -118.158586) (xy 249.894636 -118.106875) (xy 249.886327 -118.053456) (xy 249.885454 -118.026434)
			(xy 249.885454 -118.021608) (xy 249.88647 -117.992144) (xy 249.887232 -117.981222) (xy 249.883422 -117.970808)
			(xy 249.88141 -117.965715) (xy 249.875511 -117.95649) (xy 249.871738 -117.95252) (xy 249.869452 -117.950234)
			(xy 249.868436 -117.931184) (xy 249.86836 -117.922012) (xy 249.873957 -117.904561) (xy 249.879358 -117.897148)
			(xy 249.96394 -117.789706) (xy 249.964194 -117.789198) (xy 249.964448 -117.788944) (xy 249.965972 -117.787166)
			(xy 249.967242 -117.785388) (xy 249.967496 -117.785134) (xy 249.968512 -117.783864) (xy 249.96902 -117.783102)
			(xy 249.972322 -117.77853) (xy 249.975878 -117.770656) (xy 249.977507 -117.766193) (xy 249.979301 -117.756863)
			(xy 249.979434 -117.752114) (xy 249.979434 -117.730778) (xy 249.979576 -117.725338) (xy 249.981883 -117.714706)
			(xy 249.984006 -117.709696) (xy 249.990356 -117.695726) (xy 249.994032 -117.686561) (xy 249.994855 -117.666849)
			(xy 249.988197 -117.648277) (xy 249.981974 -117.640608) (xy 249.97283 -117.630194) (xy 249.956725 -117.609998)
			(xy 249.92952 -117.566088) (xy 249.908469 -117.518917) (xy 249.893953 -117.469344) (xy 249.886237 -117.418269)
			(xy 249.885454 -117.39245) (xy 249.885454 -117.386608) (xy 249.88647 -117.357144) (xy 249.887232 -117.346222)
			(xy 249.883422 -117.335808) (xy 249.88141 -117.330715) (xy 249.875511 -117.32149) (xy 249.871738 -117.31752)
			(xy 249.869452 -117.315234) (xy 249.868436 -117.296184) (xy 249.86836 -117.287012) (xy 249.873957 -117.269561)
			(xy 249.879358 -117.262148) (xy 249.96394 -117.154706) (xy 249.964194 -117.154198) (xy 249.964448 -117.153944)
			(xy 249.965972 -117.152166) (xy 249.967242 -117.150388) (xy 249.967496 -117.150134) (xy 249.968512 -117.148864)
			(xy 249.96902 -117.148102) (xy 249.972322 -117.14353) (xy 249.975878 -117.135656) (xy 249.977507 -117.131193)
			(xy 249.979301 -117.121863) (xy 249.979434 -117.117114) (xy 249.979434 -117.095778) (xy 249.979576 -117.090338)
			(xy 249.981883 -117.079706) (xy 249.984006 -117.074696) (xy 249.990356 -117.060726) (xy 249.994032 -117.051561)
			(xy 249.994855 -117.031849) (xy 249.988197 -117.013277) (xy 249.981974 -117.005608) (xy 249.97283 -116.995194)
			(xy 249.956398 -116.974577) (xy 249.928757 -116.929683) (xy 249.907547 -116.881416) (xy 249.893169 -116.830693)
			(xy 249.885896 -116.778476) (xy 249.885454 -116.752116) (xy 249.885454 -116.751608) (xy 249.885939 -116.724355)
			(xy 249.893695 -116.670405) (xy 249.909049 -116.618107) (xy 249.931689 -116.568526) (xy 249.961154 -116.522672)
			(xy 249.996845 -116.481478) (xy 250.038035 -116.445782) (xy 250.083886 -116.416311) (xy 250.133464 -116.393665)
			(xy 250.18576 -116.378304) (xy 250.239709 -116.370542) (xy 250.266962 -116.3701) (xy 250.274582 -116.3701)
			(xy 250.293124 -116.370862) (xy 250.293632 -116.370862) (xy 250.299982 -116.371116) (xy 250.31065 -116.36629)
			(xy 250.31617 -116.36362) (xy 250.325804 -116.356039) (xy 250.3297 -116.351304) (xy 250.381516 -116.285772)
			(xy 250.38304 -116.283994) (xy 250.38878 -116.274931) (xy 250.392994 -116.253924) (xy 250.391168 -116.243354)
			(xy 249.71756 -114.02187) (xy 249.714648 -114.013537) (xy 249.704116 -113.99939) (xy 249.696986 -113.994184)
			(xy 249.682508 -113.984532) (xy 249.672348 -113.985548) (xy 249.661651 -113.986647) (xy 249.640175 -113.987792)
			(xy 249.629422 -113.987834) (xy 249.629168 -113.987834) (xy 249.601918 -113.987346) (xy 249.547972 -113.979586)
			(xy 249.49568 -113.964228) (xy 249.446105 -113.941586) (xy 249.400256 -113.912119) (xy 249.359068 -113.876428)
			(xy 249.323377 -113.835239) (xy 249.293911 -113.78939) (xy 249.27127 -113.739815) (xy 249.255913 -113.687522)
			(xy 249.248154 -113.633576) (xy 249.24766 -113.606326) (xy 249.24766 -113.59896) (xy 249.247914 -113.585244)
			(xy 249.24131 -113.573306) (xy 249.237798 -113.567386) (xy 249.228132 -113.557594) (xy 249.22226 -113.554002)
			(xy 249.145298 -113.509552) (xy 249.139303 -113.506386) (xy 249.126169 -113.503045) (xy 249.11939 -113.502948)
			(xy 249.105674 -113.502948) (xy 249.093736 -113.51006) (xy 249.071383 -113.52301) (xy 249.02393 -113.543428)
			(xy 248.974155 -113.557252) (xy 248.92297 -113.564231) (xy 248.89714 -113.56467) (xy 248.86989 -113.56421)
			(xy 248.815943 -113.556459) (xy 248.763649 -113.54111) (xy 248.714071 -113.518475) (xy 248.66822 -113.489015)
			(xy 248.627027 -113.453329) (xy 248.591333 -113.412144) (xy 248.561863 -113.366298) (xy 248.539218 -113.316725)
			(xy 248.523858 -113.264434) (xy 248.516096 -113.210489) (xy 248.51609 -113.155989) (xy 248.523841 -113.102043)
			(xy 248.53919 -113.049748) (xy 248.561825 -113.000171) (xy 248.591286 -112.954319) (xy 248.626972 -112.913127)
			(xy 248.668157 -112.877433) (xy 248.714002 -112.847963) (xy 248.763575 -112.825318) (xy 248.815866 -112.809958)
			(xy 248.869811 -112.802196) (xy 248.924312 -112.80219) (xy 248.978258 -112.809941) (xy 249.030552 -112.82529)
			(xy 249.08013 -112.847926) (xy 249.125981 -112.877386) (xy 249.167174 -112.913072) (xy 249.202868 -112.954257)
			(xy 249.232337 -113.000103) (xy 249.254983 -113.049676) (xy 249.270342 -113.101967) (xy 249.278104 -113.155912)
			(xy 249.278648 -113.183162) (xy 249.278648 -113.190528) (xy 249.278394 -113.204498) (xy 249.284998 -113.216436)
			(xy 249.288534 -113.222171) (xy 249.298062 -113.231691) (xy 249.303794 -113.235232) (xy 249.342402 -113.257838)
			(xy 249.380756 -113.279936) (xy 249.386863 -113.283188) (xy 249.400253 -113.286653) (xy 249.407172 -113.286794)
			(xy 249.420634 -113.28654) (xy 249.432318 -113.279428) (xy 249.437144 -113.276634) (xy 249.43943 -113.275364)
			(xy 249.444764 -113.272316) (xy 249.445526 -113.271808) (xy 249.447812 -113.270538) (xy 249.448066 -113.270538)
			(xy 249.45549 -113.2661) (xy 249.467044 -113.253244) (xy 249.470672 -113.245392) (xy 249.473974 -113.237772)
			(xy 249.474736 -113.220246) (xy 248.965974 -111.541306) (xy 248.961746 -111.53158) (xy 248.946944 -111.516423)
			(xy 248.927301 -111.508488) (xy 248.916698 -111.508286) (xy 248.916444 -111.508286) (xy 248.903744 -111.50854)
			(xy 248.902474 -111.50854) (xy 248.875232 -111.508039) (xy 248.821308 -111.500256) (xy 248.769038 -111.484882)
			(xy 248.719487 -111.462228) (xy 248.673663 -111.432757) (xy 248.632497 -111.397066) (xy 248.596827 -111.355882)
			(xy 248.567378 -111.310042) (xy 248.54475 -111.26048) (xy 248.529402 -111.208203) (xy 248.521647 -111.154274)
			(xy 248.52122 -111.127032) (xy 248.521679 -111.100114) (xy 248.529238 -111.04681) (xy 248.54421 -110.995097)
			(xy 248.566299 -110.946) (xy 248.595066 -110.900493) (xy 248.629941 -110.859479) (xy 248.670232 -110.823771)
			(xy 248.692416 -110.808516) (xy 248.697496 -110.805214) (xy 248.705878 -110.796324) (xy 248.726706 -110.758986)
			(xy 248.725436 -110.74781) (xy 246.954294 -104.905302) (xy 246.797322 -104.386888) (xy 246.661178 -103.937562)
			(xy 246.659617 -103.932801) (xy 246.654875 -103.923977) (xy 246.65178 -103.920036) (xy 246.64543 -103.912416)
			(xy 246.63654 -103.90759) (xy 246.611239 -103.893371) (xy 246.564872 -103.858466) (xy 246.524325 -103.816945)
			(xy 246.49053 -103.769764) (xy 246.464267 -103.71801) (xy 246.446141 -103.662877) (xy 246.436571 -103.605636)
			(xy 246.435626 -103.576628) (xy 246.435626 -103.571294) (xy 246.436267 -103.540209) (xy 246.446387 -103.478867)
			(xy 246.466296 -103.419969) (xy 246.48033 -103.392224) (xy 246.485156 -103.38308) (xy 246.486172 -103.373682)
			(xy 246.486559 -103.368614) (xy 246.485537 -103.358503) (xy 246.48414 -103.353616) (xy 246.413782 -103.121714)
			(xy 246.41302 -103.119174) (xy 246.412766 -103.118412) (xy 246.41175 -103.115364) (xy 246.325136 -102.82936)
			(xy 246.265954 -102.634288) (xy 246.262104 -102.625472) (xy 246.249055 -102.611357) (xy 246.240554 -102.606856)
			(xy 246.17045 -102.574852) (xy 246.165442 -102.57272) (xy 246.154809 -102.570408) (xy 246.149368 -102.57028)
			(xy 246.1387 -102.57028) (xy 246.13235 -102.573074) (xy 246.105316 -102.585012) (xy 246.048672 -102.601856)
			(xy 245.990194 -102.610378) (xy 245.960646 -102.61092) (xy 245.960392 -102.61092) (xy 245.931163 -102.610398)
			(xy 245.8733 -102.602078) (xy 245.817209 -102.585608) (xy 245.764034 -102.561324) (xy 245.714855 -102.529719)
			(xy 245.670675 -102.491438) (xy 245.632391 -102.447259) (xy 245.600785 -102.398082) (xy 245.576498 -102.344907)
			(xy 245.560026 -102.288818) (xy 245.551703 -102.230955) (xy 245.551198 -102.201726) (xy 245.551684 -102.172965)
			(xy 245.559734 -102.116009) (xy 245.575679 -102.060742) (xy 245.599205 -102.008251) (xy 245.629849 -101.959571)
			(xy 245.667007 -101.915661) (xy 245.709946 -101.877386) (xy 245.757822 -101.845501) (xy 245.80969 -101.820632)
			(xy 245.864529 -101.80327) (xy 245.892828 -101.79812) (xy 245.90375 -101.796342) (xy 245.912894 -101.790246)
			(xy 245.917242 -101.787139) (xy 245.924664 -101.779454) (xy 245.927626 -101.775006) (xy 245.943374 -101.749352)
			(xy 245.967758 -101.709982) (xy 245.972753 -101.701134) (xy 245.976032 -101.681097) (xy 245.974108 -101.67112)
			(xy 243.458746 -93.37294) (xy 243.05895 -92.054172) (xy 242.691412 -90.841576) (xy 242.688923 -90.834257)
			(xy 242.680265 -90.821458) (xy 242.674394 -90.81643) (xy 242.652419 -90.798213) (xy 242.613609 -90.75636)
			(xy 242.581469 -90.709192) (xy 242.556716 -90.657761) (xy 242.539904 -90.603215) (xy 242.531408 -90.546773)
			(xy 242.530884 -90.518234) (xy 242.530884 -90.517726) (xy 242.531454 -90.488415) (xy 242.540505 -90.430493)
			(xy 242.548918 -90.40241) (xy 242.548918 -90.372438) (xy 242.449096 -90.042238) (xy 241.211354 -85.959442)
			(xy 241.207562 -85.949053) (xy 241.192816 -85.932602) (xy 241.182906 -85.927692) (xy 241.175794 -85.925152)
			(xy 241.173254 -85.924644) (xy 241.145128 -85.918123) (xy 241.091108 -85.897747) (xy 241.040774 -85.869465)
			(xy 240.995276 -85.833924) (xy 240.955651 -85.791934) (xy 240.922803 -85.744454) (xy 240.897484 -85.692567)
			(xy 240.88027 -85.637458) (xy 240.871555 -85.580385) (xy 240.870994 -85.551518) (xy 240.871547 -85.522343)
			(xy 240.880429 -85.464673) (xy 240.89799 -85.409027) (xy 240.92382 -85.356705) (xy 240.957316 -85.308927)
			(xy 240.997696 -85.266806) (xy 241.04402 -85.231325) (xy 241.095207 -85.203313) (xy 241.122454 -85.19287)
			(xy 241.125248 -85.191854) (xy 241.133425 -85.187947) (xy 241.146537 -85.175455) (xy 241.154467 -85.159173)
			(xy 241.155728 -85.150198) (xy 241.159792 -84.671408) (xy 241.1603 -84.62137) (xy 241.162078 -84.376006)
			(xy 241.161846 -84.367177) (xy 241.155996 -84.350522) (xy 241.150648 -84.343494) (xy 241.14506 -84.33689)
			(xy 241.130074 -84.327746) (xy 241.12093 -84.325968) (xy 241.09514 -84.320553) (xy 241.045257 -84.303568)
			(xy 240.998186 -84.279878) (xy 240.954824 -84.249934) (xy 240.915997 -84.214306) (xy 240.882444 -84.173673)
			(xy 240.854803 -84.128808) (xy 240.833602 -84.080565) (xy 240.819243 -84.029862) (xy 240.812 -83.977666)
			(xy 240.811558 -83.951318) (xy 240.812076 -83.922602) (xy 240.820681 -83.865818) (xy 240.8377 -83.810965)
			(xy 240.862748 -83.759283) (xy 240.895259 -83.711938) (xy 240.934499 -83.670002) (xy 240.979582 -83.63442)
			(xy 241.029488 -83.605997) (xy 241.08309 -83.585375) (xy 241.111024 -83.5787) (xy 241.119152 -83.576922)
			(xy 241.13363 -83.568286) (xy 241.157252 -83.540092) (xy 241.162693 -83.533144) (xy 241.168913 -83.516644)
			(xy 241.169444 -83.507834) (xy 241.172238 -83.155028) (xy 241.171815 -83.144061) (xy 241.162852 -83.124054)
			(xy 241.154966 -83.11642) (xy 241.111532 -83.07832) (xy 241.100356 -83.075272) (xy 241.089434 -83.072224)
			(xy 241.078512 -83.074002) (xy 241.064122 -83.076044) (xy 241.035134 -83.078206) (xy 241.0206 -83.07832)
			(xy 240.993348 -83.077834) (xy 240.9394 -83.070078) (xy 240.887105 -83.054723) (xy 240.837527 -83.032082)
			(xy 240.791675 -83.002616) (xy 240.750484 -82.966924) (xy 240.714791 -82.925734) (xy 240.685324 -82.879884)
			(xy 240.662681 -82.830307) (xy 240.647325 -82.778012) (xy 240.639567 -82.724064) (xy 240.639092 -82.696812)
			(xy 240.639576 -82.669572) (xy 240.647325 -82.615645) (xy 240.662666 -82.563369) (xy 240.685288 -82.513807)
			(xy 240.71473 -82.467968) (xy 240.750394 -82.426783) (xy 240.791554 -82.39109) (xy 240.837374 -82.361616)
			(xy 240.88692 -82.338959) (xy 240.939185 -82.323581) (xy 240.993106 -82.315795) (xy 241.020346 -82.315304)
			(xy 241.020854 -82.315304) (xy 241.039462 -82.31563) (xy 241.076484 -82.319452) (xy 241.094768 -82.322924)
			(xy 241.098324 -82.323432) (xy 241.113056 -82.319368) (xy 241.11699 -82.317992) (xy 241.124396 -82.314169)
			(xy 241.127788 -82.311748) (xy 241.161316 -82.283808) (xy 241.169129 -82.276729) (xy 241.178695 -82.257966)
			(xy 241.179858 -82.247486) (xy 241.185954 -81.519522) (xy 241.185177 -81.509801) (xy 241.17728 -81.491988)
			(xy 241.163308 -81.478407) (xy 241.154458 -81.47431) (xy 241.143282 -81.469992) (xy 241.064542 -81.439512)
			(xy 241.054845 -81.436251) (xy 241.034414 -81.436889) (xy 241.015849 -81.445441) (xy 241.008662 -81.45272)
			(xy 241.008408 -81.452974) (xy 240.990253 -81.47262) (xy 240.949391 -81.50714) (xy 240.904106 -81.535612)
			(xy 240.855287 -81.557476) (xy 240.803891 -81.572304) (xy 240.750928 -81.579804) (xy 240.724182 -81.580228)
			(xy 240.69693 -81.579741) (xy 240.642982 -81.571982) (xy 240.590686 -81.556624) (xy 240.541109 -81.533981)
			(xy 240.495258 -81.504513) (xy 240.454068 -81.468819) (xy 240.418376 -81.427627) (xy 240.38891 -81.381776)
			(xy 240.366269 -81.332197) (xy 240.350914 -81.279901) (xy 240.343158 -81.225952) (xy 240.343158 -81.171448)
			(xy 240.350914 -81.117499) (xy 240.366269 -81.065203) (xy 240.38891 -81.015624) (xy 240.418376 -80.969773)
			(xy 240.454068 -80.928581) (xy 240.495258 -80.892887) (xy 240.541109 -80.863419) (xy 240.590686 -80.840776)
			(xy 240.642982 -80.825418) (xy 240.69693 -80.817659) (xy 240.724182 -80.817212) (xy 240.751377 -80.817693)
			(xy 240.805216 -80.825416) (xy 240.857413 -80.840707) (xy 240.906908 -80.863256) (xy 240.952699 -80.892607)
			(xy 240.993857 -80.928164) (xy 241.029548 -80.969206) (xy 241.059048 -81.014901) (xy 241.081758 -81.064323)
			(xy 241.089942 -81.090262) (xy 241.089942 -81.090516) (xy 241.093225 -81.100087) (xy 241.106005 -81.115754)
			(xy 241.123855 -81.12525) (xy 241.133884 -81.126584) (xy 241.138456 -81.126584) (xy 241.14846 -81.12619)
			(xy 241.167016 -81.11873) (xy 241.174524 -81.112106) (xy 241.181382 -81.105248) (xy 241.189256 -81.086706)
			(xy 241.190526 -80.9498) (xy 241.188494 -80.93583) (xy 241.18697 -80.929988) (xy 241.18316 -80.923638)
			(xy 241.170357 -80.901664) (xy 241.150047 -80.855038) (xy 241.136114 -80.806126) (xy 241.128804 -80.755797)
			(xy 241.128247 -80.704943) (xy 241.134454 -80.654466) (xy 241.140488 -80.62976) (xy 241.140742 -80.628998)
			(xy 241.146728 -80.607579) (xy 241.163024 -80.566196) (xy 241.173254 -80.546448) (xy 241.186716 -80.52308)
			(xy 241.190272 -80.517238) (xy 241.19205 -80.510634) (xy 241.194082 -80.497172) (xy 241.243866 -74.475848)
			(xy 241.243623 -74.467289) (xy 241.238174 -74.451066) (xy 241.233198 -74.444098) (xy 241.228118 -74.437748)
			(xy 241.213894 -74.428604) (xy 241.205004 -74.426318) (xy 241.177531 -74.419217) (xy 241.124904 -74.398003)
			(xy 241.075995 -74.369235) (xy 241.031882 -74.333547) (xy 240.993534 -74.291725) (xy 240.961797 -74.244688)
			(xy 240.93737 -74.193474) (xy 240.920789 -74.139209) (xy 240.91242 -74.083087) (xy 240.911888 -74.054716)
			(xy 240.912404 -74.026003) (xy 240.921 -73.969224) (xy 240.937999 -73.914371) (xy 240.96302 -73.862682)
			(xy 240.995497 -73.815322) (xy 241.034699 -73.773358) (xy 241.079743 -73.737737) (xy 241.129611 -73.709261)
			(xy 241.183181 -73.688572) (xy 241.2111 -73.681844) (xy 241.211354 -73.681844) (xy 241.219621 -73.679688)
			(xy 241.23416 -73.670733) (xy 241.239802 -73.664318) (xy 241.245136 -73.657714) (xy 241.250978 -73.641458)
			(xy 241.331496 -63.910464) (xy 241.331438 -63.906191) (xy 241.330035 -63.89776) (xy 241.328702 -63.8937)
			(xy 241.326416 -63.886842) (xy 241.320828 -63.879476) (xy 241.304287 -63.856934) (xy 241.27728 -63.807979)
			(xy 241.257703 -63.755608) (xy 241.245974 -63.700942) (xy 241.242345 -63.64515) (xy 241.246894 -63.589425)
			(xy 241.259521 -63.534959) (xy 241.279959 -63.482918) (xy 241.307769 -63.434415) (xy 241.324638 -63.412116)
			(xy 241.324892 -63.411862) (xy 241.329311 -63.405746) (xy 241.334745 -63.391677) (xy 241.33556 -63.384176)
			(xy 241.34191 -62.625986) (xy 241.34191 -62.624462) (xy 241.341656 -62.60719) (xy 241.341656 -61.913262)
			(xy 241.341206 -61.903421) (xy 241.333783 -61.885193) (xy 241.320017 -61.871128) (xy 241.311176 -61.86678)
			(xy 241.300254 -61.861954) (xy 241.291385 -61.859075) (xy 241.272756 -61.859196) (xy 241.263932 -61.862208)
			(xy 241.250724 -61.868304) (xy 241.246152 -61.870336) (xy 241.241834 -61.873892) (xy 241.241072 -61.8744)
			(xy 241.24031 -61.875162) (xy 241.219419 -61.892462) (xy 241.173676 -61.921612) (xy 241.124274 -61.944009)
			(xy 241.072204 -61.959204) (xy 241.01851 -61.966892) (xy 240.99139 -61.967364) (xy 240.964139 -61.9669)
			(xy 240.910191 -61.959142) (xy 240.857897 -61.943784) (xy 240.808321 -61.921141) (xy 240.762472 -61.891672)
			(xy 240.721284 -61.855977) (xy 240.685596 -61.814784) (xy 240.656134 -61.768931) (xy 240.633497 -61.719352)
			(xy 240.618147 -61.667056) (xy 240.610396 -61.613107) (xy 240.609882 -61.585856) (xy 240.610364 -61.558699)
			(xy 240.618073 -61.504934) (xy 240.63333 -61.452806) (xy 240.655825 -61.403369) (xy 240.685104 -61.357622)
			(xy 240.720575 -61.316489) (xy 240.761521 -61.280803) (xy 240.807114 -61.251285) (xy 240.856433 -61.228532)
			(xy 240.90848 -61.213003) (xy 240.962204 -61.205012) (xy 240.989358 -61.204348) (xy 240.991644 -61.204348)
			(xy 241.019086 -61.204847) (xy 241.073399 -61.212745) (xy 241.126024 -61.228331) (xy 241.17588 -61.251282)
			(xy 241.199162 -61.265816) (xy 241.202972 -61.268356) (xy 241.205766 -61.270134) (xy 241.215926 -61.275468)
			(xy 241.220244 -61.276738) (xy 241.23015 -61.28004) (xy 241.235184 -61.281343) (xy 241.245552 -61.282105)
			(xy 241.250724 -61.281564) (xy 241.2619 -61.28004) (xy 241.271298 -61.273944) (xy 241.275362 -61.271658)
			(xy 241.27587 -61.271404) (xy 241.28349 -61.267086) (xy 241.283998 -61.267086) (xy 241.322606 -61.245496)
			(xy 241.32794 -61.242448) (xy 241.334544 -61.231018) (xy 241.337798 -61.225107) (xy 241.341389 -61.212107)
			(xy 241.341656 -61.205364) (xy 241.341656 -60.653422) (xy 241.341656 -60.650374) (xy 241.335052 -60.535058)
			(xy 241.289586 -59.725814) (xy 241.289586 -59.724544) (xy 241.197384 -58.708036) (xy 241.195962 -58.700532)
			(xy 241.189251 -58.686819) (xy 241.184176 -58.681112) (xy 241.182398 -58.679334) (xy 241.177318 -58.675016)
			(xy 241.145568 -58.653426) (xy 241.140596 -58.650806) (xy 241.129828 -58.647593) (xy 241.124232 -58.647076)
			(xy 241.120422 -58.646822) (xy 241.101372 -58.646822) (xy 241.094006 -58.649108) (xy 241.08283 -58.65241)
			(xy 241.078258 -58.65368) (xy 241.07013 -58.655712) (xy 241.048032 -58.660538) (xy 241.046254 -58.660792)
			(xy 241.046 -58.660792) (xy 241.042952 -58.6613) (xy 241.04219 -58.6613) (xy 241.035332 -58.66257)
			(xy 241.023711 -58.664215) (xy 241.000326 -58.66625) (xy 240.988596 -58.666634) (xy 240.974118 -58.66638)
			(xy 240.947154 -58.665483) (xy 240.893869 -58.65703) (xy 240.842308 -58.641153) (xy 240.793498 -58.61817)
			(xy 240.748414 -58.588537) (xy 240.707955 -58.552848) (xy 240.672929 -58.511813) (xy 240.644035 -58.466253)
			(xy 240.621849 -58.417075) (xy 240.606814 -58.365262) (xy 240.599229 -58.311847) (xy 240.598706 -58.284872)
			(xy 240.599194 -58.257622) (xy 240.606954 -58.203679) (xy 240.622312 -58.151388) (xy 240.644955 -58.101815)
			(xy 240.674422 -58.055969) (xy 240.710114 -58.014784) (xy 240.751303 -57.979097) (xy 240.797152 -57.949634)
			(xy 240.846727 -57.926997) (xy 240.89902 -57.911645) (xy 240.952964 -57.903891) (xy 240.980214 -57.903364)
			(xy 240.980976 -57.903364) (xy 241.001067 -57.903606) (xy 241.04103 -57.907803) (xy 241.060732 -57.911746)
			(xy 241.069876 -57.912508) (xy 241.082576 -57.91073) (xy 241.08283 -57.91073) (xy 241.085116 -57.910222)
			(xy 241.08942 -57.908765) (xy 241.09747 -57.90455) (xy 241.101118 -57.90184) (xy 241.104928 -57.898538)
			(xy 241.105944 -57.897522) (xy 241.113111 -57.889501) (xy 241.120733 -57.869415) (xy 241.120676 -57.85866)
			(xy 241.074194 -57.343548) (xy 241.072296 -57.321181) (xy 241.070266 -57.276333) (xy 241.07013 -57.253886)
			(xy 241.07013 -57.253632) (xy 241.07013 -57.253378) (xy 241.07013 -57.25287) (xy 241.070638 -57.215786)
			(xy 241.070638 -57.215278) (xy 241.087656 -56.13019) (xy 241.087656 -56.126634) (xy 241.025172 -55.016654)
			(xy 241.0248 -55.011656) (xy 241.022377 -55.001932) (xy 241.020346 -54.99735) (xy 241.01679 -54.989984)
			(xy 241.015774 -54.988206) (xy 241.015012 -54.986936) (xy 241.014758 -54.986682) (xy 241.002602 -54.96485)
			(xy 240.983437 -54.918701) (xy 240.970453 -54.870447) (xy 240.96387 -54.820913) (xy 240.96345 -54.795928)
			(xy 240.96345 -54.786022) (xy 240.964381 -54.759786) (xy 240.97254 -54.707925) (xy 240.987707 -54.657666)
			(xy 240.998248 -54.633622) (xy 241.001042 -54.627526) (xy 241.003328 -54.616858) (xy 241.00282 -54.607714)
			(xy 241.000788 -54.573424) (xy 241.000788 -54.572916) (xy 240.99647 -54.497224) (xy 240.959132 -53.830982)
			(xy 240.923826 -53.20665) (xy 240.922909 -53.197417) (xy 240.915341 -53.180492) (xy 240.909094 -53.17363)
			(xy 240.90376 -53.168296) (xy 240.90249 -53.16728) (xy 240.901474 -53.166264) (xy 240.899188 -53.164232)
			(xy 240.89868 -53.163724) (xy 240.896902 -53.1622) (xy 240.896394 -53.161692) (xy 240.88725 -53.153056)
			(xy 240.886742 -53.152294) (xy 240.870486 -53.134768) (xy 240.852896 -53.113841) (xy 240.823261 -53.067903)
			(xy 240.800487 -53.018205) (xy 240.785038 -52.965765) (xy 240.777232 -52.911658) (xy 240.77676 -52.884324)
			(xy 240.77676 -52.878736) (xy 240.777014 -52.87137) (xy 240.778568 -52.841856) (xy 240.789667 -52.783808)
			(xy 240.809604 -52.728173) (xy 240.823242 -52.701952) (xy 240.833917 -52.682889) (xy 240.859 -52.647114)
			(xy 240.87328 -52.630578) (xy 240.874042 -52.629816) (xy 240.87455 -52.629308) (xy 240.875058 -52.6288)
			(xy 240.87582 -52.627784) (xy 240.876074 -52.62753) (xy 240.88217 -52.619402) (xy 240.885805 -52.612945)
			(xy 240.889551 -52.598617) (xy 240.889536 -52.591208) (xy 240.805716 -51.095148) (xy 240.794032 -50.887122)
			(xy 240.77803 -50.60188) (xy 240.775744 -50.595276) (xy 240.76787 -50.568606) (xy 240.76787 -50.568352)
			(xy 240.766346 -50.562256) (xy 240.763075 -50.548328) (xy 240.758367 -50.520105) (xy 240.756948 -50.505868)
			(xy 240.756948 -50.504852) (xy 240.756694 -50.502566) (xy 240.75644 -50.500534) (xy 240.756186 -50.495454)
			(xy 240.755932 -50.488088) (xy 240.755932 -50.483516) (xy 240.755678 -50.481484) (xy 240.755678 -50.475388)
			(xy 240.755678 -50.47234) (xy 240.755678 -50.472086) (xy 240.755949 -50.451735) (xy 240.760272 -50.411262)
			(xy 240.764314 -50.391314) (xy 240.765838 -50.384456) (xy 240.707164 -49.337722) (xy 240.63071 -47.977552)
			(xy 240.628778 -47.967369) (xy 240.618028 -47.949671) (xy 240.609882 -47.943262) (xy 240.604548 -47.939706)
			(xy 240.588546 -47.93107) (xy 240.580164 -47.929546) (xy 240.57991 -47.929546) (xy 240.554474 -47.924654)
			(xy 240.505129 -47.908906) (xy 240.458365 -47.886635) (xy 240.415039 -47.858248) (xy 240.375947 -47.824267)
			(xy 240.341805 -47.785315) (xy 240.32718 -47.763938) (xy 240.321084 -47.754794) (xy 240.283746 -47.731172)
			(xy 240.271554 -47.730156) (xy 240.243868 -47.727362) (xy 240.24336 -47.727362) (xy 240.204244 -47.723298)
			(xy 240.199902 -47.722945) (xy 240.191216 -47.723587) (xy 240.186972 -47.724568) (xy 240.18494 -47.725076)
			(xy 240.18367 -47.725584) (xy 240.181892 -47.726092) (xy 240.175542 -47.728378) (xy 240.165382 -47.734982)
			(xy 240.161318 -47.7393) (xy 240.154054 -47.746905) (xy 240.138806 -47.761392) (xy 240.130838 -47.768256)
			(xy 240.107311 -47.787486) (xy 240.055365 -47.819006) (xy 239.999079 -47.841891) (xy 239.939877 -47.855562)
			(xy 239.909604 -47.858172) (xy 239.890046 -47.858934) (xy 239.883188 -47.858934) (xy 239.881918 -47.858934)
			(xy 239.881664 -47.858934) (xy 239.862868 -47.858426) (xy 239.859312 -47.858172) (xy 239.859058 -47.858172)
			(xy 239.832635 -47.856007) (xy 239.780714 -47.845295) (xy 239.730775 -47.827501) (xy 239.68378 -47.802966)
			(xy 239.640632 -47.772164) (xy 239.602162 -47.735686) (xy 239.569112 -47.694235) (xy 239.542116 -47.648609)
			(xy 239.521694 -47.599685) (xy 239.50824 -47.548407) (xy 239.504728 -47.52213) (xy 239.503712 -47.512732)
			(xy 239.502442 -47.493174) (xy 239.502188 -47.477426) (xy 239.502188 -47.476918) (xy 239.502188 -47.476664)
			(xy 239.503204 -47.447962) (xy 239.503966 -47.43704) (xy 239.500156 -47.426626) (xy 239.498147 -47.421531)
			(xy 239.492253 -47.412301) (xy 239.488472 -47.408338) (xy 239.486186 -47.406052) (xy 239.48517 -47.387002)
			(xy 239.485091 -47.37783) (xy 239.490687 -47.360376) (xy 239.496092 -47.352966) (xy 239.580674 -47.245524)
			(xy 239.580928 -47.245016) (xy 239.581182 -47.244762) (xy 239.582706 -47.242984) (xy 239.583976 -47.241206)
			(xy 239.58423 -47.240952) (xy 239.585246 -47.239682) (xy 239.585754 -47.23892) (xy 239.589056 -47.234348)
			(xy 239.592612 -47.226474) (xy 239.594242 -47.222011) (xy 239.596038 -47.212681) (xy 239.596168 -47.207932)
			(xy 239.596168 -47.186596) (xy 239.596309 -47.181156) (xy 239.598614 -47.170523) (xy 239.60074 -47.165514)
			(xy 239.606836 -47.152052) (xy 239.610445 -47.143392) (xy 239.611658 -47.124682) (xy 239.606017 -47.106801)
			(xy 239.600486 -47.09922) (xy 239.594898 -47.092108) (xy 239.591342 -47.087536) (xy 239.590834 -47.086774)
			(xy 239.58931 -47.084996) (xy 239.570422 -47.061126) (xy 239.539676 -47.008598) (xy 239.517648 -46.951858)
			(xy 239.504897 -46.892343) (xy 239.502696 -46.861984) (xy 239.502188 -46.843442) (xy 239.502188 -46.842426)
			(xy 239.50265 -46.815172) (xy 239.510404 -46.761218) (xy 239.525757 -46.708917) (xy 239.548398 -46.659333)
			(xy 239.577865 -46.613476) (xy 239.613559 -46.57228) (xy 239.654752 -46.536583) (xy 239.700607 -46.507113)
			(xy 239.750189 -46.484468) (xy 239.802489 -46.46911) (xy 239.856442 -46.461352) (xy 239.883696 -46.460918)
			(xy 239.91127 -46.461404) (xy 239.965842 -46.469347) (xy 240.018702 -46.485066) (xy 240.068747 -46.508235)
			(xy 240.114932 -46.538371) (xy 240.156296 -46.574844) (xy 240.174526 -46.595538) (xy 240.175796 -46.597062)
			(xy 240.17605 -46.597316) (xy 240.182146 -46.604428) (xy 240.189004 -46.609254) (xy 240.193068 -46.612302)
			(xy 240.21669 -46.623224) (xy 240.218214 -46.623986) (xy 240.218722 -46.623986) (xy 240.221262 -46.624748)
			(xy 240.221516 -46.624748) (xy 240.222278 -46.625002) (xy 240.224564 -46.625764) (xy 240.23701 -46.627542)
			(xy 240.28781 -46.627542) (xy 240.300002 -46.626018) (xy 240.316258 -46.621954) (xy 240.321084 -46.619668)
			(xy 240.33226 -46.614334) (xy 240.337086 -46.612048) (xy 240.346992 -46.604428) (xy 240.350802 -46.599856)
			(xy 240.357719 -46.591693) (xy 240.372334 -46.576065) (xy 240.380012 -46.568614) (xy 240.380266 -46.56836)
			(xy 240.404904 -46.546516) (xy 240.405412 -46.546008) (xy 240.408968 -46.54296) (xy 240.409222 -46.542706)
			(xy 240.410492 -46.54169) (xy 240.422938 -46.532292) (xy 240.435384 -46.52391) (xy 240.450464 -46.514105)
			(xy 240.48214 -46.497058) (xy 240.49863 -46.489874) (xy 240.505742 -46.486826) (xy 240.510568 -46.483016)
			(xy 240.519204 -46.474126) (xy 240.538762 -46.445932) (xy 240.541048 -46.438312) (xy 240.543842 -46.429422)
			(xy 240.543334 -46.420532) (xy 240.543334 -46.420278) (xy 240.526824 -46.124622) (xy 240.526316 -46.11497)
			(xy 240.517934 -46.096428) (xy 240.510822 -46.089824) (xy 240.510314 -46.089316) (xy 240.508028 -46.087284)
			(xy 240.50752 -46.086776) (xy 240.504218 -46.083728) (xy 240.503456 -46.082966) (xy 240.495328 -46.074838)
			(xy 240.486184 -46.071028) (xy 240.481445 -46.069158) (xy 240.471465 -46.067115) (xy 240.466372 -46.066964)
			(xy 240.439448 -46.066964) (xy 240.434876 -46.067218) (xy 240.431008 -46.067717) (xy 240.423482 -46.069761)
			(xy 240.41989 -46.071282) (xy 240.398554 -46.082458) (xy 240.393474 -46.087284) (xy 240.39322 -46.087538)
			(xy 240.371912 -46.106655) (xy 240.324636 -46.138936) (xy 240.273066 -46.163784) (xy 240.218359 -46.180642)
			(xy 240.161747 -46.189131) (xy 240.133124 -46.189646) (xy 240.132362 -46.189646) (xy 240.117376 -46.189646)
			(xy 240.109502 -46.188884) (xy 240.070894 -46.184566) (xy 240.070386 -46.184566) (xy 240.06937 -46.184312)
			(xy 240.068862 -46.184312) (xy 240.066068 -46.183804) (xy 240.06302 -46.183296) (xy 240.062512 -46.183296)
			(xy 240.06048 -46.182788) (xy 240.058194 -46.182534) (xy 240.039906 -46.178216) (xy 240.039398 -46.178216)
			(xy 240.013538 -46.171201) (xy 239.963949 -46.150907) (xy 239.917691 -46.123867) (xy 239.896396 -46.107604)
			(xy 239.896142 -46.10735) (xy 239.89157 -46.103794) (xy 239.885982 -46.101) (xy 239.880657 -46.098537)
			(xy 239.869241 -46.095839) (xy 239.863376 -46.095666) (xy 239.842294 -46.095666) (xy 239.836854 -46.095526)
			(xy 239.826221 -46.093222) (xy 239.821212 -46.091094) (xy 239.80775 -46.084998) (xy 239.79909 -46.081388)
			(xy 239.78038 -46.080175) (xy 239.762501 -46.085819) (xy 239.754918 -46.091348) (xy 239.747806 -46.096936)
			(xy 239.743234 -46.100492) (xy 239.742472 -46.101) (xy 239.721829 -46.117637) (xy 239.676815 -46.145647)
			(xy 239.628356 -46.167154) (xy 239.577386 -46.181745) (xy 239.524886 -46.189138) (xy 239.498378 -46.189646)
			(xy 239.488472 -46.189646) (xy 239.459752 -46.188403) (xy 239.403153 -46.178345) (xy 239.348709 -46.159896)
			(xy 239.297656 -46.133474) (xy 239.274096 -46.117002) (xy 239.26546 -46.110906) (xy 239.26038 -46.106588)
			(xy 239.253014 -46.102016) (xy 239.250982 -46.101) (xy 239.245657 -46.098537) (xy 239.234241 -46.095839)
			(xy 239.228376 -46.095666) (xy 239.207294 -46.095666) (xy 239.201854 -46.095526) (xy 239.191221 -46.093222)
			(xy 239.186212 -46.091094) (xy 239.17275 -46.084998) (xy 239.16409 -46.081388) (xy 239.14538 -46.080175)
			(xy 239.127501 -46.085819) (xy 239.119918 -46.091348) (xy 239.112806 -46.096936) (xy 239.108234 -46.100492)
			(xy 239.107472 -46.101) (xy 239.086829 -46.117637) (xy 239.041815 -46.145647) (xy 238.993356 -46.167154)
			(xy 238.942386 -46.181745) (xy 238.889886 -46.189138) (xy 238.863378 -46.189646) (xy 238.863124 -46.189646)
			(xy 238.835867 -46.189185) (xy 238.781908 -46.18143) (xy 238.729602 -46.166074) (xy 238.680014 -46.143431)
			(xy 238.634153 -46.11396) (xy 238.592954 -46.078263) (xy 238.557254 -46.037066) (xy 238.527781 -45.991207)
			(xy 238.505134 -45.94162) (xy 238.489775 -45.889315) (xy 238.482017 -45.835357) (xy 238.482017 -45.780843)
			(xy 238.489775 -45.726885) (xy 238.505134 -45.67458) (xy 238.527781 -45.624993) (xy 238.557254 -45.579134)
			(xy 238.592954 -45.537937) (xy 238.634153 -45.50224) (xy 238.680014 -45.472769) (xy 238.729602 -45.450126)
			(xy 238.781908 -45.43477) (xy 238.835867 -45.427015) (xy 238.863124 -45.42663) (xy 238.863378 -45.42663)
			(xy 238.888996 -45.427038) (xy 238.939771 -45.433889) (xy 238.98917 -45.447483) (xy 239.036301 -45.467575)
			(xy 239.080314 -45.493802) (xy 239.100614 -45.509434) (xy 239.10544 -45.513244) (xy 239.112806 -45.516546)
			(xy 239.117545 -45.518417) (xy 239.127525 -45.520464) (xy 239.132618 -45.52061) (xy 239.153954 -45.52061)
			(xy 239.159393 -45.520755) (xy 239.170023 -45.523067) (xy 239.175036 -45.525182) (xy 239.188498 -45.531278)
			(xy 239.19716 -45.534895) (xy 239.215879 -45.536122) (xy 239.233774 -45.530498) (xy 239.24133 -45.524928)
			(xy 239.248442 -45.51934) (xy 239.253014 -45.515784) (xy 239.253776 -45.515276) (xy 239.274418 -45.498637)
			(xy 239.319432 -45.470623) (xy 239.36789 -45.44911) (xy 239.418861 -45.434513) (xy 239.471361 -45.427114)
			(xy 239.49787 -45.42663) (xy 239.507776 -45.42663) (xy 239.538564 -45.428) (xy 239.599118 -45.439436)
			(xy 239.657049 -45.460449) (xy 239.710854 -45.490493) (xy 239.73536 -45.50918) (xy 239.74044 -45.513244)
			(xy 239.748314 -45.5168) (xy 239.752942 -45.518571) (xy 239.762664 -45.520486) (xy 239.767618 -45.52061)
			(xy 239.788954 -45.52061) (xy 239.794393 -45.520755) (xy 239.805023 -45.523067) (xy 239.810036 -45.525182)
			(xy 239.823498 -45.531278) (xy 239.83216 -45.534895) (xy 239.850879 -45.536122) (xy 239.868774 -45.530498)
			(xy 239.87633 -45.524928) (xy 239.883442 -45.51934) (xy 239.888014 -45.515784) (xy 239.888776 -45.515276)
			(xy 239.909418 -45.498637) (xy 239.954432 -45.470623) (xy 240.00289 -45.44911) (xy 240.053861 -45.434513)
			(xy 240.106361 -45.427114) (xy 240.13287 -45.42663) (xy 240.133124 -45.42663) (xy 240.159097 -45.427069)
			(xy 240.210564 -45.434114) (xy 240.260601 -45.448071) (xy 240.308284 -45.468682) (xy 240.330736 -45.481748)
			(xy 240.332768 -45.483018) (xy 240.340759 -45.487157) (xy 240.358497 -45.490124) (xy 240.376174 -45.486815)
			(xy 240.384076 -45.48251) (xy 240.461038 -45.436282) (xy 240.469651 -45.430463) (xy 240.481709 -45.413555)
			(xy 240.484406 -45.403516) (xy 240.48593 -45.396404) (xy 240.424716 -44.309284) (xy 240.424462 -44.30522)
			(xy 240.134394 -42.158412) (xy 239.893602 -40.375586) (xy 239.889832 -40.346131) (xy 239.885383 -40.28691)
			(xy 239.884712 -40.257222) (xy 239.878616 -39.8653) (xy 239.876584 -39.725346) (xy 239.876101 -39.720384)
			(xy 239.873421 -39.710783) (xy 239.87125 -39.706296) (xy 239.87125 -39.706042) (xy 239.852017 -39.666102)
			(xy 239.819896 -39.583471) (xy 239.795241 -39.498314) (xy 239.778245 -39.411304) (xy 239.769043 -39.323129)
			(xy 239.767872 -39.278814) (xy 239.760252 -38.78453) (xy 239.760252 -38.766496) (xy 239.760692 -38.726361)
			(xy 239.767222 -38.646355) (xy 239.780167 -38.567134) (xy 239.799442 -38.489211) (xy 239.811814 -38.451028)
			(xy 239.813983 -38.443649) (xy 239.814364 -38.428283) (xy 239.812576 -38.420802) (xy 239.811306 -38.417246)
			(xy 239.796959 -38.377312) (xy 239.774301 -38.295531) (xy 239.758665 -38.212122) (xy 239.750163 -38.127687)
			(xy 239.749076 -38.085268) (xy 239.741456 -37.59073) (xy 239.741456 -37.574474) (xy 239.74189 -37.530556)
			(xy 239.74952 -37.443052) (xy 239.756696 -37.399722) (xy 239.76838 -37.34308) (xy 239.770158 -37.336476)
			(xy 239.770412 -37.334698) (xy 239.764824 -37.27704) (xy 239.764316 -37.271198) (xy 239.757966 -37.251894)
			(xy 239.755426 -37.247322) (xy 239.731076 -37.202617) (xy 239.690669 -37.109176) (xy 239.660088 -37.012074)
			(xy 239.649254 -36.962334) (xy 239.647476 -36.95319) (xy 239.633252 -36.930584) (xy 239.630204 -36.926774)
			(xy 239.626394 -36.922964) (xy 239.614202 -36.912804) (xy 239.608868 -36.908486) (xy 239.605634 -36.905885)
			(xy 239.598487 -36.901669) (xy 239.594644 -36.900104) (xy 239.587278 -36.89731) (xy 239.578642 -36.896802)
			(xy 239.578388 -36.896802) (xy 239.551996 -36.895099) (xy 239.50002 -36.885323) (xy 239.44989 -36.868468)
			(xy 239.402567 -36.844856) (xy 239.358955 -36.814939) (xy 239.319889 -36.77929) (xy 239.286116 -36.73859)
			(xy 239.258284 -36.693618) (xy 239.236925 -36.645236) (xy 239.222447 -36.59437) (xy 239.215128 -36.541991)
			(xy 239.21466 -36.515548) (xy 239.215162 -36.487794) (xy 239.223211 -36.432872) (xy 239.239132 -36.379696)
			(xy 239.262588 -36.329386) (xy 239.293085 -36.283006) (xy 239.32998 -36.241533) (xy 239.372493 -36.205843)
			(xy 239.419728 -36.176688) (xy 239.470689 -36.154683) (xy 239.497362 -36.146994) (xy 239.50295 -36.14547)
			(xy 239.514888 -36.139374) (xy 239.521394 -36.135753) (xy 239.5321 -36.125416) (xy 239.53597 -36.119054)
			(xy 239.553242 -36.088066) (xy 239.553242 -36.087558) (xy 239.57153 -36.053522) (xy 239.57459 -36.046245)
			(xy 239.576545 -36.030589) (xy 239.57534 -36.022788) (xy 239.574578 -36.018216) (xy 239.57407 -36.014914)
			(xy 239.570006 -36.002214) (xy 239.557814 -35.959542) (xy 239.54867 -35.921696) (xy 239.541558 -35.886644)
			(xy 239.532668 -35.830002) (xy 239.532668 -35.828478) (xy 239.53216 -35.82543) (xy 239.530382 -35.809174)
			(xy 239.528604 -35.791648) (xy 239.524794 -35.752532) (xy 239.504982 -35.55365) (xy 239.503865 -35.54786)
			(xy 239.499376 -35.536958) (xy 239.496092 -35.53206) (xy 239.491012 -35.525964) (xy 239.489742 -35.524694)
			(xy 239.481106 -35.517582) (xy 239.45596 -35.518852) (xy 239.45342 -35.518852) (xy 239.440974 -35.51936)
			(xy 239.415574 -35.519868) (xy 239.403128 -35.519868) (xy 239.356732 -35.518989) (xy 239.264399 -35.509669)
			(xy 239.173331 -35.491807) (xy 239.084319 -35.465557) (xy 238.998132 -35.431146) (xy 238.915517 -35.388873)
			(xy 238.876078 -35.36442) (xy 238.874046 -35.364928) (xy 238.869982 -35.36569) (xy 238.852984 -35.368566)
			(xy 238.818641 -35.371621) (xy 238.801402 -35.371786) (xy 238.800894 -35.371786) (xy 238.773642 -35.371322)
			(xy 238.719693 -35.363564) (xy 238.667397 -35.348208) (xy 238.617819 -35.325565) (xy 238.571968 -35.296096)
			(xy 238.530778 -35.260402) (xy 238.495087 -35.219209) (xy 238.465622 -35.173356) (xy 238.442983 -35.123777)
			(xy 238.42763 -35.07148) (xy 238.419876 -35.01753) (xy 238.419386 -34.990278) (xy 238.419386 -34.989008)
			(xy 238.419863 -34.964279) (xy 238.426422 -34.915255) (xy 238.439264 -34.86749) (xy 238.448342 -34.844482)
			(xy 238.45012 -34.840164) (xy 238.456724 -34.824162) (xy 238.457994 -34.818574) (xy 238.453422 -34.802826)
			(xy 238.440925 -34.758474) (xy 238.423215 -34.668039) (xy 238.413932 -34.576355) (xy 238.413036 -34.530284)
			(xy 238.413036 -34.519108) (xy 238.413612 -34.477574) (xy 238.420813 -34.394817) (xy 238.434867 -34.312943)
			(xy 238.455677 -34.232521) (xy 238.483099 -34.154107) (xy 238.49965 -34.11601) (xy 238.502698 -34.106358)
			(xy 238.506254 -34.091118) (xy 238.506254 -34.090102) (xy 238.502698 -34.074862) (xy 238.49965 -34.06521)
			(xy 238.482969 -34.026807) (xy 238.455358 -33.947757) (xy 238.434477 -33.866669) (xy 238.420474 -33.784115)
			(xy 238.413447 -33.700677) (xy 238.413036 -33.65881) (xy 238.413036 -33.658302) (xy 238.413307 -33.626014)
			(xy 238.417504 -33.561575) (xy 238.421418 -33.529524) (xy 238.424918 -33.504119) (xy 238.434193 -33.453675)
			(xy 238.43996 -33.428686) (xy 238.443978 -33.412172) (xy 238.452998 -33.379399) (xy 238.457994 -33.363154)
			(xy 238.456216 -33.35528) (xy 238.45393 -33.349692) (xy 238.444415 -33.328077) (xy 238.430193 -33.28304)
			(xy 238.421639 -33.236593) (xy 238.419894 -33.21304) (xy 238.419894 -33.208722) (xy 238.419386 -33.19018)
			(xy 238.419386 -33.18256) (xy 238.42038 -33.155663) (xy 238.428997 -33.102533) (xy 238.444996 -33.051143)
			(xy 238.46806 -33.002511) (xy 238.497731 -32.957604) (xy 238.533419 -32.917313) (xy 238.574415 -32.882439)
			(xy 238.619907 -32.853673) (xy 238.668991 -32.831587) (xy 238.720691 -32.816619) (xy 238.773982 -32.809067)
			(xy 238.800894 -32.808672) (xy 238.801148 -32.808672) (xy 238.815619 -32.808784) (xy 238.84448 -32.810942)
			(xy 238.858806 -32.81299) (xy 238.867626 -32.813989) (xy 238.885041 -32.81062) (xy 238.892842 -32.806386)
			(xy 238.931883 -32.783274) (xy 239.013387 -32.743405) (xy 239.098174 -32.711101) (xy 239.185543 -32.686627)
			(xy 239.274773 -32.670185) (xy 239.365128 -32.661911) (xy 239.410494 -32.661352) (xy 239.410748 -32.661352)
			(xy 239.456087 -32.66188) (xy 239.54639 -32.670137) (xy 239.635571 -32.68655) (xy 239.722896 -32.710986)
			(xy 239.807644 -32.743241) (xy 239.889118 -32.783051) (xy 239.928146 -32.806132) (xy 239.935872 -32.810392)
			(xy 239.953151 -32.81389) (xy 239.961928 -32.81299) (xy 239.976634 -32.810911) (xy 240.006258 -32.808752)
			(xy 240.02111 -32.808672) (xy 240.021872 -32.808672) (xy 240.05159 -32.809363) (xy 240.110276 -32.818807)
			(xy 240.138712 -32.827468) (xy 240.152428 -32.83204) (xy 240.163858 -32.831024) (xy 240.171743 -32.830018)
			(xy 240.186366 -32.823813) (xy 240.19256 -32.818832) (xy 240.212118 -32.804608) (xy 240.212626 -32.804354)
			(xy 240.255552 -32.77362) (xy 240.258585 -32.771271) (xy 240.263951 -32.76579) (xy 240.26622 -32.762698)
			(xy 240.267744 -32.760666) (xy 240.267998 -32.760412) (xy 240.26749 -32.73806) (xy 240.26749 -32.737806)
			(xy 240.267236 -32.722566) (xy 240.267236 -32.720788) (xy 240.26749 -32.696912) (xy 240.269334 -32.647678)
			(xy 240.281537 -32.549908) (xy 240.303334 -32.453821) (xy 240.334512 -32.360355) (xy 240.354104 -32.31515)
			(xy 240.355882 -32.311086) (xy 240.360454 -32.29102) (xy 240.360454 -32.290004) (xy 240.355882 -32.269938)
			(xy 240.354104 -32.265874) (xy 240.334544 -32.220658) (xy 240.303393 -32.127187) (xy 240.281596 -32.031104)
			(xy 240.269365 -31.933342) (xy 240.26749 -31.884112) (xy 240.267236 -31.860236) (xy 240.267236 -31.858458)
			(xy 240.26749 -31.843218) (xy 240.26749 -31.840424) (xy 240.267998 -31.821628) (xy 240.265526 -31.817672)
			(xy 240.25939 -31.810645) (xy 240.255806 -31.807658) (xy 240.210594 -31.774638) (xy 240.210086 -31.774638)
			(xy 240.190782 -31.760668) (xy 240.185318 -31.757163) (xy 240.173099 -31.752795) (xy 240.166652 -31.752032)
			(xy 240.166144 -31.752032) (xy 240.16208 -31.751778) (xy 240.142522 -31.751778) (xy 240.134902 -31.754064)
			(xy 240.107293 -31.762249) (xy 240.050407 -31.771184) (xy 240.021618 -31.771844) (xy 240.019586 -31.771844)
			(xy 240.003311 -31.771664) (xy 239.970881 -31.768866) (xy 239.954816 -31.766256) (xy 239.94491 -31.764478)
			(xy 239.904924 -31.789198) (xy 239.821148 -31.831861) (xy 239.733731 -31.866454) (xy 239.643447 -31.892671)
			(xy 239.551097 -31.910279) (xy 239.457501 -31.919122) (xy 239.410494 -31.919672) (xy 239.364862 -31.919187)
			(xy 239.273976 -31.9109) (xy 239.184227 -31.894339) (xy 239.096369 -31.869644) (xy 239.011135 -31.837022)
			(xy 238.929239 -31.796746) (xy 238.890048 -31.773368) (xy 238.884419 -31.770543) (xy 238.872213 -31.767456)
			(xy 238.865918 -31.767272) (xy 238.859822 -31.767272) (xy 238.856266 -31.76778) (xy 238.85525 -31.768034)
			(xy 238.85398 -31.768034) (xy 238.8362 -31.77032) (xy 238.830866 -31.770828) (xy 238.82985 -31.770828)
			(xy 238.827818 -31.771082) (xy 238.826802 -31.771082) (xy 238.806736 -31.771844) (xy 238.800894 -31.771844)
			(xy 238.773642 -31.771358) (xy 238.719693 -31.763601) (xy 238.667397 -31.748246) (xy 238.617818 -31.725605)
			(xy 238.571966 -31.696139) (xy 238.530774 -31.660448) (xy 238.495079 -31.619258) (xy 238.46561 -31.573408)
			(xy 238.442965 -31.523831) (xy 238.427606 -31.471536) (xy 238.419844 -31.417588) (xy 238.419386 -31.390336)
			(xy 238.419386 -31.389066) (xy 238.419859 -31.364336) (xy 238.426411 -31.31531) (xy 238.439247 -31.267541)
			(xy 238.448342 -31.24454) (xy 238.45012 -31.240222) (xy 238.456724 -31.22422) (xy 238.457994 -31.218632)
			(xy 238.453422 -31.202884) (xy 238.440693 -31.157586) (xy 238.422808 -31.065204) (xy 238.413698 -30.971547)
			(xy 238.413036 -30.9245) (xy 238.413036 -30.91561) (xy 238.413636 -30.878397) (xy 238.419695 -30.804211)
			(xy 238.431272 -30.730684) (xy 238.439452 -30.694376) (xy 238.450818 -30.648428) (xy 238.481096 -30.558742)
			(xy 238.499904 -30.515306) (xy 238.501682 -30.511242) (xy 238.506254 -30.491176) (xy 238.506254 -30.49016)
			(xy 238.501682 -30.470094) (xy 238.499904 -30.46603) (xy 238.483177 -30.42756) (xy 238.455487 -30.348366)
			(xy 238.43455 -30.267126) (xy 238.420513 -30.184414) (xy 238.413475 -30.100815) (xy 238.413036 -30.058868)
			(xy 238.413492 -30.015527) (xy 238.420998 -29.929172) (xy 238.428022 -29.886402) (xy 238.43218 -29.863598)
			(xy 238.442343 -29.818368) (xy 238.448342 -29.795978) (xy 238.458248 -29.76245) (xy 238.45647 -29.755084)
			(xy 238.444766 -29.729286) (xy 238.428248 -29.6751) (xy 238.41991 -29.61907) (xy 238.419386 -29.590746)
			(xy 238.419386 -29.590238) (xy 238.419847 -29.562983) (xy 238.427599 -29.509028) (xy 238.442952 -29.456725)
			(xy 238.465592 -29.40714) (xy 238.495059 -29.361282) (xy 238.530753 -29.320084) (xy 238.571946 -29.284385)
			(xy 238.617801 -29.254913) (xy 238.667384 -29.232267) (xy 238.719685 -29.216909) (xy 238.773639 -29.20915)
			(xy 238.800894 -29.20873) (xy 238.801656 -29.20873) (xy 238.819352 -29.20894) (xy 238.854589 -29.212246)
			(xy 238.872014 -29.215334) (xy 238.876078 -29.216096) (xy 238.87684 -29.21635) (xy 238.916782 -29.191702)
			(xy 239.000455 -29.149169) (xy 239.087754 -29.114684) (xy 239.177906 -29.088552) (xy 239.270114 -29.071004)
			(xy 239.363562 -29.062196) (xy 239.410494 -29.061664) (xy 239.457399 -29.062191) (xy 239.550795 -29.070976)
			(xy 239.642955 -29.088488) (xy 239.733064 -29.114573) (xy 239.820327 -29.149) (xy 239.903975 -29.191464)
			(xy 239.943894 -29.216096) (xy 239.94491 -29.215842) (xy 239.948466 -29.215334) (xy 239.966144 -29.21222)
			(xy 240.00189 -29.20891) (xy 240.01984 -29.20873) (xy 240.020856 -29.20873) (xy 240.046249 -29.209144)
			(xy 240.096583 -29.215894) (xy 240.121186 -29.222192) (xy 240.122964 -29.2227) (xy 240.124234 -29.222954)
			(xy 240.128044 -29.22397) (xy 240.142014 -29.228542) (xy 240.142522 -29.228542) (xy 240.147856 -29.230574)
			(xy 240.160556 -29.231844) (xy 240.166398 -29.231082) (xy 240.177066 -29.228288) (xy 240.189258 -29.221684)
			(xy 240.25225 -29.17571) (xy 240.253012 -29.175202) (xy 240.257838 -29.171646) (xy 240.264442 -29.165296)
			(xy 240.267998 -29.16047) (xy 240.26749 -29.137864) (xy 240.26749 -29.13761) (xy 240.267236 -29.122624)
			(xy 240.267236 -29.120846) (xy 240.26749 -29.09697) (xy 240.269336 -29.047737) (xy 240.281543 -28.949968)
			(xy 240.303344 -28.853882) (xy 240.334525 -28.760418) (xy 240.354104 -28.715208) (xy 240.355882 -28.711144)
			(xy 240.360454 -28.691078) (xy 240.360454 -28.690062) (xy 240.355882 -28.669996) (xy 240.354104 -28.665932)
			(xy 240.337376 -28.627462) (xy 240.309687 -28.548268) (xy 240.28875 -28.467028) (xy 240.274713 -28.384316)
			(xy 240.267674 -28.300717) (xy 240.267236 -28.25877) (xy 240.267692 -28.215429) (xy 240.275198 -28.129074)
			(xy 240.282222 -28.086304) (xy 240.286386 -28.063565) (xy 240.29655 -28.018461) (xy 240.302542 -27.996134)
			(xy 240.302542 -27.995626) (xy 240.309654 -27.972004) (xy 240.309654 -27.971496) (xy 240.312448 -27.962352)
			(xy 240.31067 -27.954986) (xy 240.308384 -27.95016) (xy 240.2988 -27.928472) (xy 240.284465 -27.883273)
			(xy 240.275834 -27.836647) (xy 240.274094 -27.813) (xy 240.274094 -27.808682) (xy 240.273586 -27.79014)
			(xy 240.273586 -27.78252) (xy 240.274583 -27.755624) (xy 240.283204 -27.7025) (xy 240.299207 -27.651114)
			(xy 240.322273 -27.602487) (xy 240.351944 -27.557585) (xy 240.387632 -27.517299) (xy 240.428628 -27.482429)
			(xy 240.474118 -27.453666) (xy 240.523199 -27.431583) (xy 240.574896 -27.416617) (xy 240.628184 -27.409066)
			(xy 240.655094 -27.408632) (xy 240.672715 -27.40874) (xy 240.707824 -27.411789) (xy 240.725198 -27.414728)
			(xy 240.72723 -27.415236) (xy 240.731548 -27.415998) (xy 240.774474 -27.39009) (xy 240.77549 -27.389582)
			(xy 240.778792 -27.387804) (xy 240.796318 -27.377898) (xy 240.797588 -27.375104) (xy 240.798096 -27.37358)
			(xy 240.798604 -27.372564) (xy 240.819686 -27.295348) (xy 240.819432 -27.281632) (xy 240.817654 -27.275028)
			(xy 240.813336 -27.259534) (xy 240.810288 -27.2542) (xy 240.798592 -27.232664) (xy 240.780174 -27.187249)
			(xy 240.767713 -27.139853) (xy 240.761415 -27.091251) (xy 240.761012 -27.066748) (xy 240.761012 -27.057604)
			(xy 240.761266 -27.05354) (xy 240.761266 -27.052778) (xy 240.763552 -27.022552) (xy 240.766656 -26.998918)
			(xy 240.778003 -26.95262) (xy 240.795048 -26.908103) (xy 240.80597 -26.886916) (xy 240.818799 -26.863799)
			(xy 240.849868 -26.821021) (xy 240.886547 -26.782944) (xy 240.907062 -26.766266) (xy 240.909094 -26.764742)
			(xy 240.916206 -26.757884) (xy 240.92916 -26.742136) (xy 240.9317 -26.736802) (xy 240.93424 -26.725118)
			(xy 240.930176 -26.647394) (xy 240.929668 -26.634948) (xy 240.914682 -26.609294) (xy 240.906808 -26.59888)
			(xy 240.899442 -26.591514) (xy 240.891314 -26.584656) (xy 240.889028 -26.583132) (xy 240.867131 -26.567858)
			(xy 240.827425 -26.532168) (xy 240.793078 -26.491295) (xy 240.764761 -26.446035) (xy 240.743025 -26.397272)
			(xy 240.728295 -26.345956) (xy 240.720858 -26.293088) (xy 240.720372 -26.266394) (xy 240.720858 -26.239125)
			(xy 240.72862 -26.185141) (xy 240.743985 -26.132811) (xy 240.766642 -26.083201) (xy 240.796128 -26.03732)
			(xy 240.831843 -25.996103) (xy 240.87306 -25.960388) (xy 240.918941 -25.930902) (xy 240.968551 -25.908245)
			(xy 241.020881 -25.89288) (xy 241.074865 -25.885118) (xy 241.129403 -25.885118) (xy 241.183387 -25.89288)
			(xy 241.235717 -25.908245) (xy 241.285327 -25.930902) (xy 241.331208 -25.960388) (xy 241.372425 -25.996103)
			(xy 241.40814 -26.03732) (xy 241.437626 -26.083201) (xy 241.460283 -26.132811) (xy 241.475648 -26.185141)
			(xy 241.48341 -26.239125) (xy 241.483896 -26.266394) (xy 241.483358 -26.295751) (xy 241.474371 -26.353772)
			(xy 241.456607 -26.409734) (xy 241.430485 -26.462316) (xy 241.396621 -26.510279) (xy 241.355813 -26.552493)
			(xy 241.332766 -26.570686) (xy 241.329464 -26.573226) (xy 241.325654 -26.577036) (xy 241.319558 -26.58491)
			(xy 241.315832 -26.591022) (xy 241.311592 -26.604687) (xy 241.311176 -26.611834) (xy 241.314986 -26.69667)
			(xy 241.319812 -26.706068) (xy 241.320828 -26.708354) (xy 241.329718 -26.72334) (xy 241.333274 -26.729182)
			(xy 241.349022 -26.745438) (xy 241.355372 -26.749756) (xy 241.377232 -26.764967) (xy 241.416884 -26.80052)
			(xy 241.4512 -26.841247) (xy 241.479512 -26.886354) (xy 241.50127 -26.934963) (xy 241.51605 -26.986127)
			(xy 241.523563 -27.038851) (xy 241.524028 -27.065478) (xy 241.524028 -27.06878) (xy 241.523354 -27.097505)
			(xy 241.514423 -27.154264) (xy 241.506248 -27.18181) (xy 241.503962 -27.189176) (xy 241.503962 -27.18943)
			(xy 241.502946 -27.192478) (xy 241.501925 -27.196716) (xy 241.501155 -27.205399) (xy 241.501422 -27.20975)
			(xy 241.501676 -27.211528) (xy 241.504216 -27.22245) (xy 241.506502 -27.228292) (xy 241.524536 -27.264106)
			(xy 241.524536 -27.264614) (xy 241.540284 -27.295094) (xy 241.542316 -27.298396) (xy 241.542824 -27.298904)
			(xy 241.544602 -27.301444) (xy 241.563652 -27.307286) (xy 241.601004 -27.319393) (xy 241.659279 -27.342846)
			(xy 248.723404 -27.342846) (xy 248.723404 -26.479246) (xy 248.723894 -26.449262) (xy 248.731722 -26.389806)
			(xy 248.747243 -26.331881) (xy 248.770192 -26.276477) (xy 248.800176 -26.224543) (xy 248.836682 -26.176967)
			(xy 248.879087 -26.134562) (xy 248.926663 -26.098056) (xy 248.978597 -26.068072) (xy 249.034001 -26.045123)
			(xy 249.091926 -26.029602) (xy 249.151382 -26.021774) (xy 249.21135 -26.021774) (xy 249.270806 -26.029602)
			(xy 249.328731 -26.045123) (xy 249.384135 -26.068072) (xy 249.436069 -26.098056) (xy 249.483645 -26.134562)
			(xy 249.52605 -26.176967) (xy 249.562556 -26.224543) (xy 249.59254 -26.276477) (xy 249.615489 -26.331881)
			(xy 249.62326 -26.360882) (xy 251.289564 -26.360882) (xy 251.293635 -26.30526) (xy 251.305761 -26.250823)
			(xy 251.325684 -26.198732) (xy 251.35298 -26.150097) (xy 251.387066 -26.105954) (xy 251.427215 -26.067245)
			(xy 251.472573 -26.034794) (xy 251.522173 -26.009293) (xy 251.574957 -25.991286) (xy 251.6298 -25.981156)
			(xy 251.685534 -25.979119) (xy 251.740971 -25.985219) (xy 251.794928 -25.999325) (xy 251.846257 -26.021137)
			(xy 251.893863 -26.050191) (xy 251.936731 -26.085866) (xy 251.973948 -26.127403) (xy 252.004721 -26.173916)
			(xy 252.028393 -26.224413) (xy 252.044461 -26.27782) (xy 252.050629 -26.319734) (xy 257.041902 -26.319734)
			(xy 257.045973 -26.264112) (xy 257.058099 -26.209675) (xy 257.078022 -26.157584) (xy 257.105318 -26.108949)
			(xy 257.139404 -26.064806) (xy 257.179553 -26.026097) (xy 257.224911 -25.993646) (xy 257.274511 -25.968145)
			(xy 257.327295 -25.950138) (xy 257.382138 -25.940008) (xy 257.437872 -25.937971) (xy 257.493309 -25.944071)
			(xy 257.547266 -25.958177) (xy 257.598595 -25.979989) (xy 257.646201 -26.009043) (xy 257.675866 -26.03373)
			(xy 263.467848 -26.03373) (xy 263.471919 -25.978108) (xy 263.484045 -25.923671) (xy 263.503968 -25.87158)
			(xy 263.531264 -25.822945) (xy 263.56535 -25.778802) (xy 263.605499 -25.740093) (xy 263.650857 -25.707642)
			(xy 263.700457 -25.682141) (xy 263.753241 -25.664134) (xy 263.808084 -25.654004) (xy 263.863818 -25.651967)
			(xy 263.919255 -25.658067) (xy 263.973212 -25.672173) (xy 264.024541 -25.693985) (xy 264.072147 -25.723039)
			(xy 264.115015 -25.758714) (xy 264.152232 -25.800251) (xy 264.183005 -25.846764) (xy 264.206677 -25.897261)
			(xy 264.222745 -25.950668) (xy 264.230865 -26.005844) (xy 264.231374 -26.03373) (xy 264.230865 -26.061616)
			(xy 264.222745 -26.116792) (xy 264.206677 -26.170199) (xy 264.183005 -26.220696) (xy 264.152232 -26.267209)
			(xy 264.115015 -26.308746) (xy 264.072147 -26.344421) (xy 264.024541 -26.373475) (xy 263.973212 -26.395287)
			(xy 263.919255 -26.409393) (xy 263.863818 -26.415493) (xy 263.808084 -26.413456) (xy 263.753241 -26.403326)
			(xy 263.700457 -26.385319) (xy 263.650857 -26.359818) (xy 263.605499 -26.327367) (xy 263.56535 -26.288658)
			(xy 263.531264 -26.244515) (xy 263.503968 -26.19588) (xy 263.484045 -26.143789) (xy 263.471919 -26.089352)
			(xy 263.467848 -26.03373) (xy 257.675866 -26.03373) (xy 257.689069 -26.044718) (xy 257.726286 -26.086255)
			(xy 257.757059 -26.132768) (xy 257.780731 -26.183265) (xy 257.796799 -26.236672) (xy 257.804919 -26.291848)
			(xy 257.805428 -26.319734) (xy 257.804919 -26.34762) (xy 257.796799 -26.402796) (xy 257.780731 -26.456203)
			(xy 257.757059 -26.5067) (xy 257.726286 -26.553213) (xy 257.689069 -26.59475) (xy 257.646201 -26.630425)
			(xy 257.598595 -26.659479) (xy 257.547266 -26.681291) (xy 257.493309 -26.695397) (xy 257.437872 -26.701497)
			(xy 257.382138 -26.69946) (xy 257.327295 -26.68933) (xy 257.274511 -26.671323) (xy 257.224911 -26.645822)
			(xy 257.179553 -26.613371) (xy 257.139404 -26.574662) (xy 257.105318 -26.530519) (xy 257.078022 -26.481884)
			(xy 257.058099 -26.429793) (xy 257.045973 -26.375356) (xy 257.041902 -26.319734) (xy 252.050629 -26.319734)
			(xy 252.052581 -26.332996) (xy 252.05309 -26.360882) (xy 252.052581 -26.388768) (xy 252.044461 -26.443944)
			(xy 252.028393 -26.497351) (xy 252.004721 -26.547848) (xy 251.973948 -26.594361) (xy 251.936731 -26.635898)
			(xy 251.893863 -26.671573) (xy 251.846257 -26.700627) (xy 251.794928 -26.722439) (xy 251.740971 -26.736545)
			(xy 251.685534 -26.742645) (xy 251.6298 -26.740608) (xy 251.574957 -26.730478) (xy 251.522173 -26.712471)
			(xy 251.472573 -26.68697) (xy 251.427215 -26.654519) (xy 251.387066 -26.61581) (xy 251.35298 -26.571667)
			(xy 251.325684 -26.523032) (xy 251.305761 -26.470941) (xy 251.293635 -26.416504) (xy 251.289564 -26.360882)
			(xy 249.62326 -26.360882) (xy 249.63101 -26.389806) (xy 249.638838 -26.449262) (xy 249.639328 -26.479246)
			(xy 249.639328 -26.971244) (xy 253.051054 -26.971244) (xy 253.055125 -26.915622) (xy 253.067251 -26.861185)
			(xy 253.087174 -26.809094) (xy 253.11447 -26.760459) (xy 253.148556 -26.716316) (xy 253.188705 -26.677607)
			(xy 253.234063 -26.645156) (xy 253.283663 -26.619655) (xy 253.336447 -26.601648) (xy 253.39129 -26.591518)
			(xy 253.447024 -26.589481) (xy 253.502461 -26.595581) (xy 253.556418 -26.609687) (xy 253.607747 -26.631499)
			(xy 253.655353 -26.660553) (xy 253.698221 -26.696228) (xy 253.735438 -26.737765) (xy 253.766211 -26.784278)
			(xy 253.789883 -26.834775) (xy 253.805951 -26.888182) (xy 253.814071 -26.943358) (xy 253.81458 -26.971244)
			(xy 253.814071 -26.99913) (xy 253.805951 -27.054306) (xy 253.789883 -27.107713) (xy 253.766211 -27.15821)
			(xy 253.735438 -27.204723) (xy 253.698221 -27.24626) (xy 253.655353 -27.281935) (xy 253.607747 -27.310989)
			(xy 253.556418 -27.332801) (xy 253.502461 -27.346907) (xy 253.447024 -27.353007) (xy 253.39129 -27.35097)
			(xy 253.336447 -27.34084) (xy 253.283663 -27.322833) (xy 253.234063 -27.297332) (xy 253.188705 -27.264881)
			(xy 253.148556 -27.226172) (xy 253.11447 -27.182029) (xy 253.087174 -27.133394) (xy 253.067251 -27.081303)
			(xy 253.055125 -27.026866) (xy 253.051054 -26.971244) (xy 249.639328 -26.971244) (xy 249.639328 -27.342846)
			(xy 249.638838 -27.37283) (xy 249.63101 -27.432286) (xy 249.615489 -27.490211) (xy 249.59254 -27.545615)
			(xy 249.562556 -27.597549) (xy 249.52605 -27.645125) (xy 249.483645 -27.68753) (xy 249.436069 -27.724036)
			(xy 249.384135 -27.75402) (xy 249.328731 -27.776969) (xy 249.270806 -27.79249) (xy 249.21135 -27.800318)
			(xy 249.151382 -27.800318) (xy 249.091926 -27.79249) (xy 249.034001 -27.776969) (xy 248.978597 -27.75402)
			(xy 248.926663 -27.724036) (xy 248.879087 -27.68753) (xy 248.836682 -27.645125) (xy 248.800176 -27.597549)
			(xy 248.770192 -27.545615) (xy 248.747243 -27.490211) (xy 248.731722 -27.432286) (xy 248.723894 -27.37283)
			(xy 248.723404 -27.342846) (xy 241.659279 -27.342846) (xy 241.673852 -27.348711) (xy 241.744164 -27.383678)
			(xy 241.778028 -27.403552) (xy 241.785075 -27.407426) (xy 241.800731 -27.411059) (xy 241.808762 -27.410664)
			(xy 241.812572 -27.410156) (xy 241.814096 -27.410156) (xy 241.817144 -27.409648) (xy 241.81816 -27.409648)
			(xy 241.818922 -27.409394) (xy 241.828828 -27.408886) (xy 241.830352 -27.408886) (xy 241.838734 -27.408378)
			(xy 241.84483 -27.408378) (xy 241.848894 -27.408378) (xy 241.868198 -27.408886) (xy 241.87785 -27.409648)
			(xy 241.904858 -27.41218) (xy 241.95782 -27.423912) (xy 242.008587 -27.443025) (xy 242.056136 -27.469134)
			(xy 242.099509 -27.501712) (xy 242.137833 -27.540104) (xy 242.154456 -27.56154) (xy 242.156488 -27.56408)
			(xy 242.200885 -27.571473) (xy 242.288225 -27.593233) (xy 242.37325 -27.622773) (xy 242.455268 -27.659852)
			(xy 242.533613 -27.70417) (xy 242.607646 -27.755364) (xy 242.676767 -27.813021) (xy 242.708938 -27.844496)
			(xy 243.620036 -28.755594) (xy 243.654293 -28.790558) (xy 243.716511 -28.866134) (xy 243.744242 -28.90647)
			(xy 243.774214 -28.951428) (xy 243.780056 -28.95854) (xy 243.935758 -29.114242) (xy 251.047504 -29.114242)
			(xy 251.047504 -28.250642) (xy 251.047994 -28.220674) (xy 251.055817 -28.161252) (xy 251.07133 -28.103359)
			(xy 251.094266 -28.047986) (xy 251.124233 -27.99608) (xy 251.16072 -27.94853) (xy 251.2031 -27.90615)
			(xy 251.25065 -27.869663) (xy 251.302556 -27.839696) (xy 251.357929 -27.81676) (xy 251.415822 -27.801247)
			(xy 251.475244 -27.793424) (xy 251.53518 -27.793424) (xy 251.594602 -27.801247) (xy 251.652495 -27.81676)
			(xy 251.707868 -27.839696) (xy 251.759774 -27.869663) (xy 251.807324 -27.90615) (xy 251.849704 -27.94853)
			(xy 251.886191 -27.99608) (xy 251.916158 -28.047986) (xy 251.939094 -28.103359) (xy 251.954607 -28.161252)
			(xy 251.96243 -28.220674) (xy 251.96292 -28.250642) (xy 251.96292 -28.469082) (xy 255.952496 -28.469082)
			(xy 255.956567 -28.41346) (xy 255.968693 -28.359023) (xy 255.988616 -28.306932) (xy 256.015912 -28.258297)
			(xy 256.049998 -28.214154) (xy 256.090147 -28.175445) (xy 256.135505 -28.142994) (xy 256.185105 -28.117493)
			(xy 256.237889 -28.099486) (xy 256.292732 -28.089356) (xy 256.348466 -28.087319) (xy 256.403903 -28.093419)
			(xy 256.45786 -28.107525) (xy 256.509189 -28.129337) (xy 256.525245 -28.139136) (xy 260.597902 -28.139136)
			(xy 260.601973 -28.083514) (xy 260.614099 -28.029077) (xy 260.634022 -27.976986) (xy 260.661318 -27.928351)
			(xy 260.695404 -27.884208) (xy 260.735553 -27.845499) (xy 260.780911 -27.813048) (xy 260.830511 -27.787547)
			(xy 260.883295 -27.76954) (xy 260.938138 -27.75941) (xy 260.993872 -27.757373) (xy 261.049309 -27.763473)
			(xy 261.103266 -27.777579) (xy 261.154595 -27.799391) (xy 261.202201 -27.828445) (xy 261.245069 -27.86412)
			(xy 261.282286 -27.905657) (xy 261.313059 -27.95217) (xy 261.336731 -28.002667) (xy 261.352799 -28.056074)
			(xy 261.360919 -28.11125) (xy 261.361428 -28.139136) (xy 261.867902 -28.139136) (xy 261.871973 -28.083514)
			(xy 261.884099 -28.029077) (xy 261.904022 -27.976986) (xy 261.931318 -27.928351) (xy 261.965404 -27.884208)
			(xy 262.005553 -27.845499) (xy 262.050911 -27.813048) (xy 262.100511 -27.787547) (xy 262.153295 -27.76954)
			(xy 262.208138 -27.75941) (xy 262.263872 -27.757373) (xy 262.319309 -27.763473) (xy 262.373266 -27.777579)
			(xy 262.424595 -27.799391) (xy 262.472201 -27.828445) (xy 262.515069 -27.86412) (xy 262.552286 -27.905657)
			(xy 262.583059 -27.95217) (xy 262.606731 -28.002667) (xy 262.622799 -28.056074) (xy 262.630919 -28.11125)
			(xy 262.631428 -28.139136) (xy 262.630919 -28.167022) (xy 262.622799 -28.222198) (xy 262.606731 -28.275605)
			(xy 262.583059 -28.326102) (xy 262.552286 -28.372615) (xy 262.515069 -28.414152) (xy 262.472201 -28.449827)
			(xy 262.424595 -28.478881) (xy 262.373266 -28.500693) (xy 262.319309 -28.514799) (xy 262.263872 -28.520899)
			(xy 262.208138 -28.518862) (xy 262.153295 -28.508732) (xy 262.100511 -28.490725) (xy 262.050911 -28.465224)
			(xy 262.005553 -28.432773) (xy 261.965404 -28.394064) (xy 261.931318 -28.349921) (xy 261.904022 -28.301286)
			(xy 261.884099 -28.249195) (xy 261.871973 -28.194758) (xy 261.867902 -28.139136) (xy 261.361428 -28.139136)
			(xy 261.360919 -28.167022) (xy 261.352799 -28.222198) (xy 261.336731 -28.275605) (xy 261.313059 -28.326102)
			(xy 261.282286 -28.372615) (xy 261.245069 -28.414152) (xy 261.202201 -28.449827) (xy 261.154595 -28.478881)
			(xy 261.103266 -28.500693) (xy 261.049309 -28.514799) (xy 260.993872 -28.520899) (xy 260.938138 -28.518862)
			(xy 260.883295 -28.508732) (xy 260.830511 -28.490725) (xy 260.780911 -28.465224) (xy 260.735553 -28.432773)
			(xy 260.695404 -28.394064) (xy 260.661318 -28.349921) (xy 260.634022 -28.301286) (xy 260.614099 -28.249195)
			(xy 260.601973 -28.194758) (xy 260.597902 -28.139136) (xy 256.525245 -28.139136) (xy 256.556795 -28.158391)
			(xy 256.599663 -28.194066) (xy 256.63688 -28.235603) (xy 256.667653 -28.282116) (xy 256.691325 -28.332613)
			(xy 256.707393 -28.38602) (xy 256.715513 -28.441196) (xy 256.716022 -28.469082) (xy 256.715513 -28.496968)
			(xy 256.707393 -28.552144) (xy 256.691325 -28.605551) (xy 256.667653 -28.656048) (xy 256.63688 -28.702561)
			(xy 256.599663 -28.744098) (xy 256.556795 -28.779773) (xy 256.509189 -28.808827) (xy 256.45786 -28.830639)
			(xy 256.403903 -28.844745) (xy 256.348466 -28.850845) (xy 256.292732 -28.848808) (xy 256.237889 -28.838678)
			(xy 256.185105 -28.820671) (xy 256.135505 -28.79517) (xy 256.090147 -28.762719) (xy 256.049998 -28.72401)
			(xy 256.015912 -28.679867) (xy 255.988616 -28.631232) (xy 255.968693 -28.579141) (xy 255.956567 -28.524704)
			(xy 255.952496 -28.469082) (xy 251.96292 -28.469082) (xy 251.96292 -29.114242) (xy 251.96243 -29.14421)
			(xy 251.954607 -29.203632) (xy 251.939094 -29.261525) (xy 251.916158 -29.316898) (xy 251.886191 -29.368804)
			(xy 251.849704 -29.416354) (xy 251.807324 -29.458734) (xy 251.759774 -29.495221) (xy 251.707868 -29.525188)
			(xy 251.652495 -29.548124) (xy 251.594602 -29.563637) (xy 251.53518 -29.57146) (xy 251.475244 -29.57146)
			(xy 251.415822 -29.563637) (xy 251.357929 -29.548124) (xy 251.302556 -29.525188) (xy 251.25065 -29.495221)
			(xy 251.2031 -29.458734) (xy 251.16072 -29.416354) (xy 251.124233 -29.368804) (xy 251.094266 -29.316898)
			(xy 251.07133 -29.261525) (xy 251.055817 -29.203632) (xy 251.047994 -29.14421) (xy 251.047504 -29.114242)
			(xy 243.935758 -29.114242) (xy 244.03431 -29.212794) (xy 244.037104 -29.215334) (xy 244.048788 -29.222446)
			(xy 244.053614 -29.224224) (xy 244.056154 -29.224986) (xy 244.066568 -29.228288) (xy 244.078518 -29.23237)
			(xy 244.101905 -29.241903) (xy 244.113304 -29.247338) (xy 244.113812 -29.247846) (xy 244.12321 -29.252418)
			(xy 244.123464 -29.252672) (xy 244.13464 -29.258768) (xy 244.139466 -29.261562) (xy 244.1448 -29.264864)
			(xy 244.167385 -29.2793) (xy 244.20865 -29.313511) (xy 244.244723 -29.353158) (xy 244.274895 -29.397462)
			(xy 244.298571 -29.445552) (xy 244.315286 -29.496481) (xy 244.324711 -29.549248) (xy 244.326156 -29.576014)
			(xy 244.326664 -29.590492) (xy 244.728238 -30.19171) (xy 244.731286 -30.196282) (xy 244.832378 -30.297374)
			(xy 245.455538 -30.92069) (xy 253.689612 -30.92069) (xy 253.689612 -30.05709) (xy 253.690102 -30.027122)
			(xy 253.697925 -29.9677) (xy 253.713438 -29.909807) (xy 253.736374 -29.854434) (xy 253.766341 -29.802528)
			(xy 253.802828 -29.754978) (xy 253.845208 -29.712598) (xy 253.892758 -29.676111) (xy 253.944664 -29.646144)
			(xy 254.000037 -29.623208) (xy 254.05793 -29.607695) (xy 254.117352 -29.599872) (xy 254.177288 -29.599872)
			(xy 254.23671 -29.607695) (xy 254.294603 -29.623208) (xy 254.349976 -29.646144) (xy 254.401882 -29.676111)
			(xy 254.449432 -29.712598) (xy 254.491812 -29.754978) (xy 254.528299 -29.802528) (xy 254.558266 -29.854434)
			(xy 254.581202 -29.909807) (xy 254.596715 -29.9677) (xy 254.604538 -30.027122) (xy 254.605028 -30.05709)
			(xy 254.605028 -30.376876) (xy 259.08889 -30.376876) (xy 259.089429 -30.347959) (xy 259.098149 -30.290788)
			(xy 259.1154 -30.235588) (xy 259.140788 -30.183625) (xy 259.17373 -30.136091) (xy 259.213471 -30.094075)
			(xy 259.235956 -30.075886) (xy 259.244769 -30.068285) (xy 259.254947 -30.047379) (xy 259.255514 -30.035754)
			(xy 259.255514 -29.955998) (xy 259.254957 -29.944369) (xy 259.24478 -29.923459) (xy 259.235956 -29.915866)
			(xy 259.213447 -29.897705) (xy 259.173715 -29.855678) (xy 259.140781 -29.808136) (xy 259.115397 -29.756169)
			(xy 259.098146 -29.700967) (xy 259.089422 -29.643794) (xy 259.08889 -29.614876) (xy 259.089376 -29.587625)
			(xy 259.097132 -29.533677) (xy 259.112487 -29.481382) (xy 259.135129 -29.431805) (xy 259.164595 -29.385955)
			(xy 259.200286 -29.344764) (xy 259.241477 -29.309073) (xy 259.287327 -29.279607) (xy 259.336904 -29.256965)
			(xy 259.389199 -29.24161) (xy 259.443147 -29.233854) (xy 259.497649 -29.233854) (xy 259.551597 -29.24161)
			(xy 259.603892 -29.256965) (xy 259.653469 -29.279607) (xy 259.699319 -29.309073) (xy 259.74051 -29.344764)
			(xy 259.776201 -29.385955) (xy 259.805667 -29.431805) (xy 259.828309 -29.481382) (xy 259.843664 -29.533677)
			(xy 259.85142 -29.587625) (xy 259.851906 -29.614876) (xy 259.851406 -29.643794) (xy 259.842678 -29.700968)
			(xy 259.825419 -29.756168) (xy 259.800024 -29.808131) (xy 259.767076 -29.855664) (xy 259.727329 -29.897678)
			(xy 259.70484 -29.915866) (xy 259.696048 -29.923487) (xy 259.685858 -29.944378) (xy 259.685282 -29.955998)
			(xy 259.685282 -30.035754) (xy 259.685811 -30.047387) (xy 259.696008 -30.068296) (xy 259.70484 -30.075886)
			(xy 259.727325 -30.094075) (xy 259.767058 -30.136096) (xy 259.799996 -30.183632) (xy 259.825384 -30.235593)
			(xy 259.84264 -30.290791) (xy 259.85137 -30.34796) (xy 259.851906 -30.376876) (xy 262.129016 -30.376876)
			(xy 262.129583 -30.347961) (xy 262.138301 -30.290792) (xy 262.155549 -30.235593) (xy 262.180931 -30.183631)
			(xy 262.213867 -30.136096) (xy 262.2536 -30.094077) (xy 262.276082 -30.075886) (xy 262.284899 -30.068289)
			(xy 262.295074 -30.04738) (xy 262.29564 -30.035754) (xy 262.29564 -29.955998) (xy 262.295109 -29.944365)
			(xy 262.284917 -29.923454) (xy 262.276082 -29.915866) (xy 262.253578 -29.897699) (xy 262.213845 -29.855673)
			(xy 262.180909 -29.808134) (xy 262.155524 -29.756168) (xy 262.138272 -29.700966) (xy 262.129548 -29.643793)
			(xy 262.129016 -29.614876) (xy 262.129502 -29.587625) (xy 262.137258 -29.533677) (xy 262.152613 -29.481382)
			(xy 262.175255 -29.431805) (xy 262.204721 -29.385955) (xy 262.240412 -29.344764) (xy 262.281603 -29.309073)
			(xy 262.327453 -29.279607) (xy 262.37703 -29.256965) (xy 262.429325 -29.24161) (xy 262.483273 -29.233854)
			(xy 262.537775 -29.233854) (xy 262.591723 -29.24161) (xy 262.644018 -29.256965) (xy 262.693595 -29.279607)
			(xy 262.739445 -29.309073) (xy 262.780636 -29.344764) (xy 262.816327 -29.385955) (xy 262.845793 -29.431805)
			(xy 262.868435 -29.481382) (xy 262.88379 -29.533677) (xy 262.891546 -29.587625) (xy 262.892032 -29.614876)
			(xy 262.891522 -29.643794) (xy 262.882795 -29.700966) (xy 262.865537 -29.756166) (xy 262.840144 -29.808129)
			(xy 262.807198 -29.855662) (xy 262.767453 -29.897677) (xy 262.744966 -29.915866) (xy 262.736179 -29.923492)
			(xy 262.725985 -29.944379) (xy 262.725408 -29.955998) (xy 262.725408 -30.035754) (xy 262.725927 -30.047388)
			(xy 262.73613 -30.068298) (xy 262.744966 -30.075886) (xy 262.767436 -30.094094) (xy 262.807173 -30.136109)
			(xy 262.840115 -30.18364) (xy 262.865506 -30.235598) (xy 262.882765 -30.290793) (xy 262.891496 -30.347961)
			(xy 262.892032 -30.376876) (xy 262.891546 -30.404127) (xy 262.88379 -30.458075) (xy 262.868435 -30.51037)
			(xy 262.845793 -30.559947) (xy 262.816327 -30.605797) (xy 262.780636 -30.646988) (xy 262.739445 -30.682679)
			(xy 262.693595 -30.712145) (xy 262.644018 -30.734787) (xy 262.591723 -30.750142) (xy 262.537775 -30.757898)
			(xy 262.483273 -30.757898) (xy 262.429325 -30.750142) (xy 262.37703 -30.734787) (xy 262.327453 -30.712145)
			(xy 262.281603 -30.682679) (xy 262.240412 -30.646988) (xy 262.204721 -30.605797) (xy 262.175255 -30.559947)
			(xy 262.152613 -30.51037) (xy 262.137258 -30.458075) (xy 262.129502 -30.404127) (xy 262.129016 -30.376876)
			(xy 259.851906 -30.376876) (xy 259.85142 -30.404127) (xy 259.843664 -30.458075) (xy 259.828309 -30.51037)
			(xy 259.805667 -30.559947) (xy 259.776201 -30.605797) (xy 259.74051 -30.646988) (xy 259.699319 -30.682679)
			(xy 259.653469 -30.712145) (xy 259.603892 -30.734787) (xy 259.551597 -30.750142) (xy 259.497649 -30.757898)
			(xy 259.443147 -30.757898) (xy 259.389199 -30.750142) (xy 259.336904 -30.734787) (xy 259.287327 -30.712145)
			(xy 259.241477 -30.682679) (xy 259.200286 -30.646988) (xy 259.164595 -30.605797) (xy 259.135129 -30.559947)
			(xy 259.112487 -30.51037) (xy 259.097132 -30.458075) (xy 259.089376 -30.404127) (xy 259.08889 -30.376876)
			(xy 254.605028 -30.376876) (xy 254.605028 -30.92069) (xy 254.604538 -30.950658) (xy 254.596715 -31.01008)
			(xy 254.581202 -31.067973) (xy 254.558266 -31.123346) (xy 254.528299 -31.175252) (xy 254.491812 -31.222802)
			(xy 254.449432 -31.265182) (xy 254.401882 -31.301669) (xy 254.349976 -31.331636) (xy 254.294603 -31.354572)
			(xy 254.23671 -31.370085) (xy 254.177288 -31.377908) (xy 254.117352 -31.377908) (xy 254.05793 -31.370085)
			(xy 254.000037 -31.354572) (xy 253.944664 -31.331636) (xy 253.892758 -31.301669) (xy 253.845208 -31.265182)
			(xy 253.802828 -31.222802) (xy 253.766341 -31.175252) (xy 253.736374 -31.123346) (xy 253.713438 -31.067973)
			(xy 253.697925 -31.01008) (xy 253.690102 -30.950658) (xy 253.689612 -30.92069) (xy 245.455538 -30.92069)
			(xy 245.84787 -31.31312) (xy 245.881564 -31.347611) (xy 245.942851 -31.42206) (xy 245.996665 -31.502076)
			(xy 246.042505 -31.586912) (xy 246.061738 -31.631128) (xy 246.366284 -32.353504) (xy 246.518288 -32.714184)
			(xy 251.047504 -32.714184) (xy 251.047504 -31.850584) (xy 251.047994 -31.820616) (xy 251.055817 -31.761194)
			(xy 251.07133 -31.703301) (xy 251.094266 -31.647928) (xy 251.124233 -31.596022) (xy 251.16072 -31.548472)
			(xy 251.2031 -31.506092) (xy 251.25065 -31.469605) (xy 251.302556 -31.439638) (xy 251.357929 -31.416702)
			(xy 251.415822 -31.401189) (xy 251.475244 -31.393366) (xy 251.53518 -31.393366) (xy 251.594602 -31.401189)
			(xy 251.652495 -31.416702) (xy 251.707868 -31.439638) (xy 251.759774 -31.469605) (xy 251.807324 -31.506092)
			(xy 251.849704 -31.548472) (xy 251.864598 -31.567882) (xy 259.198616 -31.567882) (xy 259.202687 -31.51226)
			(xy 259.214813 -31.457823) (xy 259.234736 -31.405732) (xy 259.262032 -31.357097) (xy 259.296118 -31.312954)
			(xy 259.336267 -31.274245) (xy 259.381625 -31.241794) (xy 259.431225 -31.216293) (xy 259.484009 -31.198286)
			(xy 259.538852 -31.188156) (xy 259.594586 -31.186119) (xy 259.650023 -31.192219) (xy 259.70398 -31.206325)
			(xy 259.755309 -31.228137) (xy 259.802915 -31.257191) (xy 259.845783 -31.292866) (xy 259.883 -31.334403)
			(xy 259.913773 -31.380916) (xy 259.937445 -31.431413) (xy 259.953513 -31.48482) (xy 259.961633 -31.539996)
			(xy 259.962142 -31.567882) (xy 259.961633 -31.595768) (xy 259.953513 -31.650944) (xy 259.937445 -31.704351)
			(xy 259.930453 -31.719266) (xy 260.48538 -31.719266) (xy 260.489451 -31.663644) (xy 260.501577 -31.609207)
			(xy 260.5215 -31.557116) (xy 260.548796 -31.508481) (xy 260.582882 -31.464338) (xy 260.623031 -31.425629)
			(xy 260.668389 -31.393178) (xy 260.717989 -31.367677) (xy 260.770773 -31.34967) (xy 260.825616 -31.33954)
			(xy 260.88135 -31.337503) (xy 260.936787 -31.343603) (xy 260.990744 -31.357709) (xy 261.042073 -31.379521)
			(xy 261.089679 -31.408575) (xy 261.132547 -31.44425) (xy 261.169764 -31.485787) (xy 261.200537 -31.5323)
			(xy 261.224209 -31.582797) (xy 261.240277 -31.636204) (xy 261.244427 -31.664402) (xy 261.760968 -31.664402)
			(xy 261.765039 -31.60878) (xy 261.777165 -31.554343) (xy 261.797088 -31.502252) (xy 261.824384 -31.453617)
			(xy 261.85847 -31.409474) (xy 261.898619 -31.370765) (xy 261.943977 -31.338314) (xy 261.993577 -31.312813)
			(xy 262.046361 -31.294806) (xy 262.101204 -31.284676) (xy 262.156938 -31.282639) (xy 262.212375 -31.288739)
			(xy 262.266332 -31.302845) (xy 262.317661 -31.324657) (xy 262.365267 -31.353711) (xy 262.408135 -31.389386)
			(xy 262.445352 -31.430923) (xy 262.476125 -31.477436) (xy 262.499797 -31.527933) (xy 262.515865 -31.58134)
			(xy 262.523985 -31.636516) (xy 262.524494 -31.664402) (xy 262.523985 -31.692288) (xy 262.515865 -31.747464)
			(xy 262.506925 -31.777178) (xy 263.026142 -31.777178) (xy 263.030213 -31.721556) (xy 263.042339 -31.667119)
			(xy 263.062262 -31.615028) (xy 263.089558 -31.566393) (xy 263.123644 -31.52225) (xy 263.163793 -31.483541)
			(xy 263.209151 -31.45109) (xy 263.258751 -31.425589) (xy 263.311535 -31.407582) (xy 263.366378 -31.397452)
			(xy 263.422112 -31.395415) (xy 263.477549 -31.401515) (xy 263.531506 -31.415621) (xy 263.582835 -31.437433)
			(xy 263.630441 -31.466487) (xy 263.673309 -31.502162) (xy 263.710526 -31.543699) (xy 263.741299 -31.590212)
			(xy 263.764971 -31.640709) (xy 263.781039 -31.694116) (xy 263.789159 -31.749292) (xy 263.789668 -31.777178)
			(xy 263.789159 -31.805064) (xy 263.781039 -31.86024) (xy 263.764971 -31.913647) (xy 263.741299 -31.964144)
			(xy 263.710526 -32.010657) (xy 263.673309 -32.052194) (xy 263.630441 -32.087869) (xy 263.582835 -32.116923)
			(xy 263.531506 -32.138735) (xy 263.477549 -32.152841) (xy 263.422112 -32.158941) (xy 263.366378 -32.156904)
			(xy 263.311535 -32.146774) (xy 263.258751 -32.128767) (xy 263.209151 -32.103266) (xy 263.163793 -32.070815)
			(xy 263.123644 -32.032106) (xy 263.089558 -31.987963) (xy 263.062262 -31.939328) (xy 263.042339 -31.887237)
			(xy 263.030213 -31.8328) (xy 263.026142 -31.777178) (xy 262.506925 -31.777178) (xy 262.499797 -31.800871)
			(xy 262.476125 -31.851368) (xy 262.445352 -31.897881) (xy 262.408135 -31.939418) (xy 262.365267 -31.975093)
			(xy 262.317661 -32.004147) (xy 262.266332 -32.025959) (xy 262.212375 -32.040065) (xy 262.156938 -32.046165)
			(xy 262.101204 -32.044128) (xy 262.046361 -32.033998) (xy 261.993577 -32.015991) (xy 261.943977 -31.99049)
			(xy 261.898619 -31.958039) (xy 261.85847 -31.91933) (xy 261.824384 -31.875187) (xy 261.797088 -31.826552)
			(xy 261.777165 -31.774461) (xy 261.765039 -31.720024) (xy 261.760968 -31.664402) (xy 261.244427 -31.664402)
			(xy 261.248397 -31.69138) (xy 261.248906 -31.719266) (xy 261.248397 -31.747152) (xy 261.240277 -31.802328)
			(xy 261.224209 -31.855735) (xy 261.200537 -31.906232) (xy 261.169764 -31.952745) (xy 261.132547 -31.994282)
			(xy 261.089679 -32.029957) (xy 261.042073 -32.059011) (xy 260.990744 -32.080823) (xy 260.936787 -32.094929)
			(xy 260.88135 -32.101029) (xy 260.825616 -32.098992) (xy 260.770773 -32.088862) (xy 260.717989 -32.070855)
			(xy 260.668389 -32.045354) (xy 260.623031 -32.012903) (xy 260.582882 -31.974194) (xy 260.548796 -31.930051)
			(xy 260.5215 -31.881416) (xy 260.501577 -31.829325) (xy 260.489451 -31.774888) (xy 260.48538 -31.719266)
			(xy 259.930453 -31.719266) (xy 259.913773 -31.754848) (xy 259.883 -31.801361) (xy 259.845783 -31.842898)
			(xy 259.802915 -31.878573) (xy 259.755309 -31.907627) (xy 259.70398 -31.929439) (xy 259.650023 -31.943545)
			(xy 259.594586 -31.949645) (xy 259.538852 -31.947608) (xy 259.484009 -31.937478) (xy 259.431225 -31.919471)
			(xy 259.381625 -31.89397) (xy 259.336267 -31.861519) (xy 259.296118 -31.82281) (xy 259.262032 -31.778667)
			(xy 259.234736 -31.730032) (xy 259.214813 -31.677941) (xy 259.202687 -31.623504) (xy 259.198616 -31.567882)
			(xy 251.864598 -31.567882) (xy 251.886191 -31.596022) (xy 251.916158 -31.647928) (xy 251.939094 -31.703301)
			(xy 251.954607 -31.761194) (xy 251.96243 -31.820616) (xy 251.96292 -31.850584) (xy 251.96292 -32.714184)
			(xy 251.96243 -32.744152) (xy 251.954607 -32.803574) (xy 251.939094 -32.861467) (xy 251.916158 -32.91684)
			(xy 251.886191 -32.968746) (xy 251.849704 -33.016296) (xy 251.807324 -33.058676) (xy 251.759774 -33.095163)
			(xy 251.707868 -33.12513) (xy 251.652495 -33.148066) (xy 251.594602 -33.163579) (xy 251.53518 -33.171402)
			(xy 251.475244 -33.171402) (xy 251.415822 -33.163579) (xy 251.357929 -33.148066) (xy 251.302556 -33.12513)
			(xy 251.25065 -33.095163) (xy 251.2031 -33.058676) (xy 251.16072 -33.016296) (xy 251.124233 -32.968746)
			(xy 251.094266 -32.91684) (xy 251.07133 -32.861467) (xy 251.055817 -32.803574) (xy 251.047994 -32.744152)
			(xy 251.047504 -32.714184) (xy 246.518288 -32.714184) (xy 246.557038 -32.806132) (xy 246.559126 -32.8108)
			(xy 246.564881 -32.819251) (xy 246.568468 -32.822896) (xy 246.575834 -32.830008) (xy 246.582438 -32.832548)
			(xy 246.607777 -32.842528) (xy 246.655567 -32.868639) (xy 246.699161 -32.901279) (xy 246.737672 -32.939783)
			(xy 246.77032 -32.98337) (xy 246.796441 -33.031155) (xy 246.815504 -33.082167) (xy 246.827123 -33.135371)
			(xy 246.82958 -33.162494) (xy 246.830596 -33.17875) (xy 246.830596 -33.190434) (xy 246.830138 -33.216341)
			(xy 246.823094 -33.267676) (xy 246.809193 -33.317593) (xy 246.799354 -33.341564) (xy 246.79529 -33.351216)
			(xy 246.79529 -33.360614) (xy 246.795317 -33.365825) (xy 246.797245 -33.376064) (xy 246.7991 -33.380934)
			(xy 247.279294 -34.520886) (xy 253.689612 -34.520886) (xy 253.689612 -33.657286) (xy 253.690102 -33.627318)
			(xy 253.697925 -33.567896) (xy 253.713438 -33.510003) (xy 253.736374 -33.45463) (xy 253.766341 -33.402724)
			(xy 253.802828 -33.355174) (xy 253.845208 -33.312794) (xy 253.892758 -33.276307) (xy 253.944664 -33.24634)
			(xy 254.000037 -33.223404) (xy 254.05793 -33.207891) (xy 254.117352 -33.200068) (xy 254.177288 -33.200068)
			(xy 254.23671 -33.207891) (xy 254.294603 -33.223404) (xy 254.349976 -33.24634) (xy 254.401882 -33.276307)
			(xy 254.449432 -33.312794) (xy 254.491812 -33.355174) (xy 254.528299 -33.402724) (xy 254.558266 -33.45463)
			(xy 254.581202 -33.510003) (xy 254.596715 -33.567896) (xy 254.604538 -33.627318) (xy 254.605028 -33.657286)
			(xy 254.605028 -34.520886) (xy 254.604538 -34.550854) (xy 254.596715 -34.610276) (xy 254.581202 -34.668169)
			(xy 254.558266 -34.723542) (xy 254.528299 -34.775448) (xy 254.491812 -34.822998) (xy 254.449432 -34.865378)
			(xy 254.401882 -34.901865) (xy 254.349976 -34.931832) (xy 254.294603 -34.954768) (xy 254.23671 -34.970281)
			(xy 254.177288 -34.978104) (xy 254.117352 -34.978104) (xy 254.05793 -34.970281) (xy 254.000037 -34.954768)
			(xy 253.944664 -34.931832) (xy 253.892758 -34.901865) (xy 253.845208 -34.865378) (xy 253.802828 -34.822998)
			(xy 253.766341 -34.775448) (xy 253.736374 -34.723542) (xy 253.713438 -34.668169) (xy 253.697925 -34.610276)
			(xy 253.690102 -34.550854) (xy 253.689612 -34.520886) (xy 247.279294 -34.520886) (xy 247.592682 -35.264852)
			(xy 262.102344 -35.264852) (xy 262.106415 -35.20923) (xy 262.118541 -35.154793) (xy 262.138464 -35.102702)
			(xy 262.16576 -35.054067) (xy 262.199846 -35.009924) (xy 262.239995 -34.971215) (xy 262.285353 -34.938764)
			(xy 262.334953 -34.913263) (xy 262.387737 -34.895256) (xy 262.44258 -34.885126) (xy 262.498314 -34.883089)
			(xy 262.553751 -34.889189) (xy 262.607708 -34.903295) (xy 262.659037 -34.925107) (xy 262.706643 -34.954161)
			(xy 262.749511 -34.989836) (xy 262.786728 -35.031373) (xy 262.817501 -35.077886) (xy 262.841173 -35.128383)
			(xy 262.857241 -35.18179) (xy 262.865361 -35.236966) (xy 262.86587 -35.264852) (xy 262.865361 -35.292738)
			(xy 262.857241 -35.347914) (xy 262.841173 -35.401321) (xy 262.817501 -35.451818) (xy 262.786728 -35.498331)
			(xy 262.749511 -35.539868) (xy 262.706643 -35.575543) (xy 262.659037 -35.604597) (xy 262.607708 -35.626409)
			(xy 262.553751 -35.640515) (xy 262.498314 -35.646615) (xy 262.44258 -35.644578) (xy 262.387737 -35.634448)
			(xy 262.334953 -35.616441) (xy 262.285353 -35.59094) (xy 262.239995 -35.558489) (xy 262.199846 -35.51978)
			(xy 262.16576 -35.475637) (xy 262.138464 -35.427002) (xy 262.118541 -35.374911) (xy 262.106415 -35.320474)
			(xy 262.102344 -35.264852) (xy 247.592682 -35.264852) (xy 247.850433 -35.876738) (xy 250.9172 -35.876738)
			(xy 250.921271 -35.821116) (xy 250.933397 -35.766679) (xy 250.95332 -35.714588) (xy 250.980616 -35.665953)
			(xy 251.014702 -35.62181) (xy 251.054851 -35.583101) (xy 251.100209 -35.55065) (xy 251.149809 -35.525149)
			(xy 251.202593 -35.507142) (xy 251.257436 -35.497012) (xy 251.31317 -35.494975) (xy 251.368607 -35.501075)
			(xy 251.422564 -35.515181) (xy 251.473893 -35.536993) (xy 251.521499 -35.566047) (xy 251.564367 -35.601722)
			(xy 251.601584 -35.643259) (xy 251.632357 -35.689772) (xy 251.656029 -35.740269) (xy 251.672097 -35.793676)
			(xy 251.680217 -35.848852) (xy 251.680726 -35.876738) (xy 254.98882 -35.876738) (xy 254.992891 -35.821116)
			(xy 255.005017 -35.766679) (xy 255.02494 -35.714588) (xy 255.052236 -35.665953) (xy 255.086322 -35.62181)
			(xy 255.126471 -35.583101) (xy 255.171829 -35.55065) (xy 255.221429 -35.525149) (xy 255.274213 -35.507142)
			(xy 255.329056 -35.497012) (xy 255.38479 -35.494975) (xy 255.440227 -35.501075) (xy 255.494184 -35.515181)
			(xy 255.545513 -35.536993) (xy 255.593119 -35.566047) (xy 255.635987 -35.601722) (xy 255.673204 -35.643259)
			(xy 255.703977 -35.689772) (xy 255.727649 -35.740269) (xy 255.743717 -35.793676) (xy 255.751837 -35.848852)
			(xy 255.752346 -35.876738) (xy 255.751837 -35.904624) (xy 255.743717 -35.9598) (xy 255.727649 -36.013207)
			(xy 255.703977 -36.063704) (xy 255.673204 -36.110217) (xy 255.635987 -36.151754) (xy 255.593119 -36.187429)
			(xy 255.545513 -36.216483) (xy 255.494184 -36.238295) (xy 255.440227 -36.252401) (xy 255.38479 -36.258501)
			(xy 255.329056 -36.256464) (xy 255.274213 -36.246334) (xy 255.221429 -36.228327) (xy 255.171829 -36.202826)
			(xy 255.126471 -36.170375) (xy 255.086322 -36.131666) (xy 255.052236 -36.087523) (xy 255.02494 -36.038888)
			(xy 255.005017 -35.986797) (xy 254.992891 -35.93236) (xy 254.98882 -35.876738) (xy 251.680726 -35.876738)
			(xy 251.680217 -35.904624) (xy 251.672097 -35.9598) (xy 251.656029 -36.013207) (xy 251.632357 -36.063704)
			(xy 251.601584 -36.110217) (xy 251.564367 -36.151754) (xy 251.521499 -36.187429) (xy 251.473893 -36.216483)
			(xy 251.422564 -36.238295) (xy 251.368607 -36.252401) (xy 251.31317 -36.258501) (xy 251.257436 -36.256464)
			(xy 251.202593 -36.246334) (xy 251.149809 -36.228327) (xy 251.100209 -36.202826) (xy 251.054851 -36.170375)
			(xy 251.014702 -36.131666) (xy 250.980616 -36.087523) (xy 250.95332 -36.038888) (xy 250.933397 -35.986797)
			(xy 250.921271 -35.93236) (xy 250.9172 -35.876738) (xy 247.850433 -35.876738) (xy 248.117172 -36.50996)
			(xy 252.813818 -36.50996) (xy 252.817889 -36.454338) (xy 252.830015 -36.399901) (xy 252.849938 -36.34781)
			(xy 252.877234 -36.299175) (xy 252.91132 -36.255032) (xy 252.951469 -36.216323) (xy 252.996827 -36.183872)
			(xy 253.046427 -36.158371) (xy 253.099211 -36.140364) (xy 253.154054 -36.130234) (xy 253.209788 -36.128197)
			(xy 253.265225 -36.134297) (xy 253.319182 -36.148403) (xy 253.370511 -36.170215) (xy 253.418117 -36.199269)
			(xy 253.460985 -36.234944) (xy 253.498202 -36.276481) (xy 253.528975 -36.322994) (xy 253.552647 -36.373491)
			(xy 253.568715 -36.426898) (xy 253.57264 -36.453572) (xy 256.128518 -36.453572) (xy 256.132589 -36.39795)
			(xy 256.144715 -36.343513) (xy 256.164638 -36.291422) (xy 256.191934 -36.242787) (xy 256.22602 -36.198644)
			(xy 256.266169 -36.159935) (xy 256.311527 -36.127484) (xy 256.361127 -36.101983) (xy 256.413911 -36.083976)
			(xy 256.468754 -36.073846) (xy 256.524488 -36.071809) (xy 256.579925 -36.077909) (xy 256.633882 -36.092015)
			(xy 256.685211 -36.113827) (xy 256.732817 -36.142881) (xy 256.775685 -36.178556) (xy 256.812902 -36.220093)
			(xy 256.843675 -36.266606) (xy 256.853211 -36.286948) (xy 263.400284 -36.286948) (xy 263.404355 -36.231326)
			(xy 263.416481 -36.176889) (xy 263.436404 -36.124798) (xy 263.4637 -36.076163) (xy 263.497786 -36.03202)
			(xy 263.537935 -35.993311) (xy 263.583293 -35.96086) (xy 263.632893 -35.935359) (xy 263.685677 -35.917352)
			(xy 263.74052 -35.907222) (xy 263.796254 -35.905185) (xy 263.851691 -35.911285) (xy 263.905648 -35.925391)
			(xy 263.956977 -35.947203) (xy 264.004583 -35.976257) (xy 264.047451 -36.011932) (xy 264.084668 -36.053469)
			(xy 264.115441 -36.099982) (xy 264.139113 -36.150479) (xy 264.155181 -36.203886) (xy 264.163301 -36.259062)
			(xy 264.16381 -36.286948) (xy 264.163301 -36.314834) (xy 264.155181 -36.37001) (xy 264.139113 -36.423417)
			(xy 264.115441 -36.473914) (xy 264.084668 -36.520427) (xy 264.047451 -36.561964) (xy 264.004583 -36.597639)
			(xy 263.956977 -36.626693) (xy 263.905648 -36.648505) (xy 263.851691 -36.662611) (xy 263.796254 -36.668711)
			(xy 263.74052 -36.666674) (xy 263.685677 -36.656544) (xy 263.632893 -36.638537) (xy 263.583293 -36.613036)
			(xy 263.537935 -36.580585) (xy 263.497786 -36.541876) (xy 263.4637 -36.497733) (xy 263.436404 -36.449098)
			(xy 263.416481 -36.397007) (xy 263.404355 -36.34257) (xy 263.400284 -36.286948) (xy 256.853211 -36.286948)
			(xy 256.867347 -36.317103) (xy 256.883415 -36.37051) (xy 256.891535 -36.425686) (xy 256.892044 -36.453572)
			(xy 256.891535 -36.481458) (xy 256.883415 -36.536634) (xy 256.867347 -36.590041) (xy 256.843675 -36.640538)
			(xy 256.812902 -36.687051) (xy 256.775685 -36.728588) (xy 256.732817 -36.764263) (xy 256.685211 -36.793317)
			(xy 256.633882 -36.815129) (xy 256.579925 -36.829235) (xy 256.524488 -36.835335) (xy 256.468754 -36.833298)
			(xy 256.413911 -36.823168) (xy 256.361127 -36.805161) (xy 256.311527 -36.77966) (xy 256.266169 -36.747209)
			(xy 256.22602 -36.7085) (xy 256.191934 -36.664357) (xy 256.164638 -36.615722) (xy 256.144715 -36.563631)
			(xy 256.132589 -36.509194) (xy 256.128518 -36.453572) (xy 253.57264 -36.453572) (xy 253.576835 -36.482074)
			(xy 253.577344 -36.50996) (xy 253.576835 -36.537846) (xy 253.568715 -36.593022) (xy 253.552647 -36.646429)
			(xy 253.528975 -36.696926) (xy 253.498202 -36.743439) (xy 253.460985 -36.784976) (xy 253.418117 -36.820651)
			(xy 253.370511 -36.849705) (xy 253.319182 -36.871517) (xy 253.265225 -36.885623) (xy 253.209788 -36.891723)
			(xy 253.154054 -36.889686) (xy 253.099211 -36.879556) (xy 253.046427 -36.861549) (xy 252.996827 -36.836048)
			(xy 252.951469 -36.803597) (xy 252.91132 -36.764888) (xy 252.877234 -36.720745) (xy 252.849938 -36.67211)
			(xy 252.830015 -36.620019) (xy 252.817889 -36.565582) (xy 252.813818 -36.50996) (xy 248.117172 -36.50996)
			(xy 248.450354 -37.300916) (xy 248.471122 -37.351975) (xy 248.502561 -37.45763) (xy 248.505973 -37.47516)
			(xy 249.959112 -37.47516) (xy 249.963183 -37.419538) (xy 249.975309 -37.365101) (xy 249.995232 -37.31301)
			(xy 250.022528 -37.264375) (xy 250.056614 -37.220232) (xy 250.096763 -37.181523) (xy 250.142121 -37.149072)
			(xy 250.191721 -37.123571) (xy 250.244505 -37.105564) (xy 250.299348 -37.095434) (xy 250.355082 -37.093397)
			(xy 250.410519 -37.099497) (xy 250.464476 -37.113603) (xy 250.515805 -37.135415) (xy 250.563411 -37.164469)
			(xy 250.606279 -37.200144) (xy 250.643496 -37.241681) (xy 250.674269 -37.288194) (xy 250.697941 -37.338691)
			(xy 250.714009 -37.392098) (xy 250.722129 -37.447274) (xy 250.722638 -37.47516) (xy 250.722129 -37.503046)
			(xy 250.714009 -37.558222) (xy 250.697941 -37.611629) (xy 250.674269 -37.662126) (xy 250.674116 -37.662358)
			(xy 252.148338 -37.662358) (xy 252.152409 -37.606736) (xy 252.164535 -37.552299) (xy 252.184458 -37.500208)
			(xy 252.211754 -37.451573) (xy 252.24584 -37.40743) (xy 252.285989 -37.368721) (xy 252.331347 -37.33627)
			(xy 252.380947 -37.310769) (xy 252.433731 -37.292762) (xy 252.488574 -37.282632) (xy 252.544308 -37.280595)
			(xy 252.599745 -37.286695) (xy 252.653702 -37.300801) (xy 252.705031 -37.322613) (xy 252.752637 -37.351667)
			(xy 252.795505 -37.387342) (xy 252.832722 -37.428879) (xy 252.863495 -37.475392) (xy 252.887167 -37.525889)
			(xy 252.903235 -37.579296) (xy 252.911355 -37.634472) (xy 252.911864 -37.662358) (xy 252.911355 -37.690244)
			(xy 252.903235 -37.74542) (xy 252.894601 -37.774118) (xy 263.664698 -37.774118) (xy 263.668769 -37.718496)
			(xy 263.680895 -37.664059) (xy 263.700818 -37.611968) (xy 263.728114 -37.563333) (xy 263.7622 -37.51919)
			(xy 263.802349 -37.480481) (xy 263.847707 -37.44803) (xy 263.897307 -37.422529) (xy 263.950091 -37.404522)
			(xy 264.004934 -37.394392) (xy 264.060668 -37.392355) (xy 264.116105 -37.398455) (xy 264.170062 -37.412561)
			(xy 264.221391 -37.434373) (xy 264.268997 -37.463427) (xy 264.311865 -37.499102) (xy 264.349082 -37.540639)
			(xy 264.379855 -37.587152) (xy 264.403527 -37.637649) (xy 264.419595 -37.691056) (xy 264.427715 -37.746232)
			(xy 264.428224 -37.774118) (xy 264.427715 -37.802004) (xy 264.419595 -37.85718) (xy 264.403527 -37.910587)
			(xy 264.379855 -37.961084) (xy 264.349082 -38.007597) (xy 264.311865 -38.049134) (xy 264.268997 -38.084809)
			(xy 264.221391 -38.113863) (xy 264.170062 -38.135675) (xy 264.116105 -38.149781) (xy 264.060668 -38.155881)
			(xy 264.004934 -38.153844) (xy 263.950091 -38.143714) (xy 263.897307 -38.125707) (xy 263.847707 -38.100206)
			(xy 263.802349 -38.067755) (xy 263.7622 -38.029046) (xy 263.728114 -37.984903) (xy 263.700818 -37.936268)
			(xy 263.680895 -37.884177) (xy 263.668769 -37.82974) (xy 263.664698 -37.774118) (xy 252.894601 -37.774118)
			(xy 252.887167 -37.798827) (xy 252.863495 -37.849324) (xy 252.832722 -37.895837) (xy 252.795505 -37.937374)
			(xy 252.752637 -37.973049) (xy 252.705031 -38.002103) (xy 252.653702 -38.023915) (xy 252.599745 -38.038021)
			(xy 252.544308 -38.044121) (xy 252.488574 -38.042084) (xy 252.433731 -38.031954) (xy 252.380947 -38.013947)
			(xy 252.331347 -37.988446) (xy 252.285989 -37.955995) (xy 252.24584 -37.917286) (xy 252.211754 -37.873143)
			(xy 252.184458 -37.824508) (xy 252.164535 -37.772417) (xy 252.152409 -37.71798) (xy 252.148338 -37.662358)
			(xy 250.674116 -37.662358) (xy 250.643496 -37.708639) (xy 250.606279 -37.750176) (xy 250.563411 -37.785851)
			(xy 250.515805 -37.814905) (xy 250.464476 -37.836717) (xy 250.410519 -37.850823) (xy 250.355082 -37.856923)
			(xy 250.299348 -37.854886) (xy 250.244505 -37.844756) (xy 250.191721 -37.826749) (xy 250.142121 -37.801248)
			(xy 250.096763 -37.768797) (xy 250.056614 -37.730088) (xy 250.022528 -37.685945) (xy 249.995232 -37.63731)
			(xy 249.975309 -37.585219) (xy 249.963183 -37.530782) (xy 249.959112 -37.47516) (xy 248.505973 -37.47516)
			(xy 248.513092 -37.511736) (xy 248.520452 -37.555369) (xy 248.528337 -37.643511) (xy 248.52884 -37.687758)
			(xy 248.52884 -37.688266) (xy 248.528586 -37.704268) (xy 248.528586 -37.704522) (xy 248.511531 -38.729951)
			(xy 255.900897 -38.729951) (xy 255.900897 -38.675449) (xy 255.908654 -38.6215) (xy 255.924011 -38.569205)
			(xy 255.946653 -38.519628) (xy 255.976121 -38.473779) (xy 256.011815 -38.432589) (xy 256.053007 -38.3969)
			(xy 256.09886 -38.367436) (xy 256.148439 -38.344798) (xy 256.200736 -38.329447) (xy 256.254684 -38.321695)
			(xy 256.281936 -38.321234) (xy 256.310239 -38.321758) (xy 256.366227 -38.330102) (xy 256.420366 -38.34663)
			(xy 256.471467 -38.370979) (xy 256.518407 -38.402615) (xy 256.560156 -38.440842) (xy 256.595795 -38.48482)
			(xy 256.610612 -38.50894) (xy 256.618228 -38.520962) (xy 256.638843 -38.540563) (xy 256.664071 -38.553706)
			(xy 256.691948 -38.559367) (xy 256.720304 -38.557105) (xy 256.746932 -38.547097) (xy 256.769758 -38.530122)
			(xy 256.77876 -38.5191) (xy 256.796974 -38.496247) (xy 256.839131 -38.455782) (xy 256.886961 -38.422212)
			(xy 256.939348 -38.396321) (xy 256.995067 -38.378713) (xy 257.052819 -38.369801) (xy 257.082036 -38.36924)
			(xy 257.109289 -38.369632) (xy 257.16324 -38.377394) (xy 257.215537 -38.392754) (xy 257.265116 -38.4154)
			(xy 257.310967 -38.444871) (xy 257.352158 -38.480567) (xy 257.38785 -38.521762) (xy 257.417317 -38.567616)
			(xy 257.439958 -38.617197) (xy 257.455314 -38.669496) (xy 257.46307 -38.723447) (xy 257.46307 -38.777953)
			(xy 257.455314 -38.831904) (xy 257.439958 -38.884203) (xy 257.417317 -38.933784) (xy 257.38785 -38.979638)
			(xy 257.352158 -39.020833) (xy 257.310967 -39.056529) (xy 257.265116 -39.086) (xy 257.215537 -39.108646)
			(xy 257.16324 -39.124006) (xy 257.109289 -39.131768) (xy 257.082036 -39.132256) (xy 257.053732 -39.131759)
			(xy 256.997743 -39.123411) (xy 256.943603 -39.106879) (xy 256.892501 -39.082525) (xy 256.845561 -39.050885)
			(xy 256.803814 -39.012654) (xy 256.768177 -38.968672) (xy 256.75336 -38.94455) (xy 256.745781 -38.932503)
			(xy 256.725157 -38.912902) (xy 256.699922 -38.899761) (xy 256.672038 -38.894104) (xy 256.643676 -38.89637)
			(xy 256.617044 -38.906383) (xy 256.594215 -38.923365) (xy 256.585212 -38.93439) (xy 256.567011 -38.957254)
			(xy 256.524852 -38.997719) (xy 256.477019 -39.031288) (xy 256.42463 -39.057178) (xy 256.368908 -39.074782)
			(xy 256.311154 -39.083691) (xy 256.281936 -39.08425) (xy 256.254684 -39.083705) (xy 256.200736 -39.075953)
			(xy 256.148439 -39.060602) (xy 256.09886 -39.037964) (xy 256.053007 -39.0085) (xy 256.011815 -38.972811)
			(xy 255.976121 -38.931621) (xy 255.946653 -38.885772) (xy 255.924011 -38.836195) (xy 255.908654 -38.7839)
			(xy 255.900897 -38.729951) (xy 248.511531 -38.729951) (xy 248.503948 -39.18585) (xy 248.502593 -39.233199)
			(xy 248.492037 -39.327338) (xy 248.482866 -39.37381) (xy 248.45645 -39.500556) (xy 248.357751 -39.97198)
			(xy 258.095748 -39.97198) (xy 258.099819 -39.916358) (xy 258.111945 -39.861921) (xy 258.131868 -39.80983)
			(xy 258.159164 -39.761195) (xy 258.19325 -39.717052) (xy 258.233399 -39.678343) (xy 258.278757 -39.645892)
			(xy 258.328357 -39.620391) (xy 258.381141 -39.602384) (xy 258.435984 -39.592254) (xy 258.491718 -39.590217)
			(xy 258.547155 -39.596317) (xy 258.601112 -39.610423) (xy 258.652441 -39.632235) (xy 258.700047 -39.661289)
			(xy 258.742915 -39.696964) (xy 258.780132 -39.738501) (xy 258.810905 -39.785014) (xy 258.834577 -39.835511)
			(xy 258.850645 -39.888918) (xy 258.858765 -39.944094) (xy 258.859274 -39.97198) (xy 258.858765 -39.999866)
			(xy 258.850645 -40.055042) (xy 258.834577 -40.108449) (xy 258.810905 -40.158946) (xy 258.780132 -40.205459)
			(xy 258.742915 -40.246996) (xy 258.700047 -40.282671) (xy 258.652441 -40.311725) (xy 258.601112 -40.333537)
			(xy 258.547155 -40.347643) (xy 258.491718 -40.353743) (xy 258.435984 -40.351706) (xy 258.381141 -40.341576)
			(xy 258.328357 -40.323569) (xy 258.278757 -40.298068) (xy 258.233399 -40.265617) (xy 258.19325 -40.226908)
			(xy 258.159164 -40.182765) (xy 258.131868 -40.13413) (xy 258.111945 -40.082039) (xy 258.099819 -40.027602)
			(xy 258.095748 -39.97198) (xy 248.357751 -39.97198) (xy 248.194068 -40.753792) (xy 248.193052 -40.762428)
			(xy 248.193814 -40.773096) (xy 248.195084 -40.777922) (xy 248.196824 -40.783515) (xy 248.202476 -40.79377)
			(xy 248.20626 -40.798242) (xy 248.273062 -40.860726) (xy 248.277853 -40.86495) (xy 248.289031 -40.871122)
			(xy 248.29516 -40.872918) (xy 248.300748 -40.874188) (xy 248.313956 -40.874188) (xy 248.320814 -40.872156)
			(xy 248.346138 -40.8655) (xy 248.398011 -40.858365) (xy 248.424192 -40.857932) (xy 248.424954 -40.857932)
			(xy 248.453475 -40.858458) (xy 248.509888 -40.866907) (xy 248.564429 -40.883611) (xy 248.615898 -40.908202)
			(xy 248.663162 -40.940139) (xy 248.684542 -40.959024) (xy 248.685558 -40.96004) (xy 248.687844 -40.961818)
			(xy 248.697242 -40.966898) (xy 248.711466 -40.974518) (xy 248.721372 -40.976804) (xy 248.790714 -40.976804)
			(xy 248.796556 -40.97655) (xy 248.815193 -40.956914) (xy 248.856935 -40.922443) (xy 248.903023 -40.894042)
			(xy 248.952581 -40.872253) (xy 249.004666 -40.857491) (xy 249.058286 -40.850036) (xy 249.085354 -40.84955)
			(xy 249.113355 -40.850023) (xy 249.168787 -40.857987) (xy 249.222522 -40.873759) (xy 249.273465 -40.897019)
			(xy 249.320579 -40.927292) (xy 249.362905 -40.963963) (xy 249.39958 -41.006284) (xy 249.429859 -41.053394)
			(xy 249.453125 -41.104335) (xy 249.468903 -41.158068) (xy 249.476874 -41.213499) (xy 249.476874 -41.269501)
			(xy 249.468903 -41.324932) (xy 249.453125 -41.378665) (xy 249.429859 -41.429606) (xy 249.39958 -41.476716)
			(xy 249.362905 -41.519037) (xy 249.320579 -41.555708) (xy 249.273465 -41.585981) (xy 249.222522 -41.609241)
			(xy 249.168787 -41.625013) (xy 249.113355 -41.632977) (xy 249.085354 -41.633394) (xy 249.058283 -41.632941)
			(xy 249.004657 -41.625494) (xy 248.952566 -41.610733) (xy 248.903004 -41.588941) (xy 248.856915 -41.560533)
			(xy 248.815176 -41.526048) (xy 248.796556 -41.506394) (xy 248.790714 -41.50614) (xy 248.727214 -41.50614)
			(xy 248.715276 -41.507664) (xy 248.70918 -41.509188) (xy 248.696988 -41.514268) (xy 248.692162 -41.517062)
			(xy 248.687844 -41.520872) (xy 248.687082 -41.521634) (xy 248.66563 -41.540957) (xy 248.618014 -41.573605)
			(xy 248.566048 -41.598758) (xy 248.510903 -41.615852) (xy 248.453821 -41.6245) (xy 248.424954 -41.625012)
			(xy 248.398591 -41.62458) (xy 248.346359 -41.617378) (xy 248.295602 -41.6031) (xy 248.247275 -41.582017)
			(xy 248.202284 -41.554522) (xy 248.181622 -41.538144) (xy 248.181114 -41.537636) (xy 248.175893 -41.533654)
			(xy 248.163932 -41.528248) (xy 248.157492 -41.526968) (xy 248.1453 -41.524936) (xy 248.050558 -41.55821)
			(xy 248.042489 -41.561427) (xy 248.028986 -41.572335) (xy 248.019895 -41.587122) (xy 248.017792 -41.595548)
			(xy 247.828054 -42.501312) (xy 247.659859 -43.305222) (xy 250.507246 -43.305222) (xy 250.507714 -43.277852)
			(xy 250.515529 -43.223672) (xy 250.531018 -43.171169) (xy 250.553859 -43.121422) (xy 250.583584 -43.075455)
			(xy 250.601226 -43.054524) (xy 250.60148 -43.05427) (xy 250.607053 -43.047174) (xy 250.613306 -43.030264)
			(xy 250.613672 -43.02125) (xy 250.613672 -42.954194) (xy 250.613324 -42.945176) (xy 250.607071 -42.928259)
			(xy 250.60148 -42.921174) (xy 250.601226 -42.921174) (xy 250.601226 -42.92092) (xy 250.583587 -42.899988)
			(xy 250.553874 -42.854015) (xy 250.531038 -42.804268) (xy 250.515547 -42.751767) (xy 250.507719 -42.697591)
			(xy 250.507246 -42.670222) (xy 250.507798 -42.641484) (xy 250.516416 -42.584659) (xy 250.53346 -42.529769)
			(xy 250.558545 -42.478057) (xy 250.591103 -42.430692) (xy 250.61037 -42.409364) (xy 250.616974 -42.402506)
			(xy 250.624086 -42.384472) (xy 250.624086 -42.295572) (xy 250.616974 -42.277538) (xy 250.61037 -42.27068)
			(xy 250.591123 -42.249333) (xy 250.558562 -42.201973) (xy 250.533473 -42.150264) (xy 250.516424 -42.095377)
			(xy 250.5078 -42.038553) (xy 250.507798 -41.981079) (xy 250.516417 -41.924255) (xy 250.533461 -41.869366)
			(xy 250.558546 -41.817655) (xy 250.591103 -41.770292) (xy 250.61037 -41.748964) (xy 250.616974 -41.742106)
			(xy 250.624086 -41.724072) (xy 250.624086 -41.635172) (xy 250.616974 -41.617138) (xy 250.61037 -41.61028)
			(xy 250.591115 -41.588939) (xy 250.558545 -41.541582) (xy 250.533449 -41.489873) (xy 250.516395 -41.434986)
			(xy 250.507769 -41.37816) (xy 250.507246 -41.349422) (xy 250.507732 -41.322171) (xy 250.515488 -41.268223)
			(xy 250.530843 -41.215928) (xy 250.553485 -41.166351) (xy 250.582951 -41.120501) (xy 250.618642 -41.07931)
			(xy 250.659833 -41.043619) (xy 250.705683 -41.014153) (xy 250.75526 -40.991511) (xy 250.807555 -40.976156)
			(xy 250.861503 -40.9684) (xy 250.916005 -40.9684) (xy 250.939126 -40.971724) (xy 258.793994 -40.971724)
			(xy 258.798065 -40.916102) (xy 258.810191 -40.861665) (xy 258.830114 -40.809574) (xy 258.85741 -40.760939)
			(xy 258.891496 -40.716796) (xy 258.931645 -40.678087) (xy 258.977003 -40.645636) (xy 259.026603 -40.620135)
			(xy 259.079387 -40.602128) (xy 259.13423 -40.591998) (xy 259.189964 -40.589961) (xy 259.245401 -40.596061)
			(xy 259.299358 -40.610167) (xy 259.350687 -40.631979) (xy 259.398293 -40.661033) (xy 259.441161 -40.696708)
			(xy 259.478378 -40.738245) (xy 259.509151 -40.784758) (xy 259.532823 -40.835255) (xy 259.548891 -40.888662)
			(xy 259.557011 -40.943838) (xy 259.55752 -40.971724) (xy 259.557011 -40.99961) (xy 259.548891 -41.054786)
			(xy 259.532823 -41.108193) (xy 259.509151 -41.15869) (xy 259.478378 -41.205203) (xy 259.441161 -41.24674)
			(xy 259.398293 -41.282415) (xy 259.350687 -41.311469) (xy 259.299358 -41.333281) (xy 259.245401 -41.347387)
			(xy 259.189964 -41.353487) (xy 259.13423 -41.35145) (xy 259.079387 -41.34132) (xy 259.026603 -41.323313)
			(xy 258.977003 -41.297812) (xy 258.931645 -41.265361) (xy 258.891496 -41.226652) (xy 258.85741 -41.182509)
			(xy 258.830114 -41.133874) (xy 258.810191 -41.081783) (xy 258.798065 -41.027346) (xy 258.793994 -40.971724)
			(xy 250.939126 -40.971724) (xy 250.969953 -40.976156) (xy 251.022248 -40.991511) (xy 251.071825 -41.014153)
			(xy 251.117675 -41.043619) (xy 251.158866 -41.07931) (xy 251.194557 -41.120501) (xy 251.224023 -41.166351)
			(xy 251.246665 -41.215928) (xy 251.26202 -41.268223) (xy 251.269776 -41.322171) (xy 251.270262 -41.349422)
			(xy 251.269735 -41.378161) (xy 251.261111 -41.434987) (xy 251.24406 -41.489877) (xy 251.21897 -41.541589)
			(xy 251.186407 -41.588952) (xy 251.167138 -41.61028) (xy 251.160534 -41.617138) (xy 251.153422 -41.635172)
			(xy 251.153422 -41.724072) (xy 251.160534 -41.742106) (xy 251.167138 -41.748964) (xy 251.186432 -41.770271)
			(xy 251.219 -41.817636) (xy 251.244093 -41.869351) (xy 251.261143 -41.924245) (xy 251.269765 -41.981075)
			(xy 251.269762 -42.038557) (xy 251.261136 -42.095387) (xy 251.244081 -42.150279) (xy 251.218984 -42.201992)
			(xy 251.186412 -42.249354) (xy 251.167138 -42.27068) (xy 251.160534 -42.277538) (xy 251.153422 -42.295572)
			(xy 251.153422 -42.384472) (xy 251.160534 -42.402506) (xy 251.167138 -42.409364) (xy 251.186415 -42.430686)
			(xy 251.218981 -42.478049) (xy 251.244073 -42.529762) (xy 251.261122 -42.584654) (xy 251.269743 -42.641483)
			(xy 251.270262 -42.670222) (xy 251.269818 -42.697593) (xy 251.261996 -42.751774) (xy 251.246503 -42.804277)
			(xy 251.225946 -42.849038) (xy 253.091948 -42.849038) (xy 253.096019 -42.793416) (xy 253.108145 -42.738979)
			(xy 253.128068 -42.686888) (xy 253.155364 -42.638253) (xy 253.18945 -42.59411) (xy 253.229599 -42.555401)
			(xy 253.274957 -42.52295) (xy 253.324557 -42.497449) (xy 253.377341 -42.479442) (xy 253.432184 -42.469312)
			(xy 253.487918 -42.467275) (xy 253.543355 -42.473375) (xy 253.597312 -42.487481) (xy 253.648641 -42.509293)
			(xy 253.696247 -42.538347) (xy 253.739115 -42.574022) (xy 253.776332 -42.615559) (xy 253.807105 -42.662072)
			(xy 253.830777 -42.712569) (xy 253.846845 -42.765976) (xy 253.854965 -42.821152) (xy 253.855326 -42.84091)
			(xy 259.133084 -42.84091) (xy 259.137155 -42.785288) (xy 259.149281 -42.730851) (xy 259.169204 -42.67876)
			(xy 259.1965 -42.630125) (xy 259.230586 -42.585982) (xy 259.270735 -42.547273) (xy 259.316093 -42.514822)
			(xy 259.365693 -42.489321) (xy 259.418477 -42.471314) (xy 259.47332 -42.461184) (xy 259.529054 -42.459147)
			(xy 259.584491 -42.465247) (xy 259.638448 -42.479353) (xy 259.689777 -42.501165) (xy 259.737383 -42.530219)
			(xy 259.780251 -42.565894) (xy 259.817468 -42.607431) (xy 259.848241 -42.653944) (xy 259.871913 -42.704441)
			(xy 259.887981 -42.757848) (xy 259.896101 -42.813024) (xy 259.89661 -42.84091) (xy 259.896101 -42.868796)
			(xy 259.887981 -42.923972) (xy 259.871913 -42.977379) (xy 259.848241 -43.027876) (xy 259.817468 -43.074389)
			(xy 259.780251 -43.115926) (xy 259.737383 -43.151601) (xy 259.689777 -43.180655) (xy 259.638448 -43.202467)
			(xy 259.584491 -43.216573) (xy 259.529054 -43.222673) (xy 259.47332 -43.220636) (xy 259.418477 -43.210506)
			(xy 259.365693 -43.192499) (xy 259.316093 -43.166998) (xy 259.270735 -43.134547) (xy 259.230586 -43.095838)
			(xy 259.1965 -43.051695) (xy 259.169204 -43.00306) (xy 259.149281 -42.950969) (xy 259.137155 -42.896532)
			(xy 259.133084 -42.84091) (xy 253.855326 -42.84091) (xy 253.855474 -42.849038) (xy 253.854965 -42.876924)
			(xy 253.846845 -42.9321) (xy 253.830777 -42.985507) (xy 253.807105 -43.036004) (xy 253.776332 -43.082517)
			(xy 253.739115 -43.124054) (xy 253.696247 -43.159729) (xy 253.648641 -43.188783) (xy 253.597312 -43.210595)
			(xy 253.543355 -43.224701) (xy 253.487918 -43.230801) (xy 253.432184 -43.228764) (xy 253.377341 -43.218634)
			(xy 253.324557 -43.200627) (xy 253.274957 -43.175126) (xy 253.229599 -43.142675) (xy 253.18945 -43.103966)
			(xy 253.155364 -43.059823) (xy 253.128068 -43.011188) (xy 253.108145 -42.959097) (xy 253.096019 -42.90466)
			(xy 253.091948 -42.849038) (xy 251.225946 -42.849038) (xy 251.223656 -42.854024) (xy 251.193926 -42.899989)
			(xy 251.176282 -42.92092) (xy 251.176028 -42.921174) (xy 251.170438 -42.928258) (xy 251.164195 -42.945177)
			(xy 251.163836 -42.954194) (xy 251.163836 -43.02125) (xy 251.164209 -43.030265) (xy 251.170445 -43.047183)
			(xy 251.176028 -43.05427) (xy 251.176282 -43.05427) (xy 251.176282 -43.054524) (xy 251.193896 -43.075476)
			(xy 251.223612 -43.121443) (xy 251.246453 -43.171186) (xy 251.26195 -43.223682) (xy 251.269785 -43.277854)
			(xy 251.270262 -43.305222) (xy 251.269776 -43.332473) (xy 251.26202 -43.386421) (xy 251.246665 -43.438716)
			(xy 251.224023 -43.488293) (xy 251.194557 -43.534143) (xy 251.158866 -43.575334) (xy 251.117675 -43.611025)
			(xy 251.071825 -43.640491) (xy 251.022248 -43.663133) (xy 250.969953 -43.678488) (xy 250.916005 -43.686244)
			(xy 250.861503 -43.686244) (xy 250.807555 -43.678488) (xy 250.75526 -43.663133) (xy 250.705683 -43.640491)
			(xy 250.659833 -43.611025) (xy 250.618642 -43.575334) (xy 250.582951 -43.534143) (xy 250.553485 -43.488293)
			(xy 250.530843 -43.438716) (xy 250.515488 -43.386421) (xy 250.507732 -43.332473) (xy 250.507246 -43.305222)
			(xy 247.659859 -43.305222) (xy 247.645936 -43.37177) (xy 247.645428 -43.37431) (xy 247.590336 -43.73626)
			(xy 252.413006 -43.73626) (xy 252.417077 -43.680638) (xy 252.429203 -43.626201) (xy 252.449126 -43.57411)
			(xy 252.476422 -43.525475) (xy 252.510508 -43.481332) (xy 252.550657 -43.442623) (xy 252.596015 -43.410172)
			(xy 252.645615 -43.384671) (xy 252.698399 -43.366664) (xy 252.753242 -43.356534) (xy 252.808976 -43.354497)
			(xy 252.864413 -43.360597) (xy 252.91837 -43.374703) (xy 252.969699 -43.396515) (xy 253.017305 -43.425569)
			(xy 253.060173 -43.461244) (xy 253.09739 -43.502781) (xy 253.128163 -43.549294) (xy 253.151835 -43.599791)
			(xy 253.167903 -43.653198) (xy 253.176023 -43.708374) (xy 253.176532 -43.73626) (xy 253.176023 -43.764146)
			(xy 253.167903 -43.819322) (xy 253.156594 -43.85691) (xy 256.919728 -43.85691) (xy 256.923799 -43.801288)
			(xy 256.935925 -43.746851) (xy 256.955848 -43.69476) (xy 256.983144 -43.646125) (xy 257.01723 -43.601982)
			(xy 257.057379 -43.563273) (xy 257.102737 -43.530822) (xy 257.152337 -43.505321) (xy 257.205121 -43.487314)
			(xy 257.259964 -43.477184) (xy 257.315698 -43.475147) (xy 257.371135 -43.481247) (xy 257.425092 -43.495353)
			(xy 257.476421 -43.517165) (xy 257.524027 -43.546219) (xy 257.566895 -43.581894) (xy 257.604112 -43.623431)
			(xy 257.634885 -43.669944) (xy 257.658557 -43.720441) (xy 257.674625 -43.773848) (xy 257.682745 -43.829024)
			(xy 257.683254 -43.85691) (xy 257.682745 -43.884796) (xy 257.674625 -43.939972) (xy 257.658557 -43.993379)
			(xy 257.634885 -44.043876) (xy 257.604112 -44.090389) (xy 257.566895 -44.131926) (xy 257.524027 -44.167601)
			(xy 257.476421 -44.196655) (xy 257.425092 -44.218467) (xy 257.371135 -44.232573) (xy 257.315698 -44.238673)
			(xy 257.259964 -44.236636) (xy 257.205121 -44.226506) (xy 257.152337 -44.208499) (xy 257.102737 -44.182998)
			(xy 257.057379 -44.150547) (xy 257.01723 -44.111838) (xy 256.983144 -44.067695) (xy 256.955848 -44.01906)
			(xy 256.935925 -43.966969) (xy 256.923799 -43.912532) (xy 256.919728 -43.85691) (xy 253.156594 -43.85691)
			(xy 253.151835 -43.872729) (xy 253.128163 -43.923226) (xy 253.09739 -43.969739) (xy 253.060173 -44.011276)
			(xy 253.017305 -44.046951) (xy 252.969699 -44.076005) (xy 252.91837 -44.097817) (xy 252.864413 -44.111923)
			(xy 252.808976 -44.118023) (xy 252.753242 -44.115986) (xy 252.698399 -44.105856) (xy 252.645615 -44.087849)
			(xy 252.596015 -44.062348) (xy 252.550657 -44.029897) (xy 252.510508 -43.991188) (xy 252.476422 -43.947045)
			(xy 252.449126 -43.89841) (xy 252.429203 -43.846319) (xy 252.417077 -43.791882) (xy 252.413006 -43.73626)
			(xy 247.590336 -43.73626) (xy 247.38056 -45.114464) (xy 252.265432 -45.114464) (xy 252.269503 -45.058842)
			(xy 252.281629 -45.004405) (xy 252.301552 -44.952314) (xy 252.328848 -44.903679) (xy 252.362934 -44.859536)
			(xy 252.403083 -44.820827) (xy 252.448441 -44.788376) (xy 252.498041 -44.762875) (xy 252.550825 -44.744868)
			(xy 252.605668 -44.734738) (xy 252.661402 -44.732701) (xy 252.716839 -44.738801) (xy 252.770796 -44.752907)
			(xy 252.822125 -44.774719) (xy 252.869731 -44.803773) (xy 252.912599 -44.839448) (xy 252.942581 -44.87291)
			(xy 259.133084 -44.87291) (xy 259.137155 -44.817288) (xy 259.149281 -44.762851) (xy 259.169204 -44.71076)
			(xy 259.1965 -44.662125) (xy 259.230586 -44.617982) (xy 259.270735 -44.579273) (xy 259.316093 -44.546822)
			(xy 259.365693 -44.521321) (xy 259.418477 -44.503314) (xy 259.47332 -44.493184) (xy 259.529054 -44.491147)
			(xy 259.584491 -44.497247) (xy 259.638448 -44.511353) (xy 259.689777 -44.533165) (xy 259.737383 -44.562219)
			(xy 259.780251 -44.597894) (xy 259.817468 -44.639431) (xy 259.848241 -44.685944) (xy 259.871913 -44.736441)
			(xy 259.887981 -44.789848) (xy 259.896101 -44.845024) (xy 259.89661 -44.87291) (xy 259.896101 -44.900796)
			(xy 259.887981 -44.955972) (xy 259.871913 -45.009379) (xy 259.848241 -45.059876) (xy 259.817468 -45.106389)
			(xy 259.780251 -45.147926) (xy 259.737383 -45.183601) (xy 259.689777 -45.212655) (xy 259.638448 -45.234467)
			(xy 259.584491 -45.248573) (xy 259.529054 -45.254673) (xy 259.47332 -45.252636) (xy 259.418477 -45.242506)
			(xy 259.365693 -45.224499) (xy 259.316093 -45.198998) (xy 259.270735 -45.166547) (xy 259.230586 -45.127838)
			(xy 259.1965 -45.083695) (xy 259.169204 -45.03506) (xy 259.149281 -44.982969) (xy 259.137155 -44.928532)
			(xy 259.133084 -44.87291) (xy 252.942581 -44.87291) (xy 252.949816 -44.880985) (xy 252.980589 -44.927498)
			(xy 253.004261 -44.977995) (xy 253.020329 -45.031402) (xy 253.028449 -45.086578) (xy 253.028958 -45.114464)
			(xy 253.028449 -45.14235) (xy 253.020329 -45.197526) (xy 253.004261 -45.250933) (xy 252.980589 -45.30143)
			(xy 252.949816 -45.347943) (xy 252.944174 -45.35424) (xy 256.903726 -45.35424) (xy 256.907797 -45.298618)
			(xy 256.919923 -45.244181) (xy 256.939846 -45.19209) (xy 256.967142 -45.143455) (xy 257.001228 -45.099312)
			(xy 257.041377 -45.060603) (xy 257.086735 -45.028152) (xy 257.136335 -45.002651) (xy 257.189119 -44.984644)
			(xy 257.243962 -44.974514) (xy 257.299696 -44.972477) (xy 257.355133 -44.978577) (xy 257.40909 -44.992683)
			(xy 257.460419 -45.014495) (xy 257.508025 -45.043549) (xy 257.550893 -45.079224) (xy 257.58811 -45.120761)
			(xy 257.618883 -45.167274) (xy 257.642555 -45.217771) (xy 257.658623 -45.271178) (xy 257.666743 -45.326354)
			(xy 257.667252 -45.35424) (xy 257.666743 -45.382126) (xy 257.658623 -45.437302) (xy 257.642555 -45.490709)
			(xy 257.618883 -45.541206) (xy 257.58811 -45.587719) (xy 257.550893 -45.629256) (xy 257.508025 -45.664931)
			(xy 257.460419 -45.693985) (xy 257.40909 -45.715797) (xy 257.355133 -45.729903) (xy 257.299696 -45.736003)
			(xy 257.243962 -45.733966) (xy 257.189119 -45.723836) (xy 257.136335 -45.705829) (xy 257.086735 -45.680328)
			(xy 257.041377 -45.647877) (xy 257.001228 -45.609168) (xy 256.967142 -45.565025) (xy 256.939846 -45.51639)
			(xy 256.919923 -45.464299) (xy 256.907797 -45.409862) (xy 256.903726 -45.35424) (xy 252.944174 -45.35424)
			(xy 252.912599 -45.38948) (xy 252.869731 -45.425155) (xy 252.822125 -45.454209) (xy 252.770796 -45.476021)
			(xy 252.716839 -45.490127) (xy 252.661402 -45.496227) (xy 252.605668 -45.49419) (xy 252.550825 -45.48406)
			(xy 252.498041 -45.466053) (xy 252.448441 -45.440552) (xy 252.403083 -45.408101) (xy 252.362934 -45.369392)
			(xy 252.328848 -45.325249) (xy 252.301552 -45.276614) (xy 252.281629 -45.224523) (xy 252.269503 -45.170086)
			(xy 252.265432 -45.114464) (xy 247.38056 -45.114464) (xy 247.233261 -46.082204) (xy 250.252484 -46.082204)
			(xy 250.252981 -46.054953) (xy 250.260737 -46.001006) (xy 250.276091 -45.948712) (xy 250.298732 -45.899136)
			(xy 250.328197 -45.853286) (xy 250.363887 -45.812095) (xy 250.405076 -45.776404) (xy 250.450925 -45.746937)
			(xy 250.500501 -45.724296) (xy 250.552795 -45.70894) (xy 250.606741 -45.701182) (xy 250.633992 -45.700696)
			(xy 250.660894 -45.701164) (xy 250.714164 -45.708735) (xy 250.765842 -45.723713) (xy 250.814904 -45.745802)
			(xy 250.860376 -45.774564) (xy 250.901358 -45.809428) (xy 250.937036 -45.849703) (xy 250.952254 -45.871892)
			(xy 250.959366 -45.882814) (xy 250.982226 -45.894752) (xy 251.094494 -45.89272) (xy 251.116846 -45.879766)
			(xy 251.123704 -45.86859) (xy 251.138636 -45.844996) (xy 251.174314 -45.802044) (xy 251.21587 -45.764751)
			(xy 251.262418 -45.733912) (xy 251.312964 -45.710188) (xy 251.366428 -45.694083) (xy 251.421668 -45.685943)
			(xy 251.449586 -45.685456) (xy 251.476579 -45.685925) (xy 251.530027 -45.693529) (xy 251.58187 -45.708588)
			(xy 251.631075 -45.7308) (xy 251.676659 -45.759723) (xy 251.69749 -45.776896) (xy 251.705618 -45.784008)
			(xy 251.726192 -45.790104) (xy 251.811536 -45.779182) (xy 251.822087 -45.777435) (xy 251.840367 -45.766361)
			(xy 251.846842 -45.757846) (xy 251.862176 -45.736601) (xy 251.897766 -45.698148) (xy 251.938287 -45.664931)
			(xy 251.982973 -45.637574) (xy 252.030984 -45.616593) (xy 252.081416 -45.602383) (xy 252.133318 -45.595211)
			(xy 252.159516 -45.594778) (xy 252.186765 -45.595293) (xy 252.240709 -45.603051) (xy 252.293 -45.618407)
			(xy 252.342574 -45.641049) (xy 252.38842 -45.670514) (xy 252.429607 -45.706204) (xy 252.465295 -45.747393)
			(xy 252.494759 -45.79324) (xy 252.517398 -45.842815) (xy 252.532752 -45.895106) (xy 252.540508 -45.949051)
			(xy 252.540508 -46.003549) (xy 252.532752 -46.057494) (xy 252.517398 -46.109785) (xy 252.494759 -46.15936)
			(xy 252.465295 -46.205207) (xy 252.429607 -46.246396) (xy 252.38842 -46.282086) (xy 252.342574 -46.311551)
			(xy 252.293 -46.334193) (xy 252.240709 -46.349549) (xy 252.186765 -46.357307) (xy 252.159516 -46.357794)
			(xy 252.132524 -46.357312) (xy 252.079077 -46.349709) (xy 252.027234 -46.334653) (xy 251.978029 -46.312444)
			(xy 251.932444 -46.283525) (xy 251.911612 -46.266354) (xy 251.903484 -46.259242) (xy 251.88291 -46.253146)
			(xy 251.797566 -46.264068) (xy 251.78702 -46.265833) (xy 251.768739 -46.276896) (xy 251.76226 -46.285404)
			(xy 251.744649 -46.309706) (xy 251.703052 -46.352965) (xy 251.679456 -46.37151) (xy 251.671582 -46.377352)
			(xy 251.661168 -46.394878) (xy 251.64796 -46.485302) (xy 251.652786 -46.504606) (xy 251.658628 -46.51248)
			(xy 251.658628 -46.512734) (xy 251.676125 -46.537482) (xy 251.703931 -46.591333) (xy 251.722869 -46.648904)
			(xy 251.730072 -46.693836) (xy 256.876296 -46.693836) (xy 256.876782 -46.666585) (xy 256.884538 -46.612637)
			(xy 256.899893 -46.560342) (xy 256.922535 -46.510765) (xy 256.952001 -46.464915) (xy 256.987692 -46.423724)
			(xy 257.028883 -46.388033) (xy 257.074733 -46.358567) (xy 257.12431 -46.335925) (xy 257.176605 -46.32057)
			(xy 257.230553 -46.312814) (xy 257.285055 -46.312814) (xy 257.339003 -46.32057) (xy 257.391298 -46.335925)
			(xy 257.440875 -46.358567) (xy 257.486725 -46.388033) (xy 257.527916 -46.423724) (xy 257.563607 -46.464915)
			(xy 257.593073 -46.510765) (xy 257.615715 -46.560342) (xy 257.63107 -46.612637) (xy 257.638826 -46.666585)
			(xy 257.639312 -46.693836) (xy 257.638838 -46.720263) (xy 257.631528 -46.772611) (xy 257.617056 -46.823446)
			(xy 257.595696 -46.871793) (xy 257.582162 -46.894496) (xy 257.581908 -46.89475) (xy 257.576571 -46.904768)
			(xy 257.574316 -46.927318) (xy 257.57759 -46.938184) (xy 257.603752 -47.01286) (xy 257.608136 -47.023375)
			(xy 257.624225 -47.039464) (xy 257.63474 -47.043848) (xy 257.634994 -47.043848) (xy 257.659513 -47.052891)
			(xy 257.705964 -47.076839) (xy 257.748715 -47.106899) (xy 257.786965 -47.142511) (xy 257.82 -47.183007)
			(xy 257.847202 -47.227631) (xy 257.868063 -47.275548) (xy 257.882192 -47.325863) (xy 257.889325 -47.377635)
			(xy 257.889756 -47.403766) (xy 257.88927 -47.431017) (xy 257.887747 -47.441612) (xy 259.161786 -47.441612)
			(xy 259.165857 -47.38599) (xy 259.177983 -47.331553) (xy 259.197906 -47.279462) (xy 259.225202 -47.230827)
			(xy 259.259288 -47.186684) (xy 259.299437 -47.147975) (xy 259.344795 -47.115524) (xy 259.394395 -47.090023)
			(xy 259.447179 -47.072016) (xy 259.502022 -47.061886) (xy 259.557756 -47.059849) (xy 259.613193 -47.065949)
			(xy 259.66715 -47.080055) (xy 259.718479 -47.101867) (xy 259.766085 -47.130921) (xy 259.808953 -47.166596)
			(xy 259.84617 -47.208133) (xy 259.876943 -47.254646) (xy 259.900615 -47.305143) (xy 259.916683 -47.35855)
			(xy 259.924803 -47.413726) (xy 259.925312 -47.441612) (xy 259.924803 -47.469498) (xy 259.916683 -47.524674)
			(xy 259.900615 -47.578081) (xy 259.876943 -47.628578) (xy 259.84617 -47.675091) (xy 259.808953 -47.716628)
			(xy 259.766085 -47.752303) (xy 259.718479 -47.781357) (xy 259.66715 -47.803169) (xy 259.613193 -47.817275)
			(xy 259.557756 -47.823375) (xy 259.502022 -47.821338) (xy 259.447179 -47.811208) (xy 259.394395 -47.793201)
			(xy 259.344795 -47.7677) (xy 259.299437 -47.735249) (xy 259.259288 -47.69654) (xy 259.225202 -47.652397)
			(xy 259.197906 -47.603762) (xy 259.177983 -47.551671) (xy 259.165857 -47.497234) (xy 259.161786 -47.441612)
			(xy 257.887747 -47.441612) (xy 257.881514 -47.484965) (xy 257.866159 -47.53726) (xy 257.843517 -47.586837)
			(xy 257.814051 -47.632687) (xy 257.77836 -47.673878) (xy 257.737169 -47.709569) (xy 257.691319 -47.739035)
			(xy 257.641742 -47.761677) (xy 257.589447 -47.777032) (xy 257.535499 -47.784788) (xy 257.480997 -47.784788)
			(xy 257.427049 -47.777032) (xy 257.374754 -47.761677) (xy 257.325177 -47.739035) (xy 257.279327 -47.709569)
			(xy 257.238136 -47.673878) (xy 257.202445 -47.632687) (xy 257.172979 -47.586837) (xy 257.150337 -47.53726)
			(xy 257.134982 -47.484965) (xy 257.127226 -47.431017) (xy 257.12674 -47.403766) (xy 257.127208 -47.377338)
			(xy 257.134518 -47.324991) (xy 257.148993 -47.274155) (xy 257.170354 -47.225809) (xy 257.18389 -47.203106)
			(xy 257.184144 -47.202852) (xy 257.189479 -47.192833) (xy 257.191738 -47.170284) (xy 257.188462 -47.159418)
			(xy 257.1623 -47.084742) (xy 257.157937 -47.074216) (xy 257.141834 -47.058131) (xy 257.131312 -47.053754)
			(xy 257.131058 -47.053754) (xy 257.106551 -47.04468) (xy 257.060098 -47.020739) (xy 257.017346 -46.990683)
			(xy 256.979094 -46.955077) (xy 256.946057 -46.914584) (xy 256.918854 -46.869964) (xy 256.897991 -46.822049)
			(xy 256.883861 -46.771736) (xy 256.876727 -46.719966) (xy 256.876296 -46.693836) (xy 251.730072 -46.693836)
			(xy 251.732462 -46.708745) (xy 251.73305 -46.739048) (xy 251.732567 -46.766299) (xy 251.724805 -46.820244)
			(xy 251.709446 -46.872536) (xy 251.686802 -46.922111) (xy 251.657335 -46.967959) (xy 251.621643 -47.009148)
			(xy 251.580454 -47.044838) (xy 251.534606 -47.074305) (xy 251.485031 -47.096948) (xy 251.432738 -47.112306)
			(xy 251.378793 -47.120067) (xy 251.351542 -47.120556) (xy 251.325508 -47.120134) (xy 251.273924 -47.11304)
			(xy 251.223782 -47.099005) (xy 251.176011 -47.078288) (xy 251.131498 -47.051275) (xy 251.111004 -47.035212)
			(xy 251.103253 -47.029461) (xy 251.084838 -47.023726) (xy 251.07519 -47.024036) (xy 250.995434 -47.030386)
			(xy 250.977654 -47.039022) (xy 250.971304 -47.046388) (xy 250.953144 -47.066054) (xy 250.912232 -47.100574)
			(xy 250.866898 -47.129041) (xy 250.818033 -47.150895) (xy 250.766593 -47.165708) (xy 250.713589 -47.17319)
			(xy 250.686824 -47.173642) (xy 250.659575 -47.1731) (xy 250.605631 -47.165347) (xy 250.553339 -47.149997)
			(xy 250.503765 -47.127361) (xy 250.457916 -47.0979) (xy 250.416726 -47.062215) (xy 250.381034 -47.021031)
			(xy 250.351567 -46.975186) (xy 250.328923 -46.925615) (xy 250.313565 -46.873326) (xy 250.305805 -46.819383)
			(xy 250.305316 -46.792134) (xy 250.305836 -46.76336) (xy 250.314488 -46.706465) (xy 250.331585 -46.651515)
			(xy 250.356739 -46.599754) (xy 250.389381 -46.552359) (xy 250.408694 -46.531022) (xy 250.41606 -46.523148)
			(xy 250.423172 -46.503336) (xy 250.415806 -46.40707) (xy 250.4059 -46.388274) (xy 250.397518 -46.38167)
			(xy 250.375333 -46.363446) (xy 250.336123 -46.32151) (xy 250.303638 -46.274174) (xy 250.278609 -46.222506)
			(xy 250.261603 -46.167672) (xy 250.253002 -46.110909) (xy 250.252484 -46.082204) (xy 247.233261 -46.082204)
			(xy 246.982234 -47.731426) (xy 246.894676 -48.30699) (xy 256.753866 -48.30699) (xy 256.757937 -48.251368)
			(xy 256.770063 -48.196931) (xy 256.789986 -48.14484) (xy 256.817282 -48.096205) (xy 256.851368 -48.052062)
			(xy 256.891517 -48.013353) (xy 256.936875 -47.980902) (xy 256.986475 -47.955401) (xy 257.039259 -47.937394)
			(xy 257.094102 -47.927264) (xy 257.149836 -47.925227) (xy 257.205273 -47.931327) (xy 257.25923 -47.945433)
			(xy 257.310559 -47.967245) (xy 257.358165 -47.996299) (xy 257.401033 -48.031974) (xy 257.43825 -48.073511)
			(xy 257.469023 -48.120024) (xy 257.492695 -48.170521) (xy 257.508763 -48.223928) (xy 257.516883 -48.279104)
			(xy 257.517392 -48.30699) (xy 257.516883 -48.334876) (xy 257.508763 -48.390052) (xy 257.492695 -48.443459)
			(xy 257.469023 -48.493956) (xy 257.43825 -48.540469) (xy 257.401033 -48.582006) (xy 257.358165 -48.617681)
			(xy 257.310559 -48.646735) (xy 257.25923 -48.668547) (xy 257.205273 -48.682653) (xy 257.149836 -48.688753)
			(xy 257.094102 -48.686716) (xy 257.039259 -48.676586) (xy 256.986475 -48.658579) (xy 256.936875 -48.633078)
			(xy 256.891517 -48.600627) (xy 256.851368 -48.561918) (xy 256.817282 -48.517775) (xy 256.789986 -48.46914)
			(xy 256.770063 -48.417049) (xy 256.757937 -48.362612) (xy 256.753866 -48.30699) (xy 246.894676 -48.30699)
			(xy 246.826824 -48.753014) (xy 253.3683 -48.753014) (xy 253.372371 -48.697392) (xy 253.384497 -48.642955)
			(xy 253.40442 -48.590864) (xy 253.431716 -48.542229) (xy 253.465802 -48.498086) (xy 253.505951 -48.459377)
			(xy 253.551309 -48.426926) (xy 253.600909 -48.401425) (xy 253.653693 -48.383418) (xy 253.708536 -48.373288)
			(xy 253.76427 -48.371251) (xy 253.819707 -48.377351) (xy 253.873664 -48.391457) (xy 253.924993 -48.413269)
			(xy 253.972599 -48.442323) (xy 254.015467 -48.477998) (xy 254.052684 -48.519535) (xy 254.083457 -48.566048)
			(xy 254.107129 -48.616545) (xy 254.123197 -48.669952) (xy 254.131317 -48.725128) (xy 254.131826 -48.753014)
			(xy 254.131317 -48.7809) (xy 254.123197 -48.836076) (xy 254.120753 -48.8442) (xy 254.387348 -48.8442)
			(xy 254.391419 -48.788578) (xy 254.403545 -48.734141) (xy 254.423468 -48.68205) (xy 254.450764 -48.633415)
			(xy 254.48485 -48.589272) (xy 254.524999 -48.550563) (xy 254.570357 -48.518112) (xy 254.619957 -48.492611)
			(xy 254.672741 -48.474604) (xy 254.727584 -48.464474) (xy 254.783318 -48.462437) (xy 254.838755 -48.468537)
			(xy 254.892712 -48.482643) (xy 254.944041 -48.504455) (xy 254.991647 -48.533509) (xy 255.034515 -48.569184)
			(xy 255.071732 -48.610721) (xy 255.102505 -48.657234) (xy 255.126177 -48.707731) (xy 255.142245 -48.761138)
			(xy 255.150365 -48.816314) (xy 255.150874 -48.8442) (xy 255.150365 -48.872086) (xy 255.147367 -48.89246)
			(xy 255.414016 -48.89246) (xy 255.418087 -48.836838) (xy 255.430213 -48.782401) (xy 255.450136 -48.73031)
			(xy 255.477432 -48.681675) (xy 255.511518 -48.637532) (xy 255.551667 -48.598823) (xy 255.597025 -48.566372)
			(xy 255.646625 -48.540871) (xy 255.699409 -48.522864) (xy 255.754252 -48.512734) (xy 255.809986 -48.510697)
			(xy 255.865423 -48.516797) (xy 255.91938 -48.530903) (xy 255.970709 -48.552715) (xy 256.018315 -48.581769)
			(xy 256.061183 -48.617444) (xy 256.0984 -48.658981) (xy 256.129173 -48.705494) (xy 256.152845 -48.755991)
			(xy 256.168913 -48.809398) (xy 256.177033 -48.864574) (xy 256.177542 -48.89246) (xy 256.177033 -48.920346)
			(xy 256.174595 -48.93691) (xy 259.133084 -48.93691) (xy 259.137155 -48.881288) (xy 259.149281 -48.826851)
			(xy 259.169204 -48.77476) (xy 259.1965 -48.726125) (xy 259.230586 -48.681982) (xy 259.270735 -48.643273)
			(xy 259.316093 -48.610822) (xy 259.365693 -48.585321) (xy 259.418477 -48.567314) (xy 259.47332 -48.557184)
			(xy 259.529054 -48.555147) (xy 259.584491 -48.561247) (xy 259.638448 -48.575353) (xy 259.689777 -48.597165)
			(xy 259.737383 -48.626219) (xy 259.780251 -48.661894) (xy 259.817468 -48.703431) (xy 259.848241 -48.749944)
			(xy 259.871913 -48.800441) (xy 259.887981 -48.853848) (xy 259.896101 -48.909024) (xy 259.89661 -48.93691)
			(xy 259.896101 -48.964796) (xy 259.887981 -49.019972) (xy 259.871913 -49.073379) (xy 259.848241 -49.123876)
			(xy 259.817468 -49.170389) (xy 259.780251 -49.211926) (xy 259.737383 -49.247601) (xy 259.689777 -49.276655)
			(xy 259.638448 -49.298467) (xy 259.584491 -49.312573) (xy 259.529054 -49.318673) (xy 259.47332 -49.316636)
			(xy 259.418477 -49.306506) (xy 259.365693 -49.288499) (xy 259.316093 -49.262998) (xy 259.270735 -49.230547)
			(xy 259.230586 -49.191838) (xy 259.1965 -49.147695) (xy 259.169204 -49.09906) (xy 259.149281 -49.046969)
			(xy 259.137155 -48.992532) (xy 259.133084 -48.93691) (xy 256.174595 -48.93691) (xy 256.168913 -48.975522)
			(xy 256.152845 -49.028929) (xy 256.129173 -49.079426) (xy 256.0984 -49.125939) (xy 256.061183 -49.167476)
			(xy 256.018315 -49.203151) (xy 255.970709 -49.232205) (xy 255.91938 -49.254017) (xy 255.865423 -49.268123)
			(xy 255.809986 -49.274223) (xy 255.754252 -49.272186) (xy 255.699409 -49.262056) (xy 255.646625 -49.244049)
			(xy 255.597025 -49.218548) (xy 255.551667 -49.186097) (xy 255.511518 -49.147388) (xy 255.477432 -49.103245)
			(xy 255.450136 -49.05461) (xy 255.430213 -49.002519) (xy 255.418087 -48.948082) (xy 255.414016 -48.89246)
			(xy 255.147367 -48.89246) (xy 255.142245 -48.927262) (xy 255.126177 -48.980669) (xy 255.102505 -49.031166)
			(xy 255.071732 -49.077679) (xy 255.034515 -49.119216) (xy 254.991647 -49.154891) (xy 254.944041 -49.183945)
			(xy 254.892712 -49.205757) (xy 254.838755 -49.219863) (xy 254.783318 -49.225963) (xy 254.727584 -49.223926)
			(xy 254.672741 -49.213796) (xy 254.619957 -49.195789) (xy 254.570357 -49.170288) (xy 254.524999 -49.137837)
			(xy 254.48485 -49.099128) (xy 254.450764 -49.054985) (xy 254.423468 -49.00635) (xy 254.403545 -48.954259)
			(xy 254.391419 -48.899822) (xy 254.387348 -48.8442) (xy 254.120753 -48.8442) (xy 254.107129 -48.889483)
			(xy 254.083457 -48.93998) (xy 254.052684 -48.986493) (xy 254.015467 -49.02803) (xy 253.972599 -49.063705)
			(xy 253.924993 -49.092759) (xy 253.873664 -49.114571) (xy 253.819707 -49.128677) (xy 253.76427 -49.134777)
			(xy 253.708536 -49.13274) (xy 253.653693 -49.12261) (xy 253.600909 -49.104603) (xy 253.551309 -49.079102)
			(xy 253.505951 -49.046651) (xy 253.465802 -49.007942) (xy 253.431716 -48.963799) (xy 253.40442 -48.915164)
			(xy 253.384497 -48.863073) (xy 253.372371 -48.808636) (xy 253.3683 -48.753014) (xy 246.826824 -48.753014)
			(xy 246.644288 -49.95291) (xy 259.133084 -49.95291) (xy 259.137155 -49.897288) (xy 259.149281 -49.842851)
			(xy 259.169204 -49.79076) (xy 259.1965 -49.742125) (xy 259.230586 -49.697982) (xy 259.270735 -49.659273)
			(xy 259.316093 -49.626822) (xy 259.365693 -49.601321) (xy 259.418477 -49.583314) (xy 259.47332 -49.573184)
			(xy 259.529054 -49.571147) (xy 259.584491 -49.577247) (xy 259.638448 -49.591353) (xy 259.689777 -49.613165)
			(xy 259.737383 -49.642219) (xy 259.780251 -49.677894) (xy 259.817468 -49.719431) (xy 259.848241 -49.765944)
			(xy 259.871913 -49.816441) (xy 259.887981 -49.869848) (xy 259.896101 -49.925024) (xy 259.89661 -49.95291)
			(xy 259.896101 -49.980796) (xy 259.887981 -50.035972) (xy 259.871913 -50.089379) (xy 259.848241 -50.139876)
			(xy 259.817468 -50.186389) (xy 259.780251 -50.227926) (xy 259.737383 -50.263601) (xy 259.689777 -50.292655)
			(xy 259.638448 -50.314467) (xy 259.584491 -50.328573) (xy 259.529054 -50.334673) (xy 259.47332 -50.332636)
			(xy 259.418477 -50.322506) (xy 259.365693 -50.304499) (xy 259.316093 -50.278998) (xy 259.270735 -50.246547)
			(xy 259.230586 -50.207838) (xy 259.1965 -50.163695) (xy 259.169204 -50.11506) (xy 259.149281 -50.062969)
			(xy 259.137155 -50.008532) (xy 259.133084 -49.95291) (xy 246.644288 -49.95291) (xy 246.63146 -50.037238)
			(xy 246.62765 -50.06213) (xy 246.627396 -50.063908) (xy 246.626634 -50.068988) (xy 246.527444 -50.721051)
			(xy 256.232883 -50.721051) (xy 256.232883 -50.666549) (xy 256.24064 -50.6126) (xy 256.255996 -50.560305)
			(xy 256.278638 -50.510728) (xy 256.308105 -50.464877) (xy 256.343797 -50.423687) (xy 256.384989 -50.387996)
			(xy 256.43084 -50.358531) (xy 256.480418 -50.335891) (xy 256.532714 -50.320537) (xy 256.586662 -50.312782)
			(xy 256.613914 -50.31232) (xy 256.640253 -50.312759) (xy 256.692432 -50.319983) (xy 256.74312 -50.33432)
			(xy 256.791353 -50.355496) (xy 256.836212 -50.383109) (xy 256.876844 -50.416633) (xy 256.912476 -50.45543)
			(xy 256.942429 -50.498762) (xy 256.966133 -50.545804) (xy 256.983138 -50.595661) (xy 256.988564 -50.621438)
			(xy 256.991588 -50.634981) (xy 257.003979 -50.6598) (xy 257.022604 -50.680357) (xy 257.046084 -50.695129)
			(xy 257.072678 -50.703021) (xy 257.100415 -50.703448) (xy 257.127239 -50.696378) (xy 257.13944 -50.689764)
			(xy 257.161399 -50.677474) (xy 257.207836 -50.658087) (xy 257.256419 -50.644971) (xy 257.306303 -50.638353)
			(xy 257.331464 -50.637948) (xy 257.358715 -50.638497) (xy 257.412664 -50.646249) (xy 257.46496 -50.6616)
			(xy 257.514539 -50.684238) (xy 257.560391 -50.713701) (xy 257.601584 -50.749391) (xy 257.637277 -50.79058)
			(xy 257.666745 -50.836429) (xy 257.689388 -50.886006) (xy 257.704744 -50.938301) (xy 257.712501 -50.992249)
			(xy 257.712501 -51.046751) (xy 257.704744 -51.100699) (xy 257.689388 -51.152994) (xy 257.666745 -51.202571)
			(xy 257.640123 -51.243992) (xy 265.332972 -51.243992) (xy 265.333416 -51.216621) (xy 265.341236 -51.16244)
			(xy 265.35673 -51.109936) (xy 265.379577 -51.060189) (xy 265.409308 -51.014224) (xy 265.426952 -50.993294)
			(xy 265.427206 -50.99304) (xy 265.432783 -50.985947) (xy 265.439035 -50.969035) (xy 265.439398 -50.96002)
			(xy 265.439398 -50.892964) (xy 265.439058 -50.883945) (xy 265.432799 -50.867029) (xy 265.427206 -50.859944)
			(xy 265.426952 -50.859944) (xy 265.426952 -50.85969) (xy 265.409303 -50.838766) (xy 265.379591 -50.792792)
			(xy 265.356756 -50.743042) (xy 265.341267 -50.69054) (xy 265.333443 -50.636362) (xy 265.332972 -50.608992)
			(xy 265.33347 -50.581741) (xy 265.341227 -50.527795) (xy 265.356582 -50.475502) (xy 265.379223 -50.425926)
			(xy 265.408688 -50.380077) (xy 265.444378 -50.338887) (xy 265.485567 -50.303196) (xy 265.531415 -50.273729)
			(xy 265.580991 -50.251087) (xy 265.633283 -50.23573) (xy 265.687229 -50.227971) (xy 265.71448 -50.227484)
			(xy 265.743398 -50.227985) (xy 265.800571 -50.236713) (xy 265.855772 -50.253972) (xy 265.907734 -50.279367)
			(xy 265.955268 -50.312315) (xy 265.997282 -50.352062) (xy 266.01547 -50.37455) (xy 266.023091 -50.383342)
			(xy 266.043982 -50.393532) (xy 266.055602 -50.394108) (xy 266.135358 -50.394108) (xy 266.146992 -50.393585)
			(xy 266.167901 -50.383384) (xy 266.17549 -50.37455) (xy 266.193674 -50.352061) (xy 266.235697 -50.312328)
			(xy 266.283234 -50.279391) (xy 266.335196 -50.254005) (xy 266.390394 -50.236749) (xy 266.447564 -50.22802)
			(xy 266.47648 -50.227484) (xy 266.503732 -50.227974) (xy 266.557682 -50.235728) (xy 266.609978 -50.251081)
			(xy 266.659558 -50.273721) (xy 266.705411 -50.303186) (xy 266.746603 -50.338877) (xy 266.782297 -50.380067)
			(xy 266.811766 -50.425917) (xy 266.834409 -50.475495) (xy 266.849766 -50.527791) (xy 266.857524 -50.58174)
			(xy 266.857988 -50.608992) (xy 266.857519 -50.635306) (xy 266.850285 -50.687435) (xy 266.835967 -50.738077)
			(xy 266.814834 -50.786276) (xy 266.787288 -50.83112) (xy 266.75385 -50.87176) (xy 266.734798 -50.889916)
			(xy 266.727387 -50.89743) (xy 266.718868 -50.916716) (xy 266.718288 -50.927254) (xy 266.718288 -51.00193)
			(xy 266.718845 -51.012476) (xy 266.727361 -51.031772) (xy 266.734798 -51.039268) (xy 266.753879 -51.057398)
			(xy 266.787334 -51.098033) (xy 266.81489 -51.142879) (xy 266.836024 -51.191085) (xy 266.850335 -51.241737)
			(xy 266.857553 -51.293874) (xy 266.857988 -51.320192) (xy 266.857537 -51.347446) (xy 266.849781 -51.401398)
			(xy 266.834425 -51.453697) (xy 266.811782 -51.503279) (xy 266.782313 -51.549133) (xy 266.746618 -51.590326)
			(xy 266.705423 -51.62602) (xy 266.659568 -51.655487) (xy 266.609986 -51.678129) (xy 266.557686 -51.693483)
			(xy 266.503734 -51.701238) (xy 266.47648 -51.7017) (xy 266.448814 -51.701203) (xy 266.394064 -51.693201)
			(xy 266.341042 -51.677382) (xy 266.290858 -51.654076) (xy 266.244563 -51.623773) (xy 266.203125 -51.587105)
			(xy 266.167413 -51.544842) (xy 266.152376 -51.521614) (xy 266.14576 -51.51192) (xy 266.125883 -51.499486)
			(xy 266.114276 -51.497738) (xy 266.034266 -51.489864) (xy 266.022627 -51.489215) (xy 266.000789 -51.497307)
			(xy 265.992356 -51.505358) (xy 265.992102 -51.505612) (xy 265.974005 -51.524177) (xy 265.933676 -51.556756)
			(xy 265.889305 -51.583571) (xy 265.84171 -51.604127) (xy 265.791769 -51.618044) (xy 265.740402 -51.625066)
			(xy 265.71448 -51.6255) (xy 265.687228 -51.625041) (xy 265.633279 -51.617281) (xy 265.580983 -51.601923)
			(xy 265.531405 -51.579279) (xy 265.485555 -51.54981) (xy 265.444364 -51.514116) (xy 265.408673 -51.472923)
			(xy 265.379207 -51.42707) (xy 265.356567 -51.377491) (xy 265.341213 -51.325194) (xy 265.333457 -51.271244)
			(xy 265.332972 -51.243992) (xy 257.640123 -51.243992) (xy 257.637277 -51.24842) (xy 257.601584 -51.289609)
			(xy 257.560391 -51.325299) (xy 257.514539 -51.354762) (xy 257.46496 -51.3774) (xy 257.412664 -51.392751)
			(xy 257.358715 -51.400503) (xy 257.331464 -51.400964) (xy 257.305128 -51.400478) (xy 257.252954 -51.393252)
			(xy 257.20227 -51.378917) (xy 257.154042 -51.357743) (xy 257.109185 -51.330135) (xy 257.068554 -51.296617)
			(xy 257.032922 -51.257827) (xy 257.002966 -51.214503) (xy 256.979257 -51.167469) (xy 256.962245 -51.11762)
			(xy 256.956814 -51.091846) (xy 256.953689 -51.078332) (xy 256.941309 -51.053527) (xy 256.922699 -51.032979)
			(xy 256.899239 -51.018209) (xy 256.872666 -51.010311) (xy 256.844947 -51.00987) (xy 256.818135 -51.016918)
			(xy 256.805938 -51.02352) (xy 256.783983 -51.035817) (xy 256.737544 -51.055203) (xy 256.688961 -51.068317)
			(xy 256.639075 -51.074933) (xy 256.613914 -51.075336) (xy 256.586662 -51.074818) (xy 256.532714 -51.067063)
			(xy 256.480418 -51.051709) (xy 256.43084 -51.029069) (xy 256.384989 -50.999604) (xy 256.343797 -50.963913)
			(xy 256.308105 -50.922723) (xy 256.278638 -50.876872) (xy 256.255996 -50.827295) (xy 256.24064 -50.775)
			(xy 256.232883 -50.721051) (xy 246.527444 -50.721051) (xy 246.521732 -50.758598) (xy 246.47398 -51.072288)
			(xy 246.441722 -51.283616) (xy 246.441722 -51.284378) (xy 246.441468 -51.286156) (xy 246.327636 -52.035456)
			(xy 259.141212 -52.035456) (xy 259.145283 -51.979834) (xy 259.157409 -51.925397) (xy 259.177332 -51.873306)
			(xy 259.204628 -51.824671) (xy 259.238714 -51.780528) (xy 259.278863 -51.741819) (xy 259.324221 -51.709368)
			(xy 259.373821 -51.683867) (xy 259.426605 -51.66586) (xy 259.481448 -51.65573) (xy 259.537182 -51.653693)
			(xy 259.592619 -51.659793) (xy 259.646576 -51.673899) (xy 259.697905 -51.695711) (xy 259.745511 -51.724765)
			(xy 259.788379 -51.76044) (xy 259.825596 -51.801977) (xy 259.856369 -51.84849) (xy 259.880041 -51.898987)
			(xy 259.896109 -51.952394) (xy 259.904229 -52.00757) (xy 259.904738 -52.035456) (xy 259.904229 -52.063342)
			(xy 259.896109 -52.118518) (xy 259.880041 -52.171925) (xy 259.856369 -52.222422) (xy 259.825596 -52.268935)
			(xy 259.788379 -52.310472) (xy 259.745511 -52.346147) (xy 259.697905 -52.375201) (xy 259.646576 -52.397013)
			(xy 259.592619 -52.411119) (xy 259.537182 -52.417219) (xy 259.481448 -52.415182) (xy 259.426605 -52.405052)
			(xy 259.373821 -52.387045) (xy 259.324221 -52.361544) (xy 259.278863 -52.329093) (xy 259.238714 -52.290384)
			(xy 259.204628 -52.246241) (xy 259.177332 -52.197606) (xy 259.157409 -52.145515) (xy 259.145283 -52.091078)
			(xy 259.141212 -52.035456) (xy 246.327636 -52.035456) (xy 246.316754 -52.107084) (xy 246.316246 -52.113688)
			(xy 246.31142 -52.414932) (xy 246.310658 -52.467764) (xy 246.310705 -52.473889) (xy 246.313409 -52.485832)
			(xy 246.315992 -52.491386) (xy 246.32793 -52.515262) (xy 246.335042 -52.524152) (xy 246.33936 -52.527454)
			(xy 246.361087 -52.545354) (xy 246.399547 -52.58646) (xy 246.431554 -52.632768) (xy 246.456414 -52.683275)
			(xy 246.473588 -52.736884) (xy 246.482704 -52.792434) (xy 246.483632 -52.82057) (xy 246.483632 -52.826666)
			(xy 246.483094 -52.855862) (xy 246.474229 -52.913578) (xy 246.456672 -52.969267) (xy 246.430832 -53.021631)
			(xy 246.414544 -53.045868) (xy 246.414036 -53.046376) (xy 246.410988 -53.050694) (xy 246.410734 -53.050948)
			(xy 246.406162 -53.057044) (xy 246.404892 -53.058822) (xy 246.401336 -53.06314) (xy 246.39524 -53.073046)
			(xy 246.391938 -53.079904) (xy 246.389652 -53.090064) (xy 246.389652 -53.117242) (xy 246.389507 -53.122681)
			(xy 246.387196 -53.133311) (xy 246.38508 -53.138324) (xy 246.37873 -53.152294) (xy 246.375059 -53.161459)
			(xy 246.374243 -53.181167) (xy 246.380904 -53.199733) (xy 246.387112 -53.207412) (xy 246.396256 -53.217826)
			(xy 246.412356 -53.238024) (xy 246.439553 -53.281936) (xy 246.460597 -53.329107) (xy 246.475107 -53.37868)
			(xy 246.482819 -53.429753) (xy 246.483632 -53.45557) (xy 246.483632 -53.461666) (xy 246.483023 -53.491575)
			(xy 246.473643 -53.550654) (xy 246.455169 -53.607549) (xy 246.428054 -53.66087) (xy 246.410988 -53.68544)
			(xy 246.404638 -53.694076) (xy 246.400828 -53.698902) (xy 246.395494 -53.707538) (xy 246.394986 -53.708554)
			(xy 246.392527 -53.71388) (xy 246.389838 -53.725296) (xy 246.389652 -53.73116) (xy 246.389652 -53.752242)
			(xy 246.389507 -53.757681) (xy 246.387196 -53.768311) (xy 246.38508 -53.773324) (xy 246.37873 -53.787294)
			(xy 246.375059 -53.796459) (xy 246.374243 -53.816167) (xy 246.380904 -53.834733) (xy 246.387112 -53.842412)
			(xy 246.396256 -53.852826) (xy 246.412356 -53.873024) (xy 246.439553 -53.916936) (xy 246.460597 -53.964107)
			(xy 246.475107 -54.01368) (xy 246.482819 -54.064753) (xy 246.483632 -54.09057) (xy 246.483632 -54.096666)
			(xy 246.483023 -54.126575) (xy 246.473643 -54.185654) (xy 246.455169 -54.242549) (xy 246.428054 -54.29587)
			(xy 246.410988 -54.32044) (xy 246.404638 -54.329076) (xy 246.400828 -54.333902) (xy 246.395494 -54.342538)
			(xy 246.394986 -54.343554) (xy 246.392527 -54.34888) (xy 246.389838 -54.360296) (xy 246.389652 -54.36616)
			(xy 246.389652 -54.387242) (xy 246.389507 -54.392681) (xy 246.387196 -54.403311) (xy 246.38508 -54.408324)
			(xy 246.380254 -54.418484) (xy 246.376952 -54.428898) (xy 246.376952 -54.449726) (xy 246.379238 -54.4576)
			(xy 246.386858 -54.477412) (xy 246.3927 -54.484016) (xy 246.40549 -54.499322) (xy 246.428142 -54.532158)
			(xy 246.437912 -54.549548) (xy 246.442484 -54.558438) (xy 246.452515 -54.578962) (xy 246.468179 -54.621876)
			(xy 246.473726 -54.644036) (xy 246.478469 -54.665569) (xy 246.483567 -54.709366) (xy 246.483886 -54.731412)
			(xy 246.483362 -54.759847) (xy 246.478674 -54.791102) (xy 248.37644 -54.791102) (xy 248.376897 -54.763731)
			(xy 248.384716 -54.709552) (xy 248.400206 -54.657048) (xy 248.42305 -54.607301) (xy 248.452777 -54.561335)
			(xy 248.47042 -54.540404) (xy 248.470674 -54.54015) (xy 248.476254 -54.53306) (xy 248.482503 -54.516145)
			(xy 248.482866 -54.50713) (xy 248.482866 -54.440074) (xy 248.482529 -54.431055) (xy 248.476268 -54.414138)
			(xy 248.470674 -54.407054) (xy 248.47042 -54.407054) (xy 248.47042 -54.4068) (xy 248.452782 -54.385866)
			(xy 248.423057 -54.339898) (xy 248.400212 -54.290152) (xy 248.384716 -54.23765) (xy 248.376887 -54.183472)
			(xy 248.376887 -54.128731) (xy 248.384715 -54.074553) (xy 248.400211 -54.022051) (xy 248.423056 -53.972305)
			(xy 248.45278 -53.926337) (xy 248.47042 -53.905404) (xy 248.470674 -53.90515) (xy 248.476254 -53.89806)
			(xy 248.482503 -53.881145) (xy 248.482866 -53.87213) (xy 248.482866 -53.805074) (xy 248.482529 -53.796055)
			(xy 248.476268 -53.779138) (xy 248.470674 -53.772054) (xy 248.47042 -53.772054) (xy 248.47042 -53.7718)
			(xy 248.452782 -53.750866) (xy 248.423057 -53.704898) (xy 248.400212 -53.655152) (xy 248.384716 -53.60265)
			(xy 248.376887 -53.548472) (xy 248.376887 -53.493731) (xy 248.384715 -53.439553) (xy 248.400211 -53.387051)
			(xy 248.423056 -53.337305) (xy 248.45278 -53.291337) (xy 248.47042 -53.270404) (xy 248.470674 -53.27015)
			(xy 248.476254 -53.26306) (xy 248.482503 -53.246145) (xy 248.482866 -53.23713) (xy 248.482866 -53.170074)
			(xy 248.482529 -53.161055) (xy 248.476268 -53.144138) (xy 248.470674 -53.137054) (xy 248.47042 -53.137054)
			(xy 248.47042 -53.1368) (xy 248.452771 -53.115876) (xy 248.42306 -53.069901) (xy 248.400225 -53.020152)
			(xy 248.384737 -52.967649) (xy 248.376912 -52.913472) (xy 248.37644 -52.886102) (xy 248.376926 -52.858851)
			(xy 248.384682 -52.804903) (xy 248.400037 -52.752608) (xy 248.422679 -52.703031) (xy 248.452145 -52.657181)
			(xy 248.487836 -52.61599) (xy 248.529027 -52.580299) (xy 248.574877 -52.550833) (xy 248.624454 -52.528191)
			(xy 248.676749 -52.512836) (xy 248.730697 -52.50508) (xy 248.785199 -52.50508) (xy 248.839147 -52.512836)
			(xy 248.891442 -52.528191) (xy 248.930551 -52.546052) (xy 253.879573 -52.546052) (xy 253.879573 -52.491548)
			(xy 253.88733 -52.4376) (xy 253.902686 -52.385304) (xy 253.925327 -52.335726) (xy 253.954794 -52.289875)
			(xy 253.990487 -52.248684) (xy 254.031678 -52.212992) (xy 254.077529 -52.183525) (xy 254.127108 -52.160884)
			(xy 254.179403 -52.145529) (xy 254.233352 -52.137773) (xy 254.260604 -52.13731) (xy 254.287974 -52.137771)
			(xy 254.342154 -52.14559) (xy 254.394657 -52.16108) (xy 254.444404 -52.183923) (xy 254.49037 -52.213648)
			(xy 254.511302 -52.23129) (xy 254.511556 -52.231544) (xy 254.518647 -52.237124) (xy 254.535561 -52.243373)
			(xy 254.544576 -52.243736) (xy 254.611632 -52.243736) (xy 254.620649 -52.243387) (xy 254.637566 -52.237133)
			(xy 254.644652 -52.231544) (xy 254.644652 -52.23129) (xy 254.644906 -52.23129) (xy 254.665839 -52.213649)
			(xy 254.711807 -52.183925) (xy 254.761553 -52.161079) (xy 254.814055 -52.145583) (xy 254.868233 -52.137754)
			(xy 254.922975 -52.137754) (xy 254.977153 -52.145583) (xy 255.029655 -52.161079) (xy 255.079401 -52.183925)
			(xy 255.125369 -52.213649) (xy 255.146302 -52.23129) (xy 255.146556 -52.231544) (xy 255.153647 -52.237124)
			(xy 255.170561 -52.243373) (xy 255.179576 -52.243736) (xy 255.246632 -52.243736) (xy 255.255649 -52.243387)
			(xy 255.272566 -52.237133) (xy 255.279652 -52.231544) (xy 255.279652 -52.23129) (xy 255.279906 -52.23129)
			(xy 255.300824 -52.213633) (xy 255.346801 -52.183924) (xy 255.396552 -52.161092) (xy 255.449056 -52.145605)
			(xy 255.503234 -52.137782) (xy 255.530604 -52.13731) (xy 255.557856 -52.13776) (xy 255.611806 -52.145517)
			(xy 255.664103 -52.160874) (xy 255.713682 -52.183516) (xy 255.759534 -52.212984) (xy 255.800726 -52.248677)
			(xy 255.836419 -52.289869) (xy 255.865886 -52.335722) (xy 255.888528 -52.385301) (xy 255.903883 -52.437598)
			(xy 255.91164 -52.491548) (xy 255.91164 -52.546052) (xy 255.905695 -52.587398) (xy 256.955288 -52.587398)
			(xy 256.959359 -52.531776) (xy 256.971485 -52.477339) (xy 256.991408 -52.425248) (xy 257.018704 -52.376613)
			(xy 257.05279 -52.33247) (xy 257.092939 -52.293761) (xy 257.138297 -52.26131) (xy 257.187897 -52.235809)
			(xy 257.240681 -52.217802) (xy 257.295524 -52.207672) (xy 257.351258 -52.205635) (xy 257.406695 -52.211735)
			(xy 257.460652 -52.225841) (xy 257.511981 -52.247653) (xy 257.559587 -52.276707) (xy 257.602455 -52.312382)
			(xy 257.639672 -52.353919) (xy 257.670445 -52.400432) (xy 257.694117 -52.450929) (xy 257.710185 -52.504336)
			(xy 257.717781 -52.555952) (xy 264.783779 -52.555952) (xy 264.783779 -52.501448) (xy 264.791536 -52.447498)
			(xy 264.806893 -52.395202) (xy 264.829536 -52.345623) (xy 264.859004 -52.299772) (xy 264.894698 -52.258581)
			(xy 264.935891 -52.22289) (xy 264.981744 -52.193424) (xy 265.031324 -52.170784) (xy 265.083622 -52.155431)
			(xy 265.137572 -52.147678) (xy 265.164824 -52.147216) (xy 265.192195 -52.147664) (xy 265.246375 -52.155486)
			(xy 265.298878 -52.170979) (xy 265.348625 -52.193825) (xy 265.394591 -52.223553) (xy 265.415522 -52.241196)
			(xy 265.415776 -52.24145) (xy 265.422861 -52.247039) (xy 265.439779 -52.253283) (xy 265.448796 -52.253642)
			(xy 265.515852 -52.253642) (xy 265.524868 -52.253275) (xy 265.541786 -52.247036) (xy 265.548872 -52.24145)
			(xy 265.548872 -52.241196) (xy 265.549126 -52.241196) (xy 265.570075 -52.223578) (xy 265.616043 -52.193863)
			(xy 265.665786 -52.171023) (xy 265.718283 -52.155527) (xy 265.772456 -52.147693) (xy 265.799824 -52.147216)
			(xy 265.827076 -52.147655) (xy 265.881024 -52.155415) (xy 265.93332 -52.170773) (xy 265.982897 -52.193417)
			(xy 266.028747 -52.222886) (xy 266.069937 -52.25858) (xy 266.105628 -52.299772) (xy 266.135094 -52.345624)
			(xy 266.157735 -52.395203) (xy 266.17309 -52.447499) (xy 266.180846 -52.501448) (xy 266.180846 -52.555952)
			(xy 266.17309 -52.609901) (xy 266.157735 -52.662197) (xy 266.135094 -52.711776) (xy 266.105628 -52.757628)
			(xy 266.069937 -52.79882) (xy 266.028747 -52.834514) (xy 265.982897 -52.863983) (xy 265.93332 -52.886627)
			(xy 265.881024 -52.901985) (xy 265.827076 -52.909745) (xy 265.799824 -52.910232) (xy 265.772453 -52.909768)
			(xy 265.718274 -52.901953) (xy 265.66577 -52.886464) (xy 265.616023 -52.863621) (xy 265.570057 -52.833895)
			(xy 265.549126 -52.816252) (xy 265.548872 -52.815998) (xy 265.541769 -52.810435) (xy 265.524865 -52.804174)
			(xy 265.515852 -52.803806) (xy 265.448796 -52.803806) (xy 265.439779 -52.80416) (xy 265.422862 -52.810409)
			(xy 265.415776 -52.815998) (xy 265.415776 -52.816252) (xy 265.415522 -52.816252) (xy 265.394586 -52.833887)
			(xy 265.348615 -52.863601) (xy 265.298869 -52.886438) (xy 265.246369 -52.90193) (xy 265.192193 -52.909758)
			(xy 265.164824 -52.910232) (xy 265.137572 -52.909722) (xy 265.083622 -52.901969) (xy 265.031324 -52.886616)
			(xy 264.981744 -52.863976) (xy 264.935891 -52.83451) (xy 264.894698 -52.798819) (xy 264.859004 -52.757628)
			(xy 264.829536 -52.711777) (xy 264.806893 -52.662198) (xy 264.791536 -52.609902) (xy 264.783779 -52.555952)
			(xy 257.717781 -52.555952) (xy 257.718305 -52.559512) (xy 257.718814 -52.587398) (xy 257.718305 -52.615284)
			(xy 257.710185 -52.67046) (xy 257.694117 -52.723867) (xy 257.670445 -52.774364) (xy 257.639672 -52.820877)
			(xy 257.602455 -52.862414) (xy 257.559587 -52.898089) (xy 257.511981 -52.927143) (xy 257.460652 -52.948955)
			(xy 257.406695 -52.963061) (xy 257.351258 -52.969161) (xy 257.295524 -52.967124) (xy 257.240681 -52.956994)
			(xy 257.187897 -52.938987) (xy 257.138297 -52.913486) (xy 257.092939 -52.881035) (xy 257.05279 -52.842326)
			(xy 257.018704 -52.798183) (xy 256.991408 -52.749548) (xy 256.971485 -52.697457) (xy 256.959359 -52.64302)
			(xy 256.955288 -52.587398) (xy 255.905695 -52.587398) (xy 255.903883 -52.600002) (xy 255.888528 -52.652299)
			(xy 255.865886 -52.701878) (xy 255.836419 -52.747731) (xy 255.800726 -52.788923) (xy 255.759534 -52.824616)
			(xy 255.713682 -52.854084) (xy 255.664103 -52.876726) (xy 255.611806 -52.892083) (xy 255.557856 -52.89984)
			(xy 255.530604 -52.900326) (xy 255.503233 -52.899876) (xy 255.449053 -52.892057) (xy 255.396549 -52.876565)
			(xy 255.346802 -52.853719) (xy 255.300836 -52.82399) (xy 255.279906 -52.806346) (xy 255.279652 -52.806092)
			(xy 255.272555 -52.80052) (xy 255.255646 -52.794265) (xy 255.246632 -52.7939) (xy 255.179576 -52.7939)
			(xy 255.170558 -52.794246) (xy 255.153641 -52.800501) (xy 255.146556 -52.806092) (xy 255.146302 -52.806346)
			(xy 255.125369 -52.823987) (xy 255.079401 -52.853711) (xy 255.029655 -52.876557) (xy 254.977153 -52.892053)
			(xy 254.922975 -52.899882) (xy 254.868233 -52.899882) (xy 254.814055 -52.892053) (xy 254.761553 -52.876557)
			(xy 254.711807 -52.853711) (xy 254.665839 -52.823987) (xy 254.644906 -52.806346) (xy 254.644652 -52.806092)
			(xy 254.637555 -52.80052) (xy 254.620646 -52.794265) (xy 254.611632 -52.7939) (xy 254.544576 -52.7939)
			(xy 254.535558 -52.794246) (xy 254.518641 -52.800501) (xy 254.511556 -52.806092) (xy 254.511556 -52.806346)
			(xy 254.511302 -52.806346) (xy 254.490373 -52.823989) (xy 254.4444 -52.853702) (xy 254.394652 -52.876538)
			(xy 254.34215 -52.892028) (xy 254.287974 -52.899854) (xy 254.260604 -52.900326) (xy 254.233352 -52.899827)
			(xy 254.179403 -52.892071) (xy 254.127108 -52.876716) (xy 254.077529 -52.854075) (xy 254.031678 -52.824608)
			(xy 253.990487 -52.788916) (xy 253.954794 -52.747725) (xy 253.925327 -52.701874) (xy 253.902686 -52.652296)
			(xy 253.88733 -52.6) (xy 253.879573 -52.546052) (xy 248.930551 -52.546052) (xy 248.941019 -52.550833)
			(xy 248.986869 -52.580299) (xy 249.02806 -52.61599) (xy 249.063751 -52.657181) (xy 249.093217 -52.703031)
			(xy 249.115859 -52.752608) (xy 249.131214 -52.804903) (xy 249.13897 -52.858851) (xy 249.139456 -52.886102)
			(xy 249.139002 -52.913473) (xy 249.131183 -52.967653) (xy 249.115692 -53.020156) (xy 249.092847 -53.069903)
			(xy 249.063119 -53.115869) (xy 249.045476 -53.1368) (xy 249.045222 -53.137054) (xy 249.039639 -53.144143)
			(xy 249.033392 -53.161058) (xy 249.03303 -53.170074) (xy 249.03303 -53.23713) (xy 249.033366 -53.246149)
			(xy 249.039627 -53.263066) (xy 249.045222 -53.27015) (xy 249.045476 -53.27015) (xy 249.045476 -53.270404)
			(xy 249.063119 -53.291335) (xy 249.092843 -53.337303) (xy 249.115688 -53.38705) (xy 249.131184 -53.439552)
			(xy 249.139012 -53.493731) (xy 249.139012 -53.548472) (xy 249.131183 -53.602651) (xy 249.115687 -53.655153)
			(xy 249.092842 -53.704899) (xy 249.063117 -53.750867) (xy 249.046546 -53.77053) (xy 249.410728 -53.77053)
			(xy 249.411257 -53.741613) (xy 249.419983 -53.684442) (xy 249.437238 -53.629243) (xy 249.462627 -53.577281)
			(xy 249.495569 -53.529747) (xy 249.535309 -53.48773) (xy 249.557794 -53.46954) (xy 249.566572 -53.461905)
			(xy 249.576772 -53.441025) (xy 249.577352 -53.429408) (xy 249.577352 -53.349652) (xy 249.576843 -53.338016)
			(xy 249.566635 -53.317106) (xy 249.557794 -53.30952) (xy 249.535319 -53.291319) (xy 249.495583 -53.249301)
			(xy 249.462644 -53.201768) (xy 249.437254 -53.149809) (xy 249.419996 -53.094613) (xy 249.411264 -53.037445)
			(xy 249.410728 -53.00853) (xy 249.411183 -52.981276) (xy 249.418937 -52.927323) (xy 249.434291 -52.875023)
			(xy 249.456933 -52.825441) (xy 249.486401 -52.779586) (xy 249.522096 -52.738392) (xy 249.56329 -52.702697)
			(xy 249.609146 -52.67323) (xy 249.658729 -52.650589) (xy 249.711029 -52.635236) (xy 249.764982 -52.627483)
			(xy 249.792236 -52.627022) (xy 249.818551 -52.627458) (xy 249.870681 -52.634699) (xy 249.921325 -52.649023)
			(xy 249.969524 -52.670162) (xy 250.014367 -52.697713) (xy 250.055005 -52.731158) (xy 250.07316 -52.750212)
			(xy 250.080693 -52.7576) (xy 250.099964 -52.766132) (xy 250.110498 -52.766722) (xy 250.185174 -52.766722)
			(xy 250.195723 -52.766186) (xy 250.215018 -52.757655) (xy 250.222512 -52.750212) (xy 250.240671 -52.73116)
			(xy 250.2813 -52.697702) (xy 250.326139 -52.670142) (xy 250.374339 -52.649003) (xy 250.424986 -52.634685)
			(xy 250.47712 -52.62746) (xy 250.503436 -52.627022) (xy 250.53069 -52.627444) (xy 250.584641 -52.635207)
			(xy 250.636939 -52.650568) (xy 250.686518 -52.673215) (xy 250.73237 -52.702688) (xy 250.77356 -52.738386)
			(xy 250.809251 -52.779583) (xy 250.838716 -52.82544) (xy 250.861355 -52.875023) (xy 250.876707 -52.927324)
			(xy 250.88446 -52.981276) (xy 250.884944 -53.00853) (xy 250.884481 -53.036197) (xy 250.88225 -53.051456)
			(xy 259.141212 -53.051456) (xy 259.145283 -52.995834) (xy 259.157409 -52.941397) (xy 259.177332 -52.889306)
			(xy 259.204628 -52.840671) (xy 259.238714 -52.796528) (xy 259.278863 -52.757819) (xy 259.324221 -52.725368)
			(xy 259.373821 -52.699867) (xy 259.426605 -52.68186) (xy 259.481448 -52.67173) (xy 259.537182 -52.669693)
			(xy 259.592619 -52.675793) (xy 259.646576 -52.689899) (xy 259.697905 -52.711711) (xy 259.745511 -52.740765)
			(xy 259.788379 -52.77644) (xy 259.825596 -52.817977) (xy 259.856369 -52.86449) (xy 259.880041 -52.914987)
			(xy 259.896109 -52.968394) (xy 259.904229 -53.02357) (xy 259.904738 -53.051456) (xy 259.904229 -53.079342)
			(xy 259.896109 -53.134518) (xy 259.880041 -53.187925) (xy 259.856369 -53.238422) (xy 259.825596 -53.284935)
			(xy 259.788379 -53.326472) (xy 259.745511 -53.362147) (xy 259.697905 -53.391201) (xy 259.646576 -53.413013)
			(xy 259.592619 -53.427119) (xy 259.537182 -53.433219) (xy 259.481448 -53.431182) (xy 259.426605 -53.421052)
			(xy 259.373821 -53.403045) (xy 259.324221 -53.377544) (xy 259.278863 -53.345093) (xy 259.238714 -53.306384)
			(xy 259.204628 -53.262241) (xy 259.177332 -53.213606) (xy 259.157409 -53.161515) (xy 259.145283 -53.107078)
			(xy 259.141212 -53.051456) (xy 250.88225 -53.051456) (xy 250.876476 -53.09095) (xy 250.860653 -53.143974)
			(xy 250.837342 -53.194159) (xy 250.807033 -53.240454) (xy 250.770359 -53.28189) (xy 250.728089 -53.317599)
			(xy 250.704858 -53.332634) (xy 250.695169 -53.339256) (xy 250.68273 -53.359128) (xy 250.680982 -53.370734)
			(xy 250.673108 -53.450744) (xy 250.672469 -53.462382) (xy 250.680556 -53.484219) (xy 250.688602 -53.492654)
			(xy 250.688856 -53.492908) (xy 250.707415 -53.511011) (xy 250.739997 -53.551337) (xy 250.766814 -53.595707)
			(xy 250.787371 -53.643301) (xy 250.801289 -53.693242) (xy 250.80831 -53.744608) (xy 250.808744 -53.77053)
			(xy 250.80825 -53.79778) (xy 250.800491 -53.851726) (xy 250.785133 -53.904018) (xy 250.762491 -53.953593)
			(xy 250.733025 -53.999442) (xy 250.697335 -54.040631) (xy 250.656147 -54.076322) (xy 250.610299 -54.105789)
			(xy 250.560724 -54.128431) (xy 250.508432 -54.143789) (xy 250.454486 -54.15155) (xy 250.427236 -54.152038)
			(xy 250.399866 -54.151566) (xy 250.345686 -54.143752) (xy 250.293183 -54.128265) (xy 250.243436 -54.105424)
			(xy 250.197469 -54.0757) (xy 250.176538 -54.058058) (xy 250.176284 -54.057804) (xy 250.169206 -54.052205)
			(xy 250.152283 -54.045966) (xy 250.143264 -54.045612) (xy 250.076208 -54.045612) (xy 250.067191 -54.04597)
			(xy 250.050274 -54.052217) (xy 250.043188 -54.057804) (xy 250.043188 -54.058058) (xy 250.042934 -54.058058)
			(xy 250.021995 -54.075688) (xy 249.976024 -54.105403) (xy 249.926279 -54.128241) (xy 249.87378 -54.143734)
			(xy 249.819605 -54.151564) (xy 249.792236 -54.152038) (xy 249.764985 -54.151511) (xy 249.711038 -54.14376)
			(xy 249.658743 -54.12841) (xy 249.609165 -54.105774) (xy 249.563314 -54.076312) (xy 249.522121 -54.040625)
			(xy 249.486427 -53.999439) (xy 249.456958 -53.953593) (xy 249.434313 -53.904018) (xy 249.418954 -53.851726)
			(xy 249.411193 -53.797781) (xy 249.410728 -53.77053) (xy 249.046546 -53.77053) (xy 249.045476 -53.7718)
			(xy 249.045222 -53.772054) (xy 249.039639 -53.779143) (xy 249.033392 -53.796058) (xy 249.03303 -53.805074)
			(xy 249.03303 -53.87213) (xy 249.033366 -53.881149) (xy 249.039627 -53.898066) (xy 249.045222 -53.90515)
			(xy 249.045476 -53.90515) (xy 249.045476 -53.905404) (xy 249.063119 -53.926335) (xy 249.092843 -53.972303)
			(xy 249.115688 -54.02205) (xy 249.131184 -54.074552) (xy 249.139012 -54.128731) (xy 249.139012 -54.183472)
			(xy 249.131183 -54.237651) (xy 249.115687 -54.290153) (xy 249.101895 -54.320186) (xy 251.33046 -54.320186)
			(xy 251.330903 -54.292815) (xy 251.338724 -54.238634) (xy 251.354218 -54.18613) (xy 251.377065 -54.136384)
			(xy 251.406796 -54.090418) (xy 251.42444 -54.069488) (xy 251.424694 -54.069234) (xy 251.430272 -54.062141)
			(xy 251.436524 -54.045229) (xy 251.436886 -54.036214) (xy 251.436886 -53.969158) (xy 251.436504 -53.960144)
			(xy 251.430274 -53.943226) (xy 251.424694 -53.936138) (xy 251.42444 -53.936138) (xy 251.42444 -53.935884)
			(xy 251.406833 -53.914926) (xy 251.377115 -53.868961) (xy 251.354272 -53.81922) (xy 251.338774 -53.766725)
			(xy 251.330938 -53.712553) (xy 251.33046 -53.685186) (xy 251.330946 -53.657935) (xy 251.338702 -53.603987)
			(xy 251.354057 -53.551692) (xy 251.376699 -53.502115) (xy 251.406165 -53.456265) (xy 251.441856 -53.415074)
			(xy 251.483047 -53.379383) (xy 251.528897 -53.349917) (xy 251.578474 -53.327275) (xy 251.630769 -53.31192)
			(xy 251.684717 -53.304164) (xy 251.739219 -53.304164) (xy 251.793167 -53.31192) (xy 251.845462 -53.327275)
			(xy 251.895039 -53.349917) (xy 251.940889 -53.379383) (xy 251.98208 -53.415074) (xy 252.017771 -53.456265)
			(xy 252.043661 -53.496551) (xy 264.333464 -53.496551) (xy 264.333464 -53.442049) (xy 264.34122 -53.3881)
			(xy 264.356575 -53.335805) (xy 264.379216 -53.286227) (xy 264.408681 -53.240376) (xy 264.444372 -53.199185)
			(xy 264.485562 -53.163492) (xy 264.531412 -53.134024) (xy 264.580988 -53.111381) (xy 264.633283 -53.096024)
			(xy 264.687231 -53.088265) (xy 264.714482 -53.087778) (xy 264.741853 -53.088236) (xy 264.796033 -53.096053)
			(xy 264.848537 -53.111543) (xy 264.898284 -53.134387) (xy 264.944249 -53.164115) (xy 264.96518 -53.181758)
			(xy 264.965434 -53.182012) (xy 264.972534 -53.187578) (xy 264.989441 -53.193837) (xy 264.998454 -53.194204)
			(xy 265.06551 -53.194204) (xy 265.074527 -53.193851) (xy 265.091444 -53.1876) (xy 265.09853 -53.182012)
			(xy 265.09853 -53.181758) (xy 265.098784 -53.181758) (xy 265.119706 -53.164106) (xy 265.165682 -53.134397)
			(xy 265.215432 -53.111565) (xy 265.267935 -53.096076) (xy 265.322112 -53.08825) (xy 265.349482 -53.087778)
			(xy 265.376735 -53.088268) (xy 265.430686 -53.096023) (xy 265.482984 -53.111377) (xy 265.532564 -53.134017)
			(xy 265.578418 -53.163484) (xy 265.619611 -53.199176) (xy 265.655306 -53.240368) (xy 265.684774 -53.28622)
			(xy 265.707417 -53.335799) (xy 265.722773 -53.388097) (xy 265.730531 -53.442047) (xy 265.730531 -53.496553)
			(xy 265.722773 -53.550503) (xy 265.707417 -53.602801) (xy 265.684774 -53.65238) (xy 265.655306 -53.698232)
			(xy 265.619611 -53.739424) (xy 265.578418 -53.775116) (xy 265.532564 -53.804583) (xy 265.482984 -53.827223)
			(xy 265.430686 -53.842577) (xy 265.376735 -53.850332) (xy 265.349482 -53.850794) (xy 265.322111 -53.85034)
			(xy 265.267932 -53.842519) (xy 265.215428 -53.827028) (xy 265.165682 -53.804183) (xy 265.119715 -53.774456)
			(xy 265.098784 -53.756814) (xy 265.09853 -53.75656) (xy 265.091443 -53.750975) (xy 265.074526 -53.744728)
			(xy 265.06551 -53.744368) (xy 264.998454 -53.744368) (xy 264.989441 -53.744758) (xy 264.972524 -53.750983)
			(xy 264.965434 -53.75656) (xy 264.965434 -53.756814) (xy 264.96518 -53.756814) (xy 264.94423 -53.774431)
			(xy 264.898262 -53.804146) (xy 264.848519 -53.826986) (xy 264.796022 -53.842482) (xy 264.74185 -53.850316)
			(xy 264.714482 -53.850794) (xy 264.687231 -53.850335) (xy 264.633283 -53.842576) (xy 264.580988 -53.827219)
			(xy 264.531412 -53.804576) (xy 264.485562 -53.775108) (xy 264.444372 -53.739415) (xy 264.408681 -53.698224)
			(xy 264.379216 -53.652373) (xy 264.356575 -53.602795) (xy 264.34122 -53.5505) (xy 264.333464 -53.496551)
			(xy 252.043661 -53.496551) (xy 252.047237 -53.502115) (xy 252.069879 -53.551692) (xy 252.085234 -53.603987)
			(xy 252.09299 -53.657935) (xy 252.093476 -53.685186) (xy 252.093008 -53.712556) (xy 252.085191 -53.766735)
			(xy 252.069703 -53.819239) (xy 252.046862 -53.868986) (xy 252.017137 -53.914952) (xy 251.999496 -53.935884)
			(xy 251.999242 -53.936138) (xy 251.993668 -53.943233) (xy 251.987415 -53.960144) (xy 251.98705 -53.969158)
			(xy 251.98705 -54.036214) (xy 251.98739 -54.045233) (xy 251.993648 -54.06215) (xy 251.999242 -54.069234)
			(xy 251.999496 -54.069234) (xy 251.999496 -54.069488) (xy 252.017142 -54.090414) (xy 252.046853 -54.136389)
			(xy 252.069688 -54.186138) (xy 252.085177 -54.23864) (xy 252.093003 -54.292816) (xy 252.093476 -54.320186)
			(xy 252.09299 -54.347437) (xy 252.085234 -54.401385) (xy 252.069879 -54.45368) (xy 252.047237 -54.503257)
			(xy 252.017771 -54.549107) (xy 251.98208 -54.590298) (xy 251.940889 -54.625989) (xy 251.895039 -54.655455)
			(xy 251.845462 -54.678097) (xy 251.793167 -54.693452) (xy 251.739219 -54.701208) (xy 251.684717 -54.701208)
			(xy 251.630769 -54.693452) (xy 251.578474 -54.678097) (xy 251.528897 -54.655455) (xy 251.483047 -54.625989)
			(xy 251.441856 -54.590298) (xy 251.406165 -54.549107) (xy 251.376699 -54.503257) (xy 251.354057 -54.45368)
			(xy 251.338702 -54.401385) (xy 251.330946 -54.347437) (xy 251.33046 -54.320186) (xy 249.101895 -54.320186)
			(xy 249.092842 -54.339899) (xy 249.063117 -54.385867) (xy 249.045476 -54.4068) (xy 249.045222 -54.407054)
			(xy 249.039639 -54.414143) (xy 249.033392 -54.431058) (xy 249.03303 -54.440074) (xy 249.03303 -54.50713)
			(xy 249.033366 -54.516149) (xy 249.039627 -54.533066) (xy 249.045222 -54.54015) (xy 249.045476 -54.54015)
			(xy 249.045476 -54.540404) (xy 249.063127 -54.561327) (xy 249.092838 -54.607302) (xy 249.115672 -54.657052)
			(xy 249.13116 -54.709554) (xy 249.138984 -54.763732) (xy 249.139101 -54.770528) (xy 252.271022 -54.770528)
			(xy 252.271499 -54.743158) (xy 252.279313 -54.688979) (xy 252.2948 -54.636476) (xy 252.317639 -54.586729)
			(xy 252.347362 -54.540762) (xy 252.365002 -54.51983) (xy 252.365256 -54.519576) (xy 252.370865 -54.512505)
			(xy 252.377097 -54.495576) (xy 252.377448 -54.486556) (xy 252.377448 -54.4195) (xy 252.377102 -54.410482)
			(xy 252.370848 -54.393564) (xy 252.365256 -54.38648) (xy 252.365002 -54.38648) (xy 252.365002 -54.386226)
			(xy 252.347362 -54.365295) (xy 252.31765 -54.319322) (xy 252.294814 -54.269574) (xy 252.279324 -54.217073)
			(xy 252.271496 -54.162897) (xy 252.271022 -54.135528) (xy 252.271508 -54.108277) (xy 252.279264 -54.054329)
			(xy 252.294619 -54.002034) (xy 252.317261 -53.952457) (xy 252.346727 -53.906607) (xy 252.382418 -53.865416)
			(xy 252.423609 -53.829725) (xy 252.469459 -53.800259) (xy 252.519036 -53.777617) (xy 252.571331 -53.762262)
			(xy 252.625279 -53.754506) (xy 252.679781 -53.754506) (xy 252.733729 -53.762262) (xy 252.786024 -53.777617)
			(xy 252.835601 -53.800259) (xy 252.881451 -53.829725) (xy 252.922642 -53.865416) (xy 252.958333 -53.906607)
			(xy 252.987799 -53.952457) (xy 252.992874 -53.96357) (xy 256.972052 -53.96357) (xy 256.976123 -53.907948)
			(xy 256.988249 -53.853511) (xy 257.008172 -53.80142) (xy 257.035468 -53.752785) (xy 257.069554 -53.708642)
			(xy 257.109703 -53.669933) (xy 257.155061 -53.637482) (xy 257.204661 -53.611981) (xy 257.257445 -53.593974)
			(xy 257.312288 -53.583844) (xy 257.368022 -53.581807) (xy 257.423459 -53.587907) (xy 257.477416 -53.602013)
			(xy 257.528745 -53.623825) (xy 257.576351 -53.652879) (xy 257.619219 -53.688554) (xy 257.656436 -53.730091)
			(xy 257.687209 -53.776604) (xy 257.710881 -53.827101) (xy 257.726949 -53.880508) (xy 257.735069 -53.935684)
			(xy 257.735578 -53.96357) (xy 257.735069 -53.991456) (xy 257.726949 -54.046632) (xy 257.710881 -54.100039)
			(xy 257.687209 -54.150536) (xy 257.656436 -54.197049) (xy 257.619219 -54.238586) (xy 257.576351 -54.274261)
			(xy 257.528745 -54.303315) (xy 257.477416 -54.325127) (xy 257.423459 -54.339233) (xy 257.368022 -54.345333)
			(xy 257.312288 -54.343296) (xy 257.257445 -54.333166) (xy 257.204661 -54.315159) (xy 257.155061 -54.289658)
			(xy 257.109703 -54.257207) (xy 257.069554 -54.218498) (xy 257.035468 -54.174355) (xy 257.008172 -54.12572)
			(xy 256.988249 -54.073629) (xy 256.976123 -54.019192) (xy 256.972052 -53.96357) (xy 252.992874 -53.96357)
			(xy 253.010441 -54.002034) (xy 253.025796 -54.054329) (xy 253.033552 -54.108277) (xy 253.034038 -54.135528)
			(xy 253.033603 -54.1629) (xy 253.02578 -54.217081) (xy 253.010285 -54.269585) (xy 252.987436 -54.319331)
			(xy 252.957703 -54.365296) (xy 252.940058 -54.386226) (xy 252.939804 -54.38648) (xy 252.93422 -54.393568)
			(xy 252.927972 -54.410484) (xy 252.927612 -54.4195) (xy 252.927612 -54.486556) (xy 252.927988 -54.495571)
			(xy 252.934222 -54.512488) (xy 252.939804 -54.519576) (xy 252.940058 -54.519576) (xy 252.940058 -54.51983)
			(xy 252.957671 -54.540783) (xy 252.987388 -54.586749) (xy 253.01023 -54.636492) (xy 253.025727 -54.688988)
			(xy 253.033561 -54.74316) (xy 253.034038 -54.770528) (xy 253.033552 -54.797779) (xy 253.025796 -54.851727)
			(xy 253.010441 -54.904022) (xy 252.987799 -54.953599) (xy 252.965015 -54.989051) (xy 262.101068 -54.989051)
			(xy 262.101068 -54.934549) (xy 262.108824 -54.880602) (xy 262.124178 -54.828308) (xy 262.146818 -54.778731)
			(xy 262.176283 -54.732881) (xy 262.211973 -54.69169) (xy 262.253161 -54.655997) (xy 262.29901 -54.62653)
			(xy 262.348585 -54.603887) (xy 262.400879 -54.588529) (xy 262.454825 -54.580769) (xy 262.482076 -54.580282)
			(xy 262.510167 -54.580796) (xy 262.565743 -54.58902) (xy 262.619512 -54.605307) (xy 262.670309 -54.629307)
			(xy 262.717036 -54.660499) (xy 262.758682 -54.698208) (xy 262.794345 -54.741619) (xy 262.809228 -54.765448)
			(xy 262.814562 -54.774338) (xy 262.83158 -54.78653) (xy 262.924798 -54.80685) (xy 262.945372 -54.802532)
			(xy 262.954008 -54.79669) (xy 262.978068 -54.780683) (xy 263.030001 -54.755342) (xy 263.08516 -54.738119)
			(xy 263.142285 -54.729406) (xy 263.171178 -54.728872) (xy 263.198429 -54.729376) (xy 263.252378 -54.737129)
			(xy 263.304674 -54.752481) (xy 263.354252 -54.77512) (xy 263.400105 -54.804584) (xy 263.441297 -54.840273)
			(xy 263.476991 -54.881462) (xy 263.50646 -54.927311) (xy 263.529104 -54.976887) (xy 263.544462 -55.029181)
			(xy 263.552221 -55.083129) (xy 263.552686 -55.11038) (xy 263.552212 -55.13775) (xy 263.544396 -55.191929)
			(xy 263.528909 -55.244432) (xy 263.506069 -55.294179) (xy 263.476346 -55.340146) (xy 263.458706 -55.361078)
			(xy 263.458452 -55.361332) (xy 263.452882 -55.36843) (xy 263.446627 -55.385338) (xy 263.44626 -55.394352)
			(xy 263.44626 -55.461408) (xy 263.4466 -55.470427) (xy 263.452858 -55.487344) (xy 263.458452 -55.494428)
			(xy 263.458706 -55.494428) (xy 263.458706 -55.494682) (xy 263.476326 -55.515631) (xy 263.506049 -55.561597)
			(xy 263.528893 -55.611341) (xy 263.54439 -55.66384) (xy 263.552219 -55.718016) (xy 263.552222 -55.772754)
			(xy 263.544396 -55.826931) (xy 263.528904 -55.879431) (xy 263.506063 -55.929177) (xy 263.476344 -55.975145)
			(xy 263.458706 -55.996078) (xy 263.458452 -55.996332) (xy 263.452882 -56.00343) (xy 263.446627 -56.020338)
			(xy 263.44626 -56.029352) (xy 263.44626 -56.096408) (xy 263.4466 -56.105427) (xy 263.452858 -56.122344)
			(xy 263.458452 -56.129428) (xy 263.458706 -56.129428) (xy 263.458706 -56.129682) (xy 263.476351 -56.150609)
			(xy 263.506062 -56.196583) (xy 263.528896 -56.246332) (xy 263.544386 -56.298834) (xy 263.552213 -56.353011)
			(xy 263.552686 -56.38038) (xy 263.5522 -56.407631) (xy 263.544444 -56.461579) (xy 263.529089 -56.513874)
			(xy 263.506447 -56.563451) (xy 263.476981 -56.609301) (xy 263.44129 -56.650492) (xy 263.400099 -56.686183)
			(xy 263.354249 -56.715649) (xy 263.304672 -56.738291) (xy 263.252377 -56.753646) (xy 263.198429 -56.761402)
			(xy 263.143927 -56.761402) (xy 263.089979 -56.753646) (xy 263.037684 -56.738291) (xy 262.988107 -56.715649)
			(xy 262.942257 -56.686183) (xy 262.901066 -56.650492) (xy 262.865375 -56.609301) (xy 262.835909 -56.563451)
			(xy 262.813267 -56.513874) (xy 262.797912 -56.461579) (xy 262.790156 -56.407631) (xy 262.78967 -56.38038)
			(xy 262.790107 -56.353009) (xy 262.797929 -56.298828) (xy 262.813424 -56.246323) (xy 262.836273 -56.196577)
			(xy 262.866005 -56.150612) (xy 262.88365 -56.129682) (xy 262.883904 -56.129428) (xy 262.889485 -56.122338)
			(xy 262.895735 -56.105424) (xy 262.896096 -56.096408) (xy 262.896096 -56.029352) (xy 262.895715 -56.020338)
			(xy 262.889484 -56.00342) (xy 262.883904 -55.996332) (xy 262.88365 -55.996332) (xy 262.88365 -55.996078)
			(xy 262.865989 -55.975162) (xy 262.836263 -55.929192) (xy 262.813417 -55.879443) (xy 262.797922 -55.826938)
			(xy 262.790094 -55.772757) (xy 262.790097 -55.718013) (xy 262.797928 -55.663833) (xy 262.813428 -55.611329)
			(xy 262.836278 -55.561582) (xy 262.866007 -55.515614) (xy 262.88365 -55.494682) (xy 262.883904 -55.494428)
			(xy 262.889485 -55.487338) (xy 262.895735 -55.470424) (xy 262.896096 -55.461408) (xy 262.896096 -55.394352)
			(xy 262.895715 -55.385338) (xy 262.889484 -55.36842) (xy 262.883904 -55.361332) (xy 262.88365 -55.360824)
			(xy 262.872704 -55.348092) (xy 262.852864 -55.320999) (xy 262.844026 -55.306722) (xy 262.838692 -55.297832)
			(xy 262.821674 -55.28564) (xy 262.728456 -55.26532) (xy 262.707882 -55.269638) (xy 262.699246 -55.27548)
			(xy 262.67517 -55.29146) (xy 262.623243 -55.316808) (xy 262.568089 -55.334039) (xy 262.510967 -55.34276)
			(xy 262.482076 -55.343298) (xy 262.454825 -55.342831) (xy 262.400879 -55.335071) (xy 262.348585 -55.319713)
			(xy 262.29901 -55.29707) (xy 262.253161 -55.267603) (xy 262.211973 -55.23191) (xy 262.176283 -55.190719)
			(xy 262.146818 -55.144869) (xy 262.124178 -55.095292) (xy 262.108824 -55.042998) (xy 262.101068 -54.989051)
			(xy 252.965015 -54.989051) (xy 252.958333 -54.999449) (xy 252.922642 -55.04064) (xy 252.881451 -55.076331)
			(xy 252.835601 -55.105797) (xy 252.786024 -55.128439) (xy 252.733729 -55.143794) (xy 252.679781 -55.15155)
			(xy 252.625279 -55.15155) (xy 252.571331 -55.143794) (xy 252.519036 -55.128439) (xy 252.469459 -55.105797)
			(xy 252.423609 -55.076331) (xy 252.382418 -55.04064) (xy 252.346727 -54.999449) (xy 252.317261 -54.953599)
			(xy 252.294619 -54.904022) (xy 252.279264 -54.851727) (xy 252.271508 -54.797779) (xy 252.271022 -54.770528)
			(xy 249.139101 -54.770528) (xy 249.139456 -54.791102) (xy 249.13897 -54.818353) (xy 249.131214 -54.872301)
			(xy 249.115859 -54.924596) (xy 249.093217 -54.974173) (xy 249.063751 -55.020023) (xy 249.02806 -55.061214)
			(xy 248.986869 -55.096905) (xy 248.941019 -55.126371) (xy 248.891442 -55.149013) (xy 248.839147 -55.164368)
			(xy 248.785199 -55.172124) (xy 248.730697 -55.172124) (xy 248.676749 -55.164368) (xy 248.624454 -55.149013)
			(xy 248.574877 -55.126371) (xy 248.529027 -55.096905) (xy 248.487836 -55.061214) (xy 248.452145 -55.020023)
			(xy 248.422679 -54.974173) (xy 248.400037 -54.924596) (xy 248.384682 -54.872301) (xy 248.376926 -54.818353)
			(xy 248.37644 -54.791102) (xy 246.478674 -54.791102) (xy 246.474926 -54.816089) (xy 246.458243 -54.870458)
			(xy 246.433682 -54.921751) (xy 246.401785 -54.968835) (xy 246.363258 -55.010668) (xy 246.318954 -55.046324)
			(xy 246.294656 -55.061104) (xy 246.290846 -55.06339) (xy 246.281892 -55.070418) (xy 246.27068 -55.090196)
			(xy 246.269256 -55.10149) (xy 246.25962 -55.722266) (xy 258.034026 -55.722266) (xy 258.038097 -55.666644)
			(xy 258.050223 -55.612207) (xy 258.070146 -55.560116) (xy 258.097442 -55.511481) (xy 258.131528 -55.467338)
			(xy 258.171677 -55.428629) (xy 258.217035 -55.396178) (xy 258.266635 -55.370677) (xy 258.319419 -55.35267)
			(xy 258.374262 -55.34254) (xy 258.429996 -55.340503) (xy 258.485433 -55.346603) (xy 258.53939 -55.360709)
			(xy 258.590719 -55.382521) (xy 258.638325 -55.411575) (xy 258.649471 -55.420851) (xy 260.424668 -55.420851)
			(xy 260.424668 -55.366349) (xy 260.432424 -55.312402) (xy 260.447778 -55.260108) (xy 260.470418 -55.210531)
			(xy 260.499883 -55.164681) (xy 260.535573 -55.12349) (xy 260.576761 -55.087797) (xy 260.62261 -55.05833)
			(xy 260.672185 -55.035687) (xy 260.724479 -55.020329) (xy 260.778425 -55.012569) (xy 260.805676 -55.012082)
			(xy 260.831989 -55.012571) (xy 260.884116 -55.019802) (xy 260.934759 -55.034118) (xy 260.982958 -55.055246)
			(xy 261.027802 -55.082788) (xy 261.068442 -55.116222) (xy 261.0866 -55.135272) (xy 261.094123 -55.142672)
			(xy 261.113402 -55.151198) (xy 261.123938 -55.151782) (xy 261.198614 -55.151782) (xy 261.209167 -55.151279)
			(xy 261.228462 -55.142726) (xy 261.235952 -55.135272) (xy 261.254084 -55.116193) (xy 261.294719 -55.082739)
			(xy 261.339565 -55.055184) (xy 261.38777 -55.03405) (xy 261.438421 -55.019737) (xy 261.490559 -55.012518)
			(xy 261.516876 -55.012082) (xy 261.544129 -55.012564) (xy 261.598081 -55.020318) (xy 261.650381 -55.035671)
			(xy 261.699963 -55.058312) (xy 261.745817 -55.087778) (xy 261.787012 -55.123471) (xy 261.822707 -55.164663)
			(xy 261.852177 -55.210516) (xy 261.87482 -55.260097) (xy 261.890177 -55.312395) (xy 261.897935 -55.366347)
			(xy 261.897935 -55.420853) (xy 261.890177 -55.474805) (xy 261.87482 -55.527103) (xy 261.852177 -55.576684)
			(xy 261.822707 -55.622537) (xy 261.787012 -55.663729) (xy 261.745817 -55.699422) (xy 261.699963 -55.728888)
			(xy 261.650381 -55.751529) (xy 261.598081 -55.766882) (xy 261.544129 -55.774636) (xy 261.516876 -55.775098)
			(xy 261.490561 -55.774647) (xy 261.438432 -55.767409) (xy 261.387789 -55.753087) (xy 261.33959 -55.731951)
			(xy 261.294747 -55.704402) (xy 261.254108 -55.670961) (xy 261.235952 -55.651908) (xy 261.228449 -55.644484)
			(xy 261.209155 -55.635972) (xy 261.198614 -55.635398) (xy 261.123938 -55.635398) (xy 261.113389 -55.635935)
			(xy 261.094094 -55.644465) (xy 261.0866 -55.651908) (xy 261.068439 -55.670958) (xy 261.02781 -55.704415)
			(xy 260.982971 -55.731975) (xy 260.934771 -55.753114) (xy 260.884125 -55.767433) (xy 260.831992 -55.774659)
			(xy 260.805676 -55.775098) (xy 260.778425 -55.774631) (xy 260.724479 -55.766871) (xy 260.672185 -55.751513)
			(xy 260.62261 -55.72887) (xy 260.576761 -55.699403) (xy 260.535573 -55.66371) (xy 260.499883 -55.622519)
			(xy 260.470418 -55.576669) (xy 260.447778 -55.527092) (xy 260.432424 -55.474798) (xy 260.424668 -55.420851)
			(xy 258.649471 -55.420851) (xy 258.681193 -55.44725) (xy 258.71841 -55.488787) (xy 258.749183 -55.5353)
			(xy 258.772855 -55.585797) (xy 258.788923 -55.639204) (xy 258.797043 -55.69438) (xy 258.797552 -55.722266)
			(xy 258.797043 -55.750152) (xy 258.788923 -55.805328) (xy 258.772855 -55.858735) (xy 258.749183 -55.909232)
			(xy 258.71841 -55.955745) (xy 258.681193 -55.997282) (xy 258.638325 -56.032957) (xy 258.590719 -56.062011)
			(xy 258.53939 -56.083823) (xy 258.485433 -56.097929) (xy 258.429996 -56.104029) (xy 258.374262 -56.101992)
			(xy 258.319419 -56.091862) (xy 258.266635 -56.073855) (xy 258.217035 -56.048354) (xy 258.171677 -56.015903)
			(xy 258.131528 -55.977194) (xy 258.097442 -55.933051) (xy 258.070146 -55.884416) (xy 258.050223 -55.832325)
			(xy 258.038097 -55.777888) (xy 258.034026 -55.722266) (xy 246.25962 -55.722266) (xy 246.248682 -56.426862)
			(xy 246.248795 -56.434072) (xy 246.252543 -56.447991) (xy 246.256048 -56.454294) (xy 246.269002 -56.475122)
			(xy 246.272532 -56.480476) (xy 246.281796 -56.489338) (xy 246.28729 -56.492648) (xy 246.287544 -56.492902)
			(xy 246.309883 -56.505807) (xy 246.351187 -56.536718) (xy 246.38795 -56.572911) (xy 246.419504 -56.613727)
			(xy 246.445272 -56.65842) (xy 246.464785 -56.706178) (xy 246.477687 -56.756128) (xy 246.481092 -56.7817)
			(xy 246.482108 -56.791098) (xy 246.483632 -56.826404) (xy 246.483632 -56.827166) (xy 246.483213 -56.852689)
			(xy 246.476385 -56.903276) (xy 246.462872 -56.952501) (xy 246.442917 -56.999485) (xy 246.440871 -57.002934)
			(xy 253.763526 -57.002934) (xy 253.764026 -56.974842) (xy 253.77225 -56.919265) (xy 253.788538 -56.865495)
			(xy 253.81254 -56.814696) (xy 253.843734 -56.767969) (xy 253.881447 -56.726325) (xy 253.924861 -56.690664)
			(xy 253.948692 -56.675782) (xy 253.957582 -56.670448) (xy 253.969774 -56.65343) (xy 253.990094 -56.560212)
			(xy 253.985776 -56.539638) (xy 253.979934 -56.531002) (xy 253.963937 -56.506936) (xy 253.938592 -56.455006)
			(xy 253.921366 -56.399848) (xy 253.91265 -56.342724) (xy 253.912116 -56.313832) (xy 253.912585 -56.286579)
			(xy 253.920338 -56.232627) (xy 253.935692 -56.180328) (xy 253.958332 -56.130746) (xy 253.987799 -56.084892)
			(xy 254.023492 -56.043698) (xy 254.064685 -56.008004) (xy 254.110539 -55.978536) (xy 254.16012 -55.955894)
			(xy 254.212419 -55.94054) (xy 254.266371 -55.932786) (xy 254.293624 -55.932324) (xy 254.320995 -55.93277)
			(xy 254.375175 -55.940592) (xy 254.427679 -55.956085) (xy 254.477425 -55.978932) (xy 254.523391 -56.008661)
			(xy 254.544322 -56.026304) (xy 254.544576 -56.026558) (xy 254.55166 -56.032148) (xy 254.568579 -56.038391)
			(xy 254.577596 -56.03875) (xy 254.644652 -56.03875) (xy 254.653668 -56.038381) (xy 254.670586 -56.032143)
			(xy 254.677672 -56.026558) (xy 254.677672 -56.026304) (xy 254.677926 -56.026304) (xy 254.698859 -56.008663)
			(xy 254.744827 -55.978939) (xy 254.794573 -55.956093) (xy 254.847075 -55.940597) (xy 254.901253 -55.932768)
			(xy 254.955995 -55.932768) (xy 255.010173 -55.940597) (xy 255.062675 -55.956093) (xy 255.112421 -55.978939)
			(xy 255.158389 -56.008663) (xy 255.179322 -56.026304) (xy 255.179576 -56.026558) (xy 255.18666 -56.032148)
			(xy 255.203579 -56.038391) (xy 255.212596 -56.03875) (xy 255.279652 -56.03875) (xy 255.288668 -56.038381)
			(xy 255.305586 -56.032143) (xy 255.312672 -56.026558) (xy 255.312672 -56.026304) (xy 255.312926 -56.026304)
			(xy 255.333876 -56.008687) (xy 255.379844 -55.978971) (xy 255.429587 -55.956131) (xy 255.482083 -55.940635)
			(xy 255.536256 -55.932801) (xy 255.563624 -55.932324) (xy 255.590876 -55.932747) (xy 255.644826 -55.940507)
			(xy 255.697122 -55.955866) (xy 255.746701 -55.97851) (xy 255.792552 -56.00798) (xy 255.833743 -56.043674)
			(xy 255.869435 -56.084867) (xy 255.898901 -56.13072) (xy 255.921542 -56.1803) (xy 255.936898 -56.232597)
			(xy 255.944654 -56.286548) (xy 255.944654 -56.297068) (xy 256.286506 -56.297068) (xy 256.290577 -56.241446)
			(xy 256.302703 -56.187009) (xy 256.322626 -56.134918) (xy 256.349922 -56.086283) (xy 256.384008 -56.04214)
			(xy 256.424157 -56.003431) (xy 256.469515 -55.97098) (xy 256.519115 -55.945479) (xy 256.571899 -55.927472)
			(xy 256.626742 -55.917342) (xy 256.682476 -55.915305) (xy 256.737913 -55.921405) (xy 256.79187 -55.935511)
			(xy 256.843199 -55.957323) (xy 256.890805 -55.986377) (xy 256.933673 -56.022052) (xy 256.97089 -56.063589)
			(xy 257.001663 -56.110102) (xy 257.025335 -56.160599) (xy 257.041403 -56.214006) (xy 257.049523 -56.269182)
			(xy 257.050032 -56.297068) (xy 257.049523 -56.324954) (xy 257.041403 -56.38013) (xy 257.025335 -56.433537)
			(xy 257.001663 -56.484034) (xy 256.97089 -56.530547) (xy 256.933673 -56.572084) (xy 256.890805 -56.607759)
			(xy 256.843199 -56.636813) (xy 256.79187 -56.658625) (xy 256.737913 -56.672731) (xy 256.682476 -56.678831)
			(xy 256.626742 -56.676794) (xy 256.571899 -56.666664) (xy 256.519115 -56.648657) (xy 256.469515 -56.623156)
			(xy 256.424157 -56.590705) (xy 256.384008 -56.551996) (xy 256.349922 -56.507853) (xy 256.322626 -56.459218)
			(xy 256.302703 -56.407127) (xy 256.290577 -56.35269) (xy 256.286506 -56.297068) (xy 255.944654 -56.297068)
			(xy 255.944654 -56.341052) (xy 255.936898 -56.395003) (xy 255.921542 -56.4473) (xy 255.898901 -56.49688)
			(xy 255.869435 -56.542733) (xy 255.833743 -56.583926) (xy 255.792552 -56.61962) (xy 255.746701 -56.64909)
			(xy 255.697122 -56.671734) (xy 255.644826 -56.687093) (xy 255.590876 -56.694853) (xy 255.563624 -56.69534)
			(xy 255.536254 -56.694874) (xy 255.482074 -56.687059) (xy 255.42957 -56.67157) (xy 255.379823 -56.648728)
			(xy 255.333857 -56.619002) (xy 255.312926 -56.60136) (xy 255.312672 -56.601106) (xy 255.305568 -56.595544)
			(xy 255.288665 -56.589282) (xy 255.279652 -56.588914) (xy 255.212596 -56.588914) (xy 255.203579 -56.589266)
			(xy 255.186661 -56.595517) (xy 255.179576 -56.601106) (xy 255.179576 -56.60136) (xy 255.179322 -56.60136)
			(xy 255.158389 -56.619001) (xy 255.112421 -56.648725) (xy 255.062675 -56.671571) (xy 255.010173 -56.687067)
			(xy 254.955995 -56.694896) (xy 254.901253 -56.694896) (xy 254.847075 -56.687067) (xy 254.794573 -56.671571)
			(xy 254.744827 -56.648725) (xy 254.698859 -56.619001) (xy 254.677926 -56.60136) (xy 254.677672 -56.601106)
			(xy 254.670568 -56.595544) (xy 254.653665 -56.589282) (xy 254.644652 -56.588914) (xy 254.577596 -56.588914)
			(xy 254.568579 -56.589266) (xy 254.551661 -56.595517) (xy 254.544576 -56.601106) (xy 254.544068 -56.60136)
			(xy 254.531333 -56.612303) (xy 254.504242 -56.632145) (xy 254.489966 -56.640984) (xy 254.481076 -56.646318)
			(xy 254.468884 -56.663336) (xy 254.448564 -56.756554) (xy 254.452882 -56.777128) (xy 254.458724 -56.785764)
			(xy 254.474714 -56.809834) (xy 254.500058 -56.861764) (xy 254.517286 -56.91692) (xy 254.526005 -56.974042)
			(xy 254.526542 -57.002934) (xy 254.526056 -57.030185) (xy 254.5183 -57.084133) (xy 254.502945 -57.136428)
			(xy 254.480303 -57.186005) (xy 254.450837 -57.231855) (xy 254.415146 -57.273046) (xy 254.373955 -57.308737)
			(xy 254.328105 -57.338203) (xy 254.278528 -57.360845) (xy 254.226233 -57.3762) (xy 254.172285 -57.383956)
			(xy 254.117783 -57.383956) (xy 254.063835 -57.3762) (xy 254.01154 -57.360845) (xy 253.961963 -57.338203)
			(xy 253.916113 -57.308737) (xy 253.874922 -57.273046) (xy 253.839231 -57.231855) (xy 253.809765 -57.186005)
			(xy 253.787123 -57.136428) (xy 253.771768 -57.084133) (xy 253.764012 -57.030185) (xy 253.763526 -57.002934)
			(xy 246.440871 -57.002934) (xy 246.416875 -57.043389) (xy 246.401336 -57.06364) (xy 246.401082 -57.063894)
			(xy 246.397526 -57.068466) (xy 246.391938 -57.079896) (xy 246.389652 -57.090056) (xy 246.389652 -57.117996)
			(xy 246.38954 -57.123093) (xy 246.387493 -57.133079) (xy 246.385588 -57.137808) (xy 246.37873 -57.153556)
			(xy 246.378476 -57.154318) (xy 246.375936 -57.159906) (xy 246.37492 -57.167526) (xy 246.37492 -57.179718)
			(xy 246.37619 -57.189624) (xy 246.382286 -57.201816) (xy 246.386858 -57.207404) (xy 246.38762 -57.208166)
			(xy 246.389144 -57.209944) (xy 246.390414 -57.211468) (xy 246.391938 -57.212992) (xy 246.394224 -57.215786)
			(xy 246.400574 -57.22366) (xy 246.404892 -57.229248) (xy 246.408702 -57.234328) (xy 246.426335 -57.259124)
			(xy 246.454333 -57.313139) (xy 246.473402 -57.370914) (xy 246.483059 -57.430984) (xy 246.483632 -57.461404)
			(xy 246.483632 -57.464198) (xy 246.483632 -57.47131) (xy 246.482897 -57.48528) (xy 262.805924 -57.48528)
			(xy 262.809995 -57.429658) (xy 262.822121 -57.375221) (xy 262.842044 -57.32313) (xy 262.86934 -57.274495)
			(xy 262.903426 -57.230352) (xy 262.943575 -57.191643) (xy 262.988933 -57.159192) (xy 263.038533 -57.133691)
			(xy 263.091317 -57.115684) (xy 263.14616 -57.105554) (xy 263.201894 -57.103517) (xy 263.257331 -57.109617)
			(xy 263.311288 -57.123723) (xy 263.362617 -57.145535) (xy 263.410223 -57.174589) (xy 263.453091 -57.210264)
			(xy 263.490308 -57.251801) (xy 263.521081 -57.298314) (xy 263.544753 -57.348811) (xy 263.560821 -57.402218)
			(xy 263.568941 -57.457394) (xy 263.56945 -57.48528) (xy 263.568941 -57.513166) (xy 263.560821 -57.568342)
			(xy 263.544753 -57.621749) (xy 263.521081 -57.672246) (xy 263.490308 -57.718759) (xy 263.453091 -57.760296)
			(xy 263.410223 -57.795971) (xy 263.362617 -57.825025) (xy 263.311288 -57.846837) (xy 263.257331 -57.860943)
			(xy 263.201894 -57.867043) (xy 263.14616 -57.865006) (xy 263.091317 -57.854876) (xy 263.038533 -57.836869)
			(xy 262.988933 -57.811368) (xy 262.943575 -57.778917) (xy 262.903426 -57.740208) (xy 262.86934 -57.696065)
			(xy 262.842044 -57.64743) (xy 262.822121 -57.595339) (xy 262.809995 -57.540902) (xy 262.805924 -57.48528)
			(xy 246.482897 -57.48528) (xy 246.482616 -57.490614) (xy 246.482362 -57.493662) (xy 246.481391 -57.504013)
			(xy 246.478467 -57.524598) (xy 246.47652 -57.53481) (xy 246.469747 -57.566095) (xy 246.447152 -57.62598)
			(xy 246.431562 -57.653936) (xy 246.422926 -57.667906) (xy 246.403622 -57.695338) (xy 246.40286 -57.6961)
			(xy 246.397272 -57.704482) (xy 246.393821 -57.71054) (xy 246.389966 -57.723933) (xy 246.389652 -57.730898)
			(xy 246.389652 -57.752996) (xy 246.38954 -57.758093) (xy 246.387493 -57.768079) (xy 246.385588 -57.772808)
			(xy 246.37873 -57.788556) (xy 246.378476 -57.789318) (xy 246.375936 -57.794906) (xy 246.37492 -57.802526)
			(xy 246.37492 -57.814718) (xy 246.37619 -57.824624) (xy 246.382286 -57.836816) (xy 246.386858 -57.842404)
			(xy 246.38762 -57.843166) (xy 246.389144 -57.844944) (xy 246.390414 -57.846468) (xy 246.391938 -57.847992)
			(xy 246.394224 -57.850786) (xy 246.400574 -57.85866) (xy 246.404892 -57.864248) (xy 246.408702 -57.869328)
			(xy 246.426335 -57.894124) (xy 246.454333 -57.948139) (xy 246.473402 -58.005914) (xy 246.483059 -58.065984)
			(xy 246.483632 -58.096404) (xy 246.483632 -58.099198) (xy 246.483632 -58.10631) (xy 246.482616 -58.125614)
			(xy 246.482362 -58.128662) (xy 246.481391 -58.139013) (xy 246.478467 -58.159598) (xy 246.47652 -58.16981)
			(xy 246.469747 -58.201095) (xy 246.447152 -58.26098) (xy 246.431562 -58.288936) (xy 246.422926 -58.302906)
			(xy 246.403622 -58.330338) (xy 246.40286 -58.3311) (xy 246.397272 -58.339482) (xy 246.393821 -58.34554)
			(xy 246.389966 -58.358933) (xy 246.389652 -58.365898) (xy 246.389652 -58.387234) (xy 246.389508 -58.392673)
			(xy 246.387198 -58.403304) (xy 246.38508 -58.408316) (xy 246.37873 -58.420508) (xy 246.376563 -58.425446)
			(xy 246.37413 -58.435949) (xy 246.373904 -58.441336) (xy 246.373904 -58.444892) (xy 246.374412 -58.450734)
			(xy 246.375682 -58.457338) (xy 246.38254 -58.471816) (xy 246.387366 -58.47715) (xy 246.405435 -58.498238)
			(xy 246.435923 -58.544652) (xy 246.459376 -58.594988) (xy 246.475301 -58.648187) (xy 246.479871 -58.679334)
			(xy 254.195326 -58.679334) (xy 254.195741 -58.653018) (xy 254.202985 -58.600887) (xy 254.217314 -58.550243)
			(xy 254.238456 -58.502044) (xy 254.266012 -58.457202) (xy 254.29946 -58.416565) (xy 254.318516 -58.39841)
			(xy 254.325918 -58.390889) (xy 254.334442 -58.371608) (xy 254.335026 -58.361072) (xy 254.335026 -58.286396)
			(xy 254.334505 -58.275846) (xy 254.325963 -58.256551) (xy 254.318516 -58.249058) (xy 254.29945 -58.230913)
			(xy 254.265993 -58.190281) (xy 254.238435 -58.145439) (xy 254.217298 -58.097236) (xy 254.202984 -58.046587)
			(xy 254.195762 -57.994451) (xy 254.195326 -57.968134) (xy 254.195812 -57.940883) (xy 254.203568 -57.886935)
			(xy 254.218923 -57.83464) (xy 254.241565 -57.785063) (xy 254.271031 -57.739213) (xy 254.306722 -57.698022)
			(xy 254.347913 -57.662331) (xy 254.393763 -57.632865) (xy 254.44334 -57.610223) (xy 254.495635 -57.594868)
			(xy 254.549583 -57.587112) (xy 254.604085 -57.587112) (xy 254.658033 -57.594868) (xy 254.710328 -57.610223)
			(xy 254.759905 -57.632865) (xy 254.805755 -57.662331) (xy 254.846946 -57.698022) (xy 254.882637 -57.739213)
			(xy 254.912103 -57.785063) (xy 254.934745 -57.83464) (xy 254.9501 -57.886935) (xy 254.957856 -57.940883)
			(xy 254.958342 -57.968134) (xy 254.957916 -57.99445) (xy 254.950675 -58.046581) (xy 254.943407 -58.072274)
			(xy 258.193538 -58.072274) (xy 258.197609 -58.016652) (xy 258.209735 -57.962215) (xy 258.229658 -57.910124)
			(xy 258.256954 -57.861489) (xy 258.29104 -57.817346) (xy 258.331189 -57.778637) (xy 258.376547 -57.746186)
			(xy 258.426147 -57.720685) (xy 258.478931 -57.702678) (xy 258.533774 -57.692548) (xy 258.589508 -57.690511)
			(xy 258.644945 -57.696611) (xy 258.698902 -57.710717) (xy 258.750231 -57.732529) (xy 258.797837 -57.761583)
			(xy 258.840705 -57.797258) (xy 258.877922 -57.838795) (xy 258.908695 -57.885308) (xy 258.932367 -57.935805)
			(xy 258.948435 -57.989212) (xy 258.956555 -58.044388) (xy 258.957064 -58.072274) (xy 258.956994 -58.076084)
			(xy 263.558018 -58.076084) (xy 263.562089 -58.020462) (xy 263.574215 -57.966025) (xy 263.594138 -57.913934)
			(xy 263.621434 -57.865299) (xy 263.65552 -57.821156) (xy 263.695669 -57.782447) (xy 263.741027 -57.749996)
			(xy 263.790627 -57.724495) (xy 263.843411 -57.706488) (xy 263.898254 -57.696358) (xy 263.953988 -57.694321)
			(xy 264.009425 -57.700421) (xy 264.063382 -57.714527) (xy 264.114711 -57.736339) (xy 264.162317 -57.765393)
			(xy 264.205185 -57.801068) (xy 264.242402 -57.842605) (xy 264.258738 -57.867296) (xy 265.843002 -57.867296)
			(xy 265.847073 -57.811674) (xy 265.859199 -57.757237) (xy 265.879122 -57.705146) (xy 265.906418 -57.656511)
			(xy 265.940504 -57.612368) (xy 265.980653 -57.573659) (xy 266.026011 -57.541208) (xy 266.075611 -57.515707)
			(xy 266.128395 -57.4977) (xy 266.183238 -57.48757) (xy 266.238972 -57.485533) (xy 266.294409 -57.491633)
			(xy 266.348366 -57.505739) (xy 266.399695 -57.527551) (xy 266.447301 -57.556605) (xy 266.490169 -57.59228)
			(xy 266.527386 -57.633817) (xy 266.558159 -57.68033) (xy 266.581831 -57.730827) (xy 266.597899 -57.784234)
			(xy 266.606019 -57.83941) (xy 266.606528 -57.867296) (xy 266.606019 -57.895182) (xy 266.597899 -57.950358)
			(xy 266.581831 -58.003765) (xy 266.558159 -58.054262) (xy 266.527386 -58.100775) (xy 266.490169 -58.142312)
			(xy 266.447301 -58.177987) (xy 266.399695 -58.207041) (xy 266.348366 -58.228853) (xy 266.294409 -58.242959)
			(xy 266.238972 -58.249059) (xy 266.183238 -58.247022) (xy 266.128395 -58.236892) (xy 266.075611 -58.218885)
			(xy 266.026011 -58.193384) (xy 265.980653 -58.160933) (xy 265.940504 -58.122224) (xy 265.906418 -58.078081)
			(xy 265.879122 -58.029446) (xy 265.859199 -57.977355) (xy 265.847073 -57.922918) (xy 265.843002 -57.867296)
			(xy 264.258738 -57.867296) (xy 264.273175 -57.889118) (xy 264.296847 -57.939615) (xy 264.312915 -57.993022)
			(xy 264.321035 -58.048198) (xy 264.321544 -58.076084) (xy 264.321035 -58.10397) (xy 264.312915 -58.159146)
			(xy 264.296847 -58.212553) (xy 264.273175 -58.26305) (xy 264.242402 -58.309563) (xy 264.205185 -58.3511)
			(xy 264.162317 -58.386775) (xy 264.114711 -58.415829) (xy 264.063382 -58.437641) (xy 264.009425 -58.451747)
			(xy 263.953988 -58.457847) (xy 263.898254 -58.45581) (xy 263.843411 -58.44568) (xy 263.790627 -58.427673)
			(xy 263.741027 -58.402172) (xy 263.695669 -58.369721) (xy 263.65552 -58.331012) (xy 263.621434 -58.286869)
			(xy 263.594138 -58.238234) (xy 263.574215 -58.186143) (xy 263.562089 -58.131706) (xy 263.558018 -58.076084)
			(xy 258.956994 -58.076084) (xy 258.956555 -58.10016) (xy 258.948435 -58.155336) (xy 258.932367 -58.208743)
			(xy 258.908695 -58.25924) (xy 258.877922 -58.305753) (xy 258.840705 -58.34729) (xy 258.797837 -58.382965)
			(xy 258.750231 -58.412019) (xy 258.698902 -58.433831) (xy 258.644945 -58.447937) (xy 258.589508 -58.454037)
			(xy 258.533774 -58.452) (xy 258.478931 -58.44187) (xy 258.426147 -58.423863) (xy 258.376547 -58.398362)
			(xy 258.331189 -58.365911) (xy 258.29104 -58.327202) (xy 258.256954 -58.283059) (xy 258.229658 -58.234424)
			(xy 258.209735 -58.182333) (xy 258.197609 -58.127896) (xy 258.193538 -58.072274) (xy 254.943407 -58.072274)
			(xy 254.936349 -58.097225) (xy 254.915209 -58.145424) (xy 254.887655 -58.190266) (xy 254.854208 -58.230903)
			(xy 254.835152 -58.249058) (xy 254.827775 -58.2566) (xy 254.819235 -58.275864) (xy 254.818642 -58.286396)
			(xy 254.818642 -58.361072) (xy 254.819161 -58.371623) (xy 254.827702 -58.390919) (xy 254.835152 -58.39841)
			(xy 254.854215 -58.416558) (xy 254.88767 -58.45719) (xy 254.915226 -58.502032) (xy 254.936363 -58.550235)
			(xy 254.939469 -58.561224) (xy 264.762232 -58.561224) (xy 264.766303 -58.505602) (xy 264.778429 -58.451165)
			(xy 264.798352 -58.399074) (xy 264.825648 -58.350439) (xy 264.859734 -58.306296) (xy 264.899883 -58.267587)
			(xy 264.945241 -58.235136) (xy 264.994841 -58.209635) (xy 265.047625 -58.191628) (xy 265.102468 -58.181498)
			(xy 265.158202 -58.179461) (xy 265.213639 -58.185561) (xy 265.267596 -58.199667) (xy 265.318925 -58.221479)
			(xy 265.366531 -58.250533) (xy 265.409399 -58.286208) (xy 265.446616 -58.327745) (xy 265.477389 -58.374258)
			(xy 265.501061 -58.424755) (xy 265.517129 -58.478162) (xy 265.525249 -58.533338) (xy 265.525758 -58.561224)
			(xy 265.525249 -58.58911) (xy 265.517129 -58.644286) (xy 265.501061 -58.697693) (xy 265.477389 -58.74819)
			(xy 265.446616 -58.794703) (xy 265.409399 -58.83624) (xy 265.366531 -58.871915) (xy 265.318925 -58.900969)
			(xy 265.267596 -58.922781) (xy 265.213639 -58.936887) (xy 265.158202 -58.942987) (xy 265.102468 -58.94095)
			(xy 265.047625 -58.93082) (xy 264.994841 -58.912813) (xy 264.945241 -58.887312) (xy 264.899883 -58.854861)
			(xy 264.859734 -58.816152) (xy 264.825648 -58.772009) (xy 264.798352 -58.723374) (xy 264.778429 -58.671283)
			(xy 264.766303 -58.616846) (xy 264.762232 -58.561224) (xy 254.939469 -58.561224) (xy 254.950679 -58.600883)
			(xy 254.957904 -58.653018) (xy 254.958342 -58.679334) (xy 254.957856 -58.706585) (xy 254.9501 -58.760533)
			(xy 254.934745 -58.812828) (xy 254.912103 -58.862405) (xy 254.882637 -58.908255) (xy 254.846946 -58.949446)
			(xy 254.805755 -58.985137) (xy 254.759905 -59.014603) (xy 254.710328 -59.037245) (xy 254.658033 -59.0526)
			(xy 254.604085 -59.060356) (xy 254.549583 -59.060356) (xy 254.495635 -59.0526) (xy 254.44334 -59.037245)
			(xy 254.393763 -59.014603) (xy 254.347913 -58.985137) (xy 254.306722 -58.949446) (xy 254.271031 -58.908255)
			(xy 254.241565 -58.862405) (xy 254.218923 -58.812828) (xy 254.203568 -58.760533) (xy 254.195812 -58.706585)
			(xy 254.195326 -58.679334) (xy 246.479871 -58.679334) (xy 246.483363 -58.70313) (xy 246.483886 -58.730896)
			(xy 246.483886 -58.731404) (xy 246.483886 -58.737754) (xy 246.483124 -58.752486) (xy 246.482049 -58.768701)
			(xy 246.477472 -58.800877) (xy 246.47398 -58.816748) (xy 246.468229 -58.840266) (xy 246.451566 -58.885725)
			(xy 246.429274 -58.928703) (xy 246.415814 -58.948828) (xy 246.412512 -58.953908) (xy 246.403114 -58.982864)
			(xy 246.403368 -58.987944) (xy 246.421769 -59.174634) (xy 263.293096 -59.174634) (xy 263.297167 -59.119012)
			(xy 263.309293 -59.064575) (xy 263.329216 -59.012484) (xy 263.356512 -58.963849) (xy 263.390598 -58.919706)
			(xy 263.430747 -58.880997) (xy 263.476105 -58.848546) (xy 263.525705 -58.823045) (xy 263.578489 -58.805038)
			(xy 263.633332 -58.794908) (xy 263.689066 -58.792871) (xy 263.744503 -58.798971) (xy 263.79846 -58.813077)
			(xy 263.849789 -58.834889) (xy 263.897395 -58.863943) (xy 263.940263 -58.899618) (xy 263.97748 -58.941155)
			(xy 264.008253 -58.987668) (xy 264.031925 -59.038165) (xy 264.047993 -59.091572) (xy 264.056113 -59.146748)
			(xy 264.056622 -59.174634) (xy 264.056113 -59.20252) (xy 264.047993 -59.257696) (xy 264.031925 -59.311103)
			(xy 264.008253 -59.3616) (xy 263.97748 -59.408113) (xy 263.940263 -59.44965) (xy 263.897395 -59.485325)
			(xy 263.849789 -59.514379) (xy 263.79846 -59.536191) (xy 263.744503 -59.550297) (xy 263.689066 -59.556397)
			(xy 263.633332 -59.55436) (xy 263.578489 -59.54423) (xy 263.525705 -59.526223) (xy 263.476105 -59.500722)
			(xy 263.430747 -59.468271) (xy 263.390598 -59.429562) (xy 263.356512 -59.385419) (xy 263.329216 -59.336784)
			(xy 263.309293 -59.284693) (xy 263.297167 -59.230256) (xy 263.293096 -59.174634) (xy 246.421769 -59.174634)
			(xy 246.49938 -59.962034) (xy 246.502682 -60.006484) (xy 246.502986 -60.01925) (xy 254.335784 -60.01925)
			(xy 254.335784 -59.96475) (xy 254.34354 -59.910804) (xy 254.358894 -59.858511) (xy 254.381534 -59.808935)
			(xy 254.410999 -59.763086) (xy 254.446688 -59.721897) (xy 254.487877 -59.686206) (xy 254.533725 -59.65674)
			(xy 254.5833 -59.634098) (xy 254.635592 -59.618742) (xy 254.689538 -59.610985) (xy 254.716788 -59.610498)
			(xy 254.744158 -59.610972) (xy 254.798337 -59.618788) (xy 254.85084 -59.634275) (xy 254.900587 -59.657115)
			(xy 254.946554 -59.686838) (xy 254.967486 -59.704478) (xy 254.96774 -59.704732) (xy 254.974837 -59.710303)
			(xy 254.991746 -59.716558) (xy 255.00076 -59.716924) (xy 255.067816 -59.716924) (xy 255.076833 -59.716569)
			(xy 255.09375 -59.710319) (xy 255.100836 -59.704732) (xy 255.100836 -59.704478) (xy 255.10109 -59.704478)
			(xy 255.122023 -59.686837) (xy 255.167991 -59.657113) (xy 255.217737 -59.634267) (xy 255.270239 -59.618771)
			(xy 255.324417 -59.610942) (xy 255.379159 -59.610942) (xy 255.433337 -59.618771) (xy 255.485839 -59.634267)
			(xy 255.535585 -59.657113) (xy 255.581553 -59.686837) (xy 255.602486 -59.704478) (xy 255.60274 -59.704732)
			(xy 255.609837 -59.710303) (xy 255.626746 -59.716558) (xy 255.63576 -59.716924) (xy 255.702816 -59.716924)
			(xy 255.711833 -59.716569) (xy 255.72875 -59.710319) (xy 255.735836 -59.704732) (xy 255.735836 -59.704478)
			(xy 255.73609 -59.704478) (xy 255.757012 -59.686827) (xy 255.802988 -59.657117) (xy 255.852738 -59.634284)
			(xy 255.905241 -59.618796) (xy 255.959418 -59.610971) (xy 255.986788 -59.610498) (xy 256.014042 -59.610949)
			(xy 256.067995 -59.618704) (xy 256.120295 -59.634059) (xy 256.169877 -59.656702) (xy 256.215733 -59.68617)
			(xy 256.256928 -59.721864) (xy 256.292623 -59.763058) (xy 256.322093 -59.808912) (xy 256.344736 -59.858494)
			(xy 256.360093 -59.910793) (xy 256.367851 -59.964746) (xy 256.367851 -60.019254) (xy 256.360093 -60.073207)
			(xy 256.344736 -60.125506) (xy 256.322093 -60.175088) (xy 256.292623 -60.220942) (xy 256.256928 -60.262136)
			(xy 256.215733 -60.29783) (xy 256.169877 -60.327298) (xy 256.120295 -60.349941) (xy 256.067995 -60.365296)
			(xy 256.014042 -60.373051) (xy 255.986788 -60.373514) (xy 255.959418 -60.373052) (xy 255.905239 -60.365232)
			(xy 255.852736 -60.349742) (xy 255.802989 -60.3269) (xy 255.757022 -60.297175) (xy 255.73609 -60.279534)
			(xy 255.735836 -60.27928) (xy 255.728745 -60.2737) (xy 255.711832 -60.26745) (xy 255.702816 -60.267088)
			(xy 255.63576 -60.267088) (xy 255.626741 -60.267428) (xy 255.609825 -60.273688) (xy 255.60274 -60.27928)
			(xy 255.602486 -60.279534) (xy 255.581553 -60.297175) (xy 255.535585 -60.326899) (xy 255.485839 -60.349745)
			(xy 255.433337 -60.365241) (xy 255.379159 -60.37307) (xy 255.324417 -60.37307) (xy 255.270239 -60.365241)
			(xy 255.217737 -60.349745) (xy 255.167991 -60.326899) (xy 255.122023 -60.297175) (xy 255.10109 -60.279534)
			(xy 255.100836 -60.27928) (xy 255.093745 -60.2737) (xy 255.076832 -60.26745) (xy 255.067816 -60.267088)
			(xy 255.00076 -60.267088) (xy 254.991741 -60.267428) (xy 254.974825 -60.273688) (xy 254.96774 -60.27928)
			(xy 254.96774 -60.279534) (xy 254.967486 -60.279534) (xy 254.946537 -60.297152) (xy 254.900568 -60.326865)
			(xy 254.850825 -60.349705) (xy 254.798328 -60.365201) (xy 254.744156 -60.373036) (xy 254.716788 -60.373514)
			(xy 254.689538 -60.373015) (xy 254.635592 -60.365258) (xy 254.5833 -60.349902) (xy 254.533725 -60.32726)
			(xy 254.487877 -60.297794) (xy 254.446688 -60.262103) (xy 254.410999 -60.220914) (xy 254.381534 -60.175065)
			(xy 254.358894 -60.125489) (xy 254.34354 -60.073196) (xy 254.335784 -60.01925) (xy 246.502986 -60.01925)
			(xy 246.503952 -60.059824) (xy 246.503952 -60.633356) (xy 265.996926 -60.633356) (xy 266.000997 -60.577734)
			(xy 266.013123 -60.523297) (xy 266.033046 -60.471206) (xy 266.060342 -60.422571) (xy 266.094428 -60.378428)
			(xy 266.134577 -60.339719) (xy 266.179935 -60.307268) (xy 266.229535 -60.281767) (xy 266.282319 -60.26376)
			(xy 266.337162 -60.25363) (xy 266.392896 -60.251593) (xy 266.448333 -60.257693) (xy 266.50229 -60.271799)
			(xy 266.553619 -60.293611) (xy 266.601225 -60.322665) (xy 266.644093 -60.35834) (xy 266.68131 -60.399877)
			(xy 266.712083 -60.44639) (xy 266.735755 -60.496887) (xy 266.751823 -60.550294) (xy 266.759943 -60.60547)
			(xy 266.760452 -60.633356) (xy 266.759943 -60.661242) (xy 266.751823 -60.716418) (xy 266.735755 -60.769825)
			(xy 266.712083 -60.820322) (xy 266.68131 -60.866835) (xy 266.644093 -60.908372) (xy 266.601225 -60.944047)
			(xy 266.553619 -60.973101) (xy 266.50229 -60.994913) (xy 266.448333 -61.009019) (xy 266.392896 -61.015119)
			(xy 266.337162 -61.013082) (xy 266.282319 -61.002952) (xy 266.229535 -60.984945) (xy 266.179935 -60.959444)
			(xy 266.134577 -60.926993) (xy 266.094428 -60.888284) (xy 266.060342 -60.844141) (xy 266.033046 -60.795506)
			(xy 266.013123 -60.743415) (xy 266.000997 -60.688978) (xy 265.996926 -60.633356) (xy 246.503952 -60.633356)
			(xy 246.503952 -61.487812) (xy 264.504422 -61.487812) (xy 264.508493 -61.43219) (xy 264.520619 -61.377753)
			(xy 264.540542 -61.325662) (xy 264.567838 -61.277027) (xy 264.601924 -61.232884) (xy 264.642073 -61.194175)
			(xy 264.687431 -61.161724) (xy 264.737031 -61.136223) (xy 264.789815 -61.118216) (xy 264.844658 -61.108086)
			(xy 264.900392 -61.106049) (xy 264.955829 -61.112149) (xy 265.009786 -61.126255) (xy 265.061115 -61.148067)
			(xy 265.108721 -61.177121) (xy 265.151589 -61.212796) (xy 265.188806 -61.254333) (xy 265.219579 -61.300846)
			(xy 265.243251 -61.351343) (xy 265.259319 -61.40475) (xy 265.267439 -61.459926) (xy 265.267948 -61.487812)
			(xy 265.267439 -61.515698) (xy 265.259319 -61.570874) (xy 265.243251 -61.624281) (xy 265.219579 -61.674778)
			(xy 265.188806 -61.721291) (xy 265.151589 -61.762828) (xy 265.108721 -61.798503) (xy 265.061115 -61.827557)
			(xy 265.009786 -61.849369) (xy 264.955829 -61.863475) (xy 264.900392 -61.869575) (xy 264.844658 -61.867538)
			(xy 264.789815 -61.857408) (xy 264.737031 -61.839401) (xy 264.687431 -61.8139) (xy 264.642073 -61.781449)
			(xy 264.601924 -61.74274) (xy 264.567838 -61.698597) (xy 264.540542 -61.649962) (xy 264.520619 -61.597871)
			(xy 264.508493 -61.543434) (xy 264.504422 -61.487812) (xy 246.503952 -61.487812) (xy 246.503952 -61.85916)
			(xy 246.503952 -61.859668) (xy 246.501849 -62.121034) (xy 262.442196 -62.121034) (xy 262.446267 -62.065412)
			(xy 262.458393 -62.010975) (xy 262.478316 -61.958884) (xy 262.505612 -61.910249) (xy 262.539698 -61.866106)
			(xy 262.579847 -61.827397) (xy 262.625205 -61.794946) (xy 262.674805 -61.769445) (xy 262.727589 -61.751438)
			(xy 262.782432 -61.741308) (xy 262.838166 -61.739271) (xy 262.893603 -61.745371) (xy 262.94756 -61.759477)
			(xy 262.998889 -61.781289) (xy 263.046495 -61.810343) (xy 263.089363 -61.846018) (xy 263.12658 -61.887555)
			(xy 263.157353 -61.934068) (xy 263.181025 -61.984565) (xy 263.197093 -62.037972) (xy 263.205213 -62.093148)
			(xy 263.205722 -62.121034) (xy 263.205213 -62.14892) (xy 263.197093 -62.204096) (xy 263.181025 -62.257503)
			(xy 263.157353 -62.308) (xy 263.12658 -62.354513) (xy 263.089363 -62.39605) (xy 263.046495 -62.431725)
			(xy 262.998889 -62.460779) (xy 262.94756 -62.482591) (xy 262.893603 -62.496697) (xy 262.838166 -62.502797)
			(xy 262.782432 -62.50076) (xy 262.727589 -62.49063) (xy 262.674805 -62.472623) (xy 262.625205 -62.447122)
			(xy 262.579847 -62.414671) (xy 262.539698 -62.375962) (xy 262.505612 -62.331819) (xy 262.478316 -62.283184)
			(xy 262.458393 -62.231093) (xy 262.446267 -62.176656) (xy 262.442196 -62.121034) (xy 246.501849 -62.121034)
			(xy 246.497856 -62.61735) (xy 246.493061 -63.213552) (xy 254.320765 -63.213552) (xy 254.320765 -63.159048)
			(xy 254.328522 -63.105098) (xy 254.343878 -63.052801) (xy 254.36652 -63.003222) (xy 254.395987 -62.95737)
			(xy 254.43168 -62.916179) (xy 254.472872 -62.880486) (xy 254.518724 -62.851019) (xy 254.568303 -62.828377)
			(xy 254.6206 -62.813022) (xy 254.67455 -62.805265) (xy 254.701802 -62.804802) (xy 254.729172 -62.805266)
			(xy 254.783351 -62.813085) (xy 254.835855 -62.828574) (xy 254.885601 -62.851416) (xy 254.931568 -62.881141)
			(xy 254.9525 -62.898782) (xy 254.952754 -62.899036) (xy 254.959847 -62.904613) (xy 254.976759 -62.910865)
			(xy 254.985774 -62.911228) (xy 255.05283 -62.911228) (xy 255.061848 -62.910879) (xy 255.078764 -62.904625)
			(xy 255.08585 -62.899036) (xy 255.08585 -62.898782) (xy 255.086104 -62.898782) (xy 255.107037 -62.881141)
			(xy 255.153005 -62.851417) (xy 255.202751 -62.828571) (xy 255.255253 -62.813075) (xy 255.309431 -62.805246)
			(xy 255.364173 -62.805246) (xy 255.418351 -62.813075) (xy 255.470853 -62.828571) (xy 255.520599 -62.851417)
			(xy 255.566567 -62.881141) (xy 255.5875 -62.898782) (xy 255.587754 -62.899036) (xy 255.594847 -62.904613)
			(xy 255.611759 -62.910865) (xy 255.620774 -62.911228) (xy 255.68783 -62.911228) (xy 255.696848 -62.910879)
			(xy 255.713764 -62.904625) (xy 255.72085 -62.899036) (xy 255.72085 -62.898782) (xy 255.721104 -62.898782)
			(xy 255.742021 -62.881125) (xy 255.787999 -62.851416) (xy 255.83775 -62.828584) (xy 255.890254 -62.813097)
			(xy 255.944432 -62.805274) (xy 255.971802 -62.804802) (xy 255.999054 -62.805268) (xy 256.053003 -62.813025)
			(xy 256.105299 -62.828381) (xy 256.154877 -62.851022) (xy 256.200728 -62.88049) (xy 256.241919 -62.916182)
			(xy 256.277612 -62.957373) (xy 256.307079 -63.003225) (xy 256.32972 -63.052803) (xy 256.339537 -63.086234)
			(xy 259.58749 -63.086234) (xy 259.591561 -63.030612) (xy 259.603687 -62.976175) (xy 259.62361 -62.924084)
			(xy 259.650906 -62.875449) (xy 259.684992 -62.831306) (xy 259.725141 -62.792597) (xy 259.770499 -62.760146)
			(xy 259.820099 -62.734645) (xy 259.872883 -62.716638) (xy 259.927726 -62.706508) (xy 259.98346 -62.704471)
			(xy 260.038897 -62.710571) (xy 260.092854 -62.724677) (xy 260.113012 -62.733243) (xy 265.866051 -62.733243)
			(xy 265.866052 -62.678736) (xy 265.873811 -62.624784) (xy 265.889169 -62.572485) (xy 265.911814 -62.522905)
			(xy 265.941284 -62.477052) (xy 265.97698 -62.43586) (xy 266.018175 -62.400167) (xy 266.06403 -62.3707)
			(xy 266.113612 -62.348059) (xy 266.165912 -62.332705) (xy 266.219865 -62.32495) (xy 266.247118 -62.324488)
			(xy 266.270673 -62.324865) (xy 266.317417 -62.330724) (xy 266.340336 -62.336172) (xy 266.354094 -62.3392)
			(xy 266.382243 -62.338346) (xy 266.40909 -62.329842) (xy 266.432597 -62.314332) (xy 266.450978 -62.292996)
			(xy 266.462837 -62.267452) (xy 266.467274 -62.239642) (xy 266.463952 -62.211676) (xy 266.458954 -62.198504)
			(xy 266.449643 -62.175115) (xy 266.436518 -62.126514) (xy 266.429895 -62.076609) (xy 266.42949 -62.051438)
			(xy 266.429914 -62.024182) (xy 266.437667 -61.970223) (xy 266.45302 -61.917918) (xy 266.475661 -61.868329)
			(xy 266.505128 -61.822468) (xy 266.540823 -61.781267) (xy 266.582018 -61.745566) (xy 266.627874 -61.716091)
			(xy 266.677459 -61.693442) (xy 266.729762 -61.67808) (xy 266.783719 -61.670319) (xy 266.838232 -61.670315)
			(xy 266.89219 -61.67807) (xy 266.944495 -61.693425) (xy 266.994082 -61.716067) (xy 267.039943 -61.745536)
			(xy 267.081142 -61.781233) (xy 267.116842 -61.822429) (xy 267.146315 -61.868286) (xy 267.168963 -61.917871)
			(xy 267.184323 -61.970175) (xy 267.192082 -62.024132) (xy 267.192084 -62.078645) (xy 267.184327 -62.132603)
			(xy 267.168971 -62.184907) (xy 267.146326 -62.234494) (xy 267.116856 -62.280353) (xy 267.081158 -62.321551)
			(xy 267.039961 -62.35725) (xy 266.994102 -62.386722) (xy 266.944516 -62.409367) (xy 266.892212 -62.424725)
			(xy 266.838254 -62.432483) (xy 266.810998 -62.432946) (xy 266.787444 -62.432565) (xy 266.740699 -62.426709)
			(xy 266.71778 -62.421262) (xy 266.704026 -62.418204) (xy 266.675869 -62.419054) (xy 266.649015 -62.427558)
			(xy 266.625502 -62.443071) (xy 266.607118 -62.464415) (xy 266.59526 -62.489966) (xy 266.590828 -62.517785)
			(xy 266.594159 -62.545756) (xy 266.599162 -62.55893) (xy 266.608484 -62.582315) (xy 266.621605 -62.630918)
			(xy 266.628223 -62.680825) (xy 266.628626 -62.705996) (xy 266.628149 -62.733249) (xy 266.620392 -62.787202)
			(xy 266.605036 -62.839501) (xy 266.582393 -62.889082) (xy 266.552925 -62.934936) (xy 266.517231 -62.97613)
			(xy 266.476037 -63.011825) (xy 266.430183 -63.041293) (xy 266.380601 -63.063936) (xy 266.328302 -63.079292)
			(xy 266.27435 -63.087049) (xy 266.219843 -63.087048) (xy 266.165891 -63.079291) (xy 266.113592 -63.063934)
			(xy 266.064011 -63.04129) (xy 266.018158 -63.011821) (xy 265.976965 -62.976125) (xy 265.941271 -62.934931)
			(xy 265.911803 -62.889076) (xy 265.889161 -62.839495) (xy 265.873806 -62.787195) (xy 265.866051 -62.733243)
			(xy 260.113012 -62.733243) (xy 260.144183 -62.746489) (xy 260.191789 -62.775543) (xy 260.234657 -62.811218)
			(xy 260.271874 -62.852755) (xy 260.302647 -62.899268) (xy 260.326319 -62.949765) (xy 260.342387 -63.003172)
			(xy 260.350507 -63.058348) (xy 260.351016 -63.086234) (xy 260.350507 -63.11412) (xy 260.342387 -63.169296)
			(xy 260.326319 -63.222703) (xy 260.302647 -63.2732) (xy 260.302494 -63.273432) (xy 261.776716 -63.273432)
			(xy 261.780787 -63.21781) (xy 261.792913 -63.163373) (xy 261.812836 -63.111282) (xy 261.840132 -63.062647)
			(xy 261.874218 -63.018504) (xy 261.914367 -62.979795) (xy 261.959725 -62.947344) (xy 262.009325 -62.921843)
			(xy 262.062109 -62.903836) (xy 262.116952 -62.893706) (xy 262.172686 -62.891669) (xy 262.228123 -62.897769)
			(xy 262.28208 -62.911875) (xy 262.333409 -62.933687) (xy 262.381015 -62.962741) (xy 262.423883 -62.998416)
			(xy 262.4611 -63.039953) (xy 262.491873 -63.086466) (xy 262.515545 -63.136963) (xy 262.531613 -63.19037)
			(xy 262.539733 -63.245546) (xy 262.540242 -63.273432) (xy 262.539733 -63.301318) (xy 262.531613 -63.356494)
			(xy 262.515545 -63.409901) (xy 262.491873 -63.460398) (xy 262.4611 -63.506911) (xy 262.423883 -63.548448)
			(xy 262.381015 -63.584123) (xy 262.333409 -63.613177) (xy 262.28208 -63.634989) (xy 262.228123 -63.649095)
			(xy 262.172686 -63.655195) (xy 262.116952 -63.653158) (xy 262.062109 -63.643028) (xy 262.009325 -63.625021)
			(xy 261.959725 -63.59952) (xy 261.914367 -63.567069) (xy 261.874218 -63.52836) (xy 261.840132 -63.484217)
			(xy 261.812836 -63.435582) (xy 261.792913 -63.383491) (xy 261.780787 -63.329054) (xy 261.776716 -63.273432)
			(xy 260.302494 -63.273432) (xy 260.271874 -63.319713) (xy 260.234657 -63.36125) (xy 260.191789 -63.396925)
			(xy 260.144183 -63.425979) (xy 260.092854 -63.447791) (xy 260.038897 -63.461897) (xy 259.98346 -63.467997)
			(xy 259.927726 -63.46596) (xy 259.872883 -63.45583) (xy 259.820099 -63.437823) (xy 259.770499 -63.412322)
			(xy 259.725141 -63.379871) (xy 259.684992 -63.341162) (xy 259.650906 -63.297019) (xy 259.62361 -63.248384)
			(xy 259.603687 -63.196293) (xy 259.591561 -63.141856) (xy 259.58749 -63.086234) (xy 256.339537 -63.086234)
			(xy 256.345076 -63.105099) (xy 256.352832 -63.159048) (xy 256.352832 -63.213552) (xy 256.345076 -63.267501)
			(xy 256.32972 -63.319797) (xy 256.307079 -63.369375) (xy 256.277612 -63.415227) (xy 256.241919 -63.456418)
			(xy 256.200728 -63.49211) (xy 256.154877 -63.521578) (xy 256.105299 -63.544219) (xy 256.053003 -63.559575)
			(xy 255.999054 -63.567332) (xy 255.971802 -63.567818) (xy 255.944431 -63.567371) (xy 255.89025 -63.559551)
			(xy 255.837746 -63.544059) (xy 255.787999 -63.521213) (xy 255.742034 -63.491482) (xy 255.721104 -63.473838)
			(xy 255.72085 -63.473584) (xy 255.713755 -63.46801) (xy 255.696845 -63.461756) (xy 255.68783 -63.461392)
			(xy 255.620774 -63.461392) (xy 255.611756 -63.461739) (xy 255.594839 -63.467994) (xy 255.587754 -63.473584)
			(xy 255.5875 -63.473838) (xy 255.566567 -63.491479) (xy 255.520599 -63.521203) (xy 255.470853 -63.544049)
			(xy 255.418351 -63.559545) (xy 255.364173 -63.567374) (xy 255.309431 -63.567374) (xy 255.255253 -63.559545)
			(xy 255.202751 -63.544049) (xy 255.153005 -63.521203) (xy 255.107037 -63.491479) (xy 255.086104 -63.473838)
			(xy 255.08585 -63.473584) (xy 255.078755 -63.46801) (xy 255.061845 -63.461756) (xy 255.05283 -63.461392)
			(xy 254.985774 -63.461392) (xy 254.976756 -63.461739) (xy 254.959839 -63.467994) (xy 254.952754 -63.473584)
			(xy 254.952754 -63.473838) (xy 254.9525 -63.473838) (xy 254.931584 -63.491497) (xy 254.885606 -63.521205)
			(xy 254.835855 -63.544036) (xy 254.783351 -63.559523) (xy 254.729172 -63.567347) (xy 254.701802 -63.567818)
			(xy 254.67455 -63.567335) (xy 254.6206 -63.559578) (xy 254.568303 -63.544223) (xy 254.518724 -63.521581)
			(xy 254.472872 -63.492114) (xy 254.43168 -63.456421) (xy 254.395987 -63.41523) (xy 254.36652 -63.369378)
			(xy 254.343878 -63.319799) (xy 254.328522 -63.267502) (xy 254.320765 -63.213552) (xy 246.493061 -63.213552)
			(xy 246.49176 -63.375286) (xy 246.49176 -65.100962) (xy 252.332488 -65.100962) (xy 252.336559 -65.04534)
			(xy 252.348685 -64.990903) (xy 252.368608 -64.938812) (xy 252.395904 -64.890177) (xy 252.42999 -64.846034)
			(xy 252.470139 -64.807325) (xy 252.515497 -64.774874) (xy 252.565097 -64.749373) (xy 252.617881 -64.731366)
			(xy 252.672724 -64.721236) (xy 252.728458 -64.719199) (xy 252.783895 -64.725299) (xy 252.837852 -64.739405)
			(xy 252.889181 -64.761217) (xy 252.936787 -64.790271) (xy 252.979655 -64.825946) (xy 253.016872 -64.867483)
			(xy 253.047645 -64.913996) (xy 253.071317 -64.964493) (xy 253.087385 -65.0179) (xy 253.095505 -65.073076)
			(xy 253.096014 -65.100962) (xy 253.095592 -65.124076) (xy 264.307318 -65.124076) (xy 264.311389 -65.068454)
			(xy 264.323515 -65.014017) (xy 264.343438 -64.961926) (xy 264.370734 -64.913291) (xy 264.40482 -64.869148)
			(xy 264.444969 -64.830439) (xy 264.490327 -64.797988) (xy 264.539927 -64.772487) (xy 264.592711 -64.75448)
			(xy 264.647554 -64.74435) (xy 264.703288 -64.742313) (xy 264.758725 -64.748413) (xy 264.812682 -64.762519)
			(xy 264.864011 -64.784331) (xy 264.911617 -64.813385) (xy 264.954485 -64.84906) (xy 264.991702 -64.890597)
			(xy 265.022475 -64.93711) (xy 265.046147 -64.987607) (xy 265.062215 -65.041014) (xy 265.070335 -65.09619)
			(xy 265.070844 -65.124076) (xy 265.070335 -65.151962) (xy 265.062215 -65.207138) (xy 265.046147 -65.260545)
			(xy 265.022475 -65.311042) (xy 264.991702 -65.357555) (xy 264.954485 -65.399092) (xy 264.911617 -65.434767)
			(xy 264.864011 -65.463821) (xy 264.812682 -65.485633) (xy 264.758725 -65.499739) (xy 264.703288 -65.505839)
			(xy 264.647554 -65.503802) (xy 264.592711 -65.493672) (xy 264.539927 -65.475665) (xy 264.490327 -65.450164)
			(xy 264.444969 -65.417713) (xy 264.40482 -65.379004) (xy 264.370734 -65.334861) (xy 264.343438 -65.286226)
			(xy 264.323515 -65.234135) (xy 264.311389 -65.179698) (xy 264.307318 -65.124076) (xy 253.095592 -65.124076)
			(xy 253.095505 -65.128848) (xy 253.087385 -65.184024) (xy 253.071317 -65.237431) (xy 253.047645 -65.287928)
			(xy 253.016872 -65.334441) (xy 252.979655 -65.375978) (xy 252.936787 -65.411653) (xy 252.889181 -65.440707)
			(xy 252.837852 -65.462519) (xy 252.783895 -65.476625) (xy 252.728458 -65.482725) (xy 252.672724 -65.480688)
			(xy 252.617881 -65.470558) (xy 252.565097 -65.452551) (xy 252.515497 -65.42705) (xy 252.470139 -65.394599)
			(xy 252.42999 -65.35589) (xy 252.395904 -65.311747) (xy 252.368608 -65.263112) (xy 252.348685 -65.211021)
			(xy 252.336559 -65.156584) (xy 252.332488 -65.100962) (xy 246.49176 -65.100962) (xy 246.49176 -65.466468)
			(xy 246.49176 -65.466976) (xy 246.490998 -65.523872) (xy 246.490744 -65.554098) (xy 246.491049 -65.562588)
			(xy 246.496596 -65.578634) (xy 246.507107 -65.591967) (xy 246.514112 -65.59677) (xy 246.516398 -65.59804)
			(xy 246.5197 -65.599818) (xy 246.531221 -65.604608) (xy 246.556118 -65.603527) (xy 246.567198 -65.597786)
			(xy 246.575326 -65.592706) (xy 246.591836 -65.574926) (xy 246.594884 -65.569592) (xy 246.595138 -65.569084)
			(xy 246.609782 -65.54411) (xy 246.645425 -65.498492) (xy 246.687537 -65.458768) (xy 246.735156 -65.425846)
			(xy 246.787194 -65.400478) (xy 246.842461 -65.383244) (xy 246.899694 -65.374538) (xy 246.92864 -65.374012)
			(xy 246.955888 -65.374501) (xy 247.009828 -65.382262) (xy 247.062116 -65.397619) (xy 247.111685 -65.420262)
			(xy 247.157528 -65.449727) (xy 247.198711 -65.485417) (xy 247.234397 -65.526604) (xy 247.263858 -65.57245)
			(xy 247.286495 -65.622022) (xy 247.301847 -65.674311) (xy 247.309602 -65.728252) (xy 247.309602 -65.782748)
			(xy 247.301847 -65.836689) (xy 247.286495 -65.888978) (xy 247.263858 -65.93855) (xy 247.234397 -65.984396)
			(xy 247.198711 -66.025583) (xy 247.157528 -66.061273) (xy 247.111685 -66.090738) (xy 247.062116 -66.113381)
			(xy 247.009828 -66.128738) (xy 246.955888 -66.136499) (xy 246.92864 -66.137028) (xy 246.899377 -66.136499)
			(xy 246.841536 -66.127567) (xy 246.785738 -66.109908) (xy 246.733292 -66.083934) (xy 246.685427 -66.050256)
			(xy 246.663972 -66.030348) (xy 246.657114 -66.023744) (xy 246.636286 -66.0146) (xy 246.632191 -66.013066)
			(xy 246.623634 -66.011273) (xy 246.619268 -66.011044) (xy 246.606568 -66.011044) (xy 246.547894 -66.034666)
			(xy 246.547386 -66.034666) (xy 246.514112 -66.047874) (xy 246.507708 -66.050935) (xy 246.496757 -66.059957)
			(xy 246.492522 -66.065654) (xy 246.488204 -66.07175) (xy 246.483886 -66.086228) (xy 246.483886 -66.094356)
			(xy 246.478298 -66.54292) (xy 246.47779 -66.589402) (xy 246.478173 -66.59978) (xy 246.486161 -66.618929)
			(xy 246.493284 -66.626486) (xy 246.540782 -66.67246) (xy 246.546116 -66.677794) (xy 246.549951 -66.681365)
			(xy 246.558788 -66.686994) (xy 246.563642 -66.68897) (xy 246.573294 -66.692526) (xy 246.583708 -66.692018)
			(xy 246.59971 -66.691764) (xy 246.630555 -66.692356) (xy 246.691443 -66.702275) (xy 246.749944 -66.721853)
			(xy 246.77751 -66.735706) (xy 246.782082 -66.737992) (xy 246.79529 -66.741294) (xy 246.800468 -66.742528)
			(xy 246.811099 -66.743039) (xy 246.816372 -66.74231) (xy 246.822468 -66.741294) (xy 246.826024 -66.740024)
			(xy 246.855455 -66.730773) (xy 246.916337 -66.720812) (xy 246.947182 -66.720212) (xy 246.949214 -66.720212)
			(xy 246.971198 -66.720533) (xy 247.01487 -66.72562) (xy 247.036336 -66.730372) (xy 247.038876 -66.731134)
			(xy 247.050814 -66.732658) (xy 247.051068 -66.732658) (xy 247.072404 -66.727832) (xy 247.075198 -66.726562)
			(xy 247.085522 -66.721956) (xy 247.106618 -66.713823) (xy 247.117362 -66.710306) (xy 247.11787 -66.710306)
			(xy 247.135468 -66.704784) (xy 247.171473 -66.696767) (xy 247.189752 -66.694304) (xy 247.19661 -66.693542)
			(xy 247.23471 -66.691764) (xy 247.235218 -66.691764) (xy 247.265775 -66.69237) (xy 247.326106 -66.702122)
			(xy 247.384108 -66.721375) (xy 247.411494 -66.734944) (xy 247.422416 -66.739262) (xy 247.43029 -66.741294)
			(xy 247.435479 -66.742475) (xy 247.446112 -66.742862) (xy 247.451372 -66.742056) (xy 247.457214 -66.74104)
			(xy 247.46077 -66.73977) (xy 247.490096 -66.730651) (xy 247.550715 -66.720819) (xy 247.58142 -66.720212)
			(xy 247.581928 -66.720212) (xy 247.58269 -66.720212) (xy 247.609943 -66.720675) (xy 247.663894 -66.728431)
			(xy 247.716192 -66.743786) (xy 247.765772 -66.766428) (xy 247.811625 -66.795896) (xy 247.852817 -66.83159)
			(xy 247.88851 -66.872783) (xy 247.917977 -66.918637) (xy 247.940618 -66.968218) (xy 247.955972 -67.020516)
			(xy 247.963726 -67.074467) (xy 247.964198 -67.10172) (xy 247.96372 -67.128832) (xy 247.95604 -67.182508)
			(xy 247.940836 -67.234557) (xy 247.918416 -67.283928) (xy 247.889232 -67.329627) (xy 247.85387 -67.370734)
			(xy 247.813045 -67.406419) (xy 247.767578 -67.435964) (xy 247.718385 -67.458774) (xy 247.666459 -67.474389)
			(xy 247.612845 -67.482494) (xy 247.585738 -67.483228) (xy 247.582182 -67.483228) (xy 247.55153 -67.482615)
			(xy 247.491016 -67.472807) (xy 247.432849 -67.453447) (xy 247.405398 -67.439794) (xy 247.400064 -67.437)
			(xy 247.386348 -67.433444) (xy 247.381289 -67.43228) (xy 247.370923 -67.431771) (xy 247.365774 -67.432428)
			(xy 247.360186 -67.433444) (xy 247.359424 -67.433698) (xy 247.329182 -67.443508) (xy 247.266496 -67.454101)
			(xy 247.23471 -67.45478) (xy 247.233948 -67.45478) (xy 247.211965 -67.454457) (xy 247.168294 -67.449365)
			(xy 247.146826 -67.44462) (xy 247.144032 -67.443858) (xy 247.132094 -67.442334) (xy 247.13184 -67.442334)
			(xy 247.110504 -67.44716) (xy 247.10771 -67.44843) (xy 247.082576 -67.459439) (xy 247.029943 -67.474951)
			(xy 246.975634 -67.482781) (xy 246.948198 -67.483228) (xy 246.935498 -67.483228) (xy 246.906627 -67.481796)
			(xy 246.849785 -67.471294) (xy 246.795183 -67.452321) (xy 246.769382 -67.439286) (xy 246.768366 -67.438778)
			(xy 246.765318 -67.437254) (xy 246.765064 -67.437254) (xy 246.751602 -67.433698) (xy 246.746413 -67.432518)
			(xy 246.735781 -67.432133) (xy 246.73052 -67.432936) (xy 246.724678 -67.433952) (xy 246.721122 -67.435222)
			(xy 246.691797 -67.444347) (xy 246.631178 -67.45418) (xy 246.600472 -67.45478) (xy 246.599964 -67.45478)
			(xy 246.59971 -67.45478) (xy 246.573802 -67.454018) (xy 246.563134 -67.45351) (xy 246.553736 -67.456812)
			(xy 246.548981 -67.458612) (xy 246.540272 -67.463857) (xy 246.536464 -67.467226) (xy 246.513848 -67.488054)
			(xy 250.979176 -67.488054) (xy 250.983247 -67.432432) (xy 250.995373 -67.377995) (xy 251.015296 -67.325904)
			(xy 251.042592 -67.277269) (xy 251.076678 -67.233126) (xy 251.116827 -67.194417) (xy 251.162185 -67.161966)
			(xy 251.211785 -67.136465) (xy 251.264569 -67.118458) (xy 251.319412 -67.108328) (xy 251.375146 -67.106291)
			(xy 251.430583 -67.112391) (xy 251.48454 -67.126497) (xy 251.535869 -67.148309) (xy 251.583475 -67.177363)
			(xy 251.626343 -67.213038) (xy 251.66356 -67.254575) (xy 251.694333 -67.301088) (xy 251.718005 -67.351585)
			(xy 251.734073 -67.404992) (xy 251.742193 -67.460168) (xy 251.742702 -67.488054) (xy 251.742193 -67.51594)
			(xy 251.739008 -67.537584) (xy 252.271274 -67.537584) (xy 252.275345 -67.481962) (xy 252.287471 -67.427525)
			(xy 252.307394 -67.375434) (xy 252.33469 -67.326799) (xy 252.368776 -67.282656) (xy 252.408925 -67.243947)
			(xy 252.454283 -67.211496) (xy 252.503883 -67.185995) (xy 252.556667 -67.167988) (xy 252.61151 -67.157858)
			(xy 252.667244 -67.155821) (xy 252.722681 -67.161921) (xy 252.776638 -67.176027) (xy 252.827967 -67.197839)
			(xy 252.875573 -67.226893) (xy 252.918441 -67.262568) (xy 252.955658 -67.304105) (xy 252.986431 -67.350618)
			(xy 253.010103 -67.401115) (xy 253.026171 -67.454522) (xy 253.034291 -67.509698) (xy 253.0348 -67.537584)
			(xy 253.034291 -67.56547) (xy 253.030246 -67.592956) (xy 253.545338 -67.592956) (xy 253.549409 -67.537334)
			(xy 253.561535 -67.482897) (xy 253.581458 -67.430806) (xy 253.608754 -67.382171) (xy 253.64284 -67.338028)
			(xy 253.682989 -67.299319) (xy 253.728347 -67.266868) (xy 253.777947 -67.241367) (xy 253.830731 -67.22336)
			(xy 253.885574 -67.21323) (xy 253.941308 -67.211193) (xy 253.996745 -67.217293) (xy 254.050702 -67.231399)
			(xy 254.102031 -67.253211) (xy 254.149637 -67.282265) (xy 254.192505 -67.31794) (xy 254.229722 -67.359477)
			(xy 254.260495 -67.40599) (xy 254.284167 -67.456487) (xy 254.300235 -67.509894) (xy 254.308352 -67.565048)
			(xy 256.646716 -67.565048) (xy 256.646716 -67.510552) (xy 256.654471 -67.456612) (xy 256.669824 -67.404324)
			(xy 256.692461 -67.354753) (xy 256.721923 -67.308908) (xy 256.757609 -67.267723) (xy 256.798792 -67.232035)
			(xy 256.844636 -67.202571) (xy 256.894205 -67.179931) (xy 256.946492 -67.164576) (xy 257.000432 -67.156818)
			(xy 257.02768 -67.15633) (xy 257.05505 -67.1568) (xy 257.109229 -67.164616) (xy 257.161733 -67.180104)
			(xy 257.21148 -67.202945) (xy 257.257446 -67.232669) (xy 257.278378 -67.25031) (xy 257.278632 -67.250564)
			(xy 257.285728 -67.256136) (xy 257.302638 -67.26239) (xy 257.311652 -67.262756) (xy 257.378708 -67.262756)
			(xy 257.387726 -67.262412) (xy 257.404644 -67.256156) (xy 257.411728 -67.250564) (xy 257.411728 -67.25031)
			(xy 257.411982 -67.25031) (xy 257.432911 -67.232667) (xy 257.478885 -67.202956) (xy 257.528633 -67.18012)
			(xy 257.581134 -67.16463) (xy 257.635311 -67.156803) (xy 257.66268 -67.15633) (xy 257.689937 -67.156716)
			(xy 257.743895 -67.164471) (xy 257.796201 -67.179827) (xy 257.845788 -67.20247) (xy 257.891648 -67.231941)
			(xy 257.932848 -67.267638) (xy 257.968547 -67.308836) (xy 257.99802 -67.354694) (xy 258.020666 -67.404281)
			(xy 258.036025 -67.456585) (xy 258.043783 -67.510543) (xy 258.043783 -67.565057) (xy 258.036025 -67.619015)
			(xy 258.020666 -67.671319) (xy 257.99802 -67.720906) (xy 257.968547 -67.766764) (xy 257.932848 -67.807962)
			(xy 257.891648 -67.843659) (xy 257.845788 -67.87313) (xy 257.796201 -67.895773) (xy 257.743895 -67.911129)
			(xy 257.689937 -67.918884) (xy 257.66268 -67.919346) (xy 257.635309 -67.918905) (xy 257.581128 -67.911083)
			(xy 257.528624 -67.895589) (xy 257.478878 -67.872741) (xy 257.432912 -67.84301) (xy 257.411982 -67.825366)
			(xy 257.411728 -67.825112) (xy 257.404637 -67.819532) (xy 257.387724 -67.813281) (xy 257.378708 -67.81292)
			(xy 257.311652 -67.81292) (xy 257.302637 -67.813298) (xy 257.28572 -67.81953) (xy 257.278632 -67.825112)
			(xy 257.278632 -67.825366) (xy 257.278378 -67.825366) (xy 257.257423 -67.842977) (xy 257.211457 -67.872694)
			(xy 257.161715 -67.895536) (xy 257.10922 -67.911034) (xy 257.055048 -67.918869) (xy 257.02768 -67.919346)
			(xy 257.000432 -67.918782) (xy 256.946492 -67.911024) (xy 256.894205 -67.895669) (xy 256.844636 -67.873029)
			(xy 256.798792 -67.843565) (xy 256.757609 -67.807877) (xy 256.721923 -67.766692) (xy 256.692461 -67.720847)
			(xy 256.669824 -67.671276) (xy 256.654471 -67.618988) (xy 256.646716 -67.565048) (xy 254.308352 -67.565048)
			(xy 254.308355 -67.56507) (xy 254.308864 -67.592956) (xy 254.308355 -67.620842) (xy 254.300235 -67.676018)
			(xy 254.284167 -67.729425) (xy 254.260495 -67.779922) (xy 254.229722 -67.826435) (xy 254.192505 -67.867972)
			(xy 254.149637 -67.903647) (xy 254.102031 -67.932701) (xy 254.050702 -67.954513) (xy 253.996745 -67.968619)
			(xy 253.941308 -67.974719) (xy 253.885574 -67.972682) (xy 253.830731 -67.962552) (xy 253.777947 -67.944545)
			(xy 253.728347 -67.919044) (xy 253.682989 -67.886593) (xy 253.64284 -67.847884) (xy 253.608754 -67.803741)
			(xy 253.581458 -67.755106) (xy 253.561535 -67.703015) (xy 253.549409 -67.648578) (xy 253.545338 -67.592956)
			(xy 253.030246 -67.592956) (xy 253.026171 -67.620646) (xy 253.010103 -67.674053) (xy 252.986431 -67.72455)
			(xy 252.955658 -67.771063) (xy 252.918441 -67.8126) (xy 252.875573 -67.848275) (xy 252.827967 -67.877329)
			(xy 252.776638 -67.899141) (xy 252.722681 -67.913247) (xy 252.667244 -67.919347) (xy 252.61151 -67.91731)
			(xy 252.556667 -67.90718) (xy 252.503883 -67.889173) (xy 252.454283 -67.863672) (xy 252.408925 -67.831221)
			(xy 252.368776 -67.792512) (xy 252.33469 -67.748369) (xy 252.307394 -67.699734) (xy 252.287471 -67.647643)
			(xy 252.275345 -67.593206) (xy 252.271274 -67.537584) (xy 251.739008 -67.537584) (xy 251.734073 -67.571116)
			(xy 251.718005 -67.624523) (xy 251.694333 -67.67502) (xy 251.66356 -67.721533) (xy 251.626343 -67.76307)
			(xy 251.583475 -67.798745) (xy 251.535869 -67.827799) (xy 251.48454 -67.849611) (xy 251.430583 -67.863717)
			(xy 251.375146 -67.869817) (xy 251.319412 -67.86778) (xy 251.264569 -67.85765) (xy 251.211785 -67.839643)
			(xy 251.162185 -67.814142) (xy 251.116827 -67.781691) (xy 251.076678 -67.742982) (xy 251.042592 -67.698839)
			(xy 251.015296 -67.650204) (xy 250.995373 -67.598113) (xy 250.983247 -67.543676) (xy 250.979176 -67.488054)
			(xy 246.513848 -67.488054) (xy 246.481854 -67.517518) (xy 246.4746 -67.524887) (xy 246.466222 -67.543771)
			(xy 246.465598 -67.554094) (xy 246.462296 -67.81165) (xy 246.455946 -68.338192) (xy 246.452827 -68.586604)
			(xy 248.825258 -68.586604) (xy 248.825712 -68.559233) (xy 248.833531 -68.505053) (xy 248.849022 -68.452549)
			(xy 248.871867 -68.402803) (xy 248.901595 -68.356837) (xy 248.919238 -68.335906) (xy 248.919492 -68.335652)
			(xy 248.925062 -68.328554) (xy 248.931319 -68.311646) (xy 248.931684 -68.302632) (xy 248.931684 -68.235576)
			(xy 248.931342 -68.226558) (xy 248.925084 -68.209641) (xy 248.919492 -68.202556) (xy 248.919238 -68.202556)
			(xy 248.919238 -68.202302) (xy 248.901592 -68.181375) (xy 248.87188 -68.135401) (xy 248.849045 -68.085653)
			(xy 248.833555 -68.033151) (xy 248.82573 -67.978974) (xy 248.825258 -67.951604) (xy 248.825781 -67.924354)
			(xy 248.833536 -67.87041) (xy 248.848889 -67.818118) (xy 248.871528 -67.768543) (xy 248.90099 -67.722694)
			(xy 248.936678 -67.681505) (xy 248.977864 -67.645813) (xy 249.023709 -67.616346) (xy 249.073282 -67.593703)
			(xy 249.125573 -67.578345) (xy 249.179516 -67.570584) (xy 249.206766 -67.570096) (xy 249.233081 -67.570521)
			(xy 249.285212 -67.577764) (xy 249.335855 -67.592092) (xy 249.384054 -67.613233) (xy 249.428896 -67.640786)
			(xy 249.469534 -67.674231) (xy 249.48769 -67.693286) (xy 249.495215 -67.700683) (xy 249.514492 -67.709211)
			(xy 249.525028 -67.709796) (xy 249.599704 -67.709796) (xy 249.610256 -67.709284) (xy 249.629551 -67.700737)
			(xy 249.637042 -67.693286) (xy 249.655181 -67.674214) (xy 249.695815 -67.640759) (xy 249.740659 -67.613203)
			(xy 249.788863 -67.592067) (xy 249.839513 -67.577753) (xy 249.891649 -67.570532) (xy 249.917966 -67.570096)
			(xy 249.945335 -67.570583) (xy 249.999514 -67.578396) (xy 250.052016 -67.59388) (xy 250.101764 -67.616717)
			(xy 250.147732 -67.646437) (xy 250.168664 -67.664076) (xy 250.168918 -67.66433) (xy 250.175993 -67.669934)
			(xy 250.192919 -67.676169) (xy 250.201938 -67.676522) (xy 250.268994 -67.676522) (xy 250.27801 -67.676157)
			(xy 250.294927 -67.669914) (xy 250.302014 -67.66433) (xy 250.302014 -67.664076) (xy 250.302268 -67.664076)
			(xy 250.323198 -67.646435) (xy 250.369172 -67.616724) (xy 250.41892 -67.593889) (xy 250.471421 -67.578398)
			(xy 250.525597 -67.57057) (xy 250.552966 -67.570096) (xy 250.580218 -67.570587) (xy 250.634168 -67.578339)
			(xy 250.686466 -67.593691) (xy 250.736046 -67.61633) (xy 250.7819 -67.645795) (xy 250.823093 -67.681486)
			(xy 250.858787 -67.722676) (xy 250.888255 -67.768527) (xy 250.910898 -67.818106) (xy 250.926254 -67.870402)
			(xy 250.934011 -67.924352) (xy 250.934474 -67.951604) (xy 250.934017 -67.978975) (xy 250.926198 -68.033154)
			(xy 250.910707 -68.085658) (xy 250.887863 -68.135405) (xy 250.858136 -68.181371) (xy 250.840494 -68.202302)
			(xy 250.84024 -68.202556) (xy 250.834659 -68.209646) (xy 250.82841 -68.22656) (xy 250.828048 -68.235576)
			(xy 250.828048 -68.302632) (xy 250.828379 -68.311652) (xy 250.834643 -68.328569) (xy 250.84024 -68.335652)
			(xy 250.840494 -68.335652) (xy 250.840494 -68.335906) (xy 250.858148 -68.356826) (xy 250.887858 -68.402802)
			(xy 250.910691 -68.452552) (xy 250.926179 -68.505056) (xy 250.934002 -68.559234) (xy 250.934474 -68.586604)
			(xy 250.934048 -68.613858) (xy 250.92629 -68.667813) (xy 250.910932 -68.720113) (xy 250.894299 -68.75653)
			(xy 254.370332 -68.75653) (xy 254.370808 -68.72916) (xy 254.378622 -68.674981) (xy 254.394108 -68.622478)
			(xy 254.416948 -68.572731) (xy 254.446671 -68.526764) (xy 254.464312 -68.505832) (xy 254.464566 -68.505578)
			(xy 254.470176 -68.498508) (xy 254.476407 -68.481578) (xy 254.476758 -68.472558) (xy 254.476758 -68.405502)
			(xy 254.476409 -68.396484) (xy 254.470157 -68.379567) (xy 254.464566 -68.372482) (xy 254.464312 -68.372482)
			(xy 254.464312 -68.372228) (xy 254.446674 -68.351295) (xy 254.416962 -68.305322) (xy 254.394126 -68.255575)
			(xy 254.378634 -68.203075) (xy 254.370806 -68.148899) (xy 254.370332 -68.12153) (xy 254.370783 -68.094276)
			(xy 254.378537 -68.040323) (xy 254.393892 -67.988022) (xy 254.416533 -67.938439) (xy 254.446002 -67.892584)
			(xy 254.481697 -67.85139) (xy 254.522892 -67.815696) (xy 254.568748 -67.786229) (xy 254.618331 -67.763588)
			(xy 254.670632 -67.748235) (xy 254.724586 -67.740483) (xy 254.75184 -67.740022) (xy 254.779209 -67.740518)
			(xy 254.833387 -67.748328) (xy 254.88589 -67.76381) (xy 254.935638 -67.786645) (xy 254.981606 -67.816363)
			(xy 255.002538 -67.834002) (xy 255.002792 -67.834256) (xy 255.009872 -67.839852) (xy 255.026794 -67.846092)
			(xy 255.035812 -67.846448) (xy 255.102868 -67.846448) (xy 255.111885 -67.846087) (xy 255.128802 -67.839843)
			(xy 255.135888 -67.834256) (xy 255.135888 -67.834002) (xy 255.136142 -67.834002) (xy 255.157085 -67.816377)
			(xy 255.203055 -67.786663) (xy 255.2528 -67.763824) (xy 255.305298 -67.74833) (xy 255.359472 -67.740498)
			(xy 255.38684 -67.740022) (xy 255.413155 -67.740456) (xy 255.465285 -67.747696) (xy 255.515929 -67.762022)
			(xy 255.564128 -67.78316) (xy 255.608971 -67.810713) (xy 255.649609 -67.844158) (xy 255.667764 -67.863212)
			(xy 255.675295 -67.870602) (xy 255.694568 -67.879133) (xy 255.705102 -67.879722) (xy 255.779778 -67.879722)
			(xy 255.790327 -67.879188) (xy 255.809622 -67.870655) (xy 255.817116 -67.863212) (xy 255.835273 -67.844158)
			(xy 255.875902 -67.8107) (xy 255.920742 -67.783141) (xy 255.968943 -67.762002) (xy 256.01959 -67.747685)
			(xy 256.071724 -67.74046) (xy 256.09804 -67.740022) (xy 256.125294 -67.740441) (xy 256.179245 -67.748203)
			(xy 256.231543 -67.763565) (xy 256.281122 -67.786213) (xy 256.326974 -67.815686) (xy 256.368165 -67.851385)
			(xy 256.403856 -67.892582) (xy 256.43332 -67.938439) (xy 256.455959 -67.988023) (xy 256.471311 -68.040323)
			(xy 256.479064 -68.094276) (xy 256.479548 -68.12153) (xy 256.479112 -68.148901) (xy 256.471289 -68.203082)
			(xy 256.455794 -68.255586) (xy 256.432945 -68.305333) (xy 256.403213 -68.351298) (xy 256.385568 -68.372228)
			(xy 256.385314 -68.372482) (xy 256.37973 -68.379571) (xy 256.373481 -68.396486) (xy 256.373122 -68.405502)
			(xy 256.373122 -68.472558) (xy 256.373494 -68.481573) (xy 256.379731 -68.498491) (xy 256.385314 -68.505578)
			(xy 256.385568 -68.505578) (xy 256.385568 -68.505832) (xy 256.403184 -68.526783) (xy 256.4329 -68.57275)
			(xy 256.455741 -68.622493) (xy 256.471238 -68.674989) (xy 256.479071 -68.729162) (xy 256.479548 -68.75653)
			(xy 256.47905 -68.78378) (xy 256.471291 -68.837725) (xy 256.455934 -68.890017) (xy 256.433292 -68.939592)
			(xy 256.403826 -68.98544) (xy 256.368136 -69.026629) (xy 256.326948 -69.06232) (xy 256.281101 -69.091787)
			(xy 256.231527 -69.11443) (xy 256.179235 -69.129789) (xy 256.12529 -69.13755) (xy 256.09804 -69.138038)
			(xy 256.071724 -69.13763) (xy 256.019592 -69.130386) (xy 255.968947 -69.116057) (xy 255.920748 -69.094913)
			(xy 255.875906 -69.067355) (xy 255.83527 -69.033905) (xy 255.817116 -69.014848) (xy 255.809584 -69.007459)
			(xy 255.790312 -68.998926) (xy 255.779778 -68.998338) (xy 255.705102 -68.998338) (xy 255.694549 -68.998843)
			(xy 255.675253 -69.007394) (xy 255.667764 -69.014848) (xy 255.649628 -69.033923) (xy 255.608993 -69.067377)
			(xy 255.564148 -69.094932) (xy 255.515944 -69.116067) (xy 255.465294 -69.13038) (xy 255.413157 -69.137601)
			(xy 255.38684 -69.138038) (xy 255.35947 -69.137564) (xy 255.305291 -69.12975) (xy 255.252787 -69.114264)
			(xy 255.20304 -69.091424) (xy 255.157073 -69.061699) (xy 255.136142 -69.044058) (xy 255.135888 -69.043804)
			(xy 255.128809 -69.038207) (xy 255.111886 -69.031966) (xy 255.102868 -69.031612) (xy 255.035812 -69.031612)
			(xy 255.026795 -69.031972) (xy 255.009878 -69.038217) (xy 255.002792 -69.043804) (xy 255.002792 -69.044058)
			(xy 255.002538 -69.044058) (xy 254.981597 -69.061686) (xy 254.935627 -69.091401) (xy 254.885882 -69.11424)
			(xy 254.833383 -69.129733) (xy 254.779209 -69.137563) (xy 254.75184 -69.138038) (xy 254.724589 -69.137508)
			(xy 254.670643 -69.129757) (xy 254.618348 -69.114407) (xy 254.56877 -69.091772) (xy 254.522918 -69.062311)
			(xy 254.481726 -69.026624) (xy 254.446031 -68.985438) (xy 254.416562 -68.939592) (xy 254.393917 -68.890018)
			(xy 254.378558 -68.837726) (xy 254.370797 -68.78378) (xy 254.370332 -68.75653) (xy 250.894299 -68.75653)
			(xy 250.888286 -68.769696) (xy 250.858815 -68.81555) (xy 250.823117 -68.856744) (xy 250.78192 -68.892437)
			(xy 250.736062 -68.921904) (xy 250.686478 -68.944545) (xy 250.634175 -68.959898) (xy 250.580221 -68.967651)
			(xy 250.552966 -68.968112) (xy 250.525595 -68.967663) (xy 250.471416 -68.959841) (xy 250.418912 -68.944347)
			(xy 250.369166 -68.921502) (xy 250.323199 -68.891774) (xy 250.302268 -68.874132) (xy 250.302014 -68.873878)
			(xy 250.294929 -68.868289) (xy 250.278011 -68.862044) (xy 250.268994 -68.861686) (xy 250.201938 -68.861686)
			(xy 250.192923 -68.862064) (xy 250.176006 -68.868297) (xy 250.168918 -68.873878) (xy 250.168918 -68.874132)
			(xy 250.168664 -68.874132) (xy 250.147723 -68.89176) (xy 250.101752 -68.921472) (xy 250.052007 -68.94431)
			(xy 249.999508 -68.959804) (xy 249.945334 -68.967636) (xy 249.917966 -68.968112) (xy 249.891651 -68.967663)
			(xy 249.839522 -68.960424) (xy 249.788879 -68.946101) (xy 249.740681 -68.924965) (xy 249.695837 -68.897416)
			(xy 249.655198 -68.863975) (xy 249.637042 -68.844922) (xy 249.629504 -68.83754) (xy 249.610236 -68.829004)
			(xy 249.599704 -68.828412) (xy 249.525028 -68.828412) (xy 249.514478 -68.828939) (xy 249.495182 -68.837475)
			(xy 249.48769 -68.844922) (xy 249.469537 -68.86398) (xy 249.428906 -68.897436) (xy 249.384065 -68.924994)
			(xy 249.335864 -68.946132) (xy 249.285216 -68.960449) (xy 249.233082 -68.967673) (xy 249.206766 -68.968112)
			(xy 249.179514 -68.967654) (xy 249.125566 -68.959893) (xy 249.073271 -68.944534) (xy 249.023693 -68.921889)
			(xy 248.977843 -68.892419) (xy 248.936654 -68.856725) (xy 248.900963 -68.815532) (xy 248.871497 -68.76968)
			(xy 248.848856 -68.720101) (xy 248.833501 -68.667805) (xy 248.825744 -68.613856) (xy 248.825258 -68.586604)
			(xy 246.452827 -68.586604) (xy 246.443754 -69.309234) (xy 246.429295 -71.09333) (xy 265.140438 -71.09333)
			(xy 265.144509 -71.037708) (xy 265.156635 -70.983271) (xy 265.176558 -70.93118) (xy 265.203854 -70.882545)
			(xy 265.23794 -70.838402) (xy 265.278089 -70.799693) (xy 265.323447 -70.767242) (xy 265.373047 -70.741741)
			(xy 265.425831 -70.723734) (xy 265.480674 -70.713604) (xy 265.536408 -70.711567) (xy 265.591845 -70.717667)
			(xy 265.645802 -70.731773) (xy 265.697131 -70.753585) (xy 265.744737 -70.782639) (xy 265.787605 -70.818314)
			(xy 265.824822 -70.859851) (xy 265.855595 -70.906364) (xy 265.879267 -70.956861) (xy 265.895335 -71.010268)
			(xy 265.903455 -71.065444) (xy 265.903964 -71.09333) (xy 265.903639 -71.11111) (xy 266.774166 -71.11111)
			(xy 266.778237 -71.055488) (xy 266.790363 -71.001051) (xy 266.810286 -70.94896) (xy 266.837582 -70.900325)
			(xy 266.871668 -70.856182) (xy 266.911817 -70.817473) (xy 266.957175 -70.785022) (xy 267.006775 -70.759521)
			(xy 267.059559 -70.741514) (xy 267.114402 -70.731384) (xy 267.170136 -70.729347) (xy 267.225573 -70.735447)
			(xy 267.27953 -70.749553) (xy 267.330859 -70.771365) (xy 267.378465 -70.800419) (xy 267.421333 -70.836094)
			(xy 267.45855 -70.877631) (xy 267.489323 -70.924144) (xy 267.512995 -70.974641) (xy 267.529063 -71.028048)
			(xy 267.537183 -71.083224) (xy 267.537692 -71.11111) (xy 267.537183 -71.138996) (xy 267.529063 -71.194172)
			(xy 267.512995 -71.247579) (xy 267.489323 -71.298076) (xy 267.45855 -71.344589) (xy 267.421333 -71.386126)
			(xy 267.378465 -71.421801) (xy 267.330859 -71.450855) (xy 267.27953 -71.472667) (xy 267.225573 -71.486773)
			(xy 267.170136 -71.492873) (xy 267.114402 -71.490836) (xy 267.059559 -71.480706) (xy 267.006775 -71.462699)
			(xy 266.957175 -71.437198) (xy 266.911817 -71.404747) (xy 266.871668 -71.366038) (xy 266.837582 -71.321895)
			(xy 266.810286 -71.27326) (xy 266.790363 -71.221169) (xy 266.778237 -71.166732) (xy 266.774166 -71.11111)
			(xy 265.903639 -71.11111) (xy 265.903455 -71.121216) (xy 265.895335 -71.176392) (xy 265.879267 -71.229799)
			(xy 265.855595 -71.280296) (xy 265.824822 -71.326809) (xy 265.787605 -71.368346) (xy 265.744737 -71.404021)
			(xy 265.697131 -71.433075) (xy 265.645802 -71.454887) (xy 265.591845 -71.468993) (xy 265.536408 -71.475093)
			(xy 265.480674 -71.473056) (xy 265.425831 -71.462926) (xy 265.373047 -71.444919) (xy 265.323447 -71.419418)
			(xy 265.278089 -71.386967) (xy 265.23794 -71.348258) (xy 265.203854 -71.304115) (xy 265.176558 -71.25548)
			(xy 265.156635 -71.203389) (xy 265.144509 -71.148952) (xy 265.140438 -71.09333) (xy 246.429295 -71.09333)
			(xy 246.425546 -71.555864) (xy 251.394466 -71.555864) (xy 251.398537 -71.500242) (xy 251.410663 -71.445805)
			(xy 251.430586 -71.393714) (xy 251.457882 -71.345079) (xy 251.491968 -71.300936) (xy 251.532117 -71.262227)
			(xy 251.577475 -71.229776) (xy 251.627075 -71.204275) (xy 251.679859 -71.186268) (xy 251.734702 -71.176138)
			(xy 251.790436 -71.174101) (xy 251.845873 -71.180201) (xy 251.89983 -71.194307) (xy 251.951159 -71.216119)
			(xy 251.998765 -71.245173) (xy 252.041633 -71.280848) (xy 252.07885 -71.322385) (xy 252.109623 -71.368898)
			(xy 252.133295 -71.419395) (xy 252.149363 -71.472802) (xy 252.157483 -71.527978) (xy 252.157992 -71.555864)
			(xy 252.157483 -71.58375) (xy 252.151644 -71.623428) (xy 252.90348 -71.623428) (xy 252.907551 -71.567806)
			(xy 252.919677 -71.513369) (xy 252.9396 -71.461278) (xy 252.966896 -71.412643) (xy 253.000982 -71.3685)
			(xy 253.041131 -71.329791) (xy 253.086489 -71.29734) (xy 253.136089 -71.271839) (xy 253.188873 -71.253832)
			(xy 253.243716 -71.243702) (xy 253.29945 -71.241665) (xy 253.354887 -71.247765) (xy 253.408844 -71.261871)
			(xy 253.460173 -71.283683) (xy 253.507779 -71.312737) (xy 253.550647 -71.348412) (xy 253.587864 -71.389949)
			(xy 253.618637 -71.436462) (xy 253.642309 -71.486959) (xy 253.658377 -71.540366) (xy 253.666497 -71.595542)
			(xy 253.667006 -71.623428) (xy 253.666497 -71.651314) (xy 253.658377 -71.70649) (xy 253.642309 -71.759897)
			(xy 253.618637 -71.810394) (xy 253.587864 -71.856907) (xy 253.550647 -71.898444) (xy 253.507779 -71.934119)
			(xy 253.460173 -71.963173) (xy 253.408844 -71.984985) (xy 253.354887 -71.999091) (xy 253.29945 -72.005191)
			(xy 253.243716 -72.003154) (xy 253.188873 -71.993024) (xy 253.136089 -71.975017) (xy 253.086489 -71.949516)
			(xy 253.041131 -71.917065) (xy 253.000982 -71.878356) (xy 252.966896 -71.834213) (xy 252.9396 -71.785578)
			(xy 252.919677 -71.733487) (xy 252.907551 -71.67905) (xy 252.90348 -71.623428) (xy 252.151644 -71.623428)
			(xy 252.149363 -71.638926) (xy 252.133295 -71.692333) (xy 252.109623 -71.74283) (xy 252.07885 -71.789343)
			(xy 252.041633 -71.83088) (xy 251.998765 -71.866555) (xy 251.951159 -71.895609) (xy 251.89983 -71.917421)
			(xy 251.845873 -71.931527) (xy 251.790436 -71.937627) (xy 251.734702 -71.93559) (xy 251.679859 -71.92546)
			(xy 251.627075 -71.907453) (xy 251.577475 -71.881952) (xy 251.532117 -71.849501) (xy 251.491968 -71.810792)
			(xy 251.457882 -71.766649) (xy 251.430586 -71.718014) (xy 251.410663 -71.665923) (xy 251.398537 -71.611486)
			(xy 251.394466 -71.555864) (xy 246.425546 -71.555864) (xy 246.358897 -79.779368) (xy 250.4473 -79.779368)
			(xy 250.451371 -79.723746) (xy 250.463497 -79.669309) (xy 250.48342 -79.617218) (xy 250.510716 -79.568583)
			(xy 250.544802 -79.52444) (xy 250.584951 -79.485731) (xy 250.630309 -79.45328) (xy 250.679909 -79.427779)
			(xy 250.732693 -79.409772) (xy 250.787536 -79.399642) (xy 250.84327 -79.397605) (xy 250.898707 -79.403705)
			(xy 250.952664 -79.417811) (xy 251.003993 -79.439623) (xy 251.051599 -79.468677) (xy 251.094467 -79.504352)
			(xy 251.131684 -79.545889) (xy 251.162457 -79.592402) (xy 251.186129 -79.642899) (xy 251.202197 -79.696306)
			(xy 251.210317 -79.751482) (xy 251.210826 -79.779368) (xy 251.210317 -79.807254) (xy 251.202197 -79.86243)
			(xy 251.186129 -79.915837) (xy 251.162457 -79.966334) (xy 251.131684 -80.012847) (xy 251.094467 -80.054384)
			(xy 251.051599 -80.090059) (xy 251.003993 -80.119113) (xy 250.952664 -80.140925) (xy 250.898707 -80.155031)
			(xy 250.84327 -80.161131) (xy 250.787536 -80.159094) (xy 250.732693 -80.148964) (xy 250.679909 -80.130957)
			(xy 250.630309 -80.105456) (xy 250.584951 -80.073005) (xy 250.544802 -80.034296) (xy 250.510716 -79.990153)
			(xy 250.48342 -79.941518) (xy 250.463497 -79.889427) (xy 250.451371 -79.83499) (xy 250.4473 -79.779368)
			(xy 246.358897 -79.779368) (xy 246.31777 -84.85378) (xy 246.318024 -84.857844) (xy 246.331232 -84.950046)
			(xy 246.365776 -85.191092) (xy 246.36603 -85.193124) (xy 246.366538 -85.195156) (xy 247.127776 -87.706962)
			(xy 247.163336 -87.82431) (xy 247.166981 -87.834535) (xy 247.181277 -87.850843) (xy 247.201009 -87.859843)
			(xy 247.21185 -87.860378) (xy 247.429528 -87.860378) (xy 247.43953 -87.859885) (xy 247.458009 -87.85222)
			(xy 247.472148 -87.838067) (xy 247.479795 -87.819581) (xy 247.480328 -87.809578) (xy 247.480328 -87.753698)
			(xy 247.480182 -87.747829) (xy 247.477496 -87.736403) (xy 247.474994 -87.731092) (xy 247.473978 -87.72906)
			(xy 247.471976 -87.72422) (xy 247.469798 -87.713976) (xy 247.46966 -87.70874) (xy 247.46966 -87.60333)
			(xy 247.469944 -87.58428) (xy 247.474524 -87.546457) (xy 247.478804 -87.527892) (xy 247.480328 -87.521796)
			(xy 247.480328 -87.360506) (xy 247.478804 -87.348314) (xy 247.475248 -87.335106) (xy 247.471946 -87.326724)
			(xy 247.470422 -87.324438) (xy 247.466358 -87.316056) (xy 247.454686 -87.290594) (xy 247.438091 -87.237097)
			(xy 247.429485 -87.181751) (xy 247.428766 -87.15375) (xy 247.428766 -87.150194) (xy 247.429371 -87.119637)
			(xy 247.439122 -87.059305) (xy 247.458372 -87.001302) (xy 247.471946 -86.973918) (xy 247.47347 -86.971124)
			(xy 247.474994 -86.968076) (xy 247.478804 -86.952328) (xy 247.480328 -86.946232) (xy 247.480328 -86.750144)
			(xy 247.478804 -86.744048) (xy 247.47453 -86.725482) (xy 247.469944 -86.68766) (xy 247.46966 -86.66861)
			(xy 247.46966 -85.532214) (xy 247.469911 -85.513036) (xy 247.474494 -85.474957) (xy 247.478804 -85.456268)
			(xy 247.480328 -85.450172) (xy 247.480328 -84.969604) (xy 247.478804 -84.963508) (xy 247.474497 -84.944819)
			(xy 247.469914 -84.906739) (xy 247.46966 -84.887562) (xy 247.46966 -83.828128) (xy 247.471438 -83.81492)
			(xy 247.472454 -83.811364) (xy 247.513602 -83.709764) (xy 247.515726 -83.704797) (xy 247.521748 -83.695832)
			(xy 247.52554 -83.691984) (xy 247.570244 -83.648804) (xy 247.570752 -83.648296) (xy 247.760744 -83.45805)
			(xy 247.763466 -83.455359) (xy 247.769589 -83.450764) (xy 247.772936 -83.448906) (xy 247.78081 -83.445604)
			(xy 247.786254 -83.443548) (xy 247.796128 -83.437397) (xy 247.800368 -83.433412) (xy 247.809512 -83.424268)
			(xy 247.814338 -83.41868) (xy 247.8151 -83.410044) (xy 247.815862 -83.4009) (xy 247.819926 -83.368134)
			(xy 247.819926 -83.36788) (xy 247.820434 -83.364832) (xy 247.825659 -83.338258) (xy 247.842619 -83.286825)
			(xy 247.866681 -83.238307) (xy 247.89736 -83.193678) (xy 247.934041 -83.153834) (xy 247.975987 -83.119577)
			(xy 248.022354 -83.091594) (xy 248.072213 -83.070448) (xy 248.12456 -83.056564) (xy 248.151396 -83.05292)
			(xy 248.160794 -83.051904) (xy 248.1961 -83.05038) (xy 248.22383 -83.050876) (xy 248.278707 -83.0589)
			(xy 248.331845 -83.074779) (xy 248.382127 -83.098178) (xy 248.428495 -83.128606) (xy 248.469973 -83.165422)
			(xy 248.505688 -83.207852) (xy 248.534888 -83.255002) (xy 248.546366 -83.28025) (xy 248.546366 -83.280504)
			(xy 248.549522 -83.28723) (xy 248.559074 -83.298599) (xy 248.565162 -83.302856) (xy 248.571258 -83.30692)
			(xy 248.57837 -83.308952) (xy 248.581849 -83.3099) (xy 248.588988 -83.310919) (xy 248.592594 -83.310984)
			(xy 250.416568 -83.310984) (xy 250.424696 -83.310222) (xy 250.425204 -83.310222) (xy 250.432725 -83.308625)
			(xy 250.44642 -83.301657) (xy 250.452128 -83.296506) (xy 250.926346 -82.822542) (xy 251.40031 -82.348578)
			(xy 251.405502 -82.342899) (xy 251.412479 -82.329192) (xy 251.414026 -82.321654) (xy 251.414026 -82.321146)
			(xy 251.414788 -82.313018) (xy 251.414788 -78.272132) (xy 251.41446 -78.263855) (xy 251.409131 -78.248182)
			(xy 251.404374 -78.241398) (xy 251.402342 -78.239112) (xy 251.400564 -78.237334) (xy 251.397262 -78.233524)
			(xy 250.537726 -77.373988) (xy 250.533998 -77.370463) (xy 250.525426 -77.364827) (xy 250.520708 -77.362812)
			(xy 250.512072 -77.359256) (xy 247.785382 -77.359256) (xy 247.760572 -77.358768) (xy 247.711564 -77.351004)
			(xy 247.664374 -77.335669) (xy 247.620163 -77.313142) (xy 247.58002 -77.283977) (xy 247.544933 -77.248892)
			(xy 247.515766 -77.208751) (xy 247.493237 -77.164541) (xy 247.4779 -77.117351) (xy 247.470133 -77.068344)
			(xy 247.46966 -77.043534) (xy 247.46966 -74.946764) (xy 247.469996 -74.939044) (xy 247.474634 -74.924312)
			(xy 247.478804 -74.917808) (xy 247.572276 -74.784458) (xy 247.572784 -74.783696) (xy 247.573546 -74.78268)
			(xy 247.574562 -74.781156) (xy 247.579172 -74.774991) (xy 247.591324 -74.765554) (xy 247.598438 -74.762614)
			(xy 247.677178 -74.733912) (xy 247.677686 -74.733658) (xy 247.692386 -74.727724) (xy 247.718156 -74.709283)
			(xy 247.738062 -74.684628) (xy 247.750657 -74.65555) (xy 247.753378 -74.639932) (xy 247.753378 -74.638916)
			(xy 247.758458 -74.596244) (xy 247.75905 -74.591961) (xy 247.761484 -74.583666) (xy 247.763284 -74.579734)
			(xy 247.8024 -74.500232) (xy 247.804335 -74.496548) (xy 247.809185 -74.489786) (xy 247.812052 -74.48677)
			(xy 248.764298 -73.53427) (xy 248.771693 -73.527415) (xy 248.790292 -73.519669) (xy 248.800366 -73.519284)
			(xy 250.411234 -73.519284) (xy 250.421301 -73.518854) (xy 250.439895 -73.511129) (xy 250.447302 -73.504298)
			(xy 250.606814 -73.344786) (xy 250.613668 -73.337391) (xy 250.62141 -73.318792) (xy 250.6218 -73.308718)
			(xy 250.6218 -72.461882) (xy 250.622227 -72.451813) (xy 250.629946 -72.433214) (xy 250.636786 -72.425814)
			(xy 250.872498 -72.190102) (xy 250.879896 -72.183255) (xy 250.898494 -72.175519) (xy 250.908566 -72.175116)
			(xy 263.783572 -72.175116) (xy 263.7917 -72.174354) (xy 263.792208 -72.174354) (xy 263.79973 -72.172758)
			(xy 263.813427 -72.165792) (xy 263.819132 -72.160638) (xy 263.862566 -72.117204) (xy 263.869968 -72.110367)
			(xy 263.888566 -72.102656) (xy 263.898634 -72.102218) (xy 267.693394 -72.102218) (xy 267.701522 -72.101456)
			(xy 267.70203 -72.101456) (xy 267.70955 -72.099857) (xy 267.723244 -72.092887) (xy 267.728954 -72.08774)
			(xy 267.994384 -71.82231) (xy 267.994638 -71.822056) (xy 268.001138 -71.814909) (xy 268.008702 -71.79715)
			(xy 268.00937 -71.787512) (xy 268.009116 -71.782432) (xy 267.49248 -65.347088) (xy 267.491972 -65.34023)
			(xy 267.490194 -65.30721) (xy 267.319252 -61.041534) (xy 267.317977 -61.032567) (xy 267.310023 -61.016309)
			(xy 267.296931 -61.003811) (xy 267.288772 -60.999878) (xy 267.283438 -60.998354) (xy 267.25774 -60.989989)
			(xy 267.208819 -60.967029) (xy 267.163624 -60.937399) (xy 267.123059 -60.901693) (xy 267.087933 -60.860623)
			(xy 267.05895 -60.815011) (xy 267.036688 -60.765768) (xy 267.021592 -60.713877) (xy 267.013964 -60.660377)
			(xy 267.013436 -60.633356) (xy 267.013968 -60.604862) (xy 267.022451 -60.548508) (xy 267.039221 -60.494042)
			(xy 267.063905 -60.442676) (xy 267.095954 -60.395553) (xy 267.134655 -60.353721) (xy 267.179148 -60.31811)
			(xy 267.228442 -60.289513) (xy 267.254736 -60.278518) (xy 267.255244 -60.278264) (xy 267.262416 -60.275146)
			(xy 267.274579 -60.265327) (xy 267.27912 -60.25896) (xy 267.28293 -60.252864) (xy 267.287248 -60.237878)
			(xy 267.245338 -59.188096) (xy 267.230606 -58.82513) (xy 267.230165 -58.818694) (xy 267.226445 -58.806344)
			(xy 267.22324 -58.800746) (xy 267.219938 -58.795158) (xy 267.21054 -58.786268) (xy 267.204698 -58.782966)
			(xy 267.179712 -58.768353) (xy 267.134062 -58.732767) (xy 267.094301 -58.690704) (xy 267.061339 -58.643125)
			(xy 267.035929 -58.591119) (xy 267.018653 -58.535875) (xy 267.009906 -58.478659) (xy 267.009372 -58.449718)
			(xy 267.009819 -58.422967) (xy 267.017279 -58.369988) (xy 267.032057 -58.318567) (xy 267.053863 -58.269711)
			(xy 267.08227 -58.224374) (xy 267.116724 -58.183442) (xy 267.15655 -58.147717) (xy 267.178536 -58.132472)
			(xy 267.179044 -58.132218) (xy 267.184319 -58.128476) (xy 267.192922 -58.118823) (xy 267.196062 -58.113168)
			(xy 267.198602 -58.107834) (xy 267.201396 -58.095388) (xy 267.196062 -57.960006) (xy 267.098526 -55.52313)
			(xy 267.097764 -55.483252) (xy 267.097764 -55.467758) (xy 267.097764 -55.466742) (xy 267.104368 -55.045864)
			(xy 267.14069 -52.726336) (xy 267.14069 -52.723796) (xy 267.042392 -49.908714) (xy 267.040956 -49.899002)
			(xy 267.031786 -49.881663) (xy 267.016764 -49.869051) (xy 267.007594 -49.865534) (xy 266.955524 -49.844706)
			(xy 266.955016 -49.844706) (xy 266.932918 -49.835816) (xy 266.928346 -49.8348) (xy 266.92098 -49.83353)
			(xy 266.90972 -49.832992) (xy 266.888496 -49.840503) (xy 266.880086 -49.848008) (xy 266.878308 -49.849786)
			(xy 266.859824 -49.867976) (xy 266.818898 -49.899825) (xy 266.774128 -49.925998) (xy 266.726298 -49.94604)
			(xy 266.676243 -49.959599) (xy 266.624837 -49.966438) (xy 266.598908 -49.96688) (xy 266.571402 -49.966417)
			(xy 266.516928 -49.958732) (xy 266.464063 -49.943512) (xy 266.413842 -49.921054) (xy 266.367252 -49.8918)
			(xy 266.345924 -49.874424) (xy 266.34567 -49.87417) (xy 266.342876 -49.871884) (xy 266.336245 -49.867481)
			(xy 266.321111 -49.862576) (xy 266.313158 -49.862232) (xy 266.308078 -49.862232) (xy 266.302639 -49.862089)
			(xy 266.292007 -49.859781) (xy 266.286996 -49.85766) (xy 266.276836 -49.852834) (xy 266.266422 -49.849532)
			(xy 266.245594 -49.849532) (xy 266.23772 -49.851818) (xy 266.217908 -49.859438) (xy 266.211304 -49.86528)
			(xy 266.195999 -49.878072) (xy 266.163165 -49.900726) (xy 266.145772 -49.910492) (xy 266.136882 -49.915064)
			(xy 266.110807 -49.927651) (xy 266.055792 -49.945692) (xy 265.998688 -49.955242) (xy 265.96975 -49.956212)
			(xy 265.9634 -49.956212) (xy 265.933489 -49.955608) (xy 265.874406 -49.946237) (xy 265.817505 -49.92777)
			(xy 265.764179 -49.90066) (xy 265.739626 -49.883568) (xy 265.731244 -49.877218) (xy 265.726418 -49.873408)
			(xy 265.717782 -49.868074) (xy 265.716766 -49.867566) (xy 265.711441 -49.865102) (xy 265.700025 -49.862404)
			(xy 265.69416 -49.862232) (xy 265.673078 -49.862232) (xy 265.667639 -49.862089) (xy 265.657007 -49.859781)
			(xy 265.651996 -49.85766) (xy 265.641836 -49.852834) (xy 265.631422 -49.849532) (xy 265.610594 -49.849532)
			(xy 265.60272 -49.851818) (xy 265.582908 -49.859438) (xy 265.576304 -49.86528) (xy 265.560999 -49.878072)
			(xy 265.528165 -49.900726) (xy 265.510772 -49.910492) (xy 265.501882 -49.915064) (xy 265.475807 -49.927651)
			(xy 265.420792 -49.945692) (xy 265.363688 -49.955242) (xy 265.33475 -49.956212) (xy 265.3284 -49.956212)
			(xy 265.298489 -49.955608) (xy 265.239406 -49.946237) (xy 265.182505 -49.92777) (xy 265.129179 -49.90066)
			(xy 265.104626 -49.883568) (xy 265.096244 -49.877218) (xy 265.091418 -49.873408) (xy 265.082782 -49.868074)
			(xy 265.081766 -49.867566) (xy 265.076441 -49.865102) (xy 265.065025 -49.862404) (xy 265.05916 -49.862232)
			(xy 265.038078 -49.862232) (xy 265.032639 -49.862089) (xy 265.022007 -49.859781) (xy 265.016996 -49.85766)
			(xy 265.003026 -49.85131) (xy 264.99386 -49.847635) (xy 264.974148 -49.846814) (xy 264.955575 -49.853467)
			(xy 264.947908 -49.859692) (xy 264.937494 -49.868836) (xy 264.916876 -49.885266) (xy 264.87198 -49.912901)
			(xy 264.823714 -49.934108) (xy 264.772992 -49.948483) (xy 264.720776 -49.955755) (xy 264.694416 -49.956212)
			(xy 264.693908 -49.956212) (xy 264.666654 -49.955749) (xy 264.612702 -49.947993) (xy 264.560403 -49.932638)
			(xy 264.510821 -49.909995) (xy 264.464967 -49.880527) (xy 264.423772 -49.844833) (xy 264.388078 -49.80364)
			(xy 264.358609 -49.757786) (xy 264.335965 -49.708205) (xy 264.320609 -49.655906) (xy 264.312851 -49.601954)
			(xy 264.312851 -49.547446) (xy 264.320609 -49.493494) (xy 264.335965 -49.441195) (xy 264.358609 -49.391614)
			(xy 264.388078 -49.34576) (xy 264.423772 -49.304567) (xy 264.464967 -49.268873) (xy 264.510821 -49.239405)
			(xy 264.560403 -49.216762) (xy 264.612702 -49.201407) (xy 264.666654 -49.193651) (xy 264.693908 -49.193196)
			(xy 264.694162 -49.193196) (xy 264.719778 -49.19361) (xy 264.770549 -49.20047) (xy 264.819942 -49.214072)
			(xy 264.867067 -49.23417) (xy 264.911074 -49.260402) (xy 264.931398 -49.276) (xy 264.936224 -49.27981)
			(xy 264.94359 -49.283112) (xy 264.948329 -49.284983) (xy 264.958309 -49.28703) (xy 264.963402 -49.287176)
			(xy 264.984738 -49.287176) (xy 264.990177 -49.287319) (xy 265.000809 -49.289627) (xy 265.00582 -49.291748)
			(xy 265.01598 -49.296574) (xy 265.026394 -49.299876) (xy 265.047222 -49.299876) (xy 265.055096 -49.29759)
			(xy 265.074908 -49.28997) (xy 265.081512 -49.284128) (xy 265.096818 -49.271337) (xy 265.129652 -49.248683)
			(xy 265.147044 -49.238916) (xy 265.155934 -49.234344) (xy 265.182007 -49.221751) (xy 265.237021 -49.203697)
			(xy 265.294126 -49.194135) (xy 265.323066 -49.193196) (xy 265.329162 -49.193196) (xy 265.354778 -49.19361)
			(xy 265.405549 -49.20047) (xy 265.454942 -49.214072) (xy 265.502067 -49.23417) (xy 265.546074 -49.260402)
			(xy 265.566398 -49.276) (xy 265.571224 -49.27981) (xy 265.57859 -49.283112) (xy 265.583329 -49.284983)
			(xy 265.593309 -49.28703) (xy 265.598402 -49.287176) (xy 265.619738 -49.287176) (xy 265.625177 -49.287319)
			(xy 265.635809 -49.289627) (xy 265.64082 -49.291748) (xy 265.65098 -49.296574) (xy 265.661394 -49.299876)
			(xy 265.682222 -49.299876) (xy 265.690096 -49.29759) (xy 265.709908 -49.28997) (xy 265.716512 -49.284128)
			(xy 265.731818 -49.271337) (xy 265.764652 -49.248683) (xy 265.782044 -49.238916) (xy 265.790934 -49.234344)
			(xy 265.817007 -49.221751) (xy 265.872021 -49.203697) (xy 265.929126 -49.194135) (xy 265.958066 -49.193196)
			(xy 265.964162 -49.193196) (xy 265.989778 -49.19361) (xy 266.040549 -49.20047) (xy 266.089942 -49.214072)
			(xy 266.137067 -49.23417) (xy 266.181074 -49.260402) (xy 266.201398 -49.276) (xy 266.206224 -49.27981)
			(xy 266.21359 -49.283112) (xy 266.218329 -49.284983) (xy 266.228309 -49.28703) (xy 266.233402 -49.287176)
			(xy 266.329922 -49.287176) (xy 266.337728 -49.286846) (xy 266.352591 -49.282053) (xy 266.359132 -49.277778)
			(xy 266.362434 -49.275238) (xy 266.365482 -49.272952) (xy 266.370308 -49.268126) (xy 266.378436 -49.257204)
			(xy 266.384024 -49.246536) (xy 266.4081 -49.231398) (xy 266.459692 -49.20747) (xy 266.514196 -49.191234)
			(xy 266.570473 -49.183031) (xy 266.598908 -49.182528) (xy 266.599416 -49.182528) (xy 266.627152 -49.183047)
			(xy 266.682058 -49.190953) (xy 266.735298 -49.206531) (xy 266.785804 -49.229472) (xy 266.832566 -49.259314)
			(xy 266.853924 -49.277016) (xy 266.859512 -49.281588) (xy 266.875514 -49.288954) (xy 266.886155 -49.293115)
			(xy 266.90897 -49.292727) (xy 266.919456 -49.288192) (xy 266.92606 -49.28489) (xy 266.926568 -49.28489)
			(xy 266.995402 -49.25187) (xy 267.003147 -49.247194) (xy 267.014988 -49.233531) (xy 267.018516 -49.2252)
			(xy 267.017246 -49.186084) (xy 267.016992 -49.182782) (xy 267.016484 -49.178718) (xy 267.013182 -49.163732)
			(xy 267.011912 -49.15535) (xy 267.011912 -49.034954) (xy 267.011912 -49.032922) (xy 266.974828 -47.977806)
			(xy 266.974574 -47.973996) (xy 265.886438 -39.919656) (xy 265.882676 -39.890264) (xy 265.878228 -39.83117)
			(xy 265.877548 -39.801546) (xy 265.86688 -39.111936) (xy 265.86434 -39.101014) (xy 265.8618 -39.095934)
			(xy 265.861546 -39.09568) (xy 265.861546 -39.095426) (xy 265.846302 -39.063949) (xy 265.819735 -38.999246)
			(xy 265.80846 -38.96614) (xy 265.793195 -38.917887) (xy 265.771332 -38.819063) (xy 265.759578 -38.718535)
			(xy 265.758168 -38.667944) (xy 265.750548 -38.17366) (xy 265.750548 -38.157404) (xy 265.750743 -38.126783)
			(xy 265.754431 -38.065653) (xy 265.757914 -38.03523) (xy 265.758168 -38.03396) (xy 265.758422 -38.029388)
			(xy 265.758168 -38.015418) (xy 265.758168 -38.013132) (xy 265.758422 -37.992812) (xy 265.764772 -37.682424)
			(xy 265.763502 -37.676328) (xy 265.753022 -37.62648) (xy 265.741062 -37.525316) (xy 265.739626 -37.474398)
			(xy 265.732006 -36.978082) (xy 265.729212 -36.9697) (xy 265.725148 -36.958778) (xy 265.722608 -36.95192)
			(xy 265.719814 -36.944554) (xy 265.719814 -36.944046) (xy 265.716512 -36.935664) (xy 265.712702 -36.92525)
			(xy 265.710162 -36.919408) (xy 265.706622 -36.913018) (xy 265.696549 -36.902446) (xy 265.69035 -36.89858)
			(xy 265.667283 -36.903894) (xy 265.620293 -36.909625) (xy 265.596624 -36.91001) (xy 265.596116 -36.91001)
			(xy 265.567934 -36.909532) (xy 265.512142 -36.901513) (xy 265.45806 -36.885635) (xy 265.406788 -36.862221)
			(xy 265.35937 -36.831749) (xy 265.316772 -36.794839) (xy 265.27986 -36.752242) (xy 265.249386 -36.704826)
			(xy 265.225971 -36.653555) (xy 265.210091 -36.599473) (xy 265.202069 -36.543682) (xy 265.202069 -36.487318)
			(xy 265.210091 -36.431527) (xy 265.225971 -36.377445) (xy 265.249386 -36.326174) (xy 265.27986 -36.278758)
			(xy 265.316772 -36.236161) (xy 265.35937 -36.199251) (xy 265.406788 -36.168779) (xy 265.45806 -36.145365)
			(xy 265.512142 -36.129487) (xy 265.567934 -36.121468) (xy 265.596116 -36.121086) (xy 265.63193 -36.122864)
			(xy 265.634724 -36.120578) (xy 265.649456 -36.107878) (xy 265.65733 -36.101274) (xy 265.669776 -36.076382)
			(xy 265.671046 -36.072064) (xy 265.67511 -36.058856) (xy 265.675618 -36.05403) (xy 265.681285 -36.008192)
			(xy 265.700076 -35.917756) (xy 265.727223 -35.829469) (xy 265.762491 -35.744099) (xy 265.783568 -35.703002)
			(xy 265.785854 -35.698684) (xy 265.791188 -35.682174) (xy 265.791442 -35.66795) (xy 265.789664 -35.661092)
			(xy 265.78814 -35.654742) (xy 265.7856 -35.644836) (xy 265.77798 -35.61715) (xy 265.77798 -35.616642)
			(xy 265.759946 -35.551364) (xy 265.757132 -35.544494) (xy 265.748226 -35.532623) (xy 265.74242 -35.527996)
			(xy 265.692382 -35.498024) (xy 265.691874 -35.498024) (xy 265.68019 -35.491166) (xy 265.67257 -35.487356)
			(xy 265.672062 -35.487356) (xy 265.66876 -35.486086) (xy 265.650726 -35.490404) (xy 265.64463 -35.491928)
			(xy 265.623648 -35.496854) (xy 265.581342 -35.505113) (xy 265.560048 -35.508438) (xy 265.55954 -35.508438)
			(xy 265.525504 -35.513264) (xy 265.524996 -35.513264) (xy 265.497786 -35.516231) (xy 265.443145 -35.519537)
			(xy 265.415776 -35.519868) (xy 265.403076 -35.519868) (xy 265.356681 -35.518986) (xy 265.264349 -35.509662)
			(xy 265.173284 -35.491796) (xy 265.084274 -35.465542) (xy 264.99809 -35.431128) (xy 264.915478 -35.388851)
			(xy 264.876026 -35.36442) (xy 264.873994 -35.364928) (xy 264.86993 -35.36569) (xy 264.852931 -35.368564)
			(xy 264.818589 -35.371614) (xy 264.80135 -35.371786) (xy 264.800842 -35.371786) (xy 264.773588 -35.371326)
			(xy 264.719633 -35.363573) (xy 264.667332 -35.348221) (xy 264.617748 -35.32558) (xy 264.571891 -35.296113)
			(xy 264.530695 -35.260419) (xy 264.494999 -35.219225) (xy 264.465529 -35.17337) (xy 264.442886 -35.123787)
			(xy 264.427531 -35.071486) (xy 264.419776 -35.017532) (xy 264.419334 -34.990278) (xy 264.419334 -34.989008)
			(xy 264.41981 -34.964279) (xy 264.426369 -34.915254) (xy 264.439209 -34.867489) (xy 264.44829 -34.844482)
			(xy 264.450068 -34.840164) (xy 264.456672 -34.824162) (xy 264.457942 -34.818574) (xy 264.45337 -34.802826)
			(xy 264.440873 -34.758474) (xy 264.423161 -34.668039) (xy 264.413878 -34.576355) (xy 264.412984 -34.530284)
			(xy 264.412984 -34.519108) (xy 264.41356 -34.477575) (xy 264.420761 -34.394817) (xy 264.434816 -34.312944)
			(xy 264.455627 -34.232522) (xy 264.48305 -34.154109) (xy 264.499598 -34.11601) (xy 264.502646 -34.106358)
			(xy 264.506202 -34.091118) (xy 264.506202 -34.090102) (xy 264.502646 -34.074862) (xy 264.499598 -34.06521)
			(xy 264.482918 -34.026807) (xy 264.455308 -33.947757) (xy 264.434428 -33.866669) (xy 264.420426 -33.784115)
			(xy 264.4134 -33.700677) (xy 264.412984 -33.65881) (xy 264.412984 -33.658302) (xy 264.413255 -33.626014)
			(xy 264.417452 -33.561575) (xy 264.421366 -33.529524) (xy 264.424866 -33.504119) (xy 264.434142 -33.453675)
			(xy 264.439908 -33.428686) (xy 264.443925 -33.412172) (xy 264.452946 -33.379399) (xy 264.457942 -33.363154)
			(xy 264.456164 -33.35528) (xy 264.453878 -33.349692) (xy 264.444362 -33.328077) (xy 264.430138 -33.283041)
			(xy 264.421583 -33.236593) (xy 264.419842 -33.21304) (xy 264.419842 -33.208722) (xy 264.419334 -33.19018)
			(xy 264.419334 -33.18256) (xy 264.420328 -33.155664) (xy 264.428946 -33.102537) (xy 264.444945 -33.051149)
			(xy 264.46801 -33.002521) (xy 264.497681 -32.957617) (xy 264.53337 -32.917331) (xy 264.574367 -32.882461)
			(xy 264.619859 -32.8537) (xy 264.668942 -32.831619) (xy 264.720642 -32.816657) (xy 264.773931 -32.809112)
			(xy 264.800842 -32.808672) (xy 264.801096 -32.808672) (xy 264.815567 -32.808786) (xy 264.844427 -32.810948)
			(xy 264.858754 -32.81299) (xy 264.867572 -32.813981) (xy 264.884979 -32.810598) (xy 264.89279 -32.806386)
			(xy 264.93183 -32.783272) (xy 265.013334 -32.743399) (xy 265.09812 -32.71109) (xy 265.185489 -32.686611)
			(xy 265.27472 -32.670165) (xy 265.365075 -32.661887) (xy 265.410442 -32.661352) (xy 265.410696 -32.661352)
			(xy 265.456035 -32.661882) (xy 265.546336 -32.670143) (xy 265.635515 -32.686561) (xy 265.722838 -32.711)
			(xy 265.807584 -32.743258) (xy 265.889054 -32.783071) (xy 265.928094 -32.806132) (xy 265.935819 -32.810401)
			(xy 265.9531 -32.813916) (xy 265.961876 -32.81299) (xy 265.976582 -32.81091) (xy 266.006206 -32.808746)
			(xy 266.021058 -32.808672) (xy 266.02182 -32.808672) (xy 266.051538 -32.809359) (xy 266.110227 -32.818795)
			(xy 266.13866 -32.827468) (xy 266.152376 -32.83204) (xy 266.163806 -32.831024) (xy 266.171688 -32.830011)
			(xy 266.186302 -32.823795) (xy 266.192508 -32.818832) (xy 266.212066 -32.804608) (xy 266.212574 -32.804354)
			(xy 266.2555 -32.77362) (xy 266.258531 -32.771269) (xy 266.263892 -32.765785) (xy 266.266168 -32.762698)
			(xy 266.267692 -32.760666) (xy 266.267946 -32.760412) (xy 266.267438 -32.73806) (xy 266.267438 -32.737806)
			(xy 266.267184 -32.722566) (xy 266.267184 -32.708596) (xy 266.268157 -32.66811) (xy 266.275858 -32.587486)
			(xy 266.290078 -32.507752) (xy 266.310725 -32.429437) (xy 266.337661 -32.353056) (xy 266.353798 -32.315912)
			(xy 266.356846 -32.30626) (xy 266.360402 -32.29102) (xy 266.360402 -32.290004) (xy 266.35583 -32.269938)
			(xy 266.354052 -32.265874) (xy 266.337322 -32.227404) (xy 266.309628 -32.148211) (xy 266.288686 -32.066972)
			(xy 266.274645 -31.984259) (xy 266.267603 -31.90066) (xy 266.267184 -31.858712) (xy 266.267184 -31.850838)
			(xy 266.267946 -31.821628) (xy 266.268708 -31.806642) (xy 266.268708 -31.805372) (xy 266.268543 -31.796209)
			(xy 266.262548 -31.778904) (xy 266.257024 -31.77159) (xy 266.227814 -31.73984) (xy 266.227306 -31.739332)
			(xy 266.219432 -31.73095) (xy 266.209272 -31.73095) (xy 266.198096 -31.73222) (xy 266.182348 -31.735776)
			(xy 266.177776 -31.737808) (xy 266.152926 -31.748548) (xy 266.100954 -31.7637) (xy 266.047364 -31.77136)
			(xy 266.020296 -31.771844) (xy 266.011152 -31.771844) (xy 265.996533 -31.771421) (xy 265.967418 -31.768626)
			(xy 265.952986 -31.766256) (xy 265.947398 -31.76524) (xy 265.944604 -31.764732) (xy 265.904635 -31.789431)
			(xy 265.820897 -31.832054) (xy 265.733519 -31.866609) (xy 265.643277 -31.892788) (xy 265.550972 -31.91036)
			(xy 265.457423 -31.919168) (xy 265.410442 -31.919672) (xy 265.363433 -31.919144) (xy 265.269831 -31.910322)
			(xy 265.177476 -31.892723) (xy 265.087189 -31.866504) (xy 264.999773 -31.831898) (xy 264.916004 -31.789213)
			(xy 264.876026 -31.764478) (xy 264.87501 -31.764732) (xy 264.868152 -31.766002) (xy 264.853787 -31.768424)
			(xy 264.824799 -31.771346) (xy 264.81024 -31.771844) (xy 264.799318 -31.771844) (xy 264.772135 -31.771257)
			(xy 264.718346 -31.76333) (xy 264.666227 -31.747848) (xy 264.616833 -31.725123) (xy 264.571166 -31.695617)
			(xy 264.530149 -31.659927) (xy 264.494615 -31.618775) (xy 264.465282 -31.572997) (xy 264.442745 -31.523517)
			(xy 264.42746 -31.47134) (xy 264.419737 -31.417521) (xy 264.419334 -31.390336) (xy 264.419334 -31.389066)
			(xy 264.419806 -31.364336) (xy 264.426358 -31.315309) (xy 264.439192 -31.26754) (xy 264.44829 -31.24454)
			(xy 264.450068 -31.240222) (xy 264.456672 -31.22422) (xy 264.457942 -31.218632) (xy 264.45337 -31.202884)
			(xy 264.44064 -31.157586) (xy 264.422755 -31.065204) (xy 264.413644 -30.971548) (xy 264.412984 -30.9245)
			(xy 264.412984 -30.91561) (xy 264.413584 -30.878397) (xy 264.419643 -30.804211) (xy 264.431221 -30.730684)
			(xy 264.4394 -30.694376) (xy 264.450766 -30.648428) (xy 264.481042 -30.558741) (xy 264.499852 -30.515306)
			(xy 264.50163 -30.511242) (xy 264.506202 -30.491176) (xy 264.506202 -30.49016) (xy 264.50163 -30.470094)
			(xy 264.499852 -30.46603) (xy 264.483124 -30.42756) (xy 264.455433 -30.348367) (xy 264.434495 -30.267127)
			(xy 264.420457 -30.184415) (xy 264.413419 -30.100815) (xy 264.412984 -30.058868) (xy 264.41344 -30.015527)
			(xy 264.420945 -29.929172) (xy 264.42797 -29.886402) (xy 264.432128 -29.863598) (xy 264.442292 -29.818368)
			(xy 264.44829 -29.795978) (xy 264.458196 -29.76245) (xy 264.456418 -29.755084) (xy 264.444713 -29.729287)
			(xy 264.428193 -29.675101) (xy 264.419853 -29.61907) (xy 264.419334 -29.590746) (xy 264.419334 -29.590238)
			(xy 264.419795 -29.562984) (xy 264.427548 -29.509032) (xy 264.442901 -29.456732) (xy 264.465542 -29.407149)
			(xy 264.495009 -29.361295) (xy 264.530704 -29.320101) (xy 264.571898 -29.284407) (xy 264.617753 -29.25494)
			(xy 264.667335 -29.232299) (xy 264.719636 -29.216947) (xy 264.773588 -29.209194) (xy 264.800842 -29.20873)
			(xy 264.801604 -29.20873) (xy 264.819299 -29.208943) (xy 264.854536 -29.212252) (xy 264.871962 -29.215334)
			(xy 264.876026 -29.216096) (xy 264.876788 -29.21635) (xy 264.916729 -29.1917) (xy 265.000402 -29.149163)
			(xy 265.0877 -29.114673) (xy 265.177852 -29.088536) (xy 265.27006 -29.070984) (xy 265.36351 -29.062171)
			(xy 265.410442 -29.061664) (xy 265.41095 -29.061664) (xy 265.457687 -29.062222) (xy 265.55075 -29.070992)
			(xy 265.642583 -29.088431) (xy 265.732382 -29.114387) (xy 265.819359 -29.148631) (xy 265.902749 -29.190863)
			(xy 265.942572 -29.215334) (xy 265.953748 -29.214318) (xy 265.95578 -29.214064) (xy 265.971662 -29.211553)
			(xy 266.003709 -29.208884) (xy 266.019788 -29.20873) (xy 266.020804 -29.20873) (xy 266.046196 -29.209147)
			(xy 266.096529 -29.215903) (xy 266.121134 -29.222192) (xy 266.122912 -29.2227) (xy 266.124182 -29.222954)
			(xy 266.127992 -29.22397) (xy 266.141962 -29.228542) (xy 266.14247 -29.228542) (xy 266.147804 -29.230574)
			(xy 266.160504 -29.231844) (xy 266.166346 -29.231082) (xy 266.177014 -29.228288) (xy 266.189206 -29.221684)
			(xy 266.252198 -29.17571) (xy 266.25296 -29.175202) (xy 266.257786 -29.171646) (xy 266.26439 -29.165296)
			(xy 266.267946 -29.16047) (xy 266.267438 -29.137864) (xy 266.267438 -29.13761) (xy 266.267184 -29.122624)
			(xy 266.267184 -29.108654) (xy 266.268155 -29.068167) (xy 266.275851 -28.987542) (xy 266.290067 -28.907807)
			(xy 266.31071 -28.829489) (xy 266.337642 -28.753106) (xy 266.353798 -28.71597) (xy 266.356846 -28.706318)
			(xy 266.360402 -28.691078) (xy 266.360402 -28.690062) (xy 266.35583 -28.669996) (xy 266.354052 -28.665932)
			(xy 266.337324 -28.627462) (xy 266.309633 -28.548269) (xy 266.288695 -28.467029) (xy 266.274657 -28.384317)
			(xy 266.267618 -28.300718) (xy 266.267184 -28.25877) (xy 266.267351 -28.234409) (xy 266.269766 -28.185746)
			(xy 266.27201 -28.161488) (xy 266.273978 -28.14242) (xy 266.279188 -28.104437) (xy 266.282424 -28.085542)
			(xy 266.288199 -28.054414) (xy 266.303198 -27.9929) (xy 266.312396 -27.962606) (xy 266.310618 -27.954986)
			(xy 266.308332 -27.95016) (xy 266.298749 -27.928471) (xy 266.284416 -27.883272) (xy 266.275786 -27.836647)
			(xy 266.274042 -27.813) (xy 266.274042 -27.808682) (xy 266.273534 -27.79014) (xy 266.273534 -27.78252)
			(xy 266.274531 -27.755626) (xy 266.283153 -27.702503) (xy 266.299156 -27.65112) (xy 266.322223 -27.602497)
			(xy 266.351895 -27.557598) (xy 266.387583 -27.517316) (xy 266.42858 -27.48245) (xy 266.47407 -27.453693)
			(xy 266.52315 -27.431615) (xy 266.574847 -27.416656) (xy 266.628133 -27.409111) (xy 266.655042 -27.408632)
			(xy 266.671767 -27.408812) (xy 266.705089 -27.411738) (xy 266.72159 -27.414474) (xy 266.731242 -27.415998)
			(xy 266.783058 -27.385264) (xy 266.783566 -27.385264) (xy 266.796012 -27.378152) (xy 266.799822 -27.368754)
			(xy 266.819634 -27.295348) (xy 266.81938 -27.281632) (xy 266.817602 -27.275028) (xy 266.813284 -27.259534)
			(xy 266.810236 -27.2542) (xy 266.798542 -27.232664) (xy 266.780126 -27.187249) (xy 266.767667 -27.139852)
			(xy 266.76137 -27.091251) (xy 266.76096 -27.066748) (xy 266.76096 -27.057604) (xy 266.761214 -27.05354)
			(xy 266.761214 -27.052778) (xy 266.7635 -27.022552) (xy 266.766605 -26.998918) (xy 266.777953 -26.952621)
			(xy 266.795 -26.908105) (xy 266.805918 -26.886916) (xy 266.818749 -26.8638) (xy 266.84982 -26.821025)
			(xy 266.886502 -26.782952) (xy 266.90701 -26.766266) (xy 266.909042 -26.764742) (xy 266.916154 -26.757884)
			(xy 266.929108 -26.742136) (xy 266.931648 -26.736802) (xy 266.934188 -26.725118) (xy 266.930124 -26.647394)
			(xy 266.929616 -26.634948) (xy 266.911328 -26.603452) (xy 266.906756 -26.59888) (xy 266.89558 -26.58745)
			(xy 266.88923 -26.583132) (xy 266.867333 -26.567858) (xy 266.827627 -26.532168) (xy 266.79328 -26.491295)
			(xy 266.764962 -26.446036) (xy 266.743227 -26.397272) (xy 266.728496 -26.345956) (xy 266.721059 -26.293088)
			(xy 266.720574 -26.266394) (xy 266.72106 -26.239143) (xy 266.728816 -26.185195) (xy 266.744171 -26.1329)
			(xy 266.766813 -26.083323) (xy 266.796279 -26.037473) (xy 266.83197 -25.996282) (xy 266.873161 -25.960591)
			(xy 266.919011 -25.931125) (xy 266.968588 -25.908483) (xy 267.020883 -25.893128) (xy 267.074831 -25.885372)
			(xy 267.129333 -25.885372) (xy 267.183281 -25.893128) (xy 267.235576 -25.908483) (xy 267.285153 -25.931125)
			(xy 267.331003 -25.960591) (xy 267.372194 -25.996282) (xy 267.407885 -26.037473) (xy 267.437351 -26.083323)
			(xy 267.459993 -26.1329) (xy 267.475348 -26.185195) (xy 267.483104 -26.239143) (xy 267.48359 -26.266394)
			(xy 267.483038 -26.295552) (xy 267.474166 -26.353189) (xy 267.456628 -26.408804) (xy 267.430831 -26.461104)
			(xy 267.397378 -26.50887) (xy 267.357046 -26.550989) (xy 267.334238 -26.569162) (xy 267.331444 -26.571194)
			(xy 267.32484 -26.577798) (xy 267.320268 -26.58364) (xy 267.316194 -26.589981) (xy 267.311542 -26.604309)
			(xy 267.311124 -26.611834) (xy 267.314934 -26.69667) (xy 267.31976 -26.706068) (xy 267.320776 -26.708354)
			(xy 267.333476 -26.72969) (xy 267.337794 -26.734008) (xy 267.34897 -26.745438) (xy 267.35532 -26.749756)
			(xy 267.377178 -26.764969) (xy 267.416825 -26.800524) (xy 267.451136 -26.841252) (xy 267.479445 -26.886359)
			(xy 267.5012 -26.934967) (xy 267.515978 -26.98613) (xy 267.52349 -27.038852) (xy 267.523976 -27.065478)
			(xy 267.523976 -27.06878) (xy 267.523303 -27.097505) (xy 267.514372 -27.154264) (xy 267.506196 -27.18181)
			(xy 267.50391 -27.189176) (xy 267.501159 -27.198775) (xy 267.502607 -27.218676) (xy 267.506704 -27.227784)
			(xy 267.53566 -27.28595) (xy 267.538708 -27.290776) (xy 267.546582 -27.299158) (xy 267.551662 -27.303476)
			(xy 267.5636 -27.307286) (xy 267.603354 -27.32024) (xy 267.658565 -27.342846) (xy 274.723352 -27.342846)
			(xy 274.723352 -26.479246) (xy 274.723842 -26.449262) (xy 274.73167 -26.389806) (xy 274.747191 -26.331881)
			(xy 274.77014 -26.276477) (xy 274.800124 -26.224543) (xy 274.83663 -26.176967) (xy 274.879035 -26.134562)
			(xy 274.926611 -26.098056) (xy 274.978545 -26.068072) (xy 275.033949 -26.045123) (xy 275.091874 -26.029602)
			(xy 275.15133 -26.021774) (xy 275.211298 -26.021774) (xy 275.270754 -26.029602) (xy 275.328679 -26.045123)
			(xy 275.384083 -26.068072) (xy 275.436017 -26.098056) (xy 275.483593 -26.134562) (xy 275.525998 -26.176967)
			(xy 275.562504 -26.224543) (xy 275.592488 -26.276477) (xy 275.615437 -26.331881) (xy 275.623208 -26.360882)
			(xy 277.289512 -26.360882) (xy 277.293583 -26.30526) (xy 277.305709 -26.250823) (xy 277.325632 -26.198732)
			(xy 277.352928 -26.150097) (xy 277.387014 -26.105954) (xy 277.427163 -26.067245) (xy 277.472521 -26.034794)
			(xy 277.522121 -26.009293) (xy 277.574905 -25.991286) (xy 277.629748 -25.981156) (xy 277.685482 -25.979119)
			(xy 277.740919 -25.985219) (xy 277.794876 -25.999325) (xy 277.846205 -26.021137) (xy 277.893811 -26.050191)
			(xy 277.936679 -26.085866) (xy 277.973896 -26.127403) (xy 278.004669 -26.173916) (xy 278.028341 -26.224413)
			(xy 278.044409 -26.27782) (xy 278.050577 -26.319734) (xy 283.04185 -26.319734) (xy 283.045921 -26.264112)
			(xy 283.058047 -26.209675) (xy 283.07797 -26.157584) (xy 283.105266 -26.108949) (xy 283.139352 -26.064806)
			(xy 283.179501 -26.026097) (xy 283.224859 -25.993646) (xy 283.274459 -25.968145) (xy 283.327243 -25.950138)
			(xy 283.382086 -25.940008) (xy 283.43782 -25.937971) (xy 283.493257 -25.944071) (xy 283.547214 -25.958177)
			(xy 283.598543 -25.979989) (xy 283.646149 -26.009043) (xy 283.675814 -26.03373) (xy 289.467796 -26.03373)
			(xy 289.471867 -25.978108) (xy 289.483993 -25.923671) (xy 289.503916 -25.87158) (xy 289.531212 -25.822945)
			(xy 289.565298 -25.778802) (xy 289.605447 -25.740093) (xy 289.650805 -25.707642) (xy 289.700405 -25.682141)
			(xy 289.753189 -25.664134) (xy 289.808032 -25.654004) (xy 289.863766 -25.651967) (xy 289.919203 -25.658067)
			(xy 289.97316 -25.672173) (xy 290.024489 -25.693985) (xy 290.072095 -25.723039) (xy 290.114963 -25.758714)
			(xy 290.15218 -25.800251) (xy 290.182953 -25.846764) (xy 290.206625 -25.897261) (xy 290.222693 -25.950668)
			(xy 290.230813 -26.005844) (xy 290.231322 -26.03373) (xy 290.230813 -26.061616) (xy 290.222693 -26.116792)
			(xy 290.206625 -26.170199) (xy 290.182953 -26.220696) (xy 290.15218 -26.267209) (xy 290.114963 -26.308746)
			(xy 290.072095 -26.344421) (xy 290.024489 -26.373475) (xy 289.97316 -26.395287) (xy 289.919203 -26.409393)
			(xy 289.863766 -26.415493) (xy 289.808032 -26.413456) (xy 289.753189 -26.403326) (xy 289.700405 -26.385319)
			(xy 289.650805 -26.359818) (xy 289.605447 -26.327367) (xy 289.565298 -26.288658) (xy 289.531212 -26.244515)
			(xy 289.503916 -26.19588) (xy 289.483993 -26.143789) (xy 289.471867 -26.089352) (xy 289.467796 -26.03373)
			(xy 283.675814 -26.03373) (xy 283.689017 -26.044718) (xy 283.726234 -26.086255) (xy 283.757007 -26.132768)
			(xy 283.780679 -26.183265) (xy 283.796747 -26.236672) (xy 283.804867 -26.291848) (xy 283.805376 -26.319734)
			(xy 283.804867 -26.34762) (xy 283.796747 -26.402796) (xy 283.780679 -26.456203) (xy 283.757007 -26.5067)
			(xy 283.726234 -26.553213) (xy 283.689017 -26.59475) (xy 283.646149 -26.630425) (xy 283.598543 -26.659479)
			(xy 283.547214 -26.681291) (xy 283.493257 -26.695397) (xy 283.43782 -26.701497) (xy 283.382086 -26.69946)
			(xy 283.327243 -26.68933) (xy 283.274459 -26.671323) (xy 283.224859 -26.645822) (xy 283.179501 -26.613371)
			(xy 283.139352 -26.574662) (xy 283.105266 -26.530519) (xy 283.07797 -26.481884) (xy 283.058047 -26.429793)
			(xy 283.045921 -26.375356) (xy 283.04185 -26.319734) (xy 278.050577 -26.319734) (xy 278.052529 -26.332996)
			(xy 278.053038 -26.360882) (xy 278.052529 -26.388768) (xy 278.044409 -26.443944) (xy 278.028341 -26.497351)
			(xy 278.004669 -26.547848) (xy 277.973896 -26.594361) (xy 277.936679 -26.635898) (xy 277.893811 -26.671573)
			(xy 277.846205 -26.700627) (xy 277.794876 -26.722439) (xy 277.740919 -26.736545) (xy 277.685482 -26.742645)
			(xy 277.629748 -26.740608) (xy 277.574905 -26.730478) (xy 277.522121 -26.712471) (xy 277.472521 -26.68697)
			(xy 277.427163 -26.654519) (xy 277.387014 -26.61581) (xy 277.352928 -26.571667) (xy 277.325632 -26.523032)
			(xy 277.305709 -26.470941) (xy 277.293583 -26.416504) (xy 277.289512 -26.360882) (xy 275.623208 -26.360882)
			(xy 275.630958 -26.389806) (xy 275.638786 -26.449262) (xy 275.639276 -26.479246) (xy 275.639276 -26.971244)
			(xy 279.051002 -26.971244) (xy 279.055073 -26.915622) (xy 279.067199 -26.861185) (xy 279.087122 -26.809094)
			(xy 279.114418 -26.760459) (xy 279.148504 -26.716316) (xy 279.188653 -26.677607) (xy 279.234011 -26.645156)
			(xy 279.283611 -26.619655) (xy 279.336395 -26.601648) (xy 279.391238 -26.591518) (xy 279.446972 -26.589481)
			(xy 279.502409 -26.595581) (xy 279.556366 -26.609687) (xy 279.607695 -26.631499) (xy 279.655301 -26.660553)
			(xy 279.698169 -26.696228) (xy 279.735386 -26.737765) (xy 279.766159 -26.784278) (xy 279.789831 -26.834775)
			(xy 279.805899 -26.888182) (xy 279.814019 -26.943358) (xy 279.814528 -26.971244) (xy 279.814019 -26.99913)
			(xy 279.805899 -27.054306) (xy 279.789831 -27.107713) (xy 279.766159 -27.15821) (xy 279.735386 -27.204723)
			(xy 279.698169 -27.24626) (xy 279.655301 -27.281935) (xy 279.607695 -27.310989) (xy 279.556366 -27.332801)
			(xy 279.502409 -27.346907) (xy 279.446972 -27.353007) (xy 279.391238 -27.35097) (xy 279.336395 -27.34084)
			(xy 279.283611 -27.322833) (xy 279.234011 -27.297332) (xy 279.188653 -27.264881) (xy 279.148504 -27.226172)
			(xy 279.114418 -27.182029) (xy 279.087122 -27.133394) (xy 279.067199 -27.081303) (xy 279.055073 -27.026866)
			(xy 279.051002 -26.971244) (xy 275.639276 -26.971244) (xy 275.639276 -27.342846) (xy 275.638786 -27.37283)
			(xy 275.630958 -27.432286) (xy 275.615437 -27.490211) (xy 275.592488 -27.545615) (xy 275.562504 -27.597549)
			(xy 275.525998 -27.645125) (xy 275.483593 -27.68753) (xy 275.436017 -27.724036) (xy 275.384083 -27.75402)
			(xy 275.328679 -27.776969) (xy 275.270754 -27.79249) (xy 275.211298 -27.800318) (xy 275.15133 -27.800318)
			(xy 275.091874 -27.79249) (xy 275.033949 -27.776969) (xy 274.978545 -27.75402) (xy 274.926611 -27.724036)
			(xy 274.879035 -27.68753) (xy 274.83663 -27.645125) (xy 274.800124 -27.597549) (xy 274.77014 -27.545615)
			(xy 274.747191 -27.490211) (xy 274.73167 -27.432286) (xy 274.723842 -27.37283) (xy 274.723352 -27.342846)
			(xy 267.658565 -27.342846) (xy 267.680736 -27.351924) (xy 267.755195 -27.389974) (xy 267.79093 -27.41168)
			(xy 267.799058 -27.41168) (xy 267.802868 -27.411172) (xy 267.803122 -27.411172) (xy 267.815314 -27.409902)
			(xy 267.816838 -27.409902) (xy 267.820394 -27.409394) (xy 267.848842 -27.408378) (xy 267.868146 -27.408886)
			(xy 267.877798 -27.409648) (xy 267.904805 -27.412183) (xy 267.957763 -27.423921) (xy 268.008525 -27.443039)
			(xy 268.056069 -27.469151) (xy 268.099437 -27.501731) (xy 268.137755 -27.540124) (xy 268.154404 -27.56154)
			(xy 268.156436 -27.56408) (xy 268.200832 -27.571475) (xy 268.28817 -27.593239) (xy 268.373192 -27.622782)
			(xy 268.455208 -27.659864) (xy 268.533549 -27.704184) (xy 268.60758 -27.755381) (xy 268.676697 -27.813039)
			(xy 268.708886 -27.844496) (xy 269.978862 -29.114242) (xy 277.047452 -29.114242) (xy 277.047452 -28.250642)
			(xy 277.047942 -28.220674) (xy 277.055765 -28.161252) (xy 277.071278 -28.103359) (xy 277.094214 -28.047986)
			(xy 277.124181 -27.99608) (xy 277.160668 -27.94853) (xy 277.203048 -27.90615) (xy 277.250598 -27.869663)
			(xy 277.302504 -27.839696) (xy 277.357877 -27.81676) (xy 277.41577 -27.801247) (xy 277.475192 -27.793424)
			(xy 277.535128 -27.793424) (xy 277.59455 -27.801247) (xy 277.652443 -27.81676) (xy 277.707816 -27.839696)
			(xy 277.759722 -27.869663) (xy 277.807272 -27.90615) (xy 277.849652 -27.94853) (xy 277.886139 -27.99608)
			(xy 277.916106 -28.047986) (xy 277.939042 -28.103359) (xy 277.954555 -28.161252) (xy 277.962378 -28.220674)
			(xy 277.962868 -28.250642) (xy 277.962868 -28.469082) (xy 281.952444 -28.469082) (xy 281.956515 -28.41346)
			(xy 281.968641 -28.359023) (xy 281.988564 -28.306932) (xy 282.01586 -28.258297) (xy 282.049946 -28.214154)
			(xy 282.090095 -28.175445) (xy 282.135453 -28.142994) (xy 282.185053 -28.117493) (xy 282.237837 -28.099486)
			(xy 282.29268 -28.089356) (xy 282.348414 -28.087319) (xy 282.403851 -28.093419) (xy 282.457808 -28.107525)
			(xy 282.509137 -28.129337) (xy 282.525193 -28.139136) (xy 286.59785 -28.139136) (xy 286.601921 -28.083514)
			(xy 286.614047 -28.029077) (xy 286.63397 -27.976986) (xy 286.661266 -27.928351) (xy 286.695352 -27.884208)
			(xy 286.735501 -27.845499) (xy 286.780859 -27.813048) (xy 286.830459 -27.787547) (xy 286.883243 -27.76954)
			(xy 286.938086 -27.75941) (xy 286.99382 -27.757373) (xy 287.049257 -27.763473) (xy 287.103214 -27.777579)
			(xy 287.154543 -27.799391) (xy 287.202149 -27.828445) (xy 287.245017 -27.86412) (xy 287.282234 -27.905657)
			(xy 287.313007 -27.95217) (xy 287.336679 -28.002667) (xy 287.352747 -28.056074) (xy 287.360867 -28.11125)
			(xy 287.361376 -28.139136) (xy 287.86785 -28.139136) (xy 287.871921 -28.083514) (xy 287.884047 -28.029077)
			(xy 287.90397 -27.976986) (xy 287.931266 -27.928351) (xy 287.965352 -27.884208) (xy 288.005501 -27.845499)
			(xy 288.050859 -27.813048) (xy 288.100459 -27.787547) (xy 288.153243 -27.76954) (xy 288.208086 -27.75941)
			(xy 288.26382 -27.757373) (xy 288.319257 -27.763473) (xy 288.373214 -27.777579) (xy 288.424543 -27.799391)
			(xy 288.472149 -27.828445) (xy 288.515017 -27.86412) (xy 288.552234 -27.905657) (xy 288.583007 -27.95217)
			(xy 288.606679 -28.002667) (xy 288.622747 -28.056074) (xy 288.630867 -28.11125) (xy 288.631376 -28.139136)
			(xy 288.630867 -28.167022) (xy 288.622747 -28.222198) (xy 288.606679 -28.275605) (xy 288.583007 -28.326102)
			(xy 288.552234 -28.372615) (xy 288.515017 -28.414152) (xy 288.472149 -28.449827) (xy 288.424543 -28.478881)
			(xy 288.373214 -28.500693) (xy 288.319257 -28.514799) (xy 288.26382 -28.520899) (xy 288.208086 -28.518862)
			(xy 288.153243 -28.508732) (xy 288.100459 -28.490725) (xy 288.050859 -28.465224) (xy 288.005501 -28.432773)
			(xy 287.965352 -28.394064) (xy 287.931266 -28.349921) (xy 287.90397 -28.301286) (xy 287.884047 -28.249195)
			(xy 287.871921 -28.194758) (xy 287.86785 -28.139136) (xy 287.361376 -28.139136) (xy 287.360867 -28.167022)
			(xy 287.352747 -28.222198) (xy 287.336679 -28.275605) (xy 287.313007 -28.326102) (xy 287.282234 -28.372615)
			(xy 287.245017 -28.414152) (xy 287.202149 -28.449827) (xy 287.154543 -28.478881) (xy 287.103214 -28.500693)
			(xy 287.049257 -28.514799) (xy 286.99382 -28.520899) (xy 286.938086 -28.518862) (xy 286.883243 -28.508732)
			(xy 286.830459 -28.490725) (xy 286.780859 -28.465224) (xy 286.735501 -28.432773) (xy 286.695352 -28.394064)
			(xy 286.661266 -28.349921) (xy 286.63397 -28.301286) (xy 286.614047 -28.249195) (xy 286.601921 -28.194758)
			(xy 286.59785 -28.139136) (xy 282.525193 -28.139136) (xy 282.556743 -28.158391) (xy 282.599611 -28.194066)
			(xy 282.636828 -28.235603) (xy 282.667601 -28.282116) (xy 282.691273 -28.332613) (xy 282.707341 -28.38602)
			(xy 282.715461 -28.441196) (xy 282.71597 -28.469082) (xy 282.715461 -28.496968) (xy 282.707341 -28.552144)
			(xy 282.691273 -28.605551) (xy 282.667601 -28.656048) (xy 282.636828 -28.702561) (xy 282.599611 -28.744098)
			(xy 282.556743 -28.779773) (xy 282.509137 -28.808827) (xy 282.457808 -28.830639) (xy 282.403851 -28.844745)
			(xy 282.348414 -28.850845) (xy 282.29268 -28.848808) (xy 282.237837 -28.838678) (xy 282.185053 -28.820671)
			(xy 282.135453 -28.79517) (xy 282.090095 -28.762719) (xy 282.049946 -28.72401) (xy 282.01586 -28.679867)
			(xy 281.988564 -28.631232) (xy 281.968641 -28.579141) (xy 281.956515 -28.524704) (xy 281.952444 -28.469082)
			(xy 277.962868 -28.469082) (xy 277.962868 -29.114242) (xy 277.962378 -29.14421) (xy 277.954555 -29.203632)
			(xy 277.939042 -29.261525) (xy 277.916106 -29.316898) (xy 277.886139 -29.368804) (xy 277.849652 -29.416354)
			(xy 277.807272 -29.458734) (xy 277.759722 -29.495221) (xy 277.707816 -29.525188) (xy 277.652443 -29.548124)
			(xy 277.59455 -29.563637) (xy 277.535128 -29.57146) (xy 277.475192 -29.57146) (xy 277.41577 -29.563637)
			(xy 277.357877 -29.548124) (xy 277.302504 -29.525188) (xy 277.250598 -29.495221) (xy 277.203048 -29.458734)
			(xy 277.160668 -29.416354) (xy 277.124181 -29.368804) (xy 277.094214 -29.316898) (xy 277.071278 -29.261525)
			(xy 277.055765 -29.203632) (xy 277.047942 -29.14421) (xy 277.047452 -29.114242) (xy 269.978862 -29.114242)
			(xy 270.110966 -29.246322) (xy 270.114014 -29.247846) (xy 270.117062 -29.24937) (xy 270.118078 -29.249878)
			(xy 270.144568 -29.263993) (xy 270.193133 -29.299263) (xy 270.23558 -29.341699) (xy 270.270861 -29.390256)
			(xy 270.284956 -29.416756) (xy 270.285464 -29.417772) (xy 270.286988 -29.42082) (xy 270.288512 -29.423868)
			(xy 270.407892 -29.543248) (xy 271.607788 -30.743398) (xy 271.632447 -30.768434) (xy 271.67859 -30.821443)
			(xy 271.69999 -30.849316) (xy 271.715139 -30.869694) (xy 271.743601 -30.911751) (xy 271.749089 -30.92069)
			(xy 279.68956 -30.92069) (xy 279.68956 -30.05709) (xy 279.69005 -30.027122) (xy 279.697873 -29.9677)
			(xy 279.713386 -29.909807) (xy 279.736322 -29.854434) (xy 279.766289 -29.802528) (xy 279.802776 -29.754978)
			(xy 279.845156 -29.712598) (xy 279.892706 -29.676111) (xy 279.944612 -29.646144) (xy 279.999985 -29.623208)
			(xy 280.057878 -29.607695) (xy 280.1173 -29.599872) (xy 280.177236 -29.599872) (xy 280.236658 -29.607695)
			(xy 280.294551 -29.623208) (xy 280.349924 -29.646144) (xy 280.40183 -29.676111) (xy 280.44938 -29.712598)
			(xy 280.49176 -29.754978) (xy 280.528247 -29.802528) (xy 280.558214 -29.854434) (xy 280.58115 -29.909807)
			(xy 280.596663 -29.9677) (xy 280.604486 -30.027122) (xy 280.604976 -30.05709) (xy 280.604976 -30.376876)
			(xy 285.088838 -30.376876) (xy 285.089397 -30.34796) (xy 285.098115 -30.29079) (xy 285.115364 -30.235592)
			(xy 285.140748 -30.18363) (xy 285.173686 -30.136095) (xy 285.213421 -30.094077) (xy 285.235904 -30.075886)
			(xy 285.244708 -30.068276) (xy 285.254893 -30.047377) (xy 285.255462 -30.035754) (xy 285.255462 -29.955998)
			(xy 285.254923 -29.944366) (xy 285.244735 -29.923455) (xy 285.235904 -29.915866) (xy 285.213405 -29.897693)
			(xy 285.173671 -29.85567) (xy 285.140733 -29.808131) (xy 285.115348 -29.756166) (xy 285.098095 -29.700965)
			(xy 285.08937 -29.643793) (xy 285.088838 -29.614876) (xy 285.089324 -29.587625) (xy 285.09708 -29.533677)
			(xy 285.112435 -29.481382) (xy 285.135077 -29.431805) (xy 285.164543 -29.385955) (xy 285.200234 -29.344764)
			(xy 285.241425 -29.309073) (xy 285.287275 -29.279607) (xy 285.336852 -29.256965) (xy 285.389147 -29.24161)
			(xy 285.443095 -29.233854) (xy 285.497597 -29.233854) (xy 285.551545 -29.24161) (xy 285.60384 -29.256965)
			(xy 285.653417 -29.279607) (xy 285.699267 -29.309073) (xy 285.740458 -29.344764) (xy 285.776149 -29.385955)
			(xy 285.805615 -29.431805) (xy 285.828257 -29.481382) (xy 285.843612 -29.533677) (xy 285.851368 -29.587625)
			(xy 285.851854 -29.614876) (xy 285.851336 -29.643793) (xy 285.842609 -29.700965) (xy 285.825352 -29.756165)
			(xy 285.799961 -29.808127) (xy 285.767016 -29.855661) (xy 285.727274 -29.897677) (xy 285.704788 -29.915866)
			(xy 285.696004 -29.923496) (xy 285.685808 -29.944379) (xy 285.68523 -29.955998) (xy 285.68523 -30.035754)
			(xy 285.685742 -30.04739) (xy 285.695949 -30.068299) (xy 285.704788 -30.075886) (xy 285.727262 -30.094088)
			(xy 285.766999 -30.136105) (xy 285.799939 -30.183638) (xy 285.825329 -30.235597) (xy 285.842587 -30.290793)
			(xy 285.851318 -30.347961) (xy 285.851854 -30.376876) (xy 288.128964 -30.376876) (xy 288.129513 -30.34796)
			(xy 288.138232 -30.290789) (xy 288.155482 -30.23559) (xy 288.180868 -30.183627) (xy 288.213808 -30.136093)
			(xy 288.253546 -30.094076) (xy 288.27603 -30.075886) (xy 288.284839 -30.06828) (xy 288.29502 -30.047378)
			(xy 288.295588 -30.035754) (xy 288.295588 -29.955998) (xy 288.29504 -29.944367) (xy 288.284858 -29.923457)
			(xy 288.27603 -29.915866) (xy 288.253536 -29.897687) (xy 288.213801 -29.855665) (xy 288.180862 -29.808128)
			(xy 288.155475 -29.756165) (xy 288.138221 -29.700965) (xy 288.129496 -29.643793) (xy 288.128964 -29.614876)
			(xy 288.12945 -29.587625) (xy 288.137206 -29.533677) (xy 288.152561 -29.481382) (xy 288.175203 -29.431805)
			(xy 288.204669 -29.385955) (xy 288.24036 -29.344764) (xy 288.281551 -29.309073) (xy 288.327401 -29.279607)
			(xy 288.376978 -29.256965) (xy 288.429273 -29.24161) (xy 288.483221 -29.233854) (xy 288.537723 -29.233854)
			(xy 288.591671 -29.24161) (xy 288.643966 -29.256965) (xy 288.693543 -29.279607) (xy 288.739393 -29.309073)
			(xy 288.780584 -29.344764) (xy 288.816275 -29.385955) (xy 288.845741 -29.431805) (xy 288.868383 -29.481382)
			(xy 288.883738 -29.533677) (xy 288.891494 -29.587625) (xy 288.89198 -29.614876) (xy 288.891452 -29.643793)
			(xy 288.882726 -29.700964) (xy 288.86547 -29.756163) (xy 288.840081 -29.808125) (xy 288.807139 -29.855659)
			(xy 288.767399 -29.897676) (xy 288.744914 -29.915866) (xy 288.736118 -29.923483) (xy 288.725932 -29.944377)
			(xy 288.725356 -29.955998) (xy 288.725356 -30.035754) (xy 288.725859 -30.047391) (xy 288.736071 -30.068301)
			(xy 288.744914 -30.075886) (xy 288.767394 -30.094081) (xy 288.807128 -30.136101) (xy 288.840068 -30.183635)
			(xy 288.865456 -30.235595) (xy 288.882714 -30.290792) (xy 288.891444 -30.34796) (xy 288.89198 -30.376876)
			(xy 288.891494 -30.404127) (xy 288.883738 -30.458075) (xy 288.868383 -30.51037) (xy 288.845741 -30.559947)
			(xy 288.816275 -30.605797) (xy 288.780584 -30.646988) (xy 288.739393 -30.682679) (xy 288.693543 -30.712145)
			(xy 288.643966 -30.734787) (xy 288.591671 -30.750142) (xy 288.537723 -30.757898) (xy 288.483221 -30.757898)
			(xy 288.429273 -30.750142) (xy 288.376978 -30.734787) (xy 288.327401 -30.712145) (xy 288.281551 -30.682679)
			(xy 288.24036 -30.646988) (xy 288.204669 -30.605797) (xy 288.175203 -30.559947) (xy 288.152561 -30.51037)
			(xy 288.137206 -30.458075) (xy 288.12945 -30.404127) (xy 288.128964 -30.376876) (xy 285.851854 -30.376876)
			(xy 285.851368 -30.404127) (xy 285.843612 -30.458075) (xy 285.828257 -30.51037) (xy 285.805615 -30.559947)
			(xy 285.776149 -30.605797) (xy 285.740458 -30.646988) (xy 285.699267 -30.682679) (xy 285.653417 -30.712145)
			(xy 285.60384 -30.734787) (xy 285.551545 -30.750142) (xy 285.497597 -30.757898) (xy 285.443095 -30.757898)
			(xy 285.389147 -30.750142) (xy 285.336852 -30.734787) (xy 285.287275 -30.712145) (xy 285.241425 -30.682679)
			(xy 285.200234 -30.646988) (xy 285.164543 -30.605797) (xy 285.135077 -30.559947) (xy 285.112435 -30.51037)
			(xy 285.09708 -30.458075) (xy 285.089324 -30.404127) (xy 285.088838 -30.376876) (xy 280.604976 -30.376876)
			(xy 280.604976 -30.92069) (xy 280.604486 -30.950658) (xy 280.596663 -31.01008) (xy 280.58115 -31.067973)
			(xy 280.558214 -31.123346) (xy 280.528247 -31.175252) (xy 280.49176 -31.222802) (xy 280.44938 -31.265182)
			(xy 280.40183 -31.301669) (xy 280.349924 -31.331636) (xy 280.294551 -31.354572) (xy 280.236658 -31.370085)
			(xy 280.177236 -31.377908) (xy 280.1173 -31.377908) (xy 280.057878 -31.370085) (xy 279.999985 -31.354572)
			(xy 279.944612 -31.331636) (xy 279.892706 -31.301669) (xy 279.845156 -31.265182) (xy 279.802776 -31.222802)
			(xy 279.766289 -31.175252) (xy 279.736322 -31.123346) (xy 279.713386 -31.067973) (xy 279.697873 -31.01008)
			(xy 279.69005 -30.950658) (xy 279.68956 -30.92069) (xy 271.749089 -30.92069) (xy 271.756886 -30.93339)
			(xy 271.757902 -30.935168) (xy 271.763998 -30.94355) (xy 271.777834 -30.958748) (xy 271.804384 -30.990128)
			(xy 271.817084 -31.006288) (xy 271.830187 -31.023208) (xy 271.855089 -31.058017) (xy 271.866868 -31.075884)
			(xy 271.883378 -31.1023) (xy 271.884394 -31.104332) (xy 271.885918 -31.106618) (xy 271.892014 -31.116778)
			(xy 271.900142 -31.130748) (xy 271.900142 -31.131002) (xy 271.906238 -31.142178) (xy 271.907254 -31.14421)
			(xy 271.919211 -31.166691) (xy 271.941065 -31.212689) (xy 271.950942 -31.236158) (xy 272.563224 -32.714184)
			(xy 277.047452 -32.714184) (xy 277.047452 -31.850584) (xy 277.047942 -31.820616) (xy 277.055765 -31.761194)
			(xy 277.071278 -31.703301) (xy 277.094214 -31.647928) (xy 277.124181 -31.596022) (xy 277.160668 -31.548472)
			(xy 277.203048 -31.506092) (xy 277.250598 -31.469605) (xy 277.302504 -31.439638) (xy 277.357877 -31.416702)
			(xy 277.41577 -31.401189) (xy 277.475192 -31.393366) (xy 277.535128 -31.393366) (xy 277.59455 -31.401189)
			(xy 277.652443 -31.416702) (xy 277.707816 -31.439638) (xy 277.759722 -31.469605) (xy 277.807272 -31.506092)
			(xy 277.849652 -31.548472) (xy 277.864546 -31.567882) (xy 285.198564 -31.567882) (xy 285.202635 -31.51226)
			(xy 285.214761 -31.457823) (xy 285.234684 -31.405732) (xy 285.26198 -31.357097) (xy 285.296066 -31.312954)
			(xy 285.336215 -31.274245) (xy 285.381573 -31.241794) (xy 285.431173 -31.216293) (xy 285.483957 -31.198286)
			(xy 285.5388 -31.188156) (xy 285.594534 -31.186119) (xy 285.649971 -31.192219) (xy 285.703928 -31.206325)
			(xy 285.755257 -31.228137) (xy 285.802863 -31.257191) (xy 285.845731 -31.292866) (xy 285.882948 -31.334403)
			(xy 285.913721 -31.380916) (xy 285.937393 -31.431413) (xy 285.953461 -31.48482) (xy 285.961581 -31.539996)
			(xy 285.96209 -31.567882) (xy 285.961581 -31.595768) (xy 285.953461 -31.650944) (xy 285.937393 -31.704351)
			(xy 285.930401 -31.719266) (xy 286.485328 -31.719266) (xy 286.489399 -31.663644) (xy 286.501525 -31.609207)
			(xy 286.521448 -31.557116) (xy 286.548744 -31.508481) (xy 286.58283 -31.464338) (xy 286.622979 -31.425629)
			(xy 286.668337 -31.393178) (xy 286.717937 -31.367677) (xy 286.770721 -31.34967) (xy 286.825564 -31.33954)
			(xy 286.881298 -31.337503) (xy 286.936735 -31.343603) (xy 286.990692 -31.357709) (xy 287.042021 -31.379521)
			(xy 287.089627 -31.408575) (xy 287.132495 -31.44425) (xy 287.169712 -31.485787) (xy 287.200485 -31.5323)
			(xy 287.224157 -31.582797) (xy 287.240225 -31.636204) (xy 287.244375 -31.664402) (xy 287.760916 -31.664402)
			(xy 287.764987 -31.60878) (xy 287.777113 -31.554343) (xy 287.797036 -31.502252) (xy 287.824332 -31.453617)
			(xy 287.858418 -31.409474) (xy 287.898567 -31.370765) (xy 287.943925 -31.338314) (xy 287.993525 -31.312813)
			(xy 288.046309 -31.294806) (xy 288.101152 -31.284676) (xy 288.156886 -31.282639) (xy 288.212323 -31.288739)
			(xy 288.26628 -31.302845) (xy 288.317609 -31.324657) (xy 288.365215 -31.353711) (xy 288.408083 -31.389386)
			(xy 288.4453 -31.430923) (xy 288.476073 -31.477436) (xy 288.499745 -31.527933) (xy 288.515813 -31.58134)
			(xy 288.523933 -31.636516) (xy 288.524442 -31.664402) (xy 288.523933 -31.692288) (xy 288.515813 -31.747464)
			(xy 288.506873 -31.777178) (xy 289.02609 -31.777178) (xy 289.030161 -31.721556) (xy 289.042287 -31.667119)
			(xy 289.06221 -31.615028) (xy 289.089506 -31.566393) (xy 289.123592 -31.52225) (xy 289.163741 -31.483541)
			(xy 289.209099 -31.45109) (xy 289.258699 -31.425589) (xy 289.311483 -31.407582) (xy 289.366326 -31.397452)
			(xy 289.42206 -31.395415) (xy 289.477497 -31.401515) (xy 289.531454 -31.415621) (xy 289.582783 -31.437433)
			(xy 289.630389 -31.466487) (xy 289.673257 -31.502162) (xy 289.710474 -31.543699) (xy 289.741247 -31.590212)
			(xy 289.764919 -31.640709) (xy 289.780987 -31.694116) (xy 289.789107 -31.749292) (xy 289.789616 -31.777178)
			(xy 289.789107 -31.805064) (xy 289.780987 -31.86024) (xy 289.764919 -31.913647) (xy 289.741247 -31.964144)
			(xy 289.710474 -32.010657) (xy 289.673257 -32.052194) (xy 289.630389 -32.087869) (xy 289.582783 -32.116923)
			(xy 289.531454 -32.138735) (xy 289.477497 -32.152841) (xy 289.42206 -32.158941) (xy 289.366326 -32.156904)
			(xy 289.311483 -32.146774) (xy 289.258699 -32.128767) (xy 289.209099 -32.103266) (xy 289.163741 -32.070815)
			(xy 289.123592 -32.032106) (xy 289.089506 -31.987963) (xy 289.06221 -31.939328) (xy 289.042287 -31.887237)
			(xy 289.030161 -31.8328) (xy 289.02609 -31.777178) (xy 288.506873 -31.777178) (xy 288.499745 -31.800871)
			(xy 288.476073 -31.851368) (xy 288.4453 -31.897881) (xy 288.408083 -31.939418) (xy 288.365215 -31.975093)
			(xy 288.317609 -32.004147) (xy 288.26628 -32.025959) (xy 288.212323 -32.040065) (xy 288.156886 -32.046165)
			(xy 288.101152 -32.044128) (xy 288.046309 -32.033998) (xy 287.993525 -32.015991) (xy 287.943925 -31.99049)
			(xy 287.898567 -31.958039) (xy 287.858418 -31.91933) (xy 287.824332 -31.875187) (xy 287.797036 -31.826552)
			(xy 287.777113 -31.774461) (xy 287.764987 -31.720024) (xy 287.760916 -31.664402) (xy 287.244375 -31.664402)
			(xy 287.248345 -31.69138) (xy 287.248854 -31.719266) (xy 287.248345 -31.747152) (xy 287.240225 -31.802328)
			(xy 287.224157 -31.855735) (xy 287.200485 -31.906232) (xy 287.169712 -31.952745) (xy 287.132495 -31.994282)
			(xy 287.089627 -32.029957) (xy 287.042021 -32.059011) (xy 286.990692 -32.080823) (xy 286.936735 -32.094929)
			(xy 286.881298 -32.101029) (xy 286.825564 -32.098992) (xy 286.770721 -32.088862) (xy 286.717937 -32.070855)
			(xy 286.668337 -32.045354) (xy 286.622979 -32.012903) (xy 286.58283 -31.974194) (xy 286.548744 -31.930051)
			(xy 286.521448 -31.881416) (xy 286.501525 -31.829325) (xy 286.489399 -31.774888) (xy 286.485328 -31.719266)
			(xy 285.930401 -31.719266) (xy 285.913721 -31.754848) (xy 285.882948 -31.801361) (xy 285.845731 -31.842898)
			(xy 285.802863 -31.878573) (xy 285.755257 -31.907627) (xy 285.703928 -31.929439) (xy 285.649971 -31.943545)
			(xy 285.594534 -31.949645) (xy 285.5388 -31.947608) (xy 285.483957 -31.937478) (xy 285.431173 -31.919471)
			(xy 285.381573 -31.89397) (xy 285.336215 -31.861519) (xy 285.296066 -31.82281) (xy 285.26198 -31.778667)
			(xy 285.234684 -31.730032) (xy 285.214761 -31.677941) (xy 285.202635 -31.623504) (xy 285.198564 -31.567882)
			(xy 277.864546 -31.567882) (xy 277.886139 -31.596022) (xy 277.916106 -31.647928) (xy 277.939042 -31.703301)
			(xy 277.954555 -31.761194) (xy 277.962378 -31.820616) (xy 277.962868 -31.850584) (xy 277.962868 -32.714184)
			(xy 277.962378 -32.744152) (xy 277.954555 -32.803574) (xy 277.939042 -32.861467) (xy 277.916106 -32.91684)
			(xy 277.886139 -32.968746) (xy 277.849652 -33.016296) (xy 277.807272 -33.058676) (xy 277.759722 -33.095163)
			(xy 277.707816 -33.12513) (xy 277.652443 -33.148066) (xy 277.59455 -33.163579) (xy 277.535128 -33.171402)
			(xy 277.475192 -33.171402) (xy 277.41577 -33.163579) (xy 277.357877 -33.148066) (xy 277.302504 -33.12513)
			(xy 277.250598 -33.095163) (xy 277.203048 -33.058676) (xy 277.160668 -33.016296) (xy 277.124181 -32.968746)
			(xy 277.094214 -32.91684) (xy 277.071278 -32.861467) (xy 277.055765 -32.803574) (xy 277.047942 -32.744152)
			(xy 277.047452 -32.714184) (xy 272.563224 -32.714184) (xy 272.569432 -32.72917) (xy 272.585942 -32.768794)
			(xy 272.612866 -32.833056) (xy 272.614442 -32.836677) (xy 272.618526 -32.843435) (xy 272.620994 -32.846518)
			(xy 272.626074 -32.852106) (xy 272.63471 -32.856932) (xy 272.635218 -32.857186) (xy 272.659873 -32.871566)
			(xy 272.704966 -32.906554) (xy 272.744341 -32.947872) (xy 272.777117 -32.994598) (xy 272.802563 -33.045687)
			(xy 272.820109 -33.099998) (xy 272.829363 -33.156318) (xy 272.83029 -33.184846) (xy 272.83029 -33.191704)
			(xy 272.829854 -33.217759) (xy 272.822721 -33.269379) (xy 272.816066 -33.294574) (xy 272.816066 -33.295082)
			(xy 272.814132 -33.303246) (xy 272.815174 -33.319983) (xy 272.818098 -33.327848) (xy 273.312125 -34.520886)
			(xy 279.68956 -34.520886) (xy 279.68956 -33.657286) (xy 279.69005 -33.627318) (xy 279.697873 -33.567896)
			(xy 279.713386 -33.510003) (xy 279.736322 -33.45463) (xy 279.766289 -33.402724) (xy 279.802776 -33.355174)
			(xy 279.845156 -33.312794) (xy 279.892706 -33.276307) (xy 279.944612 -33.24634) (xy 279.999985 -33.223404)
			(xy 280.057878 -33.207891) (xy 280.1173 -33.200068) (xy 280.177236 -33.200068) (xy 280.236658 -33.207891)
			(xy 280.294551 -33.223404) (xy 280.349924 -33.24634) (xy 280.40183 -33.276307) (xy 280.44938 -33.312794)
			(xy 280.49176 -33.355174) (xy 280.528247 -33.402724) (xy 280.558214 -33.45463) (xy 280.58115 -33.510003)
			(xy 280.596663 -33.567896) (xy 280.604486 -33.627318) (xy 280.604976 -33.657286) (xy 280.604976 -34.520886)
			(xy 280.604486 -34.550854) (xy 280.596663 -34.610276) (xy 280.58115 -34.668169) (xy 280.558214 -34.723542)
			(xy 280.528247 -34.775448) (xy 280.49176 -34.822998) (xy 280.44938 -34.865378) (xy 280.40183 -34.901865)
			(xy 280.349924 -34.931832) (xy 280.294551 -34.954768) (xy 280.236658 -34.970281) (xy 280.177236 -34.978104)
			(xy 280.1173 -34.978104) (xy 280.057878 -34.970281) (xy 279.999985 -34.954768) (xy 279.944612 -34.931832)
			(xy 279.892706 -34.901865) (xy 279.845156 -34.865378) (xy 279.802776 -34.822998) (xy 279.766289 -34.775448)
			(xy 279.736322 -34.723542) (xy 279.713386 -34.668169) (xy 279.697873 -34.610276) (xy 279.69005 -34.550854)
			(xy 279.68956 -34.520886) (xy 273.312125 -34.520886) (xy 273.620195 -35.264852) (xy 288.102292 -35.264852)
			(xy 288.106363 -35.20923) (xy 288.118489 -35.154793) (xy 288.138412 -35.102702) (xy 288.165708 -35.054067)
			(xy 288.199794 -35.009924) (xy 288.239943 -34.971215) (xy 288.285301 -34.938764) (xy 288.334901 -34.913263)
			(xy 288.387685 -34.895256) (xy 288.442528 -34.885126) (xy 288.498262 -34.883089) (xy 288.553699 -34.889189)
			(xy 288.607656 -34.903295) (xy 288.658985 -34.925107) (xy 288.706591 -34.954161) (xy 288.749459 -34.989836)
			(xy 288.786676 -35.031373) (xy 288.817449 -35.077886) (xy 288.841121 -35.128383) (xy 288.857189 -35.18179)
			(xy 288.865309 -35.236966) (xy 288.865818 -35.264852) (xy 288.865309 -35.292738) (xy 288.857189 -35.347914)
			(xy 288.841121 -35.401321) (xy 288.817449 -35.451818) (xy 288.786676 -35.498331) (xy 288.749459 -35.539868)
			(xy 288.706591 -35.575543) (xy 288.658985 -35.604597) (xy 288.607656 -35.626409) (xy 288.553699 -35.640515)
			(xy 288.498262 -35.646615) (xy 288.442528 -35.644578) (xy 288.387685 -35.634448) (xy 288.334901 -35.616441)
			(xy 288.285301 -35.59094) (xy 288.239943 -35.558489) (xy 288.199794 -35.51978) (xy 288.165708 -35.475637)
			(xy 288.138412 -35.427002) (xy 288.118489 -35.374911) (xy 288.106363 -35.320474) (xy 288.102292 -35.264852)
			(xy 273.620195 -35.264852) (xy 273.80184 -35.70351) (xy 273.873537 -35.876738) (xy 276.917148 -35.876738)
			(xy 276.921219 -35.821116) (xy 276.933345 -35.766679) (xy 276.953268 -35.714588) (xy 276.980564 -35.665953)
			(xy 277.01465 -35.62181) (xy 277.054799 -35.583101) (xy 277.100157 -35.55065) (xy 277.149757 -35.525149)
			(xy 277.202541 -35.507142) (xy 277.257384 -35.497012) (xy 277.313118 -35.494975) (xy 277.368555 -35.501075)
			(xy 277.422512 -35.515181) (xy 277.473841 -35.536993) (xy 277.521447 -35.566047) (xy 277.564315 -35.601722)
			(xy 277.601532 -35.643259) (xy 277.632305 -35.689772) (xy 277.655977 -35.740269) (xy 277.672045 -35.793676)
			(xy 277.680165 -35.848852) (xy 277.680674 -35.876738) (xy 280.988768 -35.876738) (xy 280.992839 -35.821116)
			(xy 281.004965 -35.766679) (xy 281.024888 -35.714588) (xy 281.052184 -35.665953) (xy 281.08627 -35.62181)
			(xy 281.126419 -35.583101) (xy 281.171777 -35.55065) (xy 281.221377 -35.525149) (xy 281.274161 -35.507142)
			(xy 281.329004 -35.497012) (xy 281.384738 -35.494975) (xy 281.440175 -35.501075) (xy 281.494132 -35.515181)
			(xy 281.545461 -35.536993) (xy 281.593067 -35.566047) (xy 281.635935 -35.601722) (xy 281.673152 -35.643259)
			(xy 281.703925 -35.689772) (xy 281.727597 -35.740269) (xy 281.743665 -35.793676) (xy 281.751785 -35.848852)
			(xy 281.752294 -35.876738) (xy 281.751785 -35.904624) (xy 281.743665 -35.9598) (xy 281.727597 -36.013207)
			(xy 281.703925 -36.063704) (xy 281.673152 -36.110217) (xy 281.635935 -36.151754) (xy 281.593067 -36.187429)
			(xy 281.545461 -36.216483) (xy 281.494132 -36.238295) (xy 281.440175 -36.252401) (xy 281.384738 -36.258501)
			(xy 281.329004 -36.256464) (xy 281.274161 -36.246334) (xy 281.221377 -36.228327) (xy 281.171777 -36.202826)
			(xy 281.126419 -36.170375) (xy 281.08627 -36.131666) (xy 281.052184 -36.087523) (xy 281.024888 -36.038888)
			(xy 281.004965 -35.986797) (xy 280.992839 -35.93236) (xy 280.988768 -35.876738) (xy 277.680674 -35.876738)
			(xy 277.680165 -35.904624) (xy 277.672045 -35.9598) (xy 277.655977 -36.013207) (xy 277.632305 -36.063704)
			(xy 277.601532 -36.110217) (xy 277.564315 -36.151754) (xy 277.521447 -36.187429) (xy 277.473841 -36.216483)
			(xy 277.422512 -36.238295) (xy 277.368555 -36.252401) (xy 277.313118 -36.258501) (xy 277.257384 -36.256464)
			(xy 277.202541 -36.246334) (xy 277.149757 -36.228327) (xy 277.100157 -36.202826) (xy 277.054799 -36.170375)
			(xy 277.01465 -36.131666) (xy 276.980564 -36.087523) (xy 276.953268 -36.038888) (xy 276.933345 -35.986797)
			(xy 276.921219 -35.93236) (xy 276.917148 -35.876738) (xy 273.873537 -35.876738) (xy 274.035012 -36.266882)
			(xy 274.069302 -36.349432) (xy 274.135781 -36.50996) (xy 278.813766 -36.50996) (xy 278.817837 -36.454338)
			(xy 278.829963 -36.399901) (xy 278.849886 -36.34781) (xy 278.877182 -36.299175) (xy 278.911268 -36.255032)
			(xy 278.951417 -36.216323) (xy 278.996775 -36.183872) (xy 279.046375 -36.158371) (xy 279.099159 -36.140364)
			(xy 279.154002 -36.130234) (xy 279.209736 -36.128197) (xy 279.265173 -36.134297) (xy 279.31913 -36.148403)
			(xy 279.370459 -36.170215) (xy 279.418065 -36.199269) (xy 279.460933 -36.234944) (xy 279.49815 -36.276481)
			(xy 279.528923 -36.322994) (xy 279.552595 -36.373491) (xy 279.568663 -36.426898) (xy 279.572588 -36.453572)
			(xy 282.128466 -36.453572) (xy 282.132537 -36.39795) (xy 282.144663 -36.343513) (xy 282.164586 -36.291422)
			(xy 282.191882 -36.242787) (xy 282.225968 -36.198644) (xy 282.266117 -36.159935) (xy 282.311475 -36.127484)
			(xy 282.361075 -36.101983) (xy 282.413859 -36.083976) (xy 282.468702 -36.073846) (xy 282.524436 -36.071809)
			(xy 282.579873 -36.077909) (xy 282.63383 -36.092015) (xy 282.685159 -36.113827) (xy 282.732765 -36.142881)
			(xy 282.775633 -36.178556) (xy 282.81285 -36.220093) (xy 282.843623 -36.266606) (xy 282.853159 -36.286948)
			(xy 289.400232 -36.286948) (xy 289.404303 -36.231326) (xy 289.416429 -36.176889) (xy 289.436352 -36.124798)
			(xy 289.463648 -36.076163) (xy 289.497734 -36.03202) (xy 289.537883 -35.993311) (xy 289.583241 -35.96086)
			(xy 289.632841 -35.935359) (xy 289.685625 -35.917352) (xy 289.740468 -35.907222) (xy 289.796202 -35.905185)
			(xy 289.851639 -35.911285) (xy 289.905596 -35.925391) (xy 289.956925 -35.947203) (xy 290.004531 -35.976257)
			(xy 290.047399 -36.011932) (xy 290.084616 -36.053469) (xy 290.115389 -36.099982) (xy 290.139061 -36.150479)
			(xy 290.155129 -36.203886) (xy 290.163249 -36.259062) (xy 290.163758 -36.286948) (xy 290.163249 -36.314834)
			(xy 290.155129 -36.37001) (xy 290.139061 -36.423417) (xy 290.115389 -36.473914) (xy 290.084616 -36.520427)
			(xy 290.047399 -36.561964) (xy 290.004531 -36.597639) (xy 289.956925 -36.626693) (xy 289.905596 -36.648505)
			(xy 289.851639 -36.662611) (xy 289.796202 -36.668711) (xy 289.740468 -36.666674) (xy 289.685625 -36.656544)
			(xy 289.632841 -36.638537) (xy 289.583241 -36.613036) (xy 289.537883 -36.580585) (xy 289.497734 -36.541876)
			(xy 289.463648 -36.497733) (xy 289.436352 -36.449098) (xy 289.416429 -36.397007) (xy 289.404303 -36.34257)
			(xy 289.400232 -36.286948) (xy 282.853159 -36.286948) (xy 282.867295 -36.317103) (xy 282.883363 -36.37051)
			(xy 282.891483 -36.425686) (xy 282.891992 -36.453572) (xy 282.891483 -36.481458) (xy 282.883363 -36.536634)
			(xy 282.867295 -36.590041) (xy 282.843623 -36.640538) (xy 282.81285 -36.687051) (xy 282.775633 -36.728588)
			(xy 282.732765 -36.764263) (xy 282.685159 -36.793317) (xy 282.63383 -36.815129) (xy 282.579873 -36.829235)
			(xy 282.524436 -36.835335) (xy 282.468702 -36.833298) (xy 282.413859 -36.823168) (xy 282.361075 -36.805161)
			(xy 282.311475 -36.77966) (xy 282.266117 -36.747209) (xy 282.225968 -36.7085) (xy 282.191882 -36.664357)
			(xy 282.164586 -36.615722) (xy 282.144663 -36.563631) (xy 282.132537 -36.509194) (xy 282.128466 -36.453572)
			(xy 279.572588 -36.453572) (xy 279.576783 -36.482074) (xy 279.577292 -36.50996) (xy 279.576783 -36.537846)
			(xy 279.568663 -36.593022) (xy 279.552595 -36.646429) (xy 279.528923 -36.696926) (xy 279.49815 -36.743439)
			(xy 279.460933 -36.784976) (xy 279.418065 -36.820651) (xy 279.370459 -36.849705) (xy 279.31913 -36.871517)
			(xy 279.265173 -36.885623) (xy 279.209736 -36.891723) (xy 279.154002 -36.889686) (xy 279.099159 -36.879556)
			(xy 279.046375 -36.861549) (xy 278.996775 -36.836048) (xy 278.951417 -36.803597) (xy 278.911268 -36.764888)
			(xy 278.877182 -36.720745) (xy 278.849886 -36.67211) (xy 278.829963 -36.620019) (xy 278.817837 -36.565582)
			(xy 278.813766 -36.50996) (xy 274.135781 -36.50996) (xy 274.231608 -36.741354) (xy 274.376134 -37.090604)
			(xy 274.390451 -37.125953) (xy 274.414228 -37.198424) (xy 274.423632 -37.235384) (xy 274.42414 -37.237924)
			(xy 274.424394 -37.23894) (xy 274.450302 -37.300916) (xy 274.471069 -37.351976) (xy 274.502507 -37.45763)
			(xy 274.50592 -37.47516) (xy 275.95906 -37.47516) (xy 275.963131 -37.419538) (xy 275.975257 -37.365101)
			(xy 275.99518 -37.31301) (xy 276.022476 -37.264375) (xy 276.056562 -37.220232) (xy 276.096711 -37.181523)
			(xy 276.142069 -37.149072) (xy 276.191669 -37.123571) (xy 276.244453 -37.105564) (xy 276.299296 -37.095434)
			(xy 276.35503 -37.093397) (xy 276.410467 -37.099497) (xy 276.464424 -37.113603) (xy 276.515753 -37.135415)
			(xy 276.563359 -37.164469) (xy 276.606227 -37.200144) (xy 276.643444 -37.241681) (xy 276.674217 -37.288194)
			(xy 276.697889 -37.338691) (xy 276.713957 -37.392098) (xy 276.722077 -37.447274) (xy 276.722586 -37.47516)
			(xy 276.722077 -37.503046) (xy 276.713957 -37.558222) (xy 276.697889 -37.611629) (xy 276.674217 -37.662126)
			(xy 276.674064 -37.662358) (xy 278.148286 -37.662358) (xy 278.152357 -37.606736) (xy 278.164483 -37.552299)
			(xy 278.184406 -37.500208) (xy 278.211702 -37.451573) (xy 278.245788 -37.40743) (xy 278.285937 -37.368721)
			(xy 278.331295 -37.33627) (xy 278.380895 -37.310769) (xy 278.433679 -37.292762) (xy 278.488522 -37.282632)
			(xy 278.544256 -37.280595) (xy 278.599693 -37.286695) (xy 278.65365 -37.300801) (xy 278.704979 -37.322613)
			(xy 278.752585 -37.351667) (xy 278.795453 -37.387342) (xy 278.83267 -37.428879) (xy 278.863443 -37.475392)
			(xy 278.887115 -37.525889) (xy 278.903183 -37.579296) (xy 278.911303 -37.634472) (xy 278.911812 -37.662358)
			(xy 278.911303 -37.690244) (xy 278.903183 -37.74542) (xy 278.894549 -37.774118) (xy 289.664646 -37.774118)
			(xy 289.668717 -37.718496) (xy 289.680843 -37.664059) (xy 289.700766 -37.611968) (xy 289.728062 -37.563333)
			(xy 289.762148 -37.51919) (xy 289.802297 -37.480481) (xy 289.847655 -37.44803) (xy 289.897255 -37.422529)
			(xy 289.950039 -37.404522) (xy 290.004882 -37.394392) (xy 290.060616 -37.392355) (xy 290.116053 -37.398455)
			(xy 290.17001 -37.412561) (xy 290.221339 -37.434373) (xy 290.268945 -37.463427) (xy 290.311813 -37.499102)
			(xy 290.34903 -37.540639) (xy 290.379803 -37.587152) (xy 290.403475 -37.637649) (xy 290.419543 -37.691056)
			(xy 290.427663 -37.746232) (xy 290.428172 -37.774118) (xy 290.427663 -37.802004) (xy 290.419543 -37.85718)
			(xy 290.403475 -37.910587) (xy 290.379803 -37.961084) (xy 290.34903 -38.007597) (xy 290.311813 -38.049134)
			(xy 290.268945 -38.084809) (xy 290.221339 -38.113863) (xy 290.17001 -38.135675) (xy 290.116053 -38.149781)
			(xy 290.060616 -38.155881) (xy 290.004882 -38.153844) (xy 289.950039 -38.143714) (xy 289.897255 -38.125707)
			(xy 289.847655 -38.100206) (xy 289.802297 -38.067755) (xy 289.762148 -38.029046) (xy 289.728062 -37.984903)
			(xy 289.700766 -37.936268) (xy 289.680843 -37.884177) (xy 289.668717 -37.82974) (xy 289.664646 -37.774118)
			(xy 278.894549 -37.774118) (xy 278.887115 -37.798827) (xy 278.863443 -37.849324) (xy 278.83267 -37.895837)
			(xy 278.795453 -37.937374) (xy 278.752585 -37.973049) (xy 278.704979 -38.002103) (xy 278.65365 -38.023915)
			(xy 278.599693 -38.038021) (xy 278.544256 -38.044121) (xy 278.488522 -38.042084) (xy 278.433679 -38.031954)
			(xy 278.380895 -38.013947) (xy 278.331295 -37.988446) (xy 278.285937 -37.955995) (xy 278.245788 -37.917286)
			(xy 278.211702 -37.873143) (xy 278.184406 -37.824508) (xy 278.164483 -37.772417) (xy 278.152357 -37.71798)
			(xy 278.148286 -37.662358) (xy 276.674064 -37.662358) (xy 276.643444 -37.708639) (xy 276.606227 -37.750176)
			(xy 276.563359 -37.785851) (xy 276.515753 -37.814905) (xy 276.464424 -37.836717) (xy 276.410467 -37.850823)
			(xy 276.35503 -37.856923) (xy 276.299296 -37.854886) (xy 276.244453 -37.844756) (xy 276.191669 -37.826749)
			(xy 276.142069 -37.801248) (xy 276.096711 -37.768797) (xy 276.056562 -37.730088) (xy 276.022476 -37.685945)
			(xy 275.99518 -37.63731) (xy 275.975257 -37.585219) (xy 275.963131 -37.530782) (xy 275.95906 -37.47516)
			(xy 274.50592 -37.47516) (xy 274.51304 -37.511736) (xy 274.5204 -37.555369) (xy 274.528285 -37.643511)
			(xy 274.528788 -37.687758) (xy 274.528788 -37.688266) (xy 274.528534 -37.704268) (xy 274.528534 -37.704522)
			(xy 274.526502 -37.830506) (xy 274.518628 -38.304978) (xy 274.513802 -38.593268) (xy 274.512446 -38.640617)
			(xy 274.502427 -38.729947) (xy 281.90092 -38.729947) (xy 281.90092 -38.675453) (xy 281.908675 -38.621512)
			(xy 281.924028 -38.569225) (xy 281.946665 -38.519654) (xy 281.976127 -38.473809) (xy 282.011813 -38.432624)
			(xy 282.052997 -38.396937) (xy 282.09884 -38.367473) (xy 282.14841 -38.344834) (xy 282.200697 -38.329479)
			(xy 282.254637 -38.321721) (xy 282.281884 -38.321234) (xy 282.310188 -38.32172) (xy 282.366178 -38.330071)
			(xy 282.420318 -38.346606) (xy 282.471419 -38.370961) (xy 282.518359 -38.402603) (xy 282.560106 -38.440835)
			(xy 282.595743 -38.484818) (xy 282.61056 -38.50894) (xy 282.618113 -38.521005) (xy 282.638741 -38.540609)
			(xy 282.663983 -38.553751) (xy 282.691873 -38.559407) (xy 282.72024 -38.557137) (xy 282.746875 -38.547117)
			(xy 282.769705 -38.530129) (xy 282.778708 -38.5191) (xy 282.796895 -38.496224) (xy 282.839058 -38.45576)
			(xy 282.886893 -38.422193) (xy 282.939285 -38.396306) (xy 282.995009 -38.378703) (xy 283.052765 -38.369797)
			(xy 283.081984 -38.36924) (xy 283.109241 -38.369606) (xy 283.163201 -38.377362) (xy 283.215507 -38.392719)
			(xy 283.265095 -38.415363) (xy 283.310956 -38.444834) (xy 283.352156 -38.480533) (xy 283.387856 -38.521731)
			(xy 283.417329 -38.567591) (xy 283.439976 -38.617178) (xy 283.455335 -38.669484) (xy 283.463093 -38.723443)
			(xy 283.463093 -38.777957) (xy 283.455335 -38.831916) (xy 283.439976 -38.884222) (xy 283.417329 -38.933809)
			(xy 283.387856 -38.979669) (xy 283.352156 -39.020867) (xy 283.310956 -39.056566) (xy 283.265095 -39.086037)
			(xy 283.215507 -39.108681) (xy 283.163201 -39.124038) (xy 283.109241 -39.131794) (xy 283.081984 -39.132256)
			(xy 283.053681 -39.131721) (xy 282.997694 -39.12338) (xy 282.943555 -39.106854) (xy 282.892453 -39.082507)
			(xy 282.845513 -39.050873) (xy 282.803764 -39.012647) (xy 282.768125 -38.968669) (xy 282.753308 -38.94455)
			(xy 282.745666 -38.932546) (xy 282.725056 -38.912948) (xy 282.699834 -38.899806) (xy 282.671962 -38.894144)
			(xy 282.643611 -38.896401) (xy 282.616987 -38.906403) (xy 282.594162 -38.923372) (xy 282.58516 -38.93439)
			(xy 282.566989 -38.957279) (xy 282.524823 -38.997743) (xy 282.476984 -39.031309) (xy 282.424589 -39.057194)
			(xy 282.368862 -39.074793) (xy 282.311104 -39.083695) (xy 282.281884 -39.08425) (xy 282.254637 -39.083679)
			(xy 282.200697 -39.075921) (xy 282.14841 -39.060566) (xy 282.09884 -39.037927) (xy 282.052997 -39.008463)
			(xy 282.011813 -38.972776) (xy 281.976127 -38.931591) (xy 281.946665 -38.885746) (xy 281.924028 -38.836175)
			(xy 281.908675 -38.783888) (xy 281.90092 -38.729947) (xy 274.502427 -38.729947) (xy 274.501888 -38.734756)
			(xy 274.49272 -38.781228) (xy 274.442682 -39.020242) (xy 274.243487 -39.97198) (xy 284.095696 -39.97198)
			(xy 284.099767 -39.916358) (xy 284.111893 -39.861921) (xy 284.131816 -39.80983) (xy 284.159112 -39.761195)
			(xy 284.193198 -39.717052) (xy 284.233347 -39.678343) (xy 284.278705 -39.645892) (xy 284.328305 -39.620391)
			(xy 284.381089 -39.602384) (xy 284.435932 -39.592254) (xy 284.491666 -39.590217) (xy 284.547103 -39.596317)
			(xy 284.60106 -39.610423) (xy 284.652389 -39.632235) (xy 284.699995 -39.661289) (xy 284.742863 -39.696964)
			(xy 284.78008 -39.738501) (xy 284.810853 -39.785014) (xy 284.834525 -39.835511) (xy 284.850593 -39.888918)
			(xy 284.858713 -39.944094) (xy 284.859222 -39.97198) (xy 284.858713 -39.999866) (xy 284.850593 -40.055042)
			(xy 284.834525 -40.108449) (xy 284.810853 -40.158946) (xy 284.78008 -40.205459) (xy 284.742863 -40.246996)
			(xy 284.699995 -40.282671) (xy 284.652389 -40.311725) (xy 284.60106 -40.333537) (xy 284.547103 -40.347643)
			(xy 284.491666 -40.353743) (xy 284.435932 -40.351706) (xy 284.381089 -40.341576) (xy 284.328305 -40.323569)
			(xy 284.278705 -40.298068) (xy 284.233347 -40.265617) (xy 284.193198 -40.226908) (xy 284.159112 -40.182765)
			(xy 284.131816 -40.13413) (xy 284.111893 -40.082039) (xy 284.099767 -40.027602) (xy 284.095696 -39.97198)
			(xy 274.243487 -39.97198) (xy 274.067524 -40.81272) (xy 274.06727 -40.813482) (xy 274.065952 -40.823163)
			(xy 274.069858 -40.84229) (xy 274.080595 -40.858594) (xy 274.088352 -40.864536) (xy 274.16506 -40.917622)
			(xy 274.173503 -40.922899) (xy 274.192927 -40.927184) (xy 274.212525 -40.923788) (xy 274.221194 -40.918892)
			(xy 274.244161 -40.904929) (xy 274.293182 -40.88289) (xy 274.344812 -40.86795) (xy 274.398028 -40.860405)
			(xy 274.424902 -40.859964) (xy 274.453641 -40.860485) (xy 274.510467 -40.869109) (xy 274.565356 -40.886162)
			(xy 274.617066 -40.911257) (xy 274.664425 -40.943827) (xy 274.68576 -40.963088) (xy 274.686014 -40.963342)
			(xy 274.689998 -40.966811) (xy 274.699092 -40.972179) (xy 274.704048 -40.97401) (xy 274.708055 -40.975296)
			(xy 274.716351 -40.976706) (xy 274.720558 -40.976804) (xy 274.789646 -40.976804) (xy 274.793854 -40.97672)
			(xy 274.802152 -40.975308) (xy 274.806156 -40.97401) (xy 274.811114 -40.972187) (xy 274.820203 -40.966808)
			(xy 274.82419 -40.963342) (xy 274.824444 -40.963088) (xy 274.845772 -40.943819) (xy 274.893135 -40.911257)
			(xy 274.944847 -40.886168) (xy 274.999737 -40.86912) (xy 275.056564 -40.860499) (xy 275.085302 -40.859964)
			(xy 275.112555 -40.86045) (xy 275.166507 -40.868207) (xy 275.218805 -40.883564) (xy 275.268386 -40.906207)
			(xy 275.314239 -40.935675) (xy 275.355432 -40.971369) (xy 275.391126 -41.012563) (xy 275.420594 -41.058416)
			(xy 275.443237 -41.107997) (xy 275.458593 -41.160295) (xy 275.46635 -41.214247) (xy 275.46635 -41.268753)
			(xy 275.458593 -41.322705) (xy 275.443237 -41.375003) (xy 275.420594 -41.424584) (xy 275.391126 -41.470437)
			(xy 275.355432 -41.511631) (xy 275.314239 -41.547325) (xy 275.268386 -41.576793) (xy 275.218805 -41.599436)
			(xy 275.166507 -41.614793) (xy 275.112555 -41.62255) (xy 275.085302 -41.62298) (xy 275.056563 -41.622459)
			(xy 274.999735 -41.613836) (xy 274.944845 -41.596786) (xy 274.893133 -41.571693) (xy 274.845771 -41.539127)
			(xy 274.824444 -41.519856) (xy 274.82419 -41.519602) (xy 274.820214 -41.516122) (xy 274.811119 -41.510748)
			(xy 274.806156 -41.508934) (xy 274.802149 -41.507649) (xy 274.793853 -41.50624) (xy 274.789646 -41.50614)
			(xy 274.720558 -41.50614) (xy 274.71635 -41.506224) (xy 274.708052 -41.507636) (xy 274.704048 -41.508934)
			(xy 274.699089 -41.510755) (xy 274.689995 -41.516129) (xy 274.686014 -41.519602) (xy 274.68576 -41.519856)
			(xy 274.664431 -41.539123) (xy 274.617067 -41.571682) (xy 274.565355 -41.596769) (xy 274.510465 -41.613815)
			(xy 274.45364 -41.622436) (xy 274.424902 -41.62298) (xy 274.412164 -41.622902) (xy 274.386743 -41.621249)
			(xy 274.374102 -41.619678) (xy 274.347605 -41.615664) (xy 274.296012 -41.601171) (xy 274.246957 -41.579595)
			(xy 274.201407 -41.551363) (xy 274.160259 -41.51703) (xy 274.124324 -41.477274) (xy 274.108926 -41.45534)
			(xy 274.108926 -41.455086) (xy 274.104545 -41.449132) (xy 274.093057 -41.439839) (xy 274.08632 -41.436798)
			(xy 274.079323 -41.434197) (xy 274.064471 -41.432767) (xy 274.05711 -41.434004) (xy 273.965416 -41.451784)
			(xy 273.95678 -41.454324) (xy 273.948977 -41.457664) (xy 273.936007 -41.468596) (xy 273.927325 -41.483169)
			(xy 273.925284 -41.491408) (xy 273.641312 -42.848276) (xy 273.54558 -43.305222) (xy 276.507194 -43.305222)
			(xy 276.507674 -43.277852) (xy 276.515489 -43.223674) (xy 276.530975 -43.171171) (xy 276.553813 -43.121424)
			(xy 276.583534 -43.075456) (xy 276.601174 -43.054524) (xy 276.601428 -43.05427) (xy 276.606995 -43.04717)
			(xy 276.613252 -43.030263) (xy 276.61362 -43.02125) (xy 276.61362 -42.954194) (xy 276.613261 -42.945177)
			(xy 276.607014 -42.928261) (xy 276.601428 -42.921174) (xy 276.601174 -42.921174) (xy 276.601174 -42.92092)
			(xy 276.583527 -42.899995) (xy 276.553817 -42.85402) (xy 276.530983 -42.80427) (xy 276.515494 -42.751768)
			(xy 276.507667 -42.697592) (xy 276.507194 -42.670222) (xy 276.507733 -42.641484) (xy 276.516352 -42.584657)
			(xy 276.533399 -42.529767) (xy 276.558487 -42.478055) (xy 276.591049 -42.430691) (xy 276.610318 -42.409364)
			(xy 276.616922 -42.402506) (xy 276.624034 -42.384472) (xy 276.624034 -42.295572) (xy 276.616922 -42.277538)
			(xy 276.610318 -42.27068) (xy 276.591069 -42.249334) (xy 276.558504 -42.201975) (xy 276.533411 -42.150266)
			(xy 276.51636 -42.095378) (xy 276.507736 -42.038554) (xy 276.507733 -41.981078) (xy 276.516353 -41.924253)
			(xy 276.5334 -41.869364) (xy 276.558488 -41.817653) (xy 276.591049 -41.770291) (xy 276.610318 -41.748964)
			(xy 276.616922 -41.742106) (xy 276.624034 -41.724072) (xy 276.624034 -41.635172) (xy 276.616922 -41.617138)
			(xy 276.610318 -41.61028) (xy 276.591054 -41.588947) (xy 276.558488 -41.541586) (xy 276.533394 -41.489876)
			(xy 276.516342 -41.434987) (xy 276.507717 -41.378161) (xy 276.507194 -41.349422) (xy 276.50768 -41.322171)
			(xy 276.515436 -41.268223) (xy 276.530791 -41.215928) (xy 276.553433 -41.166351) (xy 276.582899 -41.120501)
			(xy 276.61859 -41.07931) (xy 276.659781 -41.043619) (xy 276.705631 -41.014153) (xy 276.755208 -40.991511)
			(xy 276.807503 -40.976156) (xy 276.861451 -40.9684) (xy 276.915953 -40.9684) (xy 276.939074 -40.971724)
			(xy 284.793942 -40.971724) (xy 284.798013 -40.916102) (xy 284.810139 -40.861665) (xy 284.830062 -40.809574)
			(xy 284.857358 -40.760939) (xy 284.891444 -40.716796) (xy 284.931593 -40.678087) (xy 284.976951 -40.645636)
			(xy 285.026551 -40.620135) (xy 285.079335 -40.602128) (xy 285.134178 -40.591998) (xy 285.189912 -40.589961)
			(xy 285.245349 -40.596061) (xy 285.299306 -40.610167) (xy 285.350635 -40.631979) (xy 285.398241 -40.661033)
			(xy 285.441109 -40.696708) (xy 285.478326 -40.738245) (xy 285.509099 -40.784758) (xy 285.532771 -40.835255)
			(xy 285.548839 -40.888662) (xy 285.556959 -40.943838) (xy 285.557468 -40.971724) (xy 285.556959 -40.99961)
			(xy 285.548839 -41.054786) (xy 285.532771 -41.108193) (xy 285.509099 -41.15869) (xy 285.478326 -41.205203)
			(xy 285.441109 -41.24674) (xy 285.398241 -41.282415) (xy 285.350635 -41.311469) (xy 285.299306 -41.333281)
			(xy 285.245349 -41.347387) (xy 285.189912 -41.353487) (xy 285.134178 -41.35145) (xy 285.079335 -41.34132)
			(xy 285.026551 -41.323313) (xy 284.976951 -41.297812) (xy 284.931593 -41.265361) (xy 284.891444 -41.226652)
			(xy 284.857358 -41.182509) (xy 284.830062 -41.133874) (xy 284.810139 -41.081783) (xy 284.798013 -41.027346)
			(xy 284.793942 -40.971724) (xy 276.939074 -40.971724) (xy 276.969901 -40.976156) (xy 277.022196 -40.991511)
			(xy 277.071773 -41.014153) (xy 277.117623 -41.043619) (xy 277.158814 -41.07931) (xy 277.194505 -41.120501)
			(xy 277.223971 -41.166351) (xy 277.246613 -41.215928) (xy 277.261968 -41.268223) (xy 277.269724 -41.322171)
			(xy 277.27021 -41.349422) (xy 277.269697 -41.378161) (xy 277.261071 -41.434989) (xy 277.244019 -41.48988)
			(xy 277.218925 -41.541591) (xy 277.186358 -41.588953) (xy 277.167086 -41.61028) (xy 277.160482 -41.617138)
			(xy 277.15337 -41.635172) (xy 277.15337 -41.724072) (xy 277.160482 -41.742106) (xy 277.167086 -41.748964)
			(xy 277.186378 -41.770272) (xy 277.218942 -41.817638) (xy 277.244032 -41.869353) (xy 277.261079 -41.924246)
			(xy 277.2697 -41.981076) (xy 277.269697 -42.038556) (xy 277.261072 -42.095385) (xy 277.24402 -42.150277)
			(xy 277.218926 -42.20199) (xy 277.186358 -42.249353) (xy 277.167086 -42.27068) (xy 277.160482 -42.277538)
			(xy 277.15337 -42.295572) (xy 277.15337 -42.384472) (xy 277.160482 -42.402506) (xy 277.167086 -42.409364)
			(xy 277.186371 -42.430679) (xy 277.218935 -42.478044) (xy 277.244024 -42.529759) (xy 277.261071 -42.584653)
			(xy 277.269691 -42.641482) (xy 277.27021 -42.670222) (xy 277.269754 -42.697593) (xy 277.261934 -42.751772)
			(xy 277.246442 -42.804275) (xy 277.225887 -42.849038) (xy 279.091896 -42.849038) (xy 279.095967 -42.793416)
			(xy 279.108093 -42.738979) (xy 279.128016 -42.686888) (xy 279.155312 -42.638253) (xy 279.189398 -42.59411)
			(xy 279.229547 -42.555401) (xy 279.274905 -42.52295) (xy 279.324505 -42.497449) (xy 279.377289 -42.479442)
			(xy 279.432132 -42.469312) (xy 279.487866 -42.467275) (xy 279.543303 -42.473375) (xy 279.59726 -42.487481)
			(xy 279.648589 -42.509293) (xy 279.696195 -42.538347) (xy 279.739063 -42.574022) (xy 279.77628 -42.615559)
			(xy 279.807053 -42.662072) (xy 279.830725 -42.712569) (xy 279.846793 -42.765976) (xy 279.854913 -42.821152)
			(xy 279.855274 -42.84091) (xy 285.133032 -42.84091) (xy 285.137103 -42.785288) (xy 285.149229 -42.730851)
			(xy 285.169152 -42.67876) (xy 285.196448 -42.630125) (xy 285.230534 -42.585982) (xy 285.270683 -42.547273)
			(xy 285.316041 -42.514822) (xy 285.365641 -42.489321) (xy 285.418425 -42.471314) (xy 285.473268 -42.461184)
			(xy 285.529002 -42.459147) (xy 285.584439 -42.465247) (xy 285.638396 -42.479353) (xy 285.689725 -42.501165)
			(xy 285.737331 -42.530219) (xy 285.780199 -42.565894) (xy 285.817416 -42.607431) (xy 285.848189 -42.653944)
			(xy 285.871861 -42.704441) (xy 285.887929 -42.757848) (xy 285.896049 -42.813024) (xy 285.896558 -42.84091)
			(xy 285.896049 -42.868796) (xy 285.887929 -42.923972) (xy 285.871861 -42.977379) (xy 285.848189 -43.027876)
			(xy 285.817416 -43.074389) (xy 285.780199 -43.115926) (xy 285.737331 -43.151601) (xy 285.689725 -43.180655)
			(xy 285.638396 -43.202467) (xy 285.584439 -43.216573) (xy 285.529002 -43.222673) (xy 285.473268 -43.220636)
			(xy 285.418425 -43.210506) (xy 285.365641 -43.192499) (xy 285.316041 -43.166998) (xy 285.270683 -43.134547)
			(xy 285.230534 -43.095838) (xy 285.196448 -43.051695) (xy 285.169152 -43.00306) (xy 285.149229 -42.950969)
			(xy 285.137103 -42.896532) (xy 285.133032 -42.84091) (xy 279.855274 -42.84091) (xy 279.855422 -42.849038)
			(xy 279.854913 -42.876924) (xy 279.846793 -42.9321) (xy 279.830725 -42.985507) (xy 279.807053 -43.036004)
			(xy 279.77628 -43.082517) (xy 279.739063 -43.124054) (xy 279.696195 -43.159729) (xy 279.648589 -43.188783)
			(xy 279.59726 -43.210595) (xy 279.543303 -43.224701) (xy 279.487866 -43.230801) (xy 279.432132 -43.228764)
			(xy 279.377289 -43.218634) (xy 279.324505 -43.200627) (xy 279.274905 -43.175126) (xy 279.229547 -43.142675)
			(xy 279.189398 -43.103966) (xy 279.155312 -43.059823) (xy 279.128016 -43.011188) (xy 279.108093 -42.959097)
			(xy 279.095967 -42.90466) (xy 279.091896 -42.849038) (xy 277.225887 -42.849038) (xy 277.223598 -42.854022)
			(xy 277.193872 -42.899988) (xy 277.17623 -42.92092) (xy 277.175976 -42.921174) (xy 277.170392 -42.928262)
			(xy 277.164144 -42.945178) (xy 277.163784 -42.954194) (xy 277.163784 -43.02125) (xy 277.164168 -43.030264)
			(xy 277.170397 -43.047181) (xy 277.175976 -43.05427) (xy 277.17623 -43.05427) (xy 277.17623 -43.054524)
			(xy 277.193852 -43.07547) (xy 277.223565 -43.121439) (xy 277.246404 -43.171184) (xy 277.261899 -43.223681)
			(xy 277.269733 -43.277854) (xy 277.27021 -43.305222) (xy 277.269724 -43.332473) (xy 277.261968 -43.386421)
			(xy 277.246613 -43.438716) (xy 277.223971 -43.488293) (xy 277.194505 -43.534143) (xy 277.158814 -43.575334)
			(xy 277.117623 -43.611025) (xy 277.071773 -43.640491) (xy 277.022196 -43.663133) (xy 276.969901 -43.678488)
			(xy 276.915953 -43.686244) (xy 276.861451 -43.686244) (xy 276.807503 -43.678488) (xy 276.755208 -43.663133)
			(xy 276.705631 -43.640491) (xy 276.659781 -43.611025) (xy 276.61859 -43.575334) (xy 276.582899 -43.534143)
			(xy 276.553433 -43.488293) (xy 276.530791 -43.438716) (xy 276.515436 -43.386421) (xy 276.50768 -43.332473)
			(xy 276.507194 -43.305222) (xy 273.54558 -43.305222) (xy 273.455275 -43.73626) (xy 278.412954 -43.73626)
			(xy 278.417025 -43.680638) (xy 278.429151 -43.626201) (xy 278.449074 -43.57411) (xy 278.47637 -43.525475)
			(xy 278.510456 -43.481332) (xy 278.550605 -43.442623) (xy 278.595963 -43.410172) (xy 278.645563 -43.384671)
			(xy 278.698347 -43.366664) (xy 278.75319 -43.356534) (xy 278.808924 -43.354497) (xy 278.864361 -43.360597)
			(xy 278.918318 -43.374703) (xy 278.969647 -43.396515) (xy 279.017253 -43.425569) (xy 279.060121 -43.461244)
			(xy 279.097338 -43.502781) (xy 279.128111 -43.549294) (xy 279.136337 -43.566842) (xy 281.533344 -43.566842)
			(xy 281.537415 -43.51122) (xy 281.549541 -43.456783) (xy 281.569464 -43.404692) (xy 281.59676 -43.356057)
			(xy 281.630846 -43.311914) (xy 281.670995 -43.273205) (xy 281.716353 -43.240754) (xy 281.765953 -43.215253)
			(xy 281.818737 -43.197246) (xy 281.87358 -43.187116) (xy 281.929314 -43.185079) (xy 281.984751 -43.191179)
			(xy 282.038708 -43.205285) (xy 282.090037 -43.227097) (xy 282.137643 -43.256151) (xy 282.180511 -43.291826)
			(xy 282.217728 -43.333363) (xy 282.248501 -43.379876) (xy 282.272173 -43.430373) (xy 282.288241 -43.48378)
			(xy 282.296361 -43.538956) (xy 282.29687 -43.566842) (xy 282.296361 -43.594728) (xy 282.288241 -43.649904)
			(xy 282.272173 -43.703311) (xy 282.248501 -43.753808) (xy 282.217728 -43.800321) (xy 282.180511 -43.841858)
			(xy 282.162424 -43.85691) (xy 282.919676 -43.85691) (xy 282.923747 -43.801288) (xy 282.935873 -43.746851)
			(xy 282.955796 -43.69476) (xy 282.983092 -43.646125) (xy 283.017178 -43.601982) (xy 283.057327 -43.563273)
			(xy 283.102685 -43.530822) (xy 283.152285 -43.505321) (xy 283.205069 -43.487314) (xy 283.259912 -43.477184)
			(xy 283.315646 -43.475147) (xy 283.371083 -43.481247) (xy 283.42504 -43.495353) (xy 283.476369 -43.517165)
			(xy 283.523975 -43.546219) (xy 283.566843 -43.581894) (xy 283.60406 -43.623431) (xy 283.634833 -43.669944)
			(xy 283.658505 -43.720441) (xy 283.674573 -43.773848) (xy 283.682693 -43.829024) (xy 283.683202 -43.85691)
			(xy 283.682693 -43.884796) (xy 283.674573 -43.939972) (xy 283.658505 -43.993379) (xy 283.634833 -44.043876)
			(xy 283.60406 -44.090389) (xy 283.566843 -44.131926) (xy 283.523975 -44.167601) (xy 283.476369 -44.196655)
			(xy 283.42504 -44.218467) (xy 283.371083 -44.232573) (xy 283.315646 -44.238673) (xy 283.259912 -44.236636)
			(xy 283.205069 -44.226506) (xy 283.152285 -44.208499) (xy 283.102685 -44.182998) (xy 283.057327 -44.150547)
			(xy 283.017178 -44.111838) (xy 282.983092 -44.067695) (xy 282.955796 -44.01906) (xy 282.935873 -43.966969)
			(xy 282.923747 -43.912532) (xy 282.919676 -43.85691) (xy 282.162424 -43.85691) (xy 282.137643 -43.877533)
			(xy 282.090037 -43.906587) (xy 282.038708 -43.928399) (xy 281.984751 -43.942505) (xy 281.929314 -43.948605)
			(xy 281.87358 -43.946568) (xy 281.818737 -43.936438) (xy 281.765953 -43.918431) (xy 281.716353 -43.89293)
			(xy 281.670995 -43.860479) (xy 281.630846 -43.82177) (xy 281.59676 -43.777627) (xy 281.569464 -43.728992)
			(xy 281.549541 -43.676901) (xy 281.537415 -43.622464) (xy 281.533344 -43.566842) (xy 279.136337 -43.566842)
			(xy 279.151783 -43.599791) (xy 279.167851 -43.653198) (xy 279.175971 -43.708374) (xy 279.17648 -43.73626)
			(xy 279.175971 -43.764146) (xy 279.167851 -43.819322) (xy 279.151783 -43.872729) (xy 279.128111 -43.923226)
			(xy 279.097338 -43.969739) (xy 279.060121 -44.011276) (xy 279.017253 -44.046951) (xy 278.969647 -44.076005)
			(xy 278.918318 -44.097817) (xy 278.864361 -44.111923) (xy 278.808924 -44.118023) (xy 278.75319 -44.115986)
			(xy 278.698347 -44.105856) (xy 278.645563 -44.087849) (xy 278.595963 -44.062348) (xy 278.550605 -44.029897)
			(xy 278.510456 -43.991188) (xy 278.47637 -43.947045) (xy 278.449074 -43.89841) (xy 278.429151 -43.846319)
			(xy 278.417025 -43.791882) (xy 278.412954 -43.73626) (xy 273.455275 -43.73626) (xy 273.378168 -44.104306)
			(xy 273.378168 -44.105322) (xy 273.187368 -45.114464) (xy 278.26538 -45.114464) (xy 278.269451 -45.058842)
			(xy 278.281577 -45.004405) (xy 278.3015 -44.952314) (xy 278.328796 -44.903679) (xy 278.362882 -44.859536)
			(xy 278.403031 -44.820827) (xy 278.448389 -44.788376) (xy 278.497989 -44.762875) (xy 278.550773 -44.744868)
			(xy 278.605616 -44.734738) (xy 278.66135 -44.732701) (xy 278.716787 -44.738801) (xy 278.770744 -44.752907)
			(xy 278.822073 -44.774719) (xy 278.869679 -44.803773) (xy 278.912547 -44.839448) (xy 278.942529 -44.87291)
			(xy 285.133032 -44.87291) (xy 285.137103 -44.817288) (xy 285.149229 -44.762851) (xy 285.169152 -44.71076)
			(xy 285.196448 -44.662125) (xy 285.230534 -44.617982) (xy 285.270683 -44.579273) (xy 285.316041 -44.546822)
			(xy 285.365641 -44.521321) (xy 285.418425 -44.503314) (xy 285.473268 -44.493184) (xy 285.529002 -44.491147)
			(xy 285.584439 -44.497247) (xy 285.638396 -44.511353) (xy 285.689725 -44.533165) (xy 285.737331 -44.562219)
			(xy 285.780199 -44.597894) (xy 285.817416 -44.639431) (xy 285.848189 -44.685944) (xy 285.871861 -44.736441)
			(xy 285.887929 -44.789848) (xy 285.896049 -44.845024) (xy 285.896558 -44.87291) (xy 285.896049 -44.900796)
			(xy 285.887929 -44.955972) (xy 285.871861 -45.009379) (xy 285.848189 -45.059876) (xy 285.817416 -45.106389)
			(xy 285.780199 -45.147926) (xy 285.737331 -45.183601) (xy 285.689725 -45.212655) (xy 285.638396 -45.234467)
			(xy 285.584439 -45.248573) (xy 285.529002 -45.254673) (xy 285.473268 -45.252636) (xy 285.418425 -45.242506)
			(xy 285.365641 -45.224499) (xy 285.316041 -45.198998) (xy 285.270683 -45.166547) (xy 285.230534 -45.127838)
			(xy 285.196448 -45.083695) (xy 285.169152 -45.03506) (xy 285.149229 -44.982969) (xy 285.137103 -44.928532)
			(xy 285.133032 -44.87291) (xy 278.942529 -44.87291) (xy 278.949764 -44.880985) (xy 278.980537 -44.927498)
			(xy 279.004209 -44.977995) (xy 279.020277 -45.031402) (xy 279.028397 -45.086578) (xy 279.028906 -45.114464)
			(xy 279.028397 -45.14235) (xy 279.020277 -45.197526) (xy 279.004209 -45.250933) (xy 278.980537 -45.30143)
			(xy 278.949764 -45.347943) (xy 278.944122 -45.35424) (xy 282.903674 -45.35424) (xy 282.907745 -45.298618)
			(xy 282.919871 -45.244181) (xy 282.939794 -45.19209) (xy 282.96709 -45.143455) (xy 283.001176 -45.099312)
			(xy 283.041325 -45.060603) (xy 283.086683 -45.028152) (xy 283.136283 -45.002651) (xy 283.189067 -44.984644)
			(xy 283.24391 -44.974514) (xy 283.299644 -44.972477) (xy 283.355081 -44.978577) (xy 283.409038 -44.992683)
			(xy 283.460367 -45.014495) (xy 283.507973 -45.043549) (xy 283.550841 -45.079224) (xy 283.588058 -45.120761)
			(xy 283.618831 -45.167274) (xy 283.642503 -45.217771) (xy 283.658571 -45.271178) (xy 283.666691 -45.326354)
			(xy 283.6672 -45.35424) (xy 283.666691 -45.382126) (xy 283.658571 -45.437302) (xy 283.642503 -45.490709)
			(xy 283.618831 -45.541206) (xy 283.588058 -45.587719) (xy 283.550841 -45.629256) (xy 283.507973 -45.664931)
			(xy 283.460367 -45.693985) (xy 283.409038 -45.715797) (xy 283.355081 -45.729903) (xy 283.299644 -45.736003)
			(xy 283.24391 -45.733966) (xy 283.189067 -45.723836) (xy 283.136283 -45.705829) (xy 283.086683 -45.680328)
			(xy 283.041325 -45.647877) (xy 283.001176 -45.609168) (xy 282.96709 -45.565025) (xy 282.939794 -45.51639)
			(xy 282.919871 -45.464299) (xy 282.907745 -45.409862) (xy 282.903674 -45.35424) (xy 278.944122 -45.35424)
			(xy 278.912547 -45.38948) (xy 278.869679 -45.425155) (xy 278.822073 -45.454209) (xy 278.770744 -45.476021)
			(xy 278.716787 -45.490127) (xy 278.66135 -45.496227) (xy 278.605616 -45.49419) (xy 278.550773 -45.48406)
			(xy 278.497989 -45.466053) (xy 278.448389 -45.440552) (xy 278.403031 -45.408101) (xy 278.362882 -45.369392)
			(xy 278.328796 -45.325249) (xy 278.3015 -45.276614) (xy 278.281577 -45.224523) (xy 278.269451 -45.170086)
			(xy 278.26538 -45.114464) (xy 273.187368 -45.114464) (xy 273.004396 -46.082204) (xy 276.252432 -46.082204)
			(xy 276.252859 -46.054949) (xy 276.260617 -46.000995) (xy 276.275974 -45.948694) (xy 276.298619 -45.899111)
			(xy 276.32809 -45.853256) (xy 276.363788 -45.812063) (xy 276.404985 -45.776369) (xy 276.450843 -45.746902)
			(xy 276.500428 -45.724262) (xy 276.55273 -45.708909) (xy 276.606685 -45.701157) (xy 276.63394 -45.700696)
			(xy 276.660844 -45.701128) (xy 276.714115 -45.708705) (xy 276.765794 -45.72369) (xy 276.814856 -45.745785)
			(xy 276.860328 -45.774552) (xy 276.901308 -45.809421) (xy 276.936985 -45.8497) (xy 276.952202 -45.871892)
			(xy 276.959314 -45.882814) (xy 276.982174 -45.894752) (xy 277.094442 -45.89272) (xy 277.116794 -45.879766)
			(xy 277.123652 -45.86859) (xy 277.138552 -45.844974) (xy 277.174234 -45.802022) (xy 277.215796 -45.76473)
			(xy 277.26235 -45.733895) (xy 277.312901 -45.710174) (xy 277.36637 -45.694074) (xy 277.421614 -45.68594)
			(xy 277.449534 -45.685456) (xy 277.476528 -45.685897) (xy 277.529977 -45.693508) (xy 277.581821 -45.708573)
			(xy 277.631025 -45.730791) (xy 277.676608 -45.75972) (xy 277.697438 -45.776896) (xy 277.705566 -45.784008)
			(xy 277.72614 -45.790104) (xy 277.811484 -45.779182) (xy 277.822029 -45.77741) (xy 277.840312 -45.766354)
			(xy 277.84679 -45.757846) (xy 277.862156 -45.736625) (xy 277.897741 -45.698172) (xy 277.938256 -45.664953)
			(xy 277.982937 -45.637593) (xy 278.030943 -45.616608) (xy 278.08137 -45.602392) (xy 278.133268 -45.595215)
			(xy 278.159464 -45.594778) (xy 278.186718 -45.595267) (xy 278.24067 -45.603019) (xy 278.292971 -45.618372)
			(xy 278.342553 -45.641011) (xy 278.388409 -45.670477) (xy 278.429605 -45.70617) (xy 278.465301 -45.747362)
			(xy 278.494771 -45.793215) (xy 278.517416 -45.842796) (xy 278.532773 -45.895094) (xy 278.540531 -45.949047)
			(xy 278.540531 -46.003553) (xy 278.532773 -46.057506) (xy 278.517416 -46.109804) (xy 278.494771 -46.159385)
			(xy 278.465301 -46.205238) (xy 278.429605 -46.24643) (xy 278.388409 -46.282123) (xy 278.342553 -46.311589)
			(xy 278.292971 -46.334228) (xy 278.24067 -46.349581) (xy 278.186718 -46.357333) (xy 278.159464 -46.357794)
			(xy 278.132471 -46.357342) (xy 278.079022 -46.349732) (xy 278.027179 -46.334669) (xy 277.977975 -46.312453)
			(xy 277.932391 -46.283528) (xy 277.91156 -46.266354) (xy 277.903432 -46.259242) (xy 277.882858 -46.253146)
			(xy 277.797514 -46.264068) (xy 277.786973 -46.265857) (xy 277.76869 -46.276902) (xy 277.762208 -46.285404)
			(xy 277.744591 -46.309701) (xy 277.702998 -46.352963) (xy 277.679404 -46.37151) (xy 277.67153 -46.377352)
			(xy 277.661116 -46.394878) (xy 277.647908 -46.485302) (xy 277.652734 -46.504606) (xy 277.658576 -46.51248)
			(xy 277.658576 -46.512734) (xy 277.676079 -46.537478) (xy 277.703882 -46.591331) (xy 277.722818 -46.648903)
			(xy 277.730021 -46.693836) (xy 282.876244 -46.693836) (xy 282.87673 -46.666585) (xy 282.884486 -46.612637)
			(xy 282.899841 -46.560342) (xy 282.922483 -46.510765) (xy 282.951949 -46.464915) (xy 282.98764 -46.423724)
			(xy 283.028831 -46.388033) (xy 283.074681 -46.358567) (xy 283.124258 -46.335925) (xy 283.176553 -46.32057)
			(xy 283.230501 -46.312814) (xy 283.285003 -46.312814) (xy 283.338951 -46.32057) (xy 283.391246 -46.335925)
			(xy 283.440823 -46.358567) (xy 283.486673 -46.388033) (xy 283.527864 -46.423724) (xy 283.563555 -46.464915)
			(xy 283.593021 -46.510765) (xy 283.615663 -46.560342) (xy 283.631018 -46.612637) (xy 283.638774 -46.666585)
			(xy 283.63926 -46.693836) (xy 283.638793 -46.720264) (xy 283.631483 -46.772612) (xy 283.617008 -46.823447)
			(xy 283.595646 -46.871793) (xy 283.58211 -46.894496) (xy 283.581856 -46.89475) (xy 283.576519 -46.904768)
			(xy 283.574262 -46.927318) (xy 283.577538 -46.938184) (xy 283.6037 -47.01286) (xy 283.608062 -47.023387)
			(xy 283.624166 -47.039471) (xy 283.634688 -47.043848) (xy 283.634942 -47.043848) (xy 283.65945 -47.05292)
			(xy 283.705902 -47.076862) (xy 283.748655 -47.106917) (xy 283.786907 -47.142524) (xy 283.819943 -47.183017)
			(xy 283.847147 -47.227638) (xy 283.868009 -47.275553) (xy 283.882139 -47.325866) (xy 283.889273 -47.377636)
			(xy 283.889704 -47.403766) (xy 283.889218 -47.431017) (xy 283.887695 -47.441612) (xy 285.161734 -47.441612)
			(xy 285.165805 -47.38599) (xy 285.177931 -47.331553) (xy 285.197854 -47.279462) (xy 285.22515 -47.230827)
			(xy 285.259236 -47.186684) (xy 285.299385 -47.147975) (xy 285.344743 -47.115524) (xy 285.394343 -47.090023)
			(xy 285.447127 -47.072016) (xy 285.50197 -47.061886) (xy 285.557704 -47.059849) (xy 285.613141 -47.065949)
			(xy 285.667098 -47.080055) (xy 285.718427 -47.101867) (xy 285.766033 -47.130921) (xy 285.808901 -47.166596)
			(xy 285.846118 -47.208133) (xy 285.876891 -47.254646) (xy 285.900563 -47.305143) (xy 285.916631 -47.35855)
			(xy 285.924751 -47.413726) (xy 285.92526 -47.441612) (xy 285.924751 -47.469498) (xy 285.916631 -47.524674)
			(xy 285.900563 -47.578081) (xy 285.876891 -47.628578) (xy 285.846118 -47.675091) (xy 285.808901 -47.716628)
			(xy 285.766033 -47.752303) (xy 285.718427 -47.781357) (xy 285.667098 -47.803169) (xy 285.613141 -47.817275)
			(xy 285.557704 -47.823375) (xy 285.50197 -47.821338) (xy 285.447127 -47.811208) (xy 285.394343 -47.793201)
			(xy 285.344743 -47.7677) (xy 285.299385 -47.735249) (xy 285.259236 -47.69654) (xy 285.22515 -47.652397)
			(xy 285.197854 -47.603762) (xy 285.177931 -47.551671) (xy 285.165805 -47.497234) (xy 285.161734 -47.441612)
			(xy 283.887695 -47.441612) (xy 283.881462 -47.484965) (xy 283.866107 -47.53726) (xy 283.843465 -47.586837)
			(xy 283.813999 -47.632687) (xy 283.778308 -47.673878) (xy 283.737117 -47.709569) (xy 283.691267 -47.739035)
			(xy 283.64169 -47.761677) (xy 283.589395 -47.777032) (xy 283.535447 -47.784788) (xy 283.480945 -47.784788)
			(xy 283.426997 -47.777032) (xy 283.374702 -47.761677) (xy 283.325125 -47.739035) (xy 283.279275 -47.709569)
			(xy 283.238084 -47.673878) (xy 283.202393 -47.632687) (xy 283.172927 -47.586837) (xy 283.150285 -47.53726)
			(xy 283.13493 -47.484965) (xy 283.127174 -47.431017) (xy 283.126688 -47.403766) (xy 283.127163 -47.377339)
			(xy 283.134472 -47.324991) (xy 283.148945 -47.274156) (xy 283.170304 -47.225809) (xy 283.183838 -47.203106)
			(xy 283.184092 -47.202852) (xy 283.189427 -47.192834) (xy 283.191684 -47.170284) (xy 283.18841 -47.159418)
			(xy 283.162248 -47.084742) (xy 283.157863 -47.074227) (xy 283.141775 -47.058138) (xy 283.13126 -47.053754)
			(xy 283.131006 -47.053754) (xy 283.106488 -47.04471) (xy 283.060036 -47.020762) (xy 283.017286 -46.990701)
			(xy 282.979036 -46.95509) (xy 282.946001 -46.914594) (xy 282.918799 -46.869971) (xy 282.897938 -46.822053)
			(xy 282.883809 -46.771739) (xy 282.876675 -46.719967) (xy 282.876244 -46.693836) (xy 277.730021 -46.693836)
			(xy 277.732411 -46.708745) (xy 277.732998 -46.739048) (xy 277.732567 -46.766301) (xy 277.724803 -46.820251)
			(xy 277.709442 -46.872547) (xy 277.686794 -46.922126) (xy 277.657322 -46.967976) (xy 277.621625 -47.009166)
			(xy 277.58043 -47.044857) (xy 277.534575 -47.074322) (xy 277.484993 -47.096962) (xy 277.432694 -47.112316)
			(xy 277.378743 -47.120071) (xy 277.35149 -47.120556) (xy 277.325456 -47.120107) (xy 277.273874 -47.11302)
			(xy 277.223732 -47.09899) (xy 277.175961 -47.07828) (xy 277.131446 -47.051272) (xy 277.110952 -47.035212)
			(xy 277.103187 -47.029483) (xy 277.084783 -47.023735) (xy 277.075138 -47.024036) (xy 276.995382 -47.030386)
			(xy 276.977602 -47.039022) (xy 276.971252 -47.046388) (xy 276.953068 -47.066031) (xy 276.912161 -47.100553)
			(xy 276.866833 -47.129023) (xy 276.817972 -47.150881) (xy 276.766536 -47.165699) (xy 276.713536 -47.173186)
			(xy 276.686772 -47.173642) (xy 276.659522 -47.173148) (xy 276.605576 -47.165389) (xy 276.553283 -47.150032)
			(xy 276.503708 -47.12739) (xy 276.45786 -47.097924) (xy 276.416671 -47.062234) (xy 276.38098 -47.021045)
			(xy 276.351513 -46.975197) (xy 276.32887 -46.925622) (xy 276.313512 -46.87333) (xy 276.305752 -46.819384)
			(xy 276.305264 -46.792134) (xy 276.305798 -46.76336) (xy 276.314448 -46.706467) (xy 276.331543 -46.651517)
			(xy 276.356694 -46.599757) (xy 276.389331 -46.55236) (xy 276.408642 -46.531022) (xy 276.416008 -46.523148)
			(xy 276.42312 -46.503336) (xy 276.415754 -46.40707) (xy 276.405848 -46.388274) (xy 276.397466 -46.38167)
			(xy 276.375291 -46.363434) (xy 276.336078 -46.321502) (xy 276.30359 -46.274169) (xy 276.27856 -46.222503)
			(xy 276.261552 -46.167671) (xy 276.25295 -46.110909) (xy 276.252432 -46.082204) (xy 273.004396 -46.082204)
			(xy 272.782284 -47.256954) (xy 272.583804 -48.30699) (xy 282.753814 -48.30699) (xy 282.757885 -48.251368)
			(xy 282.770011 -48.196931) (xy 282.789934 -48.14484) (xy 282.81723 -48.096205) (xy 282.851316 -48.052062)
			(xy 282.891465 -48.013353) (xy 282.936823 -47.980902) (xy 282.986423 -47.955401) (xy 283.039207 -47.937394)
			(xy 283.09405 -47.927264) (xy 283.149784 -47.925227) (xy 283.205221 -47.931327) (xy 283.259178 -47.945433)
			(xy 283.310507 -47.967245) (xy 283.358113 -47.996299) (xy 283.400981 -48.031974) (xy 283.438198 -48.073511)
			(xy 283.468971 -48.120024) (xy 283.492643 -48.170521) (xy 283.508711 -48.223928) (xy 283.516831 -48.279104)
			(xy 283.51734 -48.30699) (xy 283.516831 -48.334876) (xy 283.508711 -48.390052) (xy 283.492643 -48.443459)
			(xy 283.468971 -48.493956) (xy 283.438198 -48.540469) (xy 283.400981 -48.582006) (xy 283.358113 -48.617681)
			(xy 283.310507 -48.646735) (xy 283.259178 -48.668547) (xy 283.205221 -48.682653) (xy 283.149784 -48.688753)
			(xy 283.09405 -48.686716) (xy 283.039207 -48.676586) (xy 282.986423 -48.658579) (xy 282.936823 -48.633078)
			(xy 282.891465 -48.600627) (xy 282.851316 -48.561918) (xy 282.81723 -48.517775) (xy 282.789934 -48.46914)
			(xy 282.770011 -48.417049) (xy 282.757885 -48.362612) (xy 282.753814 -48.30699) (xy 272.583804 -48.30699)
			(xy 272.499495 -48.753014) (xy 279.368248 -48.753014) (xy 279.372319 -48.697392) (xy 279.384445 -48.642955)
			(xy 279.404368 -48.590864) (xy 279.431664 -48.542229) (xy 279.46575 -48.498086) (xy 279.505899 -48.459377)
			(xy 279.551257 -48.426926) (xy 279.600857 -48.401425) (xy 279.653641 -48.383418) (xy 279.708484 -48.373288)
			(xy 279.764218 -48.371251) (xy 279.819655 -48.377351) (xy 279.873612 -48.391457) (xy 279.924941 -48.413269)
			(xy 279.972547 -48.442323) (xy 280.015415 -48.477998) (xy 280.052632 -48.519535) (xy 280.083405 -48.566048)
			(xy 280.107077 -48.616545) (xy 280.123145 -48.669952) (xy 280.131265 -48.725128) (xy 280.131774 -48.753014)
			(xy 280.131265 -48.7809) (xy 280.123145 -48.836076) (xy 280.107077 -48.889483) (xy 280.105681 -48.89246)
			(xy 281.413964 -48.89246) (xy 281.418035 -48.836838) (xy 281.430161 -48.782401) (xy 281.450084 -48.73031)
			(xy 281.47738 -48.681675) (xy 281.511466 -48.637532) (xy 281.551615 -48.598823) (xy 281.596973 -48.566372)
			(xy 281.646573 -48.540871) (xy 281.699357 -48.522864) (xy 281.7542 -48.512734) (xy 281.809934 -48.510697)
			(xy 281.865371 -48.516797) (xy 281.919328 -48.530903) (xy 281.970657 -48.552715) (xy 282.018263 -48.581769)
			(xy 282.061131 -48.617444) (xy 282.098348 -48.658981) (xy 282.129121 -48.705494) (xy 282.152793 -48.755991)
			(xy 282.168861 -48.809398) (xy 282.176981 -48.864574) (xy 282.17749 -48.89246) (xy 282.176981 -48.920346)
			(xy 282.174543 -48.93691) (xy 285.133032 -48.93691) (xy 285.137103 -48.881288) (xy 285.149229 -48.826851)
			(xy 285.169152 -48.77476) (xy 285.196448 -48.726125) (xy 285.230534 -48.681982) (xy 285.270683 -48.643273)
			(xy 285.316041 -48.610822) (xy 285.365641 -48.585321) (xy 285.418425 -48.567314) (xy 285.473268 -48.557184)
			(xy 285.529002 -48.555147) (xy 285.584439 -48.561247) (xy 285.638396 -48.575353) (xy 285.689725 -48.597165)
			(xy 285.737331 -48.626219) (xy 285.780199 -48.661894) (xy 285.817416 -48.703431) (xy 285.848189 -48.749944)
			(xy 285.871861 -48.800441) (xy 285.887929 -48.853848) (xy 285.896049 -48.909024) (xy 285.896558 -48.93691)
			(xy 285.896049 -48.964796) (xy 285.887929 -49.019972) (xy 285.871861 -49.073379) (xy 285.848189 -49.123876)
			(xy 285.817416 -49.170389) (xy 285.780199 -49.211926) (xy 285.737331 -49.247601) (xy 285.689725 -49.276655)
			(xy 285.638396 -49.298467) (xy 285.584439 -49.312573) (xy 285.529002 -49.318673) (xy 285.473268 -49.316636)
			(xy 285.418425 -49.306506) (xy 285.365641 -49.288499) (xy 285.316041 -49.262998) (xy 285.270683 -49.230547)
			(xy 285.230534 -49.191838) (xy 285.196448 -49.147695) (xy 285.169152 -49.09906) (xy 285.149229 -49.046969)
			(xy 285.137103 -48.992532) (xy 285.133032 -48.93691) (xy 282.174543 -48.93691) (xy 282.168861 -48.975522)
			(xy 282.152793 -49.028929) (xy 282.129121 -49.079426) (xy 282.098348 -49.125939) (xy 282.061131 -49.167476)
			(xy 282.018263 -49.203151) (xy 281.970657 -49.232205) (xy 281.919328 -49.254017) (xy 281.865371 -49.268123)
			(xy 281.809934 -49.274223) (xy 281.7542 -49.272186) (xy 281.699357 -49.262056) (xy 281.646573 -49.244049)
			(xy 281.596973 -49.218548) (xy 281.551615 -49.186097) (xy 281.511466 -49.147388) (xy 281.47738 -49.103245)
			(xy 281.450084 -49.05461) (xy 281.430161 -49.002519) (xy 281.418035 -48.948082) (xy 281.413964 -48.89246)
			(xy 280.105681 -48.89246) (xy 280.083405 -48.93998) (xy 280.052632 -48.986493) (xy 280.015415 -49.02803)
			(xy 279.972547 -49.063705) (xy 279.924941 -49.092759) (xy 279.873612 -49.114571) (xy 279.819655 -49.128677)
			(xy 279.764218 -49.134777) (xy 279.708484 -49.13274) (xy 279.653641 -49.12261) (xy 279.600857 -49.104603)
			(xy 279.551257 -49.079102) (xy 279.505899 -49.046651) (xy 279.46575 -49.007942) (xy 279.431664 -48.963799)
			(xy 279.404368 -48.915164) (xy 279.384445 -48.863073) (xy 279.372319 -48.808636) (xy 279.368248 -48.753014)
			(xy 272.499495 -48.753014) (xy 272.423636 -49.154334) (xy 272.357342 -49.505108) (xy 272.35658 -49.513744)
			(xy 272.349744 -49.95291) (xy 285.133032 -49.95291) (xy 285.137103 -49.897288) (xy 285.149229 -49.842851)
			(xy 285.169152 -49.79076) (xy 285.196448 -49.742125) (xy 285.230534 -49.697982) (xy 285.270683 -49.659273)
			(xy 285.316041 -49.626822) (xy 285.365641 -49.601321) (xy 285.418425 -49.583314) (xy 285.473268 -49.573184)
			(xy 285.529002 -49.571147) (xy 285.584439 -49.577247) (xy 285.638396 -49.591353) (xy 285.689725 -49.613165)
			(xy 285.737331 -49.642219) (xy 285.780199 -49.677894) (xy 285.817416 -49.719431) (xy 285.848189 -49.765944)
			(xy 285.871861 -49.816441) (xy 285.887929 -49.869848) (xy 285.896049 -49.925024) (xy 285.896558 -49.95291)
			(xy 285.896049 -49.980796) (xy 285.887929 -50.035972) (xy 285.871861 -50.089379) (xy 285.848189 -50.139876)
			(xy 285.817416 -50.186389) (xy 285.780199 -50.227926) (xy 285.737331 -50.263601) (xy 285.689725 -50.292655)
			(xy 285.638396 -50.314467) (xy 285.584439 -50.328573) (xy 285.529002 -50.334673) (xy 285.473268 -50.332636)
			(xy 285.418425 -50.322506) (xy 285.365641 -50.304499) (xy 285.316041 -50.278998) (xy 285.270683 -50.246547)
			(xy 285.230534 -50.207838) (xy 285.196448 -50.163695) (xy 285.169152 -50.11506) (xy 285.149229 -50.062969)
			(xy 285.137103 -50.008532) (xy 285.133032 -49.95291) (xy 272.349744 -49.95291) (xy 272.333144 -51.019456)
			(xy 282.949394 -51.019456) (xy 282.953465 -50.963834) (xy 282.965591 -50.909397) (xy 282.985514 -50.857306)
			(xy 283.01281 -50.808671) (xy 283.046896 -50.764528) (xy 283.087045 -50.725819) (xy 283.132403 -50.693368)
			(xy 283.182003 -50.667867) (xy 283.234787 -50.64986) (xy 283.28963 -50.63973) (xy 283.345364 -50.637693)
			(xy 283.400801 -50.643793) (xy 283.454758 -50.657899) (xy 283.506087 -50.679711) (xy 283.553693 -50.708765)
			(xy 283.596561 -50.74444) (xy 283.633778 -50.785977) (xy 283.664551 -50.83249) (xy 283.688223 -50.882987)
			(xy 283.704291 -50.936394) (xy 283.712411 -50.99157) (xy 283.71292 -51.019456) (xy 283.712411 -51.047342)
			(xy 283.704291 -51.102518) (xy 283.688223 -51.155925) (xy 283.664551 -51.206422) (xy 283.639695 -51.243992)
			(xy 291.33292 -51.243992) (xy 291.333377 -51.216621) (xy 291.341196 -51.162442) (xy 291.356687 -51.109938)
			(xy 291.379531 -51.060192) (xy 291.409258 -51.014225) (xy 291.4269 -50.993294) (xy 291.427154 -50.99304)
			(xy 291.432736 -50.985951) (xy 291.438984 -50.969036) (xy 291.439346 -50.96002) (xy 291.439346 -50.892964)
			(xy 291.439018 -50.883944) (xy 291.432752 -50.867027) (xy 291.427154 -50.859944) (xy 291.4269 -50.859944)
			(xy 291.4269 -50.85969) (xy 291.409243 -50.838773) (xy 291.379534 -50.792796) (xy 291.356701 -50.743045)
			(xy 291.341214 -50.690541) (xy 291.333391 -50.636362) (xy 291.33292 -50.608992) (xy 291.333348 -50.581738)
			(xy 291.341107 -50.527784) (xy 291.356465 -50.475484) (xy 291.379111 -50.425902) (xy 291.408582 -50.380047)
			(xy 291.44428 -50.338854) (xy 291.485476 -50.303161) (xy 291.531333 -50.273693) (xy 291.580918 -50.251053)
			(xy 291.633219 -50.235699) (xy 291.687174 -50.227945) (xy 291.714428 -50.227484) (xy 291.743345 -50.228022)
			(xy 291.800516 -50.236743) (xy 291.855716 -50.253995) (xy 291.907679 -50.279382) (xy 291.955213 -50.312324)
			(xy 291.997229 -50.352065) (xy 292.015418 -50.37455) (xy 292.023018 -50.383364) (xy 292.043925 -50.393542)
			(xy 292.05555 -50.394108) (xy 292.135306 -50.394108) (xy 292.146936 -50.393555) (xy 292.167846 -50.383376)
			(xy 292.175438 -50.37455) (xy 292.193595 -50.352038) (xy 292.235623 -50.312307) (xy 292.283166 -50.279373)
			(xy 292.335133 -50.25399) (xy 292.390336 -50.236739) (xy 292.44751 -50.228016) (xy 292.476428 -50.227484)
			(xy 292.50368 -50.227952) (xy 292.557628 -50.235712) (xy 292.609922 -50.25107) (xy 292.659499 -50.273714)
			(xy 292.705349 -50.303182) (xy 292.746538 -50.338876) (xy 292.78223 -50.380067) (xy 292.811696 -50.425919)
			(xy 292.834337 -50.475497) (xy 292.849692 -50.527792) (xy 292.85745 -50.58174) (xy 292.857936 -50.608992)
			(xy 292.857452 -50.635305) (xy 292.850219 -50.687433) (xy 292.835902 -50.738075) (xy 292.814773 -50.786273)
			(xy 292.78723 -50.831117) (xy 292.753796 -50.871758) (xy 292.734746 -50.889916) (xy 292.727342 -50.897436)
			(xy 292.718818 -50.916717) (xy 292.718236 -50.927254) (xy 292.718236 -51.00193) (xy 292.718779 -51.012478)
			(xy 292.727303 -51.031775) (xy 292.734746 -51.039268) (xy 292.753836 -51.057388) (xy 292.787289 -51.098027)
			(xy 292.814842 -51.142875) (xy 292.835974 -51.191082) (xy 292.850284 -51.241735) (xy 292.857501 -51.293874)
			(xy 292.857936 -51.320192) (xy 292.857415 -51.347442) (xy 292.84966 -51.401387) (xy 292.834307 -51.453679)
			(xy 292.811669 -51.503255) (xy 292.782206 -51.549104) (xy 292.746519 -51.590293) (xy 292.705332 -51.625985)
			(xy 292.659486 -51.655452) (xy 292.609913 -51.678095) (xy 292.557622 -51.693453) (xy 292.503678 -51.701212)
			(xy 292.476428 -51.7017) (xy 292.448764 -51.701166) (xy 292.394016 -51.69317) (xy 292.340994 -51.677358)
			(xy 292.290811 -51.654058) (xy 292.244515 -51.62376) (xy 292.203076 -51.587098) (xy 292.167362 -51.544839)
			(xy 292.152324 -51.521614) (xy 292.145686 -51.511939) (xy 292.125825 -51.499495) (xy 292.114224 -51.497738)
			(xy 292.034214 -51.489864) (xy 292.022576 -51.489244) (xy 292.000739 -51.497316) (xy 291.992304 -51.505358)
			(xy 291.99205 -51.505612) (xy 291.973978 -51.524202) (xy 291.933644 -51.556779) (xy 291.889267 -51.583591)
			(xy 291.841667 -51.604142) (xy 291.791722 -51.618054) (xy 291.740352 -51.625069) (xy 291.714428 -51.6255)
			(xy 291.687175 -51.625019) (xy 291.633225 -51.617265) (xy 291.580927 -51.601912) (xy 291.531346 -51.579273)
			(xy 291.485493 -51.549807) (xy 291.444299 -51.514115) (xy 291.408605 -51.472923) (xy 291.379137 -51.427071)
			(xy 291.356495 -51.377492) (xy 291.341139 -51.325195) (xy 291.333383 -51.271244) (xy 291.33292 -51.243992)
			(xy 283.639695 -51.243992) (xy 283.633778 -51.252935) (xy 283.596561 -51.294472) (xy 283.553693 -51.330147)
			(xy 283.506087 -51.359201) (xy 283.454758 -51.381013) (xy 283.400801 -51.395119) (xy 283.345364 -51.401219)
			(xy 283.28963 -51.399182) (xy 283.234787 -51.389052) (xy 283.182003 -51.371045) (xy 283.132403 -51.345544)
			(xy 283.087045 -51.313093) (xy 283.046896 -51.274384) (xy 283.01281 -51.230241) (xy 282.985514 -51.181606)
			(xy 282.965591 -51.129515) (xy 282.953465 -51.075078) (xy 282.949394 -51.019456) (xy 272.333144 -51.019456)
			(xy 272.31733 -52.035456) (xy 285.14116 -52.035456) (xy 285.145231 -51.979834) (xy 285.157357 -51.925397)
			(xy 285.17728 -51.873306) (xy 285.204576 -51.824671) (xy 285.238662 -51.780528) (xy 285.278811 -51.741819)
			(xy 285.324169 -51.709368) (xy 285.373769 -51.683867) (xy 285.426553 -51.66586) (xy 285.481396 -51.65573)
			(xy 285.53713 -51.653693) (xy 285.592567 -51.659793) (xy 285.646524 -51.673899) (xy 285.697853 -51.695711)
			(xy 285.745459 -51.724765) (xy 285.788327 -51.76044) (xy 285.825544 -51.801977) (xy 285.856317 -51.84849)
			(xy 285.879989 -51.898987) (xy 285.896057 -51.952394) (xy 285.904177 -52.00757) (xy 285.904686 -52.035456)
			(xy 285.904177 -52.063342) (xy 285.896057 -52.118518) (xy 285.879989 -52.171925) (xy 285.856317 -52.222422)
			(xy 285.825544 -52.268935) (xy 285.788327 -52.310472) (xy 285.745459 -52.346147) (xy 285.697853 -52.375201)
			(xy 285.646524 -52.397013) (xy 285.592567 -52.411119) (xy 285.53713 -52.417219) (xy 285.481396 -52.415182)
			(xy 285.426553 -52.405052) (xy 285.373769 -52.387045) (xy 285.324169 -52.361544) (xy 285.278811 -52.329093)
			(xy 285.238662 -52.290384) (xy 285.204576 -52.246241) (xy 285.17728 -52.197606) (xy 285.157357 -52.145515)
			(xy 285.145231 -52.091078) (xy 285.14116 -52.035456) (xy 272.31733 -52.035456) (xy 272.316448 -52.092098)
			(xy 272.310606 -52.467256) (xy 272.310652 -52.473381) (xy 272.313357 -52.485324) (xy 272.31594 -52.490878)
			(xy 272.327878 -52.514754) (xy 272.33499 -52.523644) (xy 272.339308 -52.526946) (xy 272.359795 -52.543806)
			(xy 272.396369 -52.582244) (xy 272.427274 -52.625372) (xy 272.451913 -52.672362) (xy 272.469815 -52.722308)
			(xy 272.480634 -52.774251) (xy 272.484162 -52.827191) (xy 272.480332 -52.880111) (xy 272.469217 -52.931991)
			(xy 272.45103 -52.981835) (xy 272.426123 -53.028683) (xy 272.410936 -53.05044) (xy 272.404586 -53.059076)
			(xy 272.400776 -53.063902) (xy 272.395442 -53.072538) (xy 272.394934 -53.073554) (xy 272.392473 -53.07888)
			(xy 272.389781 -53.090296) (xy 272.3896 -53.09616) (xy 272.3896 -53.117242) (xy 272.389456 -53.122681)
			(xy 272.387147 -53.133312) (xy 272.385028 -53.138324) (xy 272.378678 -53.152294) (xy 272.375009 -53.16146)
			(xy 272.374195 -53.181167) (xy 272.380849 -53.199735) (xy 272.38706 -53.207412) (xy 272.396204 -53.217826)
			(xy 272.412306 -53.238023) (xy 272.439507 -53.281934) (xy 272.460554 -53.329105) (xy 272.475066 -53.378678)
			(xy 272.482778 -53.429752) (xy 272.48358 -53.45557) (xy 272.48358 -53.461666) (xy 272.482971 -53.491575)
			(xy 272.47359 -53.550653) (xy 272.455114 -53.607547) (xy 272.427995 -53.660865) (xy 272.410936 -53.68544)
			(xy 272.404586 -53.694076) (xy 272.400776 -53.698902) (xy 272.395442 -53.707538) (xy 272.394934 -53.708554)
			(xy 272.392473 -53.71388) (xy 272.389781 -53.725296) (xy 272.3896 -53.73116) (xy 272.3896 -53.752242)
			(xy 272.389456 -53.757681) (xy 272.387147 -53.768312) (xy 272.385028 -53.773324) (xy 272.378678 -53.787294)
			(xy 272.375009 -53.79646) (xy 272.374195 -53.816167) (xy 272.380849 -53.834735) (xy 272.38706 -53.842412)
			(xy 272.396204 -53.852826) (xy 272.412306 -53.873023) (xy 272.439507 -53.916934) (xy 272.460554 -53.964105)
			(xy 272.475066 -54.013678) (xy 272.482778 -54.064752) (xy 272.48358 -54.09057) (xy 272.48358 -54.096666)
			(xy 272.482971 -54.126575) (xy 272.47359 -54.185653) (xy 272.455114 -54.242547) (xy 272.427995 -54.295865)
			(xy 272.410936 -54.32044) (xy 272.404586 -54.329076) (xy 272.400776 -54.333902) (xy 272.395442 -54.342538)
			(xy 272.394934 -54.343554) (xy 272.392473 -54.34888) (xy 272.389781 -54.360296) (xy 272.3896 -54.36616)
			(xy 272.3896 -54.387242) (xy 272.389456 -54.392681) (xy 272.387147 -54.403312) (xy 272.385028 -54.408324)
			(xy 272.37944 -54.4195) (xy 272.375514 -54.428767) (xy 272.374364 -54.448838) (xy 272.380967 -54.467827)
			(xy 272.387314 -54.475634) (xy 272.387314 -54.475888) (xy 272.405576 -54.49706) (xy 272.436399 -54.543706)
			(xy 272.460107 -54.594341) (xy 272.476196 -54.647886) (xy 272.484323 -54.703203) (xy 272.48485 -54.731158)
			(xy 272.48485 -54.731412) (xy 272.484318 -54.760459) (xy 272.479642 -54.791102) (xy 274.376388 -54.791102)
			(xy 274.376858 -54.763732) (xy 274.384675 -54.709553) (xy 274.400164 -54.65705) (xy 274.423004 -54.607303)
			(xy 274.452728 -54.561336) (xy 274.470368 -54.540404) (xy 274.470622 -54.54015) (xy 274.476196 -54.533055)
			(xy 274.48245 -54.516145) (xy 274.482814 -54.50713) (xy 274.482814 -54.440074) (xy 274.482466 -54.431056)
			(xy 274.476212 -54.41414) (xy 274.470622 -54.407054) (xy 274.470368 -54.407054) (xy 274.470368 -54.4068)
			(xy 274.452728 -54.385866) (xy 274.423 -54.3399) (xy 274.400152 -54.290154) (xy 274.384653 -54.237652)
			(xy 274.376824 -54.183472) (xy 274.376823 -54.128731) (xy 274.384653 -54.074551) (xy 274.400151 -54.022049)
			(xy 274.422998 -53.972303) (xy 274.452726 -53.926336) (xy 274.470368 -53.905404) (xy 274.470622 -53.90515)
			(xy 274.476196 -53.898055) (xy 274.48245 -53.881145) (xy 274.482814 -53.87213) (xy 274.482814 -53.805074)
			(xy 274.482466 -53.796056) (xy 274.476212 -53.77914) (xy 274.470622 -53.772054) (xy 274.470368 -53.772054)
			(xy 274.470368 -53.7718) (xy 274.452728 -53.750866) (xy 274.423 -53.7049) (xy 274.400152 -53.655154)
			(xy 274.384653 -53.602652) (xy 274.376824 -53.548472) (xy 274.376823 -53.493731) (xy 274.384653 -53.439551)
			(xy 274.400151 -53.387049) (xy 274.422998 -53.337303) (xy 274.452726 -53.291336) (xy 274.470368 -53.270404)
			(xy 274.470622 -53.27015) (xy 274.476196 -53.263055) (xy 274.48245 -53.246145) (xy 274.482814 -53.23713)
			(xy 274.482814 -53.170074) (xy 274.482466 -53.161056) (xy 274.476212 -53.14414) (xy 274.470622 -53.137054)
			(xy 274.470368 -53.137054) (xy 274.470368 -53.1368) (xy 274.45271 -53.115883) (xy 274.423002 -53.069905)
			(xy 274.400171 -53.020154) (xy 274.384684 -52.96765) (xy 274.37686 -52.913472) (xy 274.376388 -52.886102)
			(xy 274.376874 -52.858851) (xy 274.38463 -52.804903) (xy 274.399985 -52.752608) (xy 274.422627 -52.703031)
			(xy 274.452093 -52.657181) (xy 274.487784 -52.61599) (xy 274.528975 -52.580299) (xy 274.574825 -52.550833)
			(xy 274.624402 -52.528191) (xy 274.676697 -52.512836) (xy 274.730645 -52.50508) (xy 274.785147 -52.50508)
			(xy 274.839095 -52.512836) (xy 274.89139 -52.528191) (xy 274.93049 -52.546048) (xy 279.879596 -52.546048)
			(xy 279.879596 -52.491552) (xy 279.887351 -52.437611) (xy 279.902703 -52.385323) (xy 279.925339 -52.335751)
			(xy 279.9548 -52.289905) (xy 279.990484 -52.248718) (xy 280.031667 -52.213029) (xy 280.077509 -52.183563)
			(xy 280.127078 -52.16092) (xy 280.179364 -52.145561) (xy 280.233304 -52.1378) (xy 280.260552 -52.13731)
			(xy 280.287921 -52.137802) (xy 280.342099 -52.145613) (xy 280.394602 -52.161096) (xy 280.44435 -52.183932)
			(xy 280.490318 -52.213651) (xy 280.51125 -52.23129) (xy 280.511504 -52.231544) (xy 280.518581 -52.237144)
			(xy 280.535505 -52.243381) (xy 280.544524 -52.243736) (xy 280.61158 -52.243736) (xy 280.620595 -52.243361)
			(xy 280.637512 -52.237125) (xy 280.6446 -52.231544) (xy 280.6446 -52.23129) (xy 280.644854 -52.23129)
			(xy 280.665787 -52.213649) (xy 280.711755 -52.183925) (xy 280.761501 -52.161079) (xy 280.814003 -52.145583)
			(xy 280.868181 -52.137754) (xy 280.922923 -52.137754) (xy 280.977101 -52.145583) (xy 281.029603 -52.161079)
			(xy 281.079349 -52.183925) (xy 281.125317 -52.213649) (xy 281.14625 -52.23129) (xy 281.146504 -52.231544)
			(xy 281.153581 -52.237144) (xy 281.170505 -52.243381) (xy 281.179524 -52.243736) (xy 281.24658 -52.243736)
			(xy 281.255595 -52.243361) (xy 281.272512 -52.237125) (xy 281.2796 -52.231544) (xy 281.2796 -52.23129)
			(xy 281.279854 -52.23129) (xy 281.300791 -52.213657) (xy 281.346763 -52.183945) (xy 281.396509 -52.161108)
			(xy 281.449008 -52.145615) (xy 281.503183 -52.137785) (xy 281.530552 -52.13731) (xy 281.557808 -52.137734)
			(xy 281.611767 -52.145485) (xy 281.664073 -52.160838) (xy 281.713662 -52.183479) (xy 281.759523 -52.212947)
			(xy 281.800724 -52.248642) (xy 281.836424 -52.289838) (xy 281.865898 -52.335696) (xy 281.888545 -52.385282)
			(xy 281.903904 -52.437586) (xy 281.911663 -52.491544) (xy 281.911663 -52.546056) (xy 281.905718 -52.587398)
			(xy 282.955236 -52.587398) (xy 282.959307 -52.531776) (xy 282.971433 -52.477339) (xy 282.991356 -52.425248)
			(xy 283.018652 -52.376613) (xy 283.052738 -52.33247) (xy 283.092887 -52.293761) (xy 283.138245 -52.26131)
			(xy 283.187845 -52.235809) (xy 283.240629 -52.217802) (xy 283.295472 -52.207672) (xy 283.351206 -52.205635)
			(xy 283.406643 -52.211735) (xy 283.4606 -52.225841) (xy 283.511929 -52.247653) (xy 283.559535 -52.276707)
			(xy 283.602403 -52.312382) (xy 283.63962 -52.353919) (xy 283.670393 -52.400432) (xy 283.694065 -52.450929)
			(xy 283.710133 -52.504336) (xy 283.717729 -52.555948) (xy 290.783802 -52.555948) (xy 290.783802 -52.501452)
			(xy 290.791557 -52.44751) (xy 290.80691 -52.395221) (xy 290.829548 -52.345649) (xy 290.85901 -52.299802)
			(xy 290.894696 -52.258616) (xy 290.93588 -52.222926) (xy 290.981724 -52.193461) (xy 291.031295 -52.17082)
			(xy 291.083583 -52.155463) (xy 291.137524 -52.147704) (xy 291.164772 -52.147216) (xy 291.192142 -52.147695)
			(xy 291.246321 -52.155509) (xy 291.298824 -52.170995) (xy 291.348571 -52.193834) (xy 291.394538 -52.223556)
			(xy 291.41547 -52.241196) (xy 291.415724 -52.24145) (xy 291.422795 -52.247059) (xy 291.439724 -52.253291)
			(xy 291.448744 -52.253642) (xy 291.5158 -52.253642) (xy 291.524818 -52.253297) (xy 291.541736 -52.247043)
			(xy 291.54882 -52.24145) (xy 291.54882 -52.241196) (xy 291.549074 -52.241196) (xy 291.570005 -52.223555)
			(xy 291.615978 -52.193844) (xy 291.665726 -52.171008) (xy 291.718227 -52.155517) (xy 291.772403 -52.14769)
			(xy 291.799772 -52.147216) (xy 291.827028 -52.147629) (xy 291.880985 -52.155383) (xy 291.93329 -52.170738)
			(xy 291.982877 -52.19338) (xy 292.028736 -52.222849) (xy 292.069935 -52.258545) (xy 292.105634 -52.299741)
			(xy 292.135106 -52.345599) (xy 292.157752 -52.395184) (xy 292.173111 -52.447487) (xy 292.180869 -52.501444)
			(xy 292.180869 -52.555956) (xy 292.173111 -52.609913) (xy 292.157752 -52.662216) (xy 292.135106 -52.711801)
			(xy 292.105634 -52.757659) (xy 292.069935 -52.798855) (xy 292.028736 -52.834551) (xy 291.982877 -52.86402)
			(xy 291.93329 -52.886662) (xy 291.880985 -52.902017) (xy 291.827028 -52.909771) (xy 291.799772 -52.910232)
			(xy 291.7724 -52.909799) (xy 291.718219 -52.901976) (xy 291.665715 -52.88648) (xy 291.615969 -52.86363)
			(xy 291.570004 -52.833897) (xy 291.549074 -52.816252) (xy 291.54882 -52.815998) (xy 291.541732 -52.810413)
			(xy 291.524816 -52.804166) (xy 291.5158 -52.803806) (xy 291.448744 -52.803806) (xy 291.439729 -52.804183)
			(xy 291.422812 -52.810417) (xy 291.415724 -52.815998) (xy 291.415724 -52.816252) (xy 291.41547 -52.816252)
			(xy 291.394516 -52.833864) (xy 291.34855 -52.863582) (xy 291.298808 -52.886424) (xy 291.246312 -52.901921)
			(xy 291.19214 -52.909755) (xy 291.164772 -52.910232) (xy 291.137524 -52.909696) (xy 291.083583 -52.901937)
			(xy 291.031295 -52.88658) (xy 290.981724 -52.863939) (xy 290.93588 -52.834474) (xy 290.894696 -52.798784)
			(xy 290.85901 -52.757598) (xy 290.829548 -52.711751) (xy 290.80691 -52.662179) (xy 290.791557 -52.60989)
			(xy 290.783802 -52.555948) (xy 283.717729 -52.555948) (xy 283.718253 -52.559512) (xy 283.718762 -52.587398)
			(xy 283.718253 -52.615284) (xy 283.710133 -52.67046) (xy 283.694065 -52.723867) (xy 283.670393 -52.774364)
			(xy 283.63962 -52.820877) (xy 283.602403 -52.862414) (xy 283.559535 -52.898089) (xy 283.511929 -52.927143)
			(xy 283.4606 -52.948955) (xy 283.406643 -52.963061) (xy 283.351206 -52.969161) (xy 283.295472 -52.967124)
			(xy 283.240629 -52.956994) (xy 283.187845 -52.938987) (xy 283.138245 -52.913486) (xy 283.092887 -52.881035)
			(xy 283.052738 -52.842326) (xy 283.018652 -52.798183) (xy 282.991356 -52.749548) (xy 282.971433 -52.697457)
			(xy 282.959307 -52.64302) (xy 282.955236 -52.587398) (xy 281.905718 -52.587398) (xy 281.903904 -52.600014)
			(xy 281.888545 -52.652318) (xy 281.865898 -52.701904) (xy 281.836424 -52.747762) (xy 281.800724 -52.788958)
			(xy 281.759523 -52.824653) (xy 281.713662 -52.854121) (xy 281.664073 -52.876762) (xy 281.611767 -52.892115)
			(xy 281.557808 -52.899866) (xy 281.530552 -52.900326) (xy 281.503182 -52.899847) (xy 281.449003 -52.892035)
			(xy 281.396499 -52.87655) (xy 281.346752 -52.853711) (xy 281.300785 -52.823987) (xy 281.279854 -52.806346)
			(xy 281.2796 -52.806092) (xy 281.272518 -52.800498) (xy 281.255598 -52.794256) (xy 281.24658 -52.7939)
			(xy 281.179524 -52.7939) (xy 281.170508 -52.794268) (xy 281.153591 -52.800508) (xy 281.146504 -52.806092)
			(xy 281.14625 -52.806346) (xy 281.125317 -52.823987) (xy 281.079349 -52.853711) (xy 281.029603 -52.876557)
			(xy 280.977101 -52.892053) (xy 280.922923 -52.899882) (xy 280.868181 -52.899882) (xy 280.814003 -52.892053)
			(xy 280.761501 -52.876557) (xy 280.711755 -52.853711) (xy 280.665787 -52.823987) (xy 280.644854 -52.806346)
			(xy 280.6446 -52.806092) (xy 280.637518 -52.800498) (xy 280.620598 -52.794256) (xy 280.61158 -52.7939)
			(xy 280.544524 -52.7939) (xy 280.535508 -52.794268) (xy 280.518591 -52.800508) (xy 280.511504 -52.806092)
			(xy 280.511504 -52.806346) (xy 280.51125 -52.806346) (xy 280.490303 -52.823967) (xy 280.444335 -52.853683)
			(xy 280.394592 -52.876524) (xy 280.342094 -52.892019) (xy 280.28792 -52.89985) (xy 280.260552 -52.900326)
			(xy 280.233304 -52.8998) (xy 280.179364 -52.892039) (xy 280.127078 -52.87668) (xy 280.077509 -52.854037)
			(xy 280.031667 -52.824571) (xy 279.990484 -52.788882) (xy 279.9548 -52.747695) (xy 279.925339 -52.701849)
			(xy 279.902703 -52.652277) (xy 279.887351 -52.599989) (xy 279.879596 -52.546048) (xy 274.93049 -52.546048)
			(xy 274.940967 -52.550833) (xy 274.986817 -52.580299) (xy 275.028008 -52.61599) (xy 275.063699 -52.657181)
			(xy 275.093165 -52.703031) (xy 275.115807 -52.752608) (xy 275.131162 -52.804903) (xy 275.138918 -52.858851)
			(xy 275.139404 -52.886102) (xy 275.138938 -52.913472) (xy 275.13112 -52.967651) (xy 275.115631 -53.020154)
			(xy 275.092789 -53.069901) (xy 275.063065 -53.115868) (xy 275.045424 -53.1368) (xy 275.04517 -53.137054)
			(xy 275.039593 -53.144147) (xy 275.033342 -53.161059) (xy 275.032978 -53.170074) (xy 275.032978 -53.23713)
			(xy 275.033325 -53.246148) (xy 275.03958 -53.263064) (xy 275.04517 -53.27015) (xy 275.045424 -53.27015)
			(xy 275.045424 -53.270404) (xy 275.063069 -53.291334) (xy 275.092797 -53.337301) (xy 275.115645 -53.387048)
			(xy 275.131144 -53.43955) (xy 275.138973 -53.49373) (xy 275.138973 -53.548473) (xy 275.131143 -53.602652)
			(xy 275.115644 -53.655155) (xy 275.092796 -53.704901) (xy 275.063067 -53.750868) (xy 275.046494 -53.77053)
			(xy 275.410676 -53.77053) (xy 275.411187 -53.741612) (xy 275.419913 -53.68444) (xy 275.437171 -53.629239)
			(xy 275.462564 -53.577277) (xy 275.49551 -53.529744) (xy 275.535255 -53.487729) (xy 275.557742 -53.46954)
			(xy 275.566528 -53.461913) (xy 275.576721 -53.441027) (xy 275.5773 -53.429408) (xy 275.5773 -53.349652)
			(xy 275.576774 -53.338018) (xy 275.566576 -53.317109) (xy 275.557742 -53.30952) (xy 275.535277 -53.291307)
			(xy 275.495539 -53.249293) (xy 275.462596 -53.201763) (xy 275.437204 -53.149806) (xy 275.419945 -53.094612)
			(xy 275.411212 -53.037445) (xy 275.410676 -53.00853) (xy 275.411183 -52.981279) (xy 275.418936 -52.92733)
			(xy 275.434287 -52.875034) (xy 275.456925 -52.825455) (xy 275.486388 -52.779603) (xy 275.522077 -52.73841)
			(xy 275.563266 -52.702716) (xy 275.609115 -52.673247) (xy 275.658691 -52.650603) (xy 275.710985 -52.635245)
			(xy 275.764933 -52.627486) (xy 275.792184 -52.627022) (xy 275.818498 -52.627493) (xy 275.870627 -52.634726)
			(xy 275.921269 -52.649044) (xy 275.969469 -52.670176) (xy 276.014312 -52.697722) (xy 276.054952 -52.73116)
			(xy 276.073108 -52.750212) (xy 276.080623 -52.757621) (xy 276.099908 -52.766141) (xy 276.110446 -52.766722)
			(xy 276.185122 -52.766722) (xy 276.195667 -52.766158) (xy 276.214963 -52.757647) (xy 276.22246 -52.750212)
			(xy 276.240596 -52.731137) (xy 276.281229 -52.697681) (xy 276.326074 -52.670124) (xy 276.374279 -52.648989)
			(xy 276.42493 -52.634676) (xy 276.477067 -52.627457) (xy 276.503384 -52.627022) (xy 276.530638 -52.62747)
			(xy 276.584591 -52.635226) (xy 276.636891 -52.650581) (xy 276.686473 -52.673224) (xy 276.732328 -52.702693)
			(xy 276.773521 -52.738389) (xy 276.809215 -52.779584) (xy 276.838683 -52.825439) (xy 276.861324 -52.875022)
			(xy 276.876677 -52.927323) (xy 276.884431 -52.981276) (xy 276.884892 -53.00853) (xy 276.884407 -53.036196)
			(xy 276.882176 -53.051456) (xy 285.14116 -53.051456) (xy 285.145231 -52.995834) (xy 285.157357 -52.941397)
			(xy 285.17728 -52.889306) (xy 285.204576 -52.840671) (xy 285.238662 -52.796528) (xy 285.278811 -52.757819)
			(xy 285.324169 -52.725368) (xy 285.373769 -52.699867) (xy 285.426553 -52.68186) (xy 285.481396 -52.67173)
			(xy 285.53713 -52.669693) (xy 285.592567 -52.675793) (xy 285.646524 -52.689899) (xy 285.697853 -52.711711)
			(xy 285.745459 -52.740765) (xy 285.788327 -52.77644) (xy 285.825544 -52.817977) (xy 285.856317 -52.86449)
			(xy 285.879989 -52.914987) (xy 285.896057 -52.968394) (xy 285.904177 -53.02357) (xy 285.904686 -53.051456)
			(xy 285.904177 -53.079342) (xy 285.896057 -53.134518) (xy 285.879989 -53.187925) (xy 285.856317 -53.238422)
			(xy 285.825544 -53.284935) (xy 285.788327 -53.326472) (xy 285.745459 -53.362147) (xy 285.697853 -53.391201)
			(xy 285.646524 -53.413013) (xy 285.592567 -53.427119) (xy 285.53713 -53.433219) (xy 285.481396 -53.431182)
			(xy 285.426553 -53.421052) (xy 285.373769 -53.403045) (xy 285.324169 -53.377544) (xy 285.278811 -53.345093)
			(xy 285.238662 -53.306384) (xy 285.204576 -53.262241) (xy 285.17728 -53.213606) (xy 285.157357 -53.161515)
			(xy 285.145231 -53.107078) (xy 285.14116 -53.051456) (xy 276.882176 -53.051456) (xy 276.876403 -53.090947)
			(xy 276.860582 -53.143969) (xy 276.837275 -53.194153) (xy 276.806969 -53.240449) (xy 276.7703 -53.281886)
			(xy 276.728035 -53.317598) (xy 276.704806 -53.332634) (xy 276.695126 -53.339267) (xy 276.682681 -53.35913)
			(xy 276.68093 -53.370734) (xy 276.673056 -53.450744) (xy 276.672403 -53.462383) (xy 276.680498 -53.484222)
			(xy 276.68855 -53.492654) (xy 276.688804 -53.492908) (xy 276.707372 -53.511002) (xy 276.739952 -53.551331)
			(xy 276.766766 -53.595703) (xy 276.787321 -53.643299) (xy 276.801238 -53.693241) (xy 276.808258 -53.744608)
			(xy 276.808692 -53.77053) (xy 276.80825 -53.797783) (xy 276.800489 -53.851733) (xy 276.785129 -53.904029)
			(xy 276.762483 -53.953608) (xy 276.733013 -53.999459) (xy 276.697317 -54.040649) (xy 276.656122 -54.07634)
			(xy 276.610267 -54.105806) (xy 276.560686 -54.128445) (xy 276.508388 -54.143799) (xy 276.454437 -54.151553)
			(xy 276.427184 -54.152038) (xy 276.399813 -54.151596) (xy 276.345632 -54.143775) (xy 276.293128 -54.128281)
			(xy 276.243381 -54.105433) (xy 276.197416 -54.075703) (xy 276.176486 -54.058058) (xy 276.176232 -54.057804)
			(xy 276.16914 -54.052225) (xy 276.152227 -54.045974) (xy 276.143212 -54.045612) (xy 276.076156 -54.045612)
			(xy 276.067142 -54.045993) (xy 276.050224 -54.052224) (xy 276.043136 -54.057804) (xy 276.043136 -54.058058)
			(xy 276.042882 -54.058058) (xy 276.021924 -54.075666) (xy 275.975959 -54.105384) (xy 275.926218 -54.128226)
			(xy 275.873723 -54.143725) (xy 275.819552 -54.15156) (xy 275.792184 -54.152038) (xy 275.764934 -54.151537)
			(xy 275.710988 -54.143779) (xy 275.658695 -54.128424) (xy 275.60912 -54.105783) (xy 275.563271 -54.076318)
			(xy 275.522082 -54.040628) (xy 275.486391 -53.99944) (xy 275.456924 -53.953592) (xy 275.434281 -53.904018)
			(xy 275.418924 -53.851726) (xy 275.411164 -53.79778) (xy 275.410676 -53.77053) (xy 275.046494 -53.77053)
			(xy 275.045424 -53.7718) (xy 275.04517 -53.772054) (xy 275.039593 -53.779147) (xy 275.033342 -53.796059)
			(xy 275.032978 -53.805074) (xy 275.032978 -53.87213) (xy 275.033325 -53.881148) (xy 275.03958 -53.898064)
			(xy 275.04517 -53.90515) (xy 275.045424 -53.90515) (xy 275.045424 -53.905404) (xy 275.063069 -53.926334)
			(xy 275.092797 -53.972301) (xy 275.115645 -54.022048) (xy 275.131144 -54.07455) (xy 275.138973 -54.12873)
			(xy 275.138973 -54.183473) (xy 275.131143 -54.237652) (xy 275.115644 -54.290155) (xy 275.101851 -54.320186)
			(xy 277.330408 -54.320186) (xy 277.330864 -54.292815) (xy 277.338684 -54.238636) (xy 277.354175 -54.186132)
			(xy 277.377019 -54.136386) (xy 277.406746 -54.090419) (xy 277.424388 -54.069488) (xy 277.424642 -54.069234)
			(xy 277.430226 -54.062146) (xy 277.436473 -54.04523) (xy 277.436834 -54.036214) (xy 277.436834 -53.969158)
			(xy 277.436442 -53.960145) (xy 277.430218 -53.943228) (xy 277.424642 -53.936138) (xy 277.424388 -53.936138)
			(xy 277.424388 -53.935884) (xy 277.406773 -53.914933) (xy 277.377058 -53.868965) (xy 277.354218 -53.819222)
			(xy 277.338721 -53.766726) (xy 277.330886 -53.712554) (xy 277.330408 -53.685186) (xy 277.330894 -53.657935)
			(xy 277.33865 -53.603987) (xy 277.354005 -53.551692) (xy 277.376647 -53.502115) (xy 277.406113 -53.456265)
			(xy 277.441804 -53.415074) (xy 277.482995 -53.379383) (xy 277.528845 -53.349917) (xy 277.578422 -53.327275)
			(xy 277.630717 -53.31192) (xy 277.684665 -53.304164) (xy 277.739167 -53.304164) (xy 277.793115 -53.31192)
			(xy 277.84541 -53.327275) (xy 277.894987 -53.349917) (xy 277.940837 -53.379383) (xy 277.982028 -53.415074)
			(xy 278.017719 -53.456265) (xy 278.043612 -53.496555) (xy 290.333341 -53.496555) (xy 290.333341 -53.442045)
			(xy 290.341099 -53.388089) (xy 290.356457 -53.335787) (xy 290.379103 -53.286203) (xy 290.408575 -53.240347)
			(xy 290.444273 -53.199152) (xy 290.485471 -53.163457) (xy 290.531329 -53.133988) (xy 290.580915 -53.111347)
			(xy 290.633219 -53.095993) (xy 290.687175 -53.088239) (xy 290.71443 -53.087778) (xy 290.741802 -53.088207)
			(xy 290.795983 -53.096031) (xy 290.848487 -53.111528) (xy 290.898234 -53.134378) (xy 290.944198 -53.164112)
			(xy 290.965128 -53.181758) (xy 290.965382 -53.182012) (xy 290.972469 -53.187599) (xy 290.989385 -53.193845)
			(xy 290.998402 -53.194204) (xy 291.065458 -53.194204) (xy 291.074473 -53.193826) (xy 291.09139 -53.187593)
			(xy 291.098478 -53.182012) (xy 291.098478 -53.181758) (xy 291.098732 -53.181758) (xy 291.119673 -53.16413)
			(xy 291.165644 -53.134418) (xy 291.215389 -53.111581) (xy 291.267888 -53.096087) (xy 291.322062 -53.088254)
			(xy 291.34943 -53.087778) (xy 291.376679 -53.088294) (xy 291.430621 -53.096054) (xy 291.48291 -53.111411)
			(xy 291.532482 -53.134053) (xy 291.578327 -53.163519) (xy 291.619512 -53.199209) (xy 291.655199 -53.240397)
			(xy 291.684661 -53.286244) (xy 291.707299 -53.335818) (xy 291.722652 -53.388108) (xy 291.730408 -53.442051)
			(xy 291.730408 -53.496549) (xy 291.722652 -53.550492) (xy 291.707299 -53.602782) (xy 291.684661 -53.652356)
			(xy 291.655199 -53.698203) (xy 291.619512 -53.739391) (xy 291.578327 -53.775081) (xy 291.532482 -53.804547)
			(xy 291.48291 -53.827189) (xy 291.430621 -53.842546) (xy 291.376679 -53.850306) (xy 291.34943 -53.850794)
			(xy 291.32206 -53.850312) (xy 291.267882 -53.842498) (xy 291.215379 -53.827013) (xy 291.165632 -53.804175)
			(xy 291.119664 -53.774454) (xy 291.098732 -53.756814) (xy 291.098478 -53.75656) (xy 291.091405 -53.750953)
			(xy 291.074478 -53.74472) (xy 291.065458 -53.744368) (xy 290.998402 -53.744368) (xy 290.989386 -53.744733)
			(xy 290.97247 -53.750976) (xy 290.965382 -53.75656) (xy 290.965382 -53.756814) (xy 290.965128 -53.756814)
			(xy 290.944198 -53.774456) (xy 290.898224 -53.804167) (xy 290.848476 -53.827002) (xy 290.795975 -53.842492)
			(xy 290.741799 -53.85032) (xy 290.71443 -53.850794) (xy 290.687175 -53.850361) (xy 290.633219 -53.842607)
			(xy 290.580915 -53.827253) (xy 290.531329 -53.804612) (xy 290.485471 -53.775143) (xy 290.444273 -53.739448)
			(xy 290.408575 -53.698253) (xy 290.379103 -53.652397) (xy 290.356457 -53.602813) (xy 290.341099 -53.550511)
			(xy 290.333341 -53.496555) (xy 278.043612 -53.496555) (xy 278.047185 -53.502115) (xy 278.069827 -53.551692)
			(xy 278.085182 -53.603987) (xy 278.092938 -53.657935) (xy 278.093424 -53.685186) (xy 278.092968 -53.712557)
			(xy 278.085151 -53.766737) (xy 278.06966 -53.819241) (xy 278.046816 -53.868988) (xy 278.017087 -53.914953)
			(xy 277.999444 -53.935884) (xy 277.99919 -53.936138) (xy 277.993622 -53.943237) (xy 277.987365 -53.960144)
			(xy 277.986998 -53.969158) (xy 277.986998 -54.036214) (xy 277.987349 -54.045231) (xy 277.993601 -54.062148)
			(xy 277.99919 -54.069234) (xy 277.999444 -54.069234) (xy 277.999444 -54.069488) (xy 278.017098 -54.090408)
			(xy 278.046806 -54.136385) (xy 278.069639 -54.186135) (xy 278.085127 -54.238638) (xy 278.092952 -54.292816)
			(xy 278.093424 -54.320186) (xy 278.092938 -54.347437) (xy 278.085182 -54.401385) (xy 278.069827 -54.45368)
			(xy 278.047185 -54.503257) (xy 278.017719 -54.549107) (xy 277.982028 -54.590298) (xy 277.940837 -54.625989)
			(xy 277.894987 -54.655455) (xy 277.84541 -54.678097) (xy 277.793115 -54.693452) (xy 277.739167 -54.701208)
			(xy 277.684665 -54.701208) (xy 277.630717 -54.693452) (xy 277.578422 -54.678097) (xy 277.528845 -54.655455)
			(xy 277.482995 -54.625989) (xy 277.441804 -54.590298) (xy 277.406113 -54.549107) (xy 277.376647 -54.503257)
			(xy 277.354005 -54.45368) (xy 277.33865 -54.401385) (xy 277.330894 -54.347437) (xy 277.330408 -54.320186)
			(xy 275.101851 -54.320186) (xy 275.092796 -54.339901) (xy 275.063067 -54.385868) (xy 275.045424 -54.4068)
			(xy 275.04517 -54.407054) (xy 275.039593 -54.414147) (xy 275.033342 -54.431059) (xy 275.032978 -54.440074)
			(xy 275.032978 -54.50713) (xy 275.033325 -54.516148) (xy 275.03958 -54.533064) (xy 275.04517 -54.54015)
			(xy 275.045424 -54.54015) (xy 275.045424 -54.540404) (xy 275.063082 -54.561321) (xy 275.09279 -54.607298)
			(xy 275.115622 -54.65705) (xy 275.131109 -54.709553) (xy 275.138932 -54.763732) (xy 275.139049 -54.770528)
			(xy 278.27097 -54.770528) (xy 278.271435 -54.743158) (xy 278.279251 -54.688978) (xy 278.294739 -54.636474)
			(xy 278.317581 -54.586727) (xy 278.347308 -54.540761) (xy 278.36495 -54.51983) (xy 278.365204 -54.519576)
			(xy 278.370807 -54.512501) (xy 278.377044 -54.495575) (xy 278.377396 -54.486556) (xy 278.377396 -54.4195)
			(xy 278.37704 -54.410483) (xy 278.370792 -54.393566) (xy 278.365204 -54.38648) (xy 278.36495 -54.38648)
			(xy 278.36495 -54.386226) (xy 278.347317 -54.365289) (xy 278.317603 -54.319318) (xy 278.294765 -54.269572)
			(xy 278.279272 -54.217072) (xy 278.271444 -54.162897) (xy 278.27097 -54.135528) (xy 278.271456 -54.108277)
			(xy 278.279212 -54.054329) (xy 278.294567 -54.002034) (xy 278.317209 -53.952457) (xy 278.346675 -53.906607)
			(xy 278.382366 -53.865416) (xy 278.423557 -53.829725) (xy 278.469407 -53.800259) (xy 278.518984 -53.777617)
			(xy 278.571279 -53.762262) (xy 278.625227 -53.754506) (xy 278.679729 -53.754506) (xy 278.733677 -53.762262)
			(xy 278.785972 -53.777617) (xy 278.835549 -53.800259) (xy 278.881399 -53.829725) (xy 278.92259 -53.865416)
			(xy 278.958281 -53.906607) (xy 278.987747 -53.952457) (xy 278.992822 -53.96357) (xy 282.972 -53.96357)
			(xy 282.976071 -53.907948) (xy 282.988197 -53.853511) (xy 283.00812 -53.80142) (xy 283.035416 -53.752785)
			(xy 283.069502 -53.708642) (xy 283.109651 -53.669933) (xy 283.155009 -53.637482) (xy 283.204609 -53.611981)
			(xy 283.257393 -53.593974) (xy 283.312236 -53.583844) (xy 283.36797 -53.581807) (xy 283.423407 -53.587907)
			(xy 283.477364 -53.602013) (xy 283.528693 -53.623825) (xy 283.576299 -53.652879) (xy 283.619167 -53.688554)
			(xy 283.656384 -53.730091) (xy 283.687157 -53.776604) (xy 283.710829 -53.827101) (xy 283.726897 -53.880508)
			(xy 283.735017 -53.935684) (xy 283.735526 -53.96357) (xy 283.735017 -53.991456) (xy 283.726897 -54.046632)
			(xy 283.710829 -54.100039) (xy 283.687157 -54.150536) (xy 283.656384 -54.197049) (xy 283.619167 -54.238586)
			(xy 283.576299 -54.274261) (xy 283.528693 -54.303315) (xy 283.477364 -54.325127) (xy 283.423407 -54.339233)
			(xy 283.36797 -54.345333) (xy 283.312236 -54.343296) (xy 283.257393 -54.333166) (xy 283.204609 -54.315159)
			(xy 283.155009 -54.289658) (xy 283.109651 -54.257207) (xy 283.069502 -54.218498) (xy 283.035416 -54.174355)
			(xy 283.00812 -54.12572) (xy 282.988197 -54.073629) (xy 282.976071 -54.019192) (xy 282.972 -53.96357)
			(xy 278.992822 -53.96357) (xy 279.010389 -54.002034) (xy 279.025744 -54.054329) (xy 279.0335 -54.108277)
			(xy 279.033986 -54.135528) (xy 279.03354 -54.162899) (xy 279.025718 -54.217079) (xy 279.010224 -54.269583)
			(xy 278.987378 -54.319329) (xy 278.957649 -54.365295) (xy 278.940006 -54.386226) (xy 278.939752 -54.38648)
			(xy 278.934162 -54.393564) (xy 278.927919 -54.410483) (xy 278.92756 -54.4195) (xy 278.92756 -54.486556)
			(xy 278.927925 -54.495572) (xy 278.934166 -54.51249) (xy 278.939752 -54.519576) (xy 278.940006 -54.519576)
			(xy 278.940006 -54.51983) (xy 278.957627 -54.540777) (xy 278.987341 -54.586746) (xy 279.01018 -54.636489)
			(xy 279.025676 -54.688987) (xy 279.033509 -54.74316) (xy 279.033986 -54.770528) (xy 279.0335 -54.797779)
			(xy 279.025744 -54.851727) (xy 279.010389 -54.904022) (xy 278.987747 -54.953599) (xy 278.964961 -54.989055)
			(xy 288.100945 -54.989055) (xy 288.100945 -54.934545) (xy 288.108703 -54.880591) (xy 288.12406 -54.82829)
			(xy 288.146705 -54.778707) (xy 288.176176 -54.732851) (xy 288.211874 -54.691657) (xy 288.25307 -54.655962)
			(xy 288.298928 -54.626494) (xy 288.348512 -54.603852) (xy 288.400814 -54.588498) (xy 288.454769 -54.580743)
			(xy 288.482024 -54.580282) (xy 288.510116 -54.580758) (xy 288.565694 -54.588988) (xy 288.619464 -54.605283)
			(xy 288.670261 -54.629289) (xy 288.716988 -54.660486) (xy 288.758632 -54.698201) (xy 288.794294 -54.741616)
			(xy 288.809176 -54.765448) (xy 288.81451 -54.774338) (xy 288.831528 -54.78653) (xy 288.924746 -54.80685)
			(xy 288.94532 -54.802532) (xy 288.953956 -54.79669) (xy 288.97803 -54.780705) (xy 289.029958 -54.755359)
			(xy 289.085113 -54.73813) (xy 289.142234 -54.729409) (xy 289.171126 -54.728872) (xy 289.198377 -54.729354)
			(xy 289.252324 -54.737113) (xy 289.304617 -54.752471) (xy 289.354193 -54.775113) (xy 289.400043 -54.80458)
			(xy 289.441232 -54.840272) (xy 289.476923 -54.881462) (xy 289.50639 -54.927312) (xy 289.529032 -54.976888)
			(xy 289.544388 -55.029182) (xy 289.552147 -55.083129) (xy 289.552634 -55.11038) (xy 289.552172 -55.137751)
			(xy 289.544356 -55.19193) (xy 289.528867 -55.244434) (xy 289.506024 -55.294181) (xy 289.476297 -55.340147)
			(xy 289.458654 -55.361078) (xy 289.4584 -55.361332) (xy 289.452836 -55.368434) (xy 289.446576 -55.385339)
			(xy 289.446208 -55.394352) (xy 289.446208 -55.461408) (xy 289.446559 -55.470425) (xy 289.452811 -55.487342)
			(xy 289.4584 -55.494428) (xy 289.458654 -55.494428) (xy 289.458654 -55.494682) (xy 289.476276 -55.51563)
			(xy 289.506003 -55.561595) (xy 289.528851 -55.611338) (xy 289.544349 -55.663838) (xy 289.55218 -55.718015)
			(xy 289.552182 -55.772755) (xy 289.544356 -55.826932) (xy 289.528861 -55.879433) (xy 289.506017 -55.929179)
			(xy 289.476294 -55.975146) (xy 289.458654 -55.996078) (xy 289.4584 -55.996332) (xy 289.452836 -56.003434)
			(xy 289.446576 -56.020339) (xy 289.446208 -56.029352) (xy 289.446208 -56.096408) (xy 289.446559 -56.105425)
			(xy 289.452811 -56.122342) (xy 289.4584 -56.129428) (xy 289.458654 -56.129428) (xy 289.458654 -56.129682)
			(xy 289.476291 -56.150616) (xy 289.506005 -56.196588) (xy 289.528842 -56.246334) (xy 289.544333 -56.298835)
			(xy 289.552161 -56.353011) (xy 289.552634 -56.38038) (xy 289.552148 -56.407631) (xy 289.544392 -56.461579)
			(xy 289.529037 -56.513874) (xy 289.506395 -56.563451) (xy 289.476929 -56.609301) (xy 289.441238 -56.650492)
			(xy 289.400047 -56.686183) (xy 289.354197 -56.715649) (xy 289.30462 -56.738291) (xy 289.252325 -56.753646)
			(xy 289.198377 -56.761402) (xy 289.143875 -56.761402) (xy 289.089927 -56.753646) (xy 289.037632 -56.738291)
			(xy 288.988055 -56.715649) (xy 288.942205 -56.686183) (xy 288.901014 -56.650492) (xy 288.865323 -56.609301)
			(xy 288.835857 -56.563451) (xy 288.813215 -56.513874) (xy 288.79786 -56.461579) (xy 288.790104 -56.407631)
			(xy 288.789618 -56.38038) (xy 288.790068 -56.353009) (xy 288.797889 -56.298829) (xy 288.813382 -56.246326)
			(xy 288.836227 -56.196579) (xy 288.865955 -56.150613) (xy 288.883598 -56.129682) (xy 288.883852 -56.129428)
			(xy 288.889439 -56.122342) (xy 288.895684 -56.105425) (xy 288.896044 -56.096408) (xy 288.896044 -56.029352)
			(xy 288.895674 -56.020336) (xy 288.889437 -56.003418) (xy 288.883852 -55.996332) (xy 288.883598 -55.996332)
			(xy 288.883598 -55.996078) (xy 288.865939 -55.975161) (xy 288.836217 -55.929189) (xy 288.813375 -55.87944)
			(xy 288.797881 -55.826936) (xy 288.790055 -55.772756) (xy 288.790057 -55.718014) (xy 288.797888 -55.663834)
			(xy 288.813385 -55.611331) (xy 288.836232 -55.561584) (xy 288.865957 -55.515615) (xy 288.883598 -55.494682)
			(xy 288.883852 -55.494428) (xy 288.889439 -55.487342) (xy 288.895684 -55.470425) (xy 288.896044 -55.461408)
			(xy 288.896044 -55.394352) (xy 288.895674 -55.385336) (xy 288.889437 -55.368418) (xy 288.883852 -55.361332)
			(xy 288.883598 -55.360824) (xy 288.872654 -55.348089) (xy 288.852813 -55.320998) (xy 288.843974 -55.306722)
			(xy 288.83864 -55.297832) (xy 288.821622 -55.28564) (xy 288.728404 -55.26532) (xy 288.70783 -55.269638)
			(xy 288.699194 -55.27548) (xy 288.675132 -55.291483) (xy 288.6232 -55.316825) (xy 288.568041 -55.33405)
			(xy 288.510917 -55.342764) (xy 288.482024 -55.343298) (xy 288.454769 -55.342857) (xy 288.400814 -55.335102)
			(xy 288.348512 -55.319748) (xy 288.298928 -55.297106) (xy 288.25307 -55.267638) (xy 288.211874 -55.231943)
			(xy 288.176176 -55.190749) (xy 288.146705 -55.144893) (xy 288.12406 -55.09531) (xy 288.108703 -55.043009)
			(xy 288.100945 -54.989055) (xy 278.964961 -54.989055) (xy 278.958281 -54.999449) (xy 278.92259 -55.04064)
			(xy 278.881399 -55.076331) (xy 278.835549 -55.105797) (xy 278.785972 -55.128439) (xy 278.733677 -55.143794)
			(xy 278.679729 -55.15155) (xy 278.625227 -55.15155) (xy 278.571279 -55.143794) (xy 278.518984 -55.128439)
			(xy 278.469407 -55.105797) (xy 278.423557 -55.076331) (xy 278.382366 -55.04064) (xy 278.346675 -54.999449)
			(xy 278.317209 -54.953599) (xy 278.294567 -54.904022) (xy 278.279212 -54.851727) (xy 278.271456 -54.797779)
			(xy 278.27097 -54.770528) (xy 275.139049 -54.770528) (xy 275.139404 -54.791102) (xy 275.138918 -54.818353)
			(xy 275.131162 -54.872301) (xy 275.115807 -54.924596) (xy 275.093165 -54.974173) (xy 275.063699 -55.020023)
			(xy 275.028008 -55.061214) (xy 274.986817 -55.096905) (xy 274.940967 -55.126371) (xy 274.89139 -55.149013)
			(xy 274.839095 -55.164368) (xy 274.785147 -55.172124) (xy 274.730645 -55.172124) (xy 274.676697 -55.164368)
			(xy 274.624402 -55.149013) (xy 274.574825 -55.126371) (xy 274.528975 -55.096905) (xy 274.487784 -55.061214)
			(xy 274.452093 -55.020023) (xy 274.422627 -54.974173) (xy 274.399985 -54.924596) (xy 274.38463 -54.872301)
			(xy 274.376874 -54.818353) (xy 274.376388 -54.791102) (xy 272.479642 -54.791102) (xy 272.475554 -54.817889)
			(xy 272.458214 -54.873335) (xy 272.432697 -54.925525) (xy 272.399587 -54.97326) (xy 272.359645 -55.015446)
			(xy 272.337022 -55.033672) (xy 272.331434 -55.03799) (xy 272.325338 -55.045864) (xy 272.309336 -55.077868)
			(xy 272.309844 -55.090822) (xy 272.327116 -55.59044) (xy 272.331699 -55.722266) (xy 284.033974 -55.722266)
			(xy 284.038045 -55.666644) (xy 284.050171 -55.612207) (xy 284.070094 -55.560116) (xy 284.09739 -55.511481)
			(xy 284.131476 -55.467338) (xy 284.171625 -55.428629) (xy 284.216983 -55.396178) (xy 284.266583 -55.370677)
			(xy 284.319367 -55.35267) (xy 284.37421 -55.34254) (xy 284.429944 -55.340503) (xy 284.485381 -55.346603)
			(xy 284.539338 -55.360709) (xy 284.590667 -55.382521) (xy 284.638273 -55.411575) (xy 284.649424 -55.420855)
			(xy 286.424545 -55.420855) (xy 286.424545 -55.366345) (xy 286.432303 -55.312391) (xy 286.44766 -55.26009)
			(xy 286.470305 -55.210507) (xy 286.499776 -55.164651) (xy 286.535474 -55.123457) (xy 286.57667 -55.087762)
			(xy 286.622528 -55.058294) (xy 286.672112 -55.035652) (xy 286.724414 -55.020298) (xy 286.778369 -55.012543)
			(xy 286.805624 -55.012082) (xy 286.831938 -55.012539) (xy 286.884067 -55.019777) (xy 286.93471 -55.034098)
			(xy 286.982908 -55.055233) (xy 287.027752 -55.08278) (xy 287.068391 -55.11622) (xy 287.086548 -55.135272)
			(xy 287.094053 -55.142693) (xy 287.113346 -55.151207) (xy 287.123886 -55.151782) (xy 287.198562 -55.151782)
			(xy 287.209112 -55.151251) (xy 287.228407 -55.142718) (xy 287.2359 -55.135272) (xy 287.254057 -55.116218)
			(xy 287.294687 -55.082762) (xy 287.339527 -55.055203) (xy 287.387728 -55.034065) (xy 287.438375 -55.019747)
			(xy 287.490508 -55.012521) (xy 287.516824 -55.012082) (xy 287.544073 -55.01259) (xy 287.598017 -55.020349)
			(xy 287.650307 -55.035706) (xy 287.69988 -55.058348) (xy 287.745726 -55.087814) (xy 287.786913 -55.123504)
			(xy 287.822601 -55.164693) (xy 287.852064 -55.210541) (xy 287.874703 -55.260115) (xy 287.890056 -55.312406)
			(xy 287.897812 -55.366351) (xy 287.897812 -55.420849) (xy 287.890056 -55.474794) (xy 287.874703 -55.527085)
			(xy 287.852064 -55.576659) (xy 287.822601 -55.622507) (xy 287.786913 -55.663696) (xy 287.745726 -55.699386)
			(xy 287.69988 -55.728852) (xy 287.650307 -55.751494) (xy 287.598017 -55.766851) (xy 287.544073 -55.77461)
			(xy 287.516824 -55.775098) (xy 287.490511 -55.774615) (xy 287.438383 -55.767384) (xy 287.38774 -55.753068)
			(xy 287.339541 -55.731938) (xy 287.294697 -55.704395) (xy 287.254057 -55.670958) (xy 287.2359 -55.651908)
			(xy 287.228379 -55.644506) (xy 287.209099 -55.635981) (xy 287.198562 -55.635398) (xy 287.123886 -55.635398)
			(xy 287.113334 -55.635907) (xy 287.094039 -55.644456) (xy 287.086548 -55.651908) (xy 287.068412 -55.670983)
			(xy 287.027778 -55.704438) (xy 286.982934 -55.731995) (xy 286.934729 -55.75313) (xy 286.884078 -55.767443)
			(xy 286.831941 -55.774662) (xy 286.805624 -55.775098) (xy 286.778369 -55.774657) (xy 286.724414 -55.766902)
			(xy 286.672112 -55.751548) (xy 286.622528 -55.728906) (xy 286.57667 -55.699438) (xy 286.535474 -55.663743)
			(xy 286.499776 -55.622549) (xy 286.470305 -55.576693) (xy 286.44766 -55.52711) (xy 286.432303 -55.474809)
			(xy 286.424545 -55.420855) (xy 284.649424 -55.420855) (xy 284.681141 -55.44725) (xy 284.718358 -55.488787)
			(xy 284.749131 -55.5353) (xy 284.772803 -55.585797) (xy 284.788871 -55.639204) (xy 284.796991 -55.69438)
			(xy 284.7975 -55.722266) (xy 284.796991 -55.750152) (xy 284.788871 -55.805328) (xy 284.772803 -55.858735)
			(xy 284.749131 -55.909232) (xy 284.718358 -55.955745) (xy 284.681141 -55.997282) (xy 284.638273 -56.032957)
			(xy 284.590667 -56.062011) (xy 284.539338 -56.083823) (xy 284.485381 -56.097929) (xy 284.429944 -56.104029)
			(xy 284.37421 -56.101992) (xy 284.319367 -56.091862) (xy 284.266583 -56.073855) (xy 284.216983 -56.048354)
			(xy 284.171625 -56.015903) (xy 284.131476 -55.977194) (xy 284.09739 -55.933051) (xy 284.070094 -55.884416)
			(xy 284.050171 -55.832325) (xy 284.038045 -55.777888) (xy 284.033974 -55.722266) (xy 272.331699 -55.722266)
			(xy 272.335752 -55.838852) (xy 272.341594 -56.007254) (xy 272.342102 -56.019192) (xy 272.34261 -56.035448)
			(xy 272.35531 -56.397652) (xy 272.358104 -56.474106) (xy 272.358104 -56.474614) (xy 272.36039 -56.528716)
			(xy 272.360898 -56.532526) (xy 272.362422 -56.53786) (xy 272.367756 -56.550306) (xy 272.37055 -56.555132)
			(xy 272.375122 -56.559958) (xy 272.376138 -56.560974) (xy 272.395984 -56.58225) (xy 272.429647 -56.629703)
			(xy 272.455715 -56.681716) (xy 272.473583 -56.737085) (xy 272.482837 -56.794525) (xy 272.48358 -56.82361)
			(xy 272.48358 -56.827928) (xy 272.483074 -56.85393) (xy 272.475876 -56.905437) (xy 272.46174 -56.955485)
			(xy 272.441022 -57.002934) (xy 279.763474 -57.002934) (xy 279.764 -56.974844) (xy 279.772222 -56.919268)
			(xy 279.788508 -56.8655) (xy 279.812505 -56.814703) (xy 279.843695 -56.767976) (xy 279.881403 -56.726329)
			(xy 279.924812 -56.690666) (xy 279.94864 -56.675782) (xy 279.95753 -56.670448) (xy 279.969722 -56.65343)
			(xy 279.990042 -56.560212) (xy 279.985724 -56.539638) (xy 279.979882 -56.531002) (xy 279.963879 -56.50694)
			(xy 279.938537 -56.455008) (xy 279.921313 -56.399849) (xy 279.912598 -56.342725) (xy 279.912064 -56.313832)
			(xy 279.912585 -56.286581) (xy 279.920337 -56.232634) (xy 279.935687 -56.180339) (xy 279.958324 -56.130761)
			(xy 279.987786 -56.084909) (xy 280.023474 -56.043716) (xy 280.064661 -56.008022) (xy 280.110508 -55.978553)
			(xy 280.160082 -55.955908) (xy 280.212375 -55.94055) (xy 280.266321 -55.932789) (xy 280.293572 -55.932324)
			(xy 280.320942 -55.932801) (xy 280.375121 -55.940615) (xy 280.427624 -55.956101) (xy 280.477371 -55.978941)
			(xy 280.523338 -56.008664) (xy 280.54427 -56.026304) (xy 280.544524 -56.026558) (xy 280.551595 -56.032168)
			(xy 280.568524 -56.038399) (xy 280.577544 -56.03875) (xy 280.6446 -56.03875) (xy 280.653618 -56.038404)
			(xy 280.670536 -56.03215) (xy 280.67762 -56.026558) (xy 280.67762 -56.026304) (xy 280.677874 -56.026304)
			(xy 280.698807 -56.008663) (xy 280.744775 -55.978939) (xy 280.794521 -55.956093) (xy 280.847023 -55.940597)
			(xy 280.901201 -55.932768) (xy 280.955943 -55.932768) (xy 281.010121 -55.940597) (xy 281.062623 -55.956093)
			(xy 281.112369 -55.978939) (xy 281.158337 -56.008663) (xy 281.17927 -56.026304) (xy 281.179524 -56.026558)
			(xy 281.186595 -56.032168) (xy 281.203524 -56.038399) (xy 281.212544 -56.03875) (xy 281.2796 -56.03875)
			(xy 281.288618 -56.038404) (xy 281.305536 -56.03215) (xy 281.31262 -56.026558) (xy 281.31262 -56.026304)
			(xy 281.312874 -56.026304) (xy 281.333806 -56.008664) (xy 281.379778 -55.978952) (xy 281.429526 -55.956116)
			(xy 281.482027 -55.940626) (xy 281.536203 -55.932798) (xy 281.563572 -55.932324) (xy 281.590828 -55.932721)
			(xy 281.644787 -55.940475) (xy 281.697093 -55.95583) (xy 281.746681 -55.978473) (xy 281.792541 -56.007943)
			(xy 281.833741 -56.04364) (xy 281.86944 -56.084836) (xy 281.898913 -56.130695) (xy 281.92156 -56.180281)
			(xy 281.936919 -56.232586) (xy 281.944677 -56.286544) (xy 281.944677 -56.297068) (xy 282.286454 -56.297068)
			(xy 282.290525 -56.241446) (xy 282.302651 -56.187009) (xy 282.322574 -56.134918) (xy 282.34987 -56.086283)
			(xy 282.383956 -56.04214) (xy 282.424105 -56.003431) (xy 282.469463 -55.97098) (xy 282.519063 -55.945479)
			(xy 282.571847 -55.927472) (xy 282.62669 -55.917342) (xy 282.682424 -55.915305) (xy 282.737861 -55.921405)
			(xy 282.791818 -55.935511) (xy 282.843147 -55.957323) (xy 282.890753 -55.986377) (xy 282.933621 -56.022052)
			(xy 282.970838 -56.063589) (xy 283.001611 -56.110102) (xy 283.025283 -56.160599) (xy 283.041351 -56.214006)
			(xy 283.049471 -56.269182) (xy 283.04998 -56.297068) (xy 283.049471 -56.324954) (xy 283.041351 -56.38013)
			(xy 283.025283 -56.433537) (xy 283.001611 -56.484034) (xy 282.970838 -56.530547) (xy 282.933621 -56.572084)
			(xy 282.890753 -56.607759) (xy 282.843147 -56.636813) (xy 282.791818 -56.658625) (xy 282.737861 -56.672731)
			(xy 282.682424 -56.678831) (xy 282.62669 -56.676794) (xy 282.571847 -56.666664) (xy 282.519063 -56.648657)
			(xy 282.469463 -56.623156) (xy 282.424105 -56.590705) (xy 282.383956 -56.551996) (xy 282.34987 -56.507853)
			(xy 282.322574 -56.459218) (xy 282.302651 -56.407127) (xy 282.290525 -56.35269) (xy 282.286454 -56.297068)
			(xy 281.944677 -56.297068) (xy 281.944677 -56.341056) (xy 281.936919 -56.395014) (xy 281.92156 -56.447319)
			(xy 281.898913 -56.496905) (xy 281.86944 -56.542764) (xy 281.833741 -56.58396) (xy 281.792541 -56.619657)
			(xy 281.746681 -56.649127) (xy 281.697093 -56.67177) (xy 281.644787 -56.687125) (xy 281.590828 -56.694879)
			(xy 281.563572 -56.69534) (xy 281.5362 -56.694905) (xy 281.482019 -56.687082) (xy 281.429515 -56.671586)
			(xy 281.379769 -56.648737) (xy 281.333804 -56.619005) (xy 281.312874 -56.60136) (xy 281.31262 -56.601106)
			(xy 281.305531 -56.595522) (xy 281.288616 -56.589274) (xy 281.2796 -56.588914) (xy 281.212544 -56.588914)
			(xy 281.203529 -56.589289) (xy 281.186612 -56.595524) (xy 281.179524 -56.601106) (xy 281.179524 -56.60136)
			(xy 281.17927 -56.60136) (xy 281.158337 -56.619001) (xy 281.112369 -56.648725) (xy 281.062623 -56.671571)
			(xy 281.010121 -56.687067) (xy 280.955943 -56.694896) (xy 280.901201 -56.694896) (xy 280.847023 -56.687067)
			(xy 280.794521 -56.671571) (xy 280.744775 -56.648725) (xy 280.698807 -56.619001) (xy 280.677874 -56.60136)
			(xy 280.67762 -56.601106) (xy 280.670531 -56.595522) (xy 280.653616 -56.589274) (xy 280.6446 -56.588914)
			(xy 280.577544 -56.588914) (xy 280.568529 -56.589289) (xy 280.551612 -56.595524) (xy 280.544524 -56.601106)
			(xy 280.544016 -56.60136) (xy 280.531285 -56.612308) (xy 280.504191 -56.632147) (xy 280.489914 -56.640984)
			(xy 280.481024 -56.646318) (xy 280.468832 -56.663336) (xy 280.448512 -56.756554) (xy 280.45283 -56.777128)
			(xy 280.458672 -56.785764) (xy 280.474656 -56.809838) (xy 280.500003 -56.861766) (xy 280.517233 -56.91692)
			(xy 280.525953 -56.974042) (xy 280.52649 -57.002934) (xy 280.526004 -57.030185) (xy 280.518248 -57.084133)
			(xy 280.502893 -57.136428) (xy 280.480251 -57.186005) (xy 280.450785 -57.231855) (xy 280.415094 -57.273046)
			(xy 280.373903 -57.308737) (xy 280.328053 -57.338203) (xy 280.278476 -57.360845) (xy 280.226181 -57.3762)
			(xy 280.172233 -57.383956) (xy 280.117731 -57.383956) (xy 280.063783 -57.3762) (xy 280.011488 -57.360845)
			(xy 279.961911 -57.338203) (xy 279.916061 -57.308737) (xy 279.87487 -57.273046) (xy 279.839179 -57.231855)
			(xy 279.809713 -57.186005) (xy 279.787071 -57.136428) (xy 279.771716 -57.084133) (xy 279.76396 -57.030185)
			(xy 279.763474 -57.002934) (xy 272.441022 -57.002934) (xy 272.440929 -57.003147) (xy 272.41383 -57.047535)
			(xy 272.397728 -57.067958) (xy 272.392394 -57.074562) (xy 272.379948 -57.107582) (xy 272.380456 -57.117996)
			(xy 272.382996 -57.185052) (xy 272.383213 -57.188811) (xy 272.384612 -57.196208) (xy 272.38579 -57.199784)
			(xy 272.389346 -57.209944) (xy 272.395188 -57.217056) (xy 272.395442 -57.21731) (xy 272.400014 -57.222898)
			(xy 272.490438 -57.33288) (xy 272.496055 -57.340389) (xy 272.501941 -57.358177) (xy 272.501035 -57.376891)
			(xy 272.493459 -57.394027) (xy 272.487136 -57.400952) (xy 272.480532 -57.407556) (xy 272.481548 -57.421526)
			(xy 272.481548 -57.42305) (xy 272.48358 -57.46115) (xy 272.48358 -57.470548) (xy 272.48297 -57.48528)
			(xy 288.805872 -57.48528) (xy 288.809943 -57.429658) (xy 288.822069 -57.375221) (xy 288.841992 -57.32313)
			(xy 288.869288 -57.274495) (xy 288.903374 -57.230352) (xy 288.943523 -57.191643) (xy 288.988881 -57.159192)
			(xy 289.038481 -57.133691) (xy 289.091265 -57.115684) (xy 289.146108 -57.105554) (xy 289.201842 -57.103517)
			(xy 289.257279 -57.109617) (xy 289.311236 -57.123723) (xy 289.362565 -57.145535) (xy 289.410171 -57.174589)
			(xy 289.453039 -57.210264) (xy 289.490256 -57.251801) (xy 289.521029 -57.298314) (xy 289.544701 -57.348811)
			(xy 289.560769 -57.402218) (xy 289.568889 -57.457394) (xy 289.569398 -57.48528) (xy 289.568889 -57.513166)
			(xy 289.560769 -57.568342) (xy 289.544701 -57.621749) (xy 289.521029 -57.672246) (xy 289.490256 -57.718759)
			(xy 289.453039 -57.760296) (xy 289.410171 -57.795971) (xy 289.362565 -57.825025) (xy 289.311236 -57.846837)
			(xy 289.257279 -57.860943) (xy 289.201842 -57.867043) (xy 289.146108 -57.865006) (xy 289.091265 -57.854876)
			(xy 289.038481 -57.836869) (xy 288.988881 -57.811368) (xy 288.943523 -57.778917) (xy 288.903374 -57.740208)
			(xy 288.869288 -57.696065) (xy 288.841992 -57.64743) (xy 288.822069 -57.595339) (xy 288.809943 -57.540902)
			(xy 288.805872 -57.48528) (xy 272.48297 -57.48528) (xy 272.482424 -57.498471) (xy 272.472954 -57.553547)
			(xy 272.455557 -57.606655) (xy 272.430604 -57.65666) (xy 272.415 -57.679844) (xy 272.413476 -57.681876)
			(xy 272.410936 -57.686194) (xy 272.40611 -57.692798) (xy 272.40357 -57.701434) (xy 272.40103 -57.709816)
			(xy 272.4023 -57.742582) (xy 272.4023 -57.74309) (xy 272.405094 -57.820814) (xy 272.405856 -57.842658)
			(xy 272.40611 -57.850024) (xy 272.415508 -57.87898) (xy 272.419826 -57.885076) (xy 272.421858 -57.888124)
			(xy 272.422366 -57.888886) (xy 272.424144 -57.891426) (xy 272.42643 -57.894982) (xy 272.439775 -57.91739)
			(xy 272.460931 -57.965061) (xy 272.475405 -58.015166) (xy 272.482927 -58.066775) (xy 272.48358 -58.092848)
			(xy 272.48358 -58.096658) (xy 272.483173 -58.121562) (xy 272.476689 -58.170946) (xy 272.463837 -58.219067)
			(xy 272.444836 -58.265109) (xy 272.43278 -58.286904) (xy 272.429478 -58.292492) (xy 272.422366 -58.317892)
			(xy 272.42262 -58.32602) (xy 272.425922 -58.420508) (xy 272.429478 -58.52287) (xy 272.431764 -58.535824)
			(xy 272.433288 -58.541158) (xy 272.435828 -58.546238) (xy 272.436336 -58.547) (xy 272.43659 -58.547508)
			(xy 272.437098 -58.54827) (xy 272.451248 -58.575563) (xy 272.471616 -58.633566) (xy 272.479813 -58.679334)
			(xy 280.195274 -58.679334) (xy 280.195706 -58.653019) (xy 280.202949 -58.600889) (xy 280.217276 -58.550246)
			(xy 280.238415 -58.502047) (xy 280.265967 -58.457205) (xy 280.29941 -58.416566) (xy 280.318464 -58.39841)
			(xy 280.325858 -58.390882) (xy 280.334388 -58.371607) (xy 280.334974 -58.361072) (xy 280.334974 -58.286396)
			(xy 280.334468 -58.275843) (xy 280.325917 -58.256548) (xy 280.318464 -58.249058) (xy 280.299388 -58.230923)
			(xy 280.265934 -58.190288) (xy 280.238379 -58.145443) (xy 280.217244 -58.097239) (xy 280.202931 -58.046588)
			(xy 280.19571 -57.994451) (xy 280.195274 -57.968134) (xy 280.19576 -57.940883) (xy 280.203516 -57.886935)
			(xy 280.218871 -57.83464) (xy 280.241513 -57.785063) (xy 280.270979 -57.739213) (xy 280.30667 -57.698022)
			(xy 280.347861 -57.662331) (xy 280.393711 -57.632865) (xy 280.443288 -57.610223) (xy 280.495583 -57.594868)
			(xy 280.549531 -57.587112) (xy 280.604033 -57.587112) (xy 280.657981 -57.594868) (xy 280.710276 -57.610223)
			(xy 280.759853 -57.632865) (xy 280.805703 -57.662331) (xy 280.846894 -57.698022) (xy 280.882585 -57.739213)
			(xy 280.912051 -57.785063) (xy 280.934693 -57.83464) (xy 280.950048 -57.886935) (xy 280.957804 -57.940883)
			(xy 280.95829 -57.968134) (xy 280.957848 -57.994449) (xy 280.950609 -58.046579) (xy 280.943341 -58.072274)
			(xy 284.193486 -58.072274) (xy 284.197557 -58.016652) (xy 284.209683 -57.962215) (xy 284.229606 -57.910124)
			(xy 284.256902 -57.861489) (xy 284.290988 -57.817346) (xy 284.331137 -57.778637) (xy 284.376495 -57.746186)
			(xy 284.426095 -57.720685) (xy 284.478879 -57.702678) (xy 284.533722 -57.692548) (xy 284.589456 -57.690511)
			(xy 284.644893 -57.696611) (xy 284.69885 -57.710717) (xy 284.750179 -57.732529) (xy 284.797785 -57.761583)
			(xy 284.840653 -57.797258) (xy 284.87787 -57.838795) (xy 284.908643 -57.885308) (xy 284.932315 -57.935805)
			(xy 284.948383 -57.989212) (xy 284.956503 -58.044388) (xy 284.957012 -58.072274) (xy 284.956942 -58.076084)
			(xy 289.557966 -58.076084) (xy 289.562037 -58.020462) (xy 289.574163 -57.966025) (xy 289.594086 -57.913934)
			(xy 289.621382 -57.865299) (xy 289.655468 -57.821156) (xy 289.695617 -57.782447) (xy 289.740975 -57.749996)
			(xy 289.790575 -57.724495) (xy 289.843359 -57.706488) (xy 289.898202 -57.696358) (xy 289.953936 -57.694321)
			(xy 290.009373 -57.700421) (xy 290.06333 -57.714527) (xy 290.114659 -57.736339) (xy 290.162265 -57.765393)
			(xy 290.205133 -57.801068) (xy 290.24235 -57.842605) (xy 290.258686 -57.867296) (xy 291.84295 -57.867296)
			(xy 291.847021 -57.811674) (xy 291.859147 -57.757237) (xy 291.87907 -57.705146) (xy 291.906366 -57.656511)
			(xy 291.940452 -57.612368) (xy 291.980601 -57.573659) (xy 292.025959 -57.541208) (xy 292.075559 -57.515707)
			(xy 292.128343 -57.4977) (xy 292.183186 -57.48757) (xy 292.23892 -57.485533) (xy 292.294357 -57.491633)
			(xy 292.348314 -57.505739) (xy 292.399643 -57.527551) (xy 292.447249 -57.556605) (xy 292.490117 -57.59228)
			(xy 292.527334 -57.633817) (xy 292.558107 -57.68033) (xy 292.581779 -57.730827) (xy 292.597847 -57.784234)
			(xy 292.605967 -57.83941) (xy 292.606476 -57.867296) (xy 292.605967 -57.895182) (xy 292.597847 -57.950358)
			(xy 292.581779 -58.003765) (xy 292.558107 -58.054262) (xy 292.527334 -58.100775) (xy 292.490117 -58.142312)
			(xy 292.447249 -58.177987) (xy 292.399643 -58.207041) (xy 292.348314 -58.228853) (xy 292.294357 -58.242959)
			(xy 292.23892 -58.249059) (xy 292.183186 -58.247022) (xy 292.128343 -58.236892) (xy 292.075559 -58.218885)
			(xy 292.025959 -58.193384) (xy 291.980601 -58.160933) (xy 291.940452 -58.122224) (xy 291.906366 -58.078081)
			(xy 291.87907 -58.029446) (xy 291.859147 -57.977355) (xy 291.847021 -57.922918) (xy 291.84295 -57.867296)
			(xy 290.258686 -57.867296) (xy 290.273123 -57.889118) (xy 290.296795 -57.939615) (xy 290.312863 -57.993022)
			(xy 290.320983 -58.048198) (xy 290.321492 -58.076084) (xy 290.320983 -58.10397) (xy 290.312863 -58.159146)
			(xy 290.296795 -58.212553) (xy 290.273123 -58.26305) (xy 290.24235 -58.309563) (xy 290.205133 -58.3511)
			(xy 290.162265 -58.386775) (xy 290.114659 -58.415829) (xy 290.06333 -58.437641) (xy 290.009373 -58.451747)
			(xy 289.953936 -58.457847) (xy 289.898202 -58.45581) (xy 289.843359 -58.44568) (xy 289.790575 -58.427673)
			(xy 289.740975 -58.402172) (xy 289.695617 -58.369721) (xy 289.655468 -58.331012) (xy 289.621382 -58.286869)
			(xy 289.594086 -58.238234) (xy 289.574163 -58.186143) (xy 289.562037 -58.131706) (xy 289.557966 -58.076084)
			(xy 284.956942 -58.076084) (xy 284.956503 -58.10016) (xy 284.948383 -58.155336) (xy 284.932315 -58.208743)
			(xy 284.908643 -58.25924) (xy 284.87787 -58.305753) (xy 284.840653 -58.34729) (xy 284.797785 -58.382965)
			(xy 284.750179 -58.412019) (xy 284.69885 -58.433831) (xy 284.644893 -58.447937) (xy 284.589456 -58.454037)
			(xy 284.533722 -58.452) (xy 284.478879 -58.44187) (xy 284.426095 -58.423863) (xy 284.376495 -58.398362)
			(xy 284.331137 -58.365911) (xy 284.290988 -58.327202) (xy 284.256902 -58.283059) (xy 284.229606 -58.234424)
			(xy 284.209683 -58.182333) (xy 284.197557 -58.127896) (xy 284.193486 -58.072274) (xy 280.943341 -58.072274)
			(xy 280.936285 -58.097222) (xy 280.915148 -58.145421) (xy 280.887597 -58.190264) (xy 280.854154 -58.230902)
			(xy 280.8351 -58.249058) (xy 280.827715 -58.256593) (xy 280.819181 -58.275863) (xy 280.81859 -58.286396)
			(xy 280.81859 -58.361072) (xy 280.819124 -58.371621) (xy 280.827656 -58.390916) (xy 280.8351 -58.39841)
			(xy 280.854153 -58.416568) (xy 280.887611 -58.457197) (xy 280.91517 -58.502037) (xy 280.936309 -58.550237)
			(xy 280.939415 -58.561224) (xy 290.76218 -58.561224) (xy 290.766251 -58.505602) (xy 290.778377 -58.451165)
			(xy 290.7983 -58.399074) (xy 290.825596 -58.350439) (xy 290.859682 -58.306296) (xy 290.899831 -58.267587)
			(xy 290.945189 -58.235136) (xy 290.994789 -58.209635) (xy 291.047573 -58.191628) (xy 291.102416 -58.181498)
			(xy 291.15815 -58.179461) (xy 291.213587 -58.185561) (xy 291.267544 -58.199667) (xy 291.318873 -58.221479)
			(xy 291.366479 -58.250533) (xy 291.409347 -58.286208) (xy 291.446564 -58.327745) (xy 291.477337 -58.374258)
			(xy 291.501009 -58.424755) (xy 291.517077 -58.478162) (xy 291.525197 -58.533338) (xy 291.525706 -58.561224)
			(xy 291.525197 -58.58911) (xy 291.517077 -58.644286) (xy 291.501009 -58.697693) (xy 291.477337 -58.74819)
			(xy 291.446564 -58.794703) (xy 291.409347 -58.83624) (xy 291.366479 -58.871915) (xy 291.318873 -58.900969)
			(xy 291.267544 -58.922781) (xy 291.213587 -58.936887) (xy 291.15815 -58.942987) (xy 291.102416 -58.94095)
			(xy 291.047573 -58.93082) (xy 290.994789 -58.912813) (xy 290.945189 -58.887312) (xy 290.899831 -58.854861)
			(xy 290.859682 -58.816152) (xy 290.825596 -58.772009) (xy 290.7983 -58.723374) (xy 290.778377 -58.671283)
			(xy 290.766251 -58.616846) (xy 290.76218 -58.561224) (xy 280.939415 -58.561224) (xy 280.950626 -58.600884)
			(xy 280.957851 -58.653018) (xy 280.95829 -58.679334) (xy 280.957804 -58.706585) (xy 280.950048 -58.760533)
			(xy 280.934693 -58.812828) (xy 280.912051 -58.862405) (xy 280.882585 -58.908255) (xy 280.846894 -58.949446)
			(xy 280.805703 -58.985137) (xy 280.759853 -59.014603) (xy 280.710276 -59.037245) (xy 280.657981 -59.0526)
			(xy 280.604033 -59.060356) (xy 280.549531 -59.060356) (xy 280.495583 -59.0526) (xy 280.443288 -59.037245)
			(xy 280.393711 -59.014603) (xy 280.347861 -58.985137) (xy 280.30667 -58.949446) (xy 280.270979 -58.908255)
			(xy 280.241513 -58.862405) (xy 280.218871 -58.812828) (xy 280.203516 -58.760533) (xy 280.19576 -58.706585)
			(xy 280.195274 -58.679334) (xy 272.479813 -58.679334) (xy 272.482453 -58.694077) (xy 272.48358 -58.7248)
			(xy 272.48358 -58.732674) (xy 272.483058 -58.759709) (xy 272.475312 -58.813223) (xy 272.460072 -58.865103)
			(xy 272.44929 -58.8899) (xy 272.449036 -58.890408) (xy 272.447766 -58.893202) (xy 272.445988 -58.89879)
			(xy 272.44294 -58.90768) (xy 272.452243 -59.174634) (xy 289.293044 -59.174634) (xy 289.297115 -59.119012)
			(xy 289.309241 -59.064575) (xy 289.329164 -59.012484) (xy 289.35646 -58.963849) (xy 289.390546 -58.919706)
			(xy 289.430695 -58.880997) (xy 289.476053 -58.848546) (xy 289.525653 -58.823045) (xy 289.578437 -58.805038)
			(xy 289.63328 -58.794908) (xy 289.689014 -58.792871) (xy 289.744451 -58.798971) (xy 289.798408 -58.813077)
			(xy 289.849737 -58.834889) (xy 289.897343 -58.863943) (xy 289.940211 -58.899618) (xy 289.977428 -58.941155)
			(xy 290.008201 -58.987668) (xy 290.031873 -59.038165) (xy 290.047941 -59.091572) (xy 290.056061 -59.146748)
			(xy 290.05657 -59.174634) (xy 290.056061 -59.20252) (xy 290.047941 -59.257696) (xy 290.031873 -59.311103)
			(xy 290.008201 -59.3616) (xy 289.977428 -59.408113) (xy 289.940211 -59.44965) (xy 289.897343 -59.485325)
			(xy 289.849737 -59.514379) (xy 289.798408 -59.536191) (xy 289.744451 -59.550297) (xy 289.689014 -59.556397)
			(xy 289.63328 -59.55436) (xy 289.578437 -59.54423) (xy 289.525653 -59.526223) (xy 289.476053 -59.500722)
			(xy 289.430695 -59.468271) (xy 289.390546 -59.429562) (xy 289.35646 -59.385419) (xy 289.329164 -59.336784)
			(xy 289.309241 -59.284693) (xy 289.297115 -59.230256) (xy 289.293044 -59.174634) (xy 272.452243 -59.174634)
			(xy 272.468848 -59.651138) (xy 272.481711 -60.019254) (xy 280.335661 -60.019254) (xy 280.335661 -59.964746)
			(xy 280.343419 -59.910793) (xy 280.358777 -59.858493) (xy 280.381422 -59.808911) (xy 280.410892 -59.763057)
			(xy 280.446589 -59.721864) (xy 280.487786 -59.686171) (xy 280.533643 -59.656704) (xy 280.583227 -59.634064)
			(xy 280.635528 -59.618712) (xy 280.689482 -59.610959) (xy 280.716736 -59.610498) (xy 280.744107 -59.610943)
			(xy 280.798287 -59.618766) (xy 280.85079 -59.63426) (xy 280.900537 -59.657107) (xy 280.946503 -59.686835)
			(xy 280.967434 -59.704478) (xy 280.967688 -59.704732) (xy 280.974771 -59.710323) (xy 280.991691 -59.716566)
			(xy 281.000708 -59.716924) (xy 281.067764 -59.716924) (xy 281.076778 -59.716545) (xy 281.093695 -59.710312)
			(xy 281.100784 -59.704732) (xy 281.100784 -59.704478) (xy 281.101038 -59.704478) (xy 281.121971 -59.686837)
			(xy 281.167939 -59.657113) (xy 281.217685 -59.634267) (xy 281.270187 -59.618771) (xy 281.324365 -59.610942)
			(xy 281.379107 -59.610942) (xy 281.433285 -59.618771) (xy 281.485787 -59.634267) (xy 281.535533 -59.657113)
			(xy 281.581501 -59.686837) (xy 281.602434 -59.704478) (xy 281.602688 -59.704732) (xy 281.609771 -59.710323)
			(xy 281.626691 -59.716566) (xy 281.635708 -59.716924) (xy 281.702764 -59.716924) (xy 281.711778 -59.716545)
			(xy 281.728695 -59.710312) (xy 281.735784 -59.704732) (xy 281.735784 -59.704478) (xy 281.736038 -59.704478)
			(xy 281.75698 -59.686851) (xy 281.80295 -59.657138) (xy 281.852695 -59.6343) (xy 281.905194 -59.618806)
			(xy 281.959368 -59.610974) (xy 281.986736 -59.610498) (xy 282.013986 -59.610974) (xy 282.067931 -59.618735)
			(xy 282.120222 -59.634094) (xy 282.169795 -59.656737) (xy 282.215642 -59.686205) (xy 282.256829 -59.721897)
			(xy 282.292517 -59.763087) (xy 282.32198 -59.808936) (xy 282.344619 -59.858512) (xy 282.359973 -59.910805)
			(xy 282.367728 -59.96475) (xy 282.367728 -60.01925) (xy 282.359973 -60.073195) (xy 282.344619 -60.125488)
			(xy 282.32198 -60.175064) (xy 282.292517 -60.220913) (xy 282.256829 -60.262103) (xy 282.215642 -60.297795)
			(xy 282.169795 -60.327263) (xy 282.120222 -60.349906) (xy 282.067931 -60.365265) (xy 282.013986 -60.373026)
			(xy 281.986736 -60.373514) (xy 281.959367 -60.373023) (xy 281.905189 -60.365211) (xy 281.852686 -60.349727)
			(xy 281.802939 -60.326891) (xy 281.756971 -60.297172) (xy 281.736038 -60.279534) (xy 281.735784 -60.27928)
			(xy 281.728708 -60.273678) (xy 281.711783 -60.267441) (xy 281.702764 -60.267088) (xy 281.635708 -60.267088)
			(xy 281.626692 -60.267451) (xy 281.609775 -60.273695) (xy 281.602688 -60.27928) (xy 281.602434 -60.279534)
			(xy 281.581501 -60.297175) (xy 281.535533 -60.326899) (xy 281.485787 -60.349745) (xy 281.433285 -60.365241)
			(xy 281.379107 -60.37307) (xy 281.324365 -60.37307) (xy 281.270187 -60.365241) (xy 281.217685 -60.349745)
			(xy 281.167939 -60.326899) (xy 281.121971 -60.297175) (xy 281.101038 -60.279534) (xy 281.100784 -60.27928)
			(xy 281.093708 -60.273678) (xy 281.076783 -60.267441) (xy 281.067764 -60.267088) (xy 281.000708 -60.267088)
			(xy 280.991692 -60.267451) (xy 280.974775 -60.273695) (xy 280.967688 -60.27928) (xy 280.967688 -60.279534)
			(xy 280.967434 -60.279534) (xy 280.946504 -60.297176) (xy 280.90053 -60.326886) (xy 280.850782 -60.349721)
			(xy 280.798281 -60.365212) (xy 280.744105 -60.37304) (xy 280.716736 -60.373514) (xy 280.689482 -60.373041)
			(xy 280.635528 -60.365288) (xy 280.583227 -60.349936) (xy 280.533643 -60.327296) (xy 280.487786 -60.297829)
			(xy 280.446589 -60.262136) (xy 280.410892 -60.220943) (xy 280.381422 -60.175089) (xy 280.358777 -60.125507)
			(xy 280.343419 -60.073207) (xy 280.335661 -60.019254) (xy 272.481711 -60.019254) (xy 272.50317 -60.633356)
			(xy 291.996874 -60.633356) (xy 292.000945 -60.577734) (xy 292.013071 -60.523297) (xy 292.032994 -60.471206)
			(xy 292.06029 -60.422571) (xy 292.094376 -60.378428) (xy 292.134525 -60.339719) (xy 292.179883 -60.307268)
			(xy 292.229483 -60.281767) (xy 292.282267 -60.26376) (xy 292.33711 -60.25363) (xy 292.392844 -60.251593)
			(xy 292.448281 -60.257693) (xy 292.502238 -60.271799) (xy 292.553567 -60.293611) (xy 292.601173 -60.322665)
			(xy 292.644041 -60.35834) (xy 292.681258 -60.399877) (xy 292.712031 -60.44639) (xy 292.735703 -60.496887)
			(xy 292.751771 -60.550294) (xy 292.759891 -60.60547) (xy 292.7604 -60.633356) (xy 292.759891 -60.661242)
			(xy 292.751771 -60.716418) (xy 292.735703 -60.769825) (xy 292.712031 -60.820322) (xy 292.681258 -60.866835)
			(xy 292.644041 -60.908372) (xy 292.601173 -60.944047) (xy 292.553567 -60.973101) (xy 292.502238 -60.994913)
			(xy 292.448281 -61.009019) (xy 292.392844 -61.015119) (xy 292.33711 -61.013082) (xy 292.282267 -61.002952)
			(xy 292.229483 -60.984945) (xy 292.179883 -60.959444) (xy 292.134525 -60.926993) (xy 292.094376 -60.888284)
			(xy 292.06029 -60.844141) (xy 292.032994 -60.795506) (xy 292.013071 -60.743415) (xy 292.000945 -60.688978)
			(xy 291.996874 -60.633356) (xy 272.50317 -60.633356) (xy 272.533028 -61.487812) (xy 290.50437 -61.487812)
			(xy 290.508441 -61.43219) (xy 290.520567 -61.377753) (xy 290.54049 -61.325662) (xy 290.567786 -61.277027)
			(xy 290.601872 -61.232884) (xy 290.642021 -61.194175) (xy 290.687379 -61.161724) (xy 290.736979 -61.136223)
			(xy 290.789763 -61.118216) (xy 290.844606 -61.108086) (xy 290.90034 -61.106049) (xy 290.955777 -61.112149)
			(xy 291.009734 -61.126255) (xy 291.061063 -61.148067) (xy 291.108669 -61.177121) (xy 291.151537 -61.212796)
			(xy 291.188754 -61.254333) (xy 291.219527 -61.300846) (xy 291.243199 -61.351343) (xy 291.259267 -61.40475)
			(xy 291.267387 -61.459926) (xy 291.267896 -61.487812) (xy 291.267387 -61.515698) (xy 291.259267 -61.570874)
			(xy 291.243199 -61.624281) (xy 291.219527 -61.674778) (xy 291.188754 -61.721291) (xy 291.151537 -61.762828)
			(xy 291.108669 -61.798503) (xy 291.061063 -61.827557) (xy 291.009734 -61.849369) (xy 290.955777 -61.863475)
			(xy 290.90034 -61.869575) (xy 290.844606 -61.867538) (xy 290.789763 -61.857408) (xy 290.736979 -61.839401)
			(xy 290.687379 -61.8139) (xy 290.642021 -61.781449) (xy 290.601872 -61.74274) (xy 290.567786 -61.698597)
			(xy 290.54049 -61.649962) (xy 290.520567 -61.597871) (xy 290.508441 -61.543434) (xy 290.50437 -61.487812)
			(xy 272.533028 -61.487812) (xy 272.534634 -61.533786) (xy 272.555125 -62.121034) (xy 288.442144 -62.121034)
			(xy 288.446215 -62.065412) (xy 288.458341 -62.010975) (xy 288.478264 -61.958884) (xy 288.50556 -61.910249)
			(xy 288.539646 -61.866106) (xy 288.579795 -61.827397) (xy 288.625153 -61.794946) (xy 288.674753 -61.769445)
			(xy 288.727537 -61.751438) (xy 288.78238 -61.741308) (xy 288.838114 -61.739271) (xy 288.893551 -61.745371)
			(xy 288.947508 -61.759477) (xy 288.998837 -61.781289) (xy 289.046443 -61.810343) (xy 289.089311 -61.846018)
			(xy 289.126528 -61.887555) (xy 289.157301 -61.934068) (xy 289.180973 -61.984565) (xy 289.197041 -62.037972)
			(xy 289.205161 -62.093148) (xy 289.20567 -62.121034) (xy 289.205161 -62.14892) (xy 289.197041 -62.204096)
			(xy 289.180973 -62.257503) (xy 289.157301 -62.308) (xy 289.126528 -62.354513) (xy 289.089311 -62.39605)
			(xy 289.046443 -62.431725) (xy 288.998837 -62.460779) (xy 288.947508 -62.482591) (xy 288.893551 -62.496697)
			(xy 288.838114 -62.502797) (xy 288.78238 -62.50076) (xy 288.727537 -62.49063) (xy 288.674753 -62.472623)
			(xy 288.625153 -62.447122) (xy 288.579795 -62.414671) (xy 288.539646 -62.375962) (xy 288.50556 -62.331819)
			(xy 288.478264 -62.283184) (xy 288.458341 -62.231093) (xy 288.446215 -62.176656) (xy 288.442144 -62.121034)
			(xy 272.555125 -62.121034) (xy 272.581624 -62.880494) (xy 272.593292 -63.213548) (xy 280.320788 -63.213548)
			(xy 280.320788 -63.159052) (xy 280.328543 -63.10511) (xy 280.343895 -63.052821) (xy 280.366532 -63.003248)
			(xy 280.395993 -62.957401) (xy 280.431678 -62.916214) (xy 280.472861 -62.880523) (xy 280.518704 -62.851056)
			(xy 280.568274 -62.828413) (xy 280.620561 -62.813054) (xy 280.674502 -62.805292) (xy 280.70175 -62.804802)
			(xy 280.729119 -62.805297) (xy 280.783297 -62.813108) (xy 280.8358 -62.82859) (xy 280.885547 -62.851425)
			(xy 280.931515 -62.881144) (xy 280.952448 -62.898782) (xy 280.952702 -62.899036) (xy 280.959781 -62.904634)
			(xy 280.976704 -62.910873) (xy 280.985722 -62.911228) (xy 281.052778 -62.911228) (xy 281.061793 -62.910854)
			(xy 281.07871 -62.904618) (xy 281.085798 -62.899036) (xy 281.085798 -62.898782) (xy 281.086052 -62.898782)
			(xy 281.106985 -62.881141) (xy 281.152953 -62.851417) (xy 281.202699 -62.828571) (xy 281.255201 -62.813075)
			(xy 281.309379 -62.805246) (xy 281.364121 -62.805246) (xy 281.418299 -62.813075) (xy 281.470801 -62.828571)
			(xy 281.520547 -62.851417) (xy 281.566515 -62.881141) (xy 281.587448 -62.898782) (xy 281.587702 -62.899036)
			(xy 281.594781 -62.904634) (xy 281.611704 -62.910873) (xy 281.620722 -62.911228) (xy 281.687778 -62.911228)
			(xy 281.696793 -62.910854) (xy 281.71371 -62.904618) (xy 281.720798 -62.899036) (xy 281.720798 -62.898782)
			(xy 281.721052 -62.898782) (xy 281.741989 -62.881149) (xy 281.787961 -62.851437) (xy 281.837707 -62.8286)
			(xy 281.890206 -62.813108) (xy 281.944381 -62.805277) (xy 281.97175 -62.804802) (xy 281.999006 -62.805241)
			(xy 282.052964 -62.812993) (xy 282.105269 -62.828345) (xy 282.154857 -62.850985) (xy 282.200717 -62.880453)
			(xy 282.241917 -62.916147) (xy 282.277617 -62.957342) (xy 282.307091 -63.003199) (xy 282.329738 -63.052784)
			(xy 282.339561 -63.086234) (xy 285.587438 -63.086234) (xy 285.591509 -63.030612) (xy 285.603635 -62.976175)
			(xy 285.623558 -62.924084) (xy 285.650854 -62.875449) (xy 285.68494 -62.831306) (xy 285.725089 -62.792597)
			(xy 285.770447 -62.760146) (xy 285.820047 -62.734645) (xy 285.872831 -62.716638) (xy 285.927674 -62.706508)
			(xy 285.983408 -62.704471) (xy 286.038845 -62.710571) (xy 286.092802 -62.724677) (xy 286.144131 -62.746489)
			(xy 286.191737 -62.775543) (xy 286.234605 -62.811218) (xy 286.271822 -62.852755) (xy 286.302595 -62.899268)
			(xy 286.326267 -62.949765) (xy 286.342335 -63.003172) (xy 286.350455 -63.058348) (xy 286.350964 -63.086234)
			(xy 286.350455 -63.11412) (xy 286.342335 -63.169296) (xy 286.326267 -63.222703) (xy 286.302595 -63.2732)
			(xy 286.302442 -63.273432) (xy 287.776664 -63.273432) (xy 287.780735 -63.21781) (xy 287.792861 -63.163373)
			(xy 287.812784 -63.111282) (xy 287.84008 -63.062647) (xy 287.874166 -63.018504) (xy 287.914315 -62.979795)
			(xy 287.959673 -62.947344) (xy 288.009273 -62.921843) (xy 288.062057 -62.903836) (xy 288.1169 -62.893706)
			(xy 288.172634 -62.891669) (xy 288.228071 -62.897769) (xy 288.282028 -62.911875) (xy 288.333357 -62.933687)
			(xy 288.380963 -62.962741) (xy 288.423831 -62.998416) (xy 288.461048 -63.039953) (xy 288.491821 -63.086466)
			(xy 288.515493 -63.136963) (xy 288.531561 -63.19037) (xy 288.539681 -63.245546) (xy 288.54019 -63.273432)
			(xy 288.539681 -63.301318) (xy 288.531561 -63.356494) (xy 288.515493 -63.409901) (xy 288.491821 -63.460398)
			(xy 288.461048 -63.506911) (xy 288.423831 -63.548448) (xy 288.380963 -63.584123) (xy 288.333357 -63.613177)
			(xy 288.282028 -63.634989) (xy 288.228071 -63.649095) (xy 288.172634 -63.655195) (xy 288.1169 -63.653158)
			(xy 288.062057 -63.643028) (xy 288.009273 -63.625021) (xy 287.959673 -63.59952) (xy 287.914315 -63.567069)
			(xy 287.874166 -63.52836) (xy 287.84008 -63.484217) (xy 287.812784 -63.435582) (xy 287.792861 -63.383491)
			(xy 287.780735 -63.329054) (xy 287.776664 -63.273432) (xy 286.302442 -63.273432) (xy 286.271822 -63.319713)
			(xy 286.234605 -63.36125) (xy 286.191737 -63.396925) (xy 286.144131 -63.425979) (xy 286.092802 -63.447791)
			(xy 286.038845 -63.461897) (xy 285.983408 -63.467997) (xy 285.927674 -63.46596) (xy 285.872831 -63.45583)
			(xy 285.820047 -63.437823) (xy 285.770447 -63.412322) (xy 285.725089 -63.379871) (xy 285.68494 -63.341162)
			(xy 285.650854 -63.297019) (xy 285.623558 -63.248384) (xy 285.603635 -63.196293) (xy 285.591509 -63.141856)
			(xy 285.587438 -63.086234) (xy 282.339561 -63.086234) (xy 282.345097 -63.105087) (xy 282.352855 -63.159044)
			(xy 282.352855 -63.213556) (xy 282.345097 -63.267513) (xy 282.329738 -63.319816) (xy 282.307091 -63.369401)
			(xy 282.277617 -63.415258) (xy 282.241917 -63.456453) (xy 282.200717 -63.492147) (xy 282.154857 -63.521615)
			(xy 282.105269 -63.544255) (xy 282.052964 -63.559607) (xy 281.999006 -63.567359) (xy 281.97175 -63.567818)
			(xy 281.94438 -63.567343) (xy 281.8902 -63.55953) (xy 281.837697 -63.544044) (xy 281.787949 -63.521204)
			(xy 281.741983 -63.49148) (xy 281.721052 -63.473838) (xy 281.720798 -63.473584) (xy 281.713717 -63.467989)
			(xy 281.696796 -63.461748) (xy 281.687778 -63.461392) (xy 281.620722 -63.461392) (xy 281.611706 -63.461761)
			(xy 281.594789 -63.468) (xy 281.587702 -63.473584) (xy 281.587448 -63.473838) (xy 281.566515 -63.491479)
			(xy 281.520547 -63.521203) (xy 281.470801 -63.544049) (xy 281.418299 -63.559545) (xy 281.364121 -63.567374)
			(xy 281.309379 -63.567374) (xy 281.255201 -63.559545) (xy 281.202699 -63.544049) (xy 281.152953 -63.521203)
			(xy 281.106985 -63.491479) (xy 281.086052 -63.473838) (xy 281.085798 -63.473584) (xy 281.078717 -63.467989)
			(xy 281.061796 -63.461748) (xy 281.052778 -63.461392) (xy 280.985722 -63.461392) (xy 280.976706 -63.461761)
			(xy 280.959789 -63.468) (xy 280.952702 -63.473584) (xy 280.952702 -63.473838) (xy 280.952448 -63.473838)
			(xy 280.931514 -63.491474) (xy 280.885541 -63.521185) (xy 280.835794 -63.544021) (xy 280.783294 -63.559513)
			(xy 280.729119 -63.567343) (xy 280.70175 -63.567818) (xy 280.674502 -63.567308) (xy 280.620561 -63.559546)
			(xy 280.568274 -63.544187) (xy 280.518704 -63.521544) (xy 280.472861 -63.492077) (xy 280.431678 -63.456386)
			(xy 280.395993 -63.415199) (xy 280.366532 -63.369352) (xy 280.343895 -63.319779) (xy 280.328543 -63.26749)
			(xy 280.320788 -63.213548) (xy 272.593292 -63.213548) (xy 272.618962 -63.946278) (xy 272.633565 -64.312292)
			(xy 291.105842 -64.312292) (xy 291.109913 -64.25667) (xy 291.122039 -64.202233) (xy 291.141962 -64.150142)
			(xy 291.169258 -64.101507) (xy 291.203344 -64.057364) (xy 291.243493 -64.018655) (xy 291.288851 -63.986204)
			(xy 291.338451 -63.960703) (xy 291.391235 -63.942696) (xy 291.446078 -63.932566) (xy 291.501812 -63.930529)
			(xy 291.557249 -63.936629) (xy 291.611206 -63.950735) (xy 291.662535 -63.972547) (xy 291.710141 -64.001601)
			(xy 291.753009 -64.037276) (xy 291.790226 -64.078813) (xy 291.820999 -64.125326) (xy 291.844671 -64.175823)
			(xy 291.860739 -64.22923) (xy 291.868859 -64.284406) (xy 291.869368 -64.312292) (xy 291.868859 -64.340178)
			(xy 291.860739 -64.395354) (xy 291.844671 -64.448761) (xy 291.820999 -64.499258) (xy 291.790226 -64.545771)
			(xy 291.753009 -64.587308) (xy 291.710141 -64.622983) (xy 291.662535 -64.652037) (xy 291.611206 -64.673849)
			(xy 291.557249 -64.687955) (xy 291.501812 -64.694055) (xy 291.446078 -64.692018) (xy 291.391235 -64.681888)
			(xy 291.338451 -64.663881) (xy 291.288851 -64.63838) (xy 291.243493 -64.605929) (xy 291.203344 -64.56722)
			(xy 291.169258 -64.523077) (xy 291.141962 -64.474442) (xy 291.122039 -64.422351) (xy 291.109913 -64.367914)
			(xy 291.105842 -64.312292) (xy 272.633565 -64.312292) (xy 272.654522 -64.837564) (xy 272.66392 -65.070482)
			(xy 272.66392 -65.071498) (xy 272.666286 -65.100962) (xy 278.332436 -65.100962) (xy 278.336507 -65.04534)
			(xy 278.348633 -64.990903) (xy 278.368556 -64.938812) (xy 278.395852 -64.890177) (xy 278.429938 -64.846034)
			(xy 278.470087 -64.807325) (xy 278.515445 -64.774874) (xy 278.565045 -64.749373) (xy 278.617829 -64.731366)
			(xy 278.672672 -64.721236) (xy 278.728406 -64.719199) (xy 278.783843 -64.725299) (xy 278.8378 -64.739405)
			(xy 278.889129 -64.761217) (xy 278.936735 -64.790271) (xy 278.979603 -64.825946) (xy 279.01682 -64.867483)
			(xy 279.047593 -64.913996) (xy 279.071265 -64.964493) (xy 279.087333 -65.0179) (xy 279.095453 -65.073076)
			(xy 279.095962 -65.100962) (xy 279.095453 -65.128848) (xy 279.087333 -65.184024) (xy 279.071265 -65.237431)
			(xy 279.047593 -65.287928) (xy 279.01682 -65.334441) (xy 278.979603 -65.375978) (xy 278.936735 -65.411653)
			(xy 278.889129 -65.440707) (xy 278.8378 -65.462519) (xy 278.783843 -65.476625) (xy 278.728406 -65.482725)
			(xy 278.672672 -65.480688) (xy 278.617829 -65.470558) (xy 278.565045 -65.452551) (xy 278.515445 -65.42705)
			(xy 278.470087 -65.394599) (xy 278.429938 -65.35589) (xy 278.395852 -65.311747) (xy 278.368556 -65.263112)
			(xy 278.348633 -65.211021) (xy 278.336507 -65.156584) (xy 278.332436 -65.100962) (xy 272.666286 -65.100962)
			(xy 272.684748 -65.330832) (xy 272.687288 -65.339976) (xy 272.690444 -65.347287) (xy 272.70054 -65.359592)
			(xy 272.7071 -65.364106) (xy 272.715482 -65.369694) (xy 272.75282 -65.394078) (xy 272.75663 -65.395602)
			(xy 272.763742 -65.398904) (xy 272.776442 -65.400174) (xy 272.784824 -65.39992) (xy 272.795746 -65.397634)
			(xy 272.799302 -65.396364) (xy 272.830465 -65.385913) (xy 272.895218 -65.374667) (xy 272.92808 -65.374012)
			(xy 272.931382 -65.374012) (xy 272.958503 -65.374687) (xy 273.012149 -65.382764) (xy 273.064109 -65.398359)
			(xy 273.113336 -65.421157) (xy 273.158837 -65.450699) (xy 273.199694 -65.486389) (xy 273.235083 -65.527508)
			(xy 273.264291 -65.573224) (xy 273.286727 -65.622618) (xy 273.30194 -65.674691) (xy 273.309622 -65.728395)
			(xy 273.310096 -65.75552) (xy 273.309608 -65.78277) (xy 273.301849 -65.836715) (xy 273.286493 -65.889006)
			(xy 273.26385 -65.93858) (xy 273.234383 -65.984427) (xy 273.198691 -66.025614) (xy 273.157502 -66.061302)
			(xy 273.111652 -66.090765) (xy 273.062076 -66.113404) (xy 273.009784 -66.128756) (xy 272.955838 -66.136511)
			(xy 272.928588 -66.137028) (xy 272.909927 -66.136838) (xy 272.872777 -66.133277) (xy 272.85442 -66.129916)
			(xy 272.842482 -66.12763) (xy 272.831306 -66.130678) (xy 272.825574 -66.132363) (xy 272.815049 -66.138008)
			(xy 272.810478 -66.141854) (xy 272.781014 -66.168524) (xy 272.772632 -66.176144) (xy 272.76438 -66.184415)
			(xy 272.755797 -66.206119) (xy 272.756122 -66.2178) (xy 272.778474 -66.497708) (xy 272.781522 -66.536062)
			(xy 272.791174 -66.656204) (xy 272.792716 -66.665133) (xy 272.801174 -66.681143) (xy 272.807684 -66.687446)
			(xy 272.815304 -66.693796) (xy 272.82902 -66.704464) (xy 272.844514 -66.716402) (xy 272.849149 -66.719409)
			(xy 272.859405 -66.723507) (xy 272.864834 -66.72453) (xy 272.882106 -66.72453) (xy 272.88617 -66.723768)
			(xy 272.901369 -66.721475) (xy 272.932014 -66.719056) (xy 272.947384 -66.718942) (xy 272.947638 -66.718942)
			(xy 272.973465 -66.719363) (xy 273.024649 -66.726304) (xy 273.074434 -66.74007) (xy 273.121914 -66.76041)
			(xy 273.166225 -66.786953) (xy 273.186652 -66.802762) (xy 273.186906 -66.803016) (xy 273.193764 -66.80835)
			(xy 273.201638 -66.811144) (xy 273.205817 -66.812554) (xy 273.214501 -66.814088) (xy 273.21891 -66.814192)
			(xy 273.238468 -66.814192) (xy 273.243907 -66.814339) (xy 273.254535 -66.816653) (xy 273.25955 -66.818764)
			(xy 273.27352 -66.825114) (xy 273.282688 -66.828798) (xy 273.302411 -66.829638) (xy 273.321001 -66.822999)
			(xy 273.328638 -66.816732) (xy 273.339052 -66.807588) (xy 273.35967 -66.79116) (xy 273.404567 -66.763528)
			(xy 273.452834 -66.742326) (xy 273.503556 -66.727956) (xy 273.555771 -66.72069) (xy 273.58213 -66.720212)
			(xy 273.582638 -66.720212) (xy 273.609886 -66.720701) (xy 273.663827 -66.728461) (xy 273.716114 -66.743819)
			(xy 273.765684 -66.766461) (xy 273.811527 -66.795927) (xy 273.852711 -66.831616) (xy 273.888396 -66.872803)
			(xy 273.917857 -66.918649) (xy 273.940494 -66.968222) (xy 273.955847 -67.02051) (xy 273.963602 -67.074452)
			(xy 273.963602 -67.128948) (xy 273.955847 -67.18289) (xy 273.940494 -67.235178) (xy 273.917857 -67.284751)
			(xy 273.888396 -67.330597) (xy 273.852711 -67.371784) (xy 273.811527 -67.407473) (xy 273.765684 -67.436939)
			(xy 273.716114 -67.459581) (xy 273.663827 -67.474939) (xy 273.609886 -67.482699) (xy 273.582638 -67.483228)
			(xy 273.557092 -67.482815) (xy 273.506457 -67.475992) (xy 273.457185 -67.462475) (xy 273.410157 -67.442507)
			(xy 273.366212 -67.416444) (xy 273.34591 -67.400932) (xy 273.341084 -67.397122) (xy 273.335496 -67.394582)
			(xy 273.330162 -67.391788) (xy 273.318986 -67.389248) (xy 273.291808 -67.389248) (xy 273.286368 -67.389108)
			(xy 273.275734 -67.386806) (xy 273.270726 -67.384676) (xy 273.259804 -67.379088) (xy 273.25647 -67.377509)
			(xy 273.249456 -67.375221) (xy 273.245834 -67.374516) (xy 273.232118 -67.374008) (xy 273.222466 -67.375278)
			(xy 273.209258 -67.381628) (xy 273.203162 -67.386708) (xy 273.181996 -67.405034) (xy 273.135313 -67.43594)
			(xy 273.084628 -67.459717) (xy 273.031019 -67.475857) (xy 272.975631 -67.484018) (xy 272.947638 -67.484498)
			(xy 272.945606 -67.484498) (xy 272.932144 -67.484498) (xy 272.925975 -67.488054) (xy 276.979124 -67.488054)
			(xy 276.983195 -67.432432) (xy 276.995321 -67.377995) (xy 277.015244 -67.325904) (xy 277.04254 -67.277269)
			(xy 277.076626 -67.233126) (xy 277.116775 -67.194417) (xy 277.162133 -67.161966) (xy 277.211733 -67.136465)
			(xy 277.264517 -67.118458) (xy 277.31936 -67.108328) (xy 277.375094 -67.106291) (xy 277.430531 -67.112391)
			(xy 277.484488 -67.126497) (xy 277.535817 -67.148309) (xy 277.583423 -67.177363) (xy 277.626291 -67.213038)
			(xy 277.663508 -67.254575) (xy 277.694281 -67.301088) (xy 277.717953 -67.351585) (xy 277.734021 -67.404992)
			(xy 277.742141 -67.460168) (xy 277.74265 -67.488054) (xy 277.742141 -67.51594) (xy 277.738956 -67.537584)
			(xy 278.271222 -67.537584) (xy 278.275293 -67.481962) (xy 278.287419 -67.427525) (xy 278.307342 -67.375434)
			(xy 278.334638 -67.326799) (xy 278.368724 -67.282656) (xy 278.408873 -67.243947) (xy 278.454231 -67.211496)
			(xy 278.503831 -67.185995) (xy 278.556615 -67.167988) (xy 278.611458 -67.157858) (xy 278.667192 -67.155821)
			(xy 278.722629 -67.161921) (xy 278.776586 -67.176027) (xy 278.827915 -67.197839) (xy 278.875521 -67.226893)
			(xy 278.918389 -67.262568) (xy 278.955606 -67.304105) (xy 278.986379 -67.350618) (xy 279.010051 -67.401115)
			(xy 279.026119 -67.454522) (xy 279.034239 -67.509698) (xy 279.034748 -67.537584) (xy 279.034239 -67.56547)
			(xy 279.030194 -67.592956) (xy 279.545286 -67.592956) (xy 279.549357 -67.537334) (xy 279.561483 -67.482897)
			(xy 279.581406 -67.430806) (xy 279.608702 -67.382171) (xy 279.642788 -67.338028) (xy 279.682937 -67.299319)
			(xy 279.728295 -67.266868) (xy 279.777895 -67.241367) (xy 279.830679 -67.22336) (xy 279.885522 -67.21323)
			(xy 279.941256 -67.211193) (xy 279.996693 -67.217293) (xy 280.05065 -67.231399) (xy 280.101979 -67.253211)
			(xy 280.149585 -67.282265) (xy 280.192453 -67.31794) (xy 280.22967 -67.359477) (xy 280.260443 -67.40599)
			(xy 280.284115 -67.456487) (xy 280.300183 -67.509894) (xy 280.3083 -67.565051) (xy 282.646593 -67.565051)
			(xy 282.646593 -67.510549) (xy 282.65435 -67.456601) (xy 282.669706 -67.404306) (xy 282.692348 -67.354729)
			(xy 282.721816 -67.308879) (xy 282.757509 -67.267689) (xy 282.798701 -67.231999) (xy 282.844553 -67.202535)
			(xy 282.894132 -67.179896) (xy 282.946428 -67.164544) (xy 283.000377 -67.156791) (xy 283.027628 -67.15633)
			(xy 283.054999 -67.156772) (xy 283.10918 -67.164595) (xy 283.161683 -67.180089) (xy 283.21143 -67.202936)
			(xy 283.257395 -67.232666) (xy 283.278326 -67.25031) (xy 283.27858 -67.250564) (xy 283.285663 -67.256156)
			(xy 283.302583 -67.262398) (xy 283.3116 -67.262756) (xy 283.378656 -67.262756) (xy 283.387672 -67.262387)
			(xy 283.404589 -67.256149) (xy 283.411676 -67.250564) (xy 283.411676 -67.25031) (xy 283.41193 -67.25031)
			(xy 283.432879 -67.232692) (xy 283.478847 -67.202976) (xy 283.52859 -67.180136) (xy 283.581087 -67.16464)
			(xy 283.63526 -67.156807) (xy 283.662628 -67.15633) (xy 283.689881 -67.156742) (xy 283.743831 -67.164502)
			(xy 283.796127 -67.179861) (xy 283.845706 -67.202506) (xy 283.891557 -67.231976) (xy 283.932748 -67.267671)
			(xy 283.96844 -67.308865) (xy 283.997907 -67.354719) (xy 284.020548 -67.404299) (xy 284.035904 -67.456597)
			(xy 284.04366 -67.510547) (xy 284.04366 -67.565053) (xy 284.035904 -67.619003) (xy 284.020548 -67.671301)
			(xy 283.997907 -67.720881) (xy 283.96844 -67.766735) (xy 283.932748 -67.807929) (xy 283.891557 -67.843624)
			(xy 283.845706 -67.873094) (xy 283.796127 -67.895739) (xy 283.743831 -67.911098) (xy 283.689881 -67.918858)
			(xy 283.662628 -67.919346) (xy 283.635258 -67.918877) (xy 283.581078 -67.911062) (xy 283.528575 -67.895574)
			(xy 283.478828 -67.872733) (xy 283.432861 -67.843008) (xy 283.41193 -67.825366) (xy 283.411676 -67.825112)
			(xy 283.4046 -67.819511) (xy 283.387675 -67.813272) (xy 283.378656 -67.81292) (xy 283.3116 -67.81292)
			(xy 283.302583 -67.813273) (xy 283.285665 -67.819523) (xy 283.27858 -67.825112) (xy 283.27858 -67.825366)
			(xy 283.278326 -67.825366) (xy 283.257391 -67.843001) (xy 283.211419 -67.872715) (xy 283.161673 -67.895552)
			(xy 283.109172 -67.911044) (xy 283.054997 -67.918872) (xy 283.027628 -67.919346) (xy 283.000377 -67.918809)
			(xy 282.946428 -67.911056) (xy 282.894132 -67.895704) (xy 282.844553 -67.873065) (xy 282.798701 -67.843601)
			(xy 282.757509 -67.807911) (xy 282.721816 -67.766721) (xy 282.692348 -67.720871) (xy 282.669706 -67.671294)
			(xy 282.65435 -67.618999) (xy 282.646593 -67.565051) (xy 280.3083 -67.565051) (xy 280.308303 -67.56507)
			(xy 280.308812 -67.592956) (xy 280.308303 -67.620842) (xy 280.300183 -67.676018) (xy 280.284115 -67.729425)
			(xy 280.260443 -67.779922) (xy 280.22967 -67.826435) (xy 280.192453 -67.867972) (xy 280.149585 -67.903647)
			(xy 280.101979 -67.932701) (xy 280.05065 -67.954513) (xy 279.996693 -67.968619) (xy 279.941256 -67.974719)
			(xy 279.885522 -67.972682) (xy 279.830679 -67.962552) (xy 279.777895 -67.944545) (xy 279.728295 -67.919044)
			(xy 279.682937 -67.886593) (xy 279.642788 -67.847884) (xy 279.608702 -67.803741) (xy 279.581406 -67.755106)
			(xy 279.561483 -67.703015) (xy 279.549357 -67.648578) (xy 279.545286 -67.592956) (xy 279.030194 -67.592956)
			(xy 279.026119 -67.620646) (xy 279.010051 -67.674053) (xy 278.986379 -67.72455) (xy 278.955606 -67.771063)
			(xy 278.918389 -67.8126) (xy 278.875521 -67.848275) (xy 278.827915 -67.877329) (xy 278.776586 -67.899141)
			(xy 278.722629 -67.913247) (xy 278.667192 -67.919347) (xy 278.611458 -67.91731) (xy 278.556615 -67.90718)
			(xy 278.503831 -67.889173) (xy 278.454231 -67.863672) (xy 278.408873 -67.831221) (xy 278.368724 -67.792512)
			(xy 278.334638 -67.748369) (xy 278.307342 -67.699734) (xy 278.287419 -67.647643) (xy 278.275293 -67.593206)
			(xy 278.271222 -67.537584) (xy 277.738956 -67.537584) (xy 277.734021 -67.571116) (xy 277.717953 -67.624523)
			(xy 277.694281 -67.67502) (xy 277.663508 -67.721533) (xy 277.626291 -67.76307) (xy 277.583423 -67.798745)
			(xy 277.535817 -67.827799) (xy 277.484488 -67.849611) (xy 277.430531 -67.863717) (xy 277.375094 -67.869817)
			(xy 277.31936 -67.86778) (xy 277.264517 -67.85765) (xy 277.211733 -67.839643) (xy 277.162133 -67.814142)
			(xy 277.116775 -67.781691) (xy 277.076626 -67.742982) (xy 277.04254 -67.698839) (xy 277.015244 -67.650204)
			(xy 276.995321 -67.598113) (xy 276.983195 -67.543676) (xy 276.979124 -67.488054) (xy 272.925975 -67.488054)
			(xy 272.910554 -67.496944) (xy 272.90014 -67.505072) (xy 272.890234 -67.515486) (xy 272.889726 -67.515994)
			(xy 272.871438 -67.535552) (xy 272.870168 -67.536822) (xy 272.866866 -67.546728) (xy 272.86534 -67.551657)
			(xy 272.864066 -67.561895) (xy 272.864326 -67.567048) (xy 272.94616 -68.586604) (xy 274.825206 -68.586604)
			(xy 274.825673 -68.559234) (xy 274.83349 -68.505055) (xy 274.848979 -68.452552) (xy 274.871821 -68.402805)
			(xy 274.901545 -68.356838) (xy 274.919186 -68.335906) (xy 274.91944 -68.335652) (xy 274.925016 -68.328558)
			(xy 274.931268 -68.311647) (xy 274.931632 -68.302632) (xy 274.931632 -68.235576) (xy 274.93128 -68.226559)
			(xy 274.925028 -68.209642) (xy 274.91944 -68.202556) (xy 274.919186 -68.202556) (xy 274.919186 -68.202302)
			(xy 274.901532 -68.181382) (xy 274.871823 -68.135406) (xy 274.84899 -68.085655) (xy 274.833503 -68.033152)
			(xy 274.825678 -67.978974) (xy 274.825206 -67.951604) (xy 274.825659 -67.924351) (xy 274.833416 -67.870399)
			(xy 274.848772 -67.8181) (xy 274.871415 -67.768519) (xy 274.900884 -67.722665) (xy 274.936579 -67.681472)
			(xy 274.977773 -67.645778) (xy 275.023627 -67.61631) (xy 275.073209 -67.593669) (xy 275.125508 -67.578314)
			(xy 275.179461 -67.570558) (xy 275.206714 -67.570096) (xy 275.233028 -67.570555) (xy 275.285157 -67.577792)
			(xy 275.3358 -67.592113) (xy 275.383999 -67.613247) (xy 275.428842 -67.640794) (xy 275.469482 -67.674234)
			(xy 275.487638 -67.693286) (xy 275.495145 -67.700704) (xy 275.514436 -67.70922) (xy 275.524976 -67.709796)
			(xy 275.599652 -67.709796) (xy 275.6102 -67.709256) (xy 275.629496 -67.700729) (xy 275.63699 -67.693286)
			(xy 275.655155 -67.67424) (xy 275.695783 -67.640782) (xy 275.740621 -67.613222) (xy 275.78882 -67.592082)
			(xy 275.839466 -67.577763) (xy 275.891598 -67.570536) (xy 275.917914 -67.570096) (xy 275.945284 -67.570555)
			(xy 275.999464 -67.578375) (xy 276.051967 -67.593865) (xy 276.101714 -67.616709) (xy 276.14768 -67.646434)
			(xy 276.168612 -67.664076) (xy 276.168866 -67.66433) (xy 276.175956 -67.669912) (xy 276.19287 -67.67616)
			(xy 276.201886 -67.676522) (xy 276.268942 -67.676522) (xy 276.277956 -67.676133) (xy 276.294873 -67.669907)
			(xy 276.301962 -67.66433) (xy 276.301962 -67.664076) (xy 276.302216 -67.664076) (xy 276.323166 -67.646459)
			(xy 276.369134 -67.616745) (xy 276.418877 -67.593905) (xy 276.471374 -67.578409) (xy 276.525546 -67.570574)
			(xy 276.552914 -67.570096) (xy 276.580166 -67.570565) (xy 276.634114 -67.578323) (xy 276.68641 -67.59368)
			(xy 276.735987 -67.616323) (xy 276.781838 -67.645792) (xy 276.823028 -67.681485) (xy 276.858719 -67.722677)
			(xy 276.888185 -67.768529) (xy 276.910826 -67.818107) (xy 276.926181 -67.870403) (xy 276.933937 -67.924352)
			(xy 276.934422 -67.951604) (xy 276.933977 -67.978975) (xy 276.926157 -68.033156) (xy 276.910664 -68.08566)
			(xy 276.887817 -68.135407) (xy 276.858087 -68.181372) (xy 276.840442 -68.202302) (xy 276.840188 -68.202556)
			(xy 276.834612 -68.20965) (xy 276.828359 -68.226561) (xy 276.827996 -68.235576) (xy 276.827996 -68.302632)
			(xy 276.828339 -68.31165) (xy 276.834596 -68.328567) (xy 276.840188 -68.335652) (xy 276.840442 -68.335652)
			(xy 276.840442 -68.335906) (xy 276.858104 -68.356819) (xy 276.887811 -68.402798) (xy 276.910642 -68.45255)
			(xy 276.926128 -68.505055) (xy 276.933951 -68.559234) (xy 276.934422 -68.586604) (xy 276.933926 -68.613855)
			(xy 276.926169 -68.667801) (xy 276.910814 -68.720095) (xy 276.894175 -68.75653) (xy 280.37028 -68.75653)
			(xy 280.370744 -68.729159) (xy 280.378559 -68.67498) (xy 280.394048 -68.622476) (xy 280.416891 -68.572729)
			(xy 280.446617 -68.526763) (xy 280.46426 -68.505832) (xy 280.464514 -68.505578) (xy 280.470117 -68.498503)
			(xy 280.476354 -68.481577) (xy 280.476706 -68.472558) (xy 280.476706 -68.405502) (xy 280.476347 -68.396485)
			(xy 280.470101 -68.379568) (xy 280.464514 -68.372482) (xy 280.46426 -68.372482) (xy 280.46426 -68.372228)
			(xy 280.446614 -68.351302) (xy 280.416904 -68.305327) (xy 280.39407 -68.255578) (xy 280.378581 -68.203076)
			(xy 280.370753 -68.148899) (xy 280.37028 -68.12153) (xy 280.370783 -68.094278) (xy 280.378536 -68.04033)
			(xy 280.393887 -67.988033) (xy 280.416526 -67.938454) (xy 280.445989 -67.892601) (xy 280.481679 -67.851409)
			(xy 280.522868 -67.815714) (xy 280.568717 -67.786246) (xy 280.618294 -67.763602) (xy 280.670588 -67.748245)
			(xy 280.724536 -67.740486) (xy 280.751788 -67.740022) (xy 280.779158 -67.74049) (xy 280.833337 -67.748306)
			(xy 280.885841 -67.763795) (xy 280.935588 -67.786636) (xy 280.981554 -67.816361) (xy 281.002486 -67.834002)
			(xy 281.00274 -67.834256) (xy 281.009835 -67.83983) (xy 281.026745 -67.846083) (xy 281.03576 -67.846448)
			(xy 281.102816 -67.846448) (xy 281.111835 -67.84611) (xy 281.128752 -67.83985) (xy 281.135836 -67.834256)
			(xy 281.135836 -67.834002) (xy 281.13609 -67.834002) (xy 281.157015 -67.816354) (xy 281.20299 -67.786644)
			(xy 281.252739 -67.763809) (xy 281.305241 -67.74832) (xy 281.359418 -67.740495) (xy 281.386788 -67.740022)
			(xy 281.413102 -67.74049) (xy 281.465231 -67.747724) (xy 281.515874 -67.762042) (xy 281.564073 -67.783175)
			(xy 281.608916 -67.810721) (xy 281.649556 -67.84416) (xy 281.667712 -67.863212) (xy 281.675226 -67.870623)
			(xy 281.694512 -67.879142) (xy 281.70505 -67.879722) (xy 281.779726 -67.879722) (xy 281.790272 -67.87916)
			(xy 281.809567 -67.870647) (xy 281.817064 -67.863212) (xy 281.835198 -67.844135) (xy 281.875832 -67.810679)
			(xy 281.920677 -67.783123) (xy 281.968882 -67.761988) (xy 282.019533 -67.747676) (xy 282.071671 -67.740457)
			(xy 282.097988 -67.740022) (xy 282.125242 -67.740467) (xy 282.179195 -67.748223) (xy 282.231495 -67.763579)
			(xy 282.281077 -67.786222) (xy 282.326932 -67.815692) (xy 282.368125 -67.851387) (xy 282.403819 -67.892583)
			(xy 282.433287 -67.938439) (xy 282.455928 -67.988022) (xy 282.471281 -68.040323) (xy 282.479035 -68.094276)
			(xy 282.479496 -68.12153) (xy 282.479048 -68.148901) (xy 282.471226 -68.203081) (xy 282.455733 -68.255584)
			(xy 282.432887 -68.305331) (xy 282.403159 -68.351297) (xy 282.385516 -68.372228) (xy 282.385262 -68.372482)
			(xy 282.379673 -68.379566) (xy 282.373429 -68.396485) (xy 282.37307 -68.405502) (xy 282.37307 -68.472558)
			(xy 282.373454 -68.481572) (xy 282.379683 -68.498489) (xy 282.385262 -68.505578) (xy 282.385516 -68.505578)
			(xy 282.385516 -68.505832) (xy 282.403139 -68.526777) (xy 282.432853 -68.572746) (xy 282.455692 -68.622491)
			(xy 282.471186 -68.674988) (xy 282.479019 -68.729162) (xy 282.479496 -68.75653) (xy 282.47905 -68.783783)
			(xy 282.471289 -68.837732) (xy 282.45593 -68.890029) (xy 282.433284 -68.939607) (xy 282.403814 -68.985457)
			(xy 282.368118 -69.026648) (xy 282.326924 -69.062339) (xy 282.28107 -69.091804) (xy 282.231489 -69.114444)
			(xy 282.179191 -69.129798) (xy 282.125241 -69.137553) (xy 282.097988 -69.138038) (xy 282.071673 -69.137598)
			(xy 282.019542 -69.130361) (xy 281.968898 -69.116037) (xy 281.920699 -69.0949) (xy 281.875856 -69.067348)
			(xy 281.835219 -69.033903) (xy 281.817064 -69.014848) (xy 281.809551 -69.007436) (xy 281.790265 -68.998916)
			(xy 281.779726 -68.998338) (xy 281.70505 -68.998338) (xy 281.6945 -68.998869) (xy 281.675204 -69.007402)
			(xy 281.667712 -69.014848) (xy 281.649553 -69.0339) (xy 281.608923 -69.067356) (xy 281.564083 -69.094914)
			(xy 281.515883 -69.116053) (xy 281.465237 -69.130371) (xy 281.413104 -69.137598) (xy 281.386788 -69.138038)
			(xy 281.359417 -69.137594) (xy 281.305236 -69.129773) (xy 281.252732 -69.11428) (xy 281.202986 -69.091433)
			(xy 281.15702 -69.061702) (xy 281.13609 -69.044058) (xy 281.135836 -69.043804) (xy 281.128743 -69.038227)
			(xy 281.111831 -69.031974) (xy 281.102816 -69.031612) (xy 281.03576 -69.031612) (xy 281.026741 -69.031947)
			(xy 281.009824 -69.03821) (xy 281.00274 -69.043804) (xy 281.00274 -69.044058) (xy 281.002486 -69.044058)
			(xy 280.981527 -69.061664) (xy 280.935562 -69.091382) (xy 280.885822 -69.114225) (xy 280.833327 -69.129724)
			(xy 280.779155 -69.13756) (xy 280.751788 -69.138038) (xy 280.724538 -69.137533) (xy 280.670592 -69.129776)
			(xy 280.6183 -69.114421) (xy 280.568724 -69.091781) (xy 280.522876 -69.062316) (xy 280.481686 -69.026626)
			(xy 280.445995 -68.985439) (xy 280.416528 -68.939591) (xy 280.393885 -68.890017) (xy 280.378528 -68.837725)
			(xy 280.370768 -68.78378) (xy 280.37028 -68.75653) (xy 276.894175 -68.75653) (xy 276.888174 -68.769671)
			(xy 276.858708 -68.815521) (xy 276.823018 -68.856711) (xy 276.781829 -68.892402) (xy 276.73598 -68.921869)
			(xy 276.686404 -68.944511) (xy 276.634111 -68.959867) (xy 276.580165 -68.967625) (xy 276.552914 -68.968112)
			(xy 276.525544 -68.967635) (xy 276.471366 -68.959819) (xy 276.418863 -68.944333) (xy 276.369116 -68.921493)
			(xy 276.323148 -68.891772) (xy 276.302216 -68.874132) (xy 276.301962 -68.873878) (xy 276.294864 -68.868309)
			(xy 276.277956 -68.862052) (xy 276.268942 -68.861686) (xy 276.201886 -68.861686) (xy 276.192869 -68.86204)
			(xy 276.175952 -68.86829) (xy 276.168866 -68.873878) (xy 276.168866 -68.874132) (xy 276.168612 -68.874132)
			(xy 276.14769 -68.891784) (xy 276.101714 -68.921493) (xy 276.051964 -68.944326) (xy 275.999461 -68.959814)
			(xy 275.945284 -68.967639) (xy 275.917914 -68.968112) (xy 275.891601 -68.967631) (xy 275.839473 -68.960399)
			(xy 275.78883 -68.946082) (xy 275.740631 -68.924952) (xy 275.695788 -68.897408) (xy 275.655147 -68.863972)
			(xy 275.63699 -68.844922) (xy 275.629471 -68.837517) (xy 275.610189 -68.828994) (xy 275.599652 -68.828412)
			(xy 275.524976 -68.828412) (xy 275.514429 -68.828965) (xy 275.495133 -68.837483) (xy 275.487638 -68.844922)
			(xy 275.46951 -68.864005) (xy 275.428874 -68.897459) (xy 275.384028 -68.925014) (xy 275.335822 -68.946147)
			(xy 275.285169 -68.960459) (xy 275.233032 -68.967677) (xy 275.206714 -68.968112) (xy 275.179462 -68.967632)
			(xy 275.125512 -68.959877) (xy 275.073214 -68.944523) (xy 275.023634 -68.921882) (xy 274.977781 -68.892416)
			(xy 274.936589 -68.856724) (xy 274.900895 -68.815533) (xy 274.871427 -68.769681) (xy 274.848784 -68.720103)
			(xy 274.833427 -68.667806) (xy 274.82567 -68.613856) (xy 274.825206 -68.586604) (xy 272.94616 -68.586604)
			(xy 273.184485 -71.555864) (xy 277.394414 -71.555864) (xy 277.398485 -71.500242) (xy 277.410611 -71.445805)
			(xy 277.430534 -71.393714) (xy 277.45783 -71.345079) (xy 277.491916 -71.300936) (xy 277.532065 -71.262227)
			(xy 277.577423 -71.229776) (xy 277.627023 -71.204275) (xy 277.679807 -71.186268) (xy 277.73465 -71.176138)
			(xy 277.790384 -71.174101) (xy 277.845821 -71.180201) (xy 277.899778 -71.194307) (xy 277.951107 -71.216119)
			(xy 277.998713 -71.245173) (xy 278.041581 -71.280848) (xy 278.078798 -71.322385) (xy 278.109571 -71.368898)
			(xy 278.133243 -71.419395) (xy 278.149311 -71.472802) (xy 278.157431 -71.527978) (xy 278.15794 -71.555864)
			(xy 278.157431 -71.58375) (xy 278.151592 -71.623428) (xy 278.903428 -71.623428) (xy 278.907499 -71.567806)
			(xy 278.919625 -71.513369) (xy 278.939548 -71.461278) (xy 278.966844 -71.412643) (xy 279.00093 -71.3685)
			(xy 279.041079 -71.329791) (xy 279.086437 -71.29734) (xy 279.136037 -71.271839) (xy 279.188821 -71.253832)
			(xy 279.243664 -71.243702) (xy 279.299398 -71.241665) (xy 279.354835 -71.247765) (xy 279.408792 -71.261871)
			(xy 279.460121 -71.283683) (xy 279.507727 -71.312737) (xy 279.550595 -71.348412) (xy 279.587812 -71.389949)
			(xy 279.618585 -71.436462) (xy 279.642257 -71.486959) (xy 279.658325 -71.540366) (xy 279.666445 -71.595542)
			(xy 279.666954 -71.623428) (xy 279.666445 -71.651314) (xy 279.658325 -71.70649) (xy 279.642257 -71.759897)
			(xy 279.618585 -71.810394) (xy 279.587812 -71.856907) (xy 279.550595 -71.898444) (xy 279.507727 -71.934119)
			(xy 279.460121 -71.963173) (xy 279.408792 -71.984985) (xy 279.354835 -71.999091) (xy 279.299398 -72.005191)
			(xy 279.243664 -72.003154) (xy 279.188821 -71.993024) (xy 279.136037 -71.975017) (xy 279.086437 -71.949516)
			(xy 279.041079 -71.917065) (xy 279.00093 -71.878356) (xy 278.966844 -71.834213) (xy 278.939548 -71.785578)
			(xy 278.919625 -71.733487) (xy 278.907499 -71.67905) (xy 278.903428 -71.623428) (xy 278.151592 -71.623428)
			(xy 278.149311 -71.638926) (xy 278.133243 -71.692333) (xy 278.109571 -71.74283) (xy 278.078798 -71.789343)
			(xy 278.041581 -71.83088) (xy 277.998713 -71.866555) (xy 277.951107 -71.895609) (xy 277.899778 -71.917421)
			(xy 277.845821 -71.931527) (xy 277.790384 -71.937627) (xy 277.73465 -71.93559) (xy 277.679807 -71.92546)
			(xy 277.627023 -71.907453) (xy 277.577423 -71.881952) (xy 277.532065 -71.849501) (xy 277.491916 -71.810792)
			(xy 277.45783 -71.766649) (xy 277.430534 -71.718014) (xy 277.410611 -71.665923) (xy 277.398485 -71.611486)
			(xy 277.394414 -71.555864) (xy 273.184485 -71.555864) (xy 273.753326 -78.642972) (xy 273.753961 -78.649096)
			(xy 273.757817 -78.660784) (xy 273.760946 -78.666086) (xy 273.762216 -78.667864) (xy 273.778076 -78.691587)
			(xy 273.803329 -78.742758) (xy 273.820674 -78.797121) (xy 273.823943 -78.81747) (xy 277.361394 -78.81747)
			(xy 277.365465 -78.761848) (xy 277.377591 -78.707411) (xy 277.397514 -78.65532) (xy 277.42481 -78.606685)
			(xy 277.458896 -78.562542) (xy 277.499045 -78.523833) (xy 277.544403 -78.491382) (xy 277.594003 -78.465881)
			(xy 277.646787 -78.447874) (xy 277.70163 -78.437744) (xy 277.757364 -78.435707) (xy 277.812801 -78.441807)
			(xy 277.866758 -78.455913) (xy 277.918087 -78.477725) (xy 277.965693 -78.506779) (xy 278.008561 -78.542454)
			(xy 278.045778 -78.583991) (xy 278.076551 -78.630504) (xy 278.100223 -78.681001) (xy 278.116291 -78.734408)
			(xy 278.124411 -78.789584) (xy 278.12492 -78.81747) (xy 278.124411 -78.845356) (xy 278.116291 -78.900532)
			(xy 278.100223 -78.953939) (xy 278.076551 -79.004436) (xy 278.045778 -79.050949) (xy 278.008561 -79.092486)
			(xy 277.965693 -79.128161) (xy 277.918087 -79.157215) (xy 277.866758 -79.179027) (xy 277.812801 -79.193133)
			(xy 277.757364 -79.199233) (xy 277.70163 -79.197196) (xy 277.646787 -79.187066) (xy 277.594003 -79.169059)
			(xy 277.544403 -79.143558) (xy 277.499045 -79.111107) (xy 277.458896 -79.072398) (xy 277.42481 -79.028255)
			(xy 277.397514 -78.97962) (xy 277.377591 -78.927529) (xy 277.365465 -78.873092) (xy 277.361394 -78.81747)
			(xy 273.823943 -78.81747) (xy 273.829726 -78.853461) (xy 273.830542 -78.881986) (xy 273.830542 -78.889098)
			(xy 273.82851 -78.926944) (xy 273.828002 -78.929992) (xy 273.826224 -78.9432) (xy 273.826224 -78.943708)
			(xy 273.820636 -78.971648) (xy 273.820636 -78.972156) (xy 273.817842 -78.983332) (xy 273.813028 -79.00071)
			(xy 273.800558 -79.034547) (xy 273.79295 -79.050896) (xy 273.79295 -79.05115) (xy 273.790541 -79.056679)
			(xy 273.788095 -79.068487) (xy 273.788124 -79.074518) (xy 273.812 -79.370682) (xy 273.812833 -79.377734)
			(xy 273.817857 -79.39101) (xy 273.821906 -79.396844) (xy 273.830542 -79.408274) (xy 273.840448 -79.412084)
			(xy 273.867371 -79.422355) (xy 273.91802 -79.449832) (xy 273.963964 -79.484608) (xy 274.00416 -79.525895)
			(xy 274.037695 -79.572753) (xy 274.063807 -79.624119) (xy 274.081903 -79.678825) (xy 274.091572 -79.73563)
			(xy 274.092594 -79.793243) (xy 274.084946 -79.850355) (xy 274.07743 -79.878174) (xy 274.068683 -79.906226)
			(xy 274.043774 -79.959444) (xy 274.011003 -80.008215) (xy 273.971143 -80.051386) (xy 273.925136 -80.087937)
			(xy 273.899884 -80.102964) (xy 273.89963 -80.102964) (xy 273.897598 -80.104234) (xy 273.890011 -80.109498)
			(xy 273.87894 -80.124258) (xy 273.873861 -80.141996) (xy 273.87423 -80.151224) (xy 273.914362 -80.649826)
			(xy 273.915124 -80.658462) (xy 273.916142 -80.665262) (xy 273.921299 -80.678004) (xy 273.925284 -80.683608)
			(xy 273.9263 -80.684878) (xy 273.929856 -80.689196) (xy 273.93265 -80.692752) (xy 273.93773 -80.697324)
			(xy 273.946112 -80.702658) (xy 273.962114 -80.710278) (xy 273.964908 -80.711548) (xy 273.972274 -80.714342)
			(xy 273.983196 -80.716628) (xy 273.988022 -80.716882) (xy 274.010628 -80.716882) (xy 274.014946 -80.716628)
			(xy 274.026122 -80.714596) (xy 274.03679 -80.710786) (xy 274.039584 -80.709262) (xy 274.04822 -80.70469)
			(xy 274.071459 -80.693292) (xy 274.119964 -80.675216) (xy 274.144994 -80.668622) (xy 274.167641 -80.663273)
			(xy 274.213705 -80.656656) (xy 274.236942 -80.655414) (xy 274.238974 -80.655414) (xy 274.24126 -80.65516)
			(xy 274.254976 -80.65516) (xy 274.255992 -80.65516) (xy 274.285961 -80.65565) (xy 274.345386 -80.663472)
			(xy 274.403281 -80.678983) (xy 274.458657 -80.701918) (xy 274.510565 -80.731885) (xy 274.558118 -80.768371)
			(xy 274.600502 -80.810752) (xy 274.636992 -80.858301) (xy 274.666964 -80.910207) (xy 274.689904 -80.965581)
			(xy 274.705421 -81.023475) (xy 274.713248 -81.082899) (xy 274.7137 -81.112868) (xy 274.7137 -81.976468)
			(xy 274.713233 -82.006438) (xy 274.705413 -82.065866) (xy 274.689902 -82.123765) (xy 274.666967 -82.179144)
			(xy 274.636999 -82.231055) (xy 274.600511 -82.27861) (xy 274.558128 -82.320995) (xy 274.510575 -82.357485)
			(xy 274.458665 -82.387456) (xy 274.403288 -82.410395) (xy 274.34539 -82.425908) (xy 274.285962 -82.433731)
			(xy 274.255992 -82.434176) (xy 274.243459 -82.434138) (xy 274.218426 -82.432866) (xy 274.205954 -82.431636)
			(xy 274.174204 -82.427064) (xy 274.173696 -82.427064) (xy 274.149312 -82.42173) (xy 274.142962 -82.420206)
			(xy 274.13077 -82.42046) (xy 274.122896 -82.422492) (xy 274.11787 -82.423978) (xy 274.10852 -82.42871)
			(xy 274.104354 -82.43189) (xy 274.078192 -82.454496) (xy 274.071781 -82.461027) (xy 274.063708 -82.477436)
			(xy 274.062444 -82.4865) (xy 274.062444 -82.49539) (xy 274.08378 -82.760312) (xy 274.096226 -82.913982)
			(xy 274.097937 -82.923965) (xy 274.108021 -82.941513) (xy 274.115784 -82.948018) (xy 274.12061 -82.95132)
			(xy 274.162266 -82.974942) (xy 274.17522 -82.975196) (xy 274.18792 -82.97545) (xy 274.199604 -82.969608)
			(xy 274.199858 -82.969354) (xy 274.224194 -82.957324) (xy 274.275086 -82.938427) (xy 274.327853 -82.925669)
			(xy 274.381757 -82.919227) (xy 274.4089 -82.918808) (xy 274.409154 -82.918808) (xy 274.439142 -82.919274)
			(xy 274.498607 -82.927097) (xy 274.556541 -82.942615) (xy 274.611954 -82.965562) (xy 274.663898 -82.995545)
			(xy 274.711484 -83.032053) (xy 274.753897 -83.074459) (xy 274.790413 -83.122039) (xy 274.820405 -83.173978)
			(xy 274.843361 -83.229387) (xy 274.84542 -83.23707) (xy 281.247848 -83.23707) (xy 281.251919 -83.181448)
			(xy 281.264045 -83.127011) (xy 281.283968 -83.07492) (xy 281.311264 -83.026285) (xy 281.34535 -82.982142)
			(xy 281.385499 -82.943433) (xy 281.430857 -82.910982) (xy 281.480457 -82.885481) (xy 281.533241 -82.867474)
			(xy 281.588084 -82.857344) (xy 281.643818 -82.855307) (xy 281.699255 -82.861407) (xy 281.753212 -82.875513)
			(xy 281.804541 -82.897325) (xy 281.852147 -82.926379) (xy 281.895015 -82.962054) (xy 281.932232 -83.003591)
			(xy 281.963005 -83.050104) (xy 281.986677 -83.100601) (xy 282.002745 -83.154008) (xy 282.010865 -83.209184)
			(xy 282.011374 -83.23707) (xy 282.010865 -83.264956) (xy 282.002745 -83.320132) (xy 281.986677 -83.373539)
			(xy 281.963005 -83.424036) (xy 281.932232 -83.470549) (xy 281.895015 -83.512086) (xy 281.852147 -83.547761)
			(xy 281.822262 -83.566) (xy 282.827982 -83.566) (xy 282.832053 -83.510378) (xy 282.844179 -83.455941)
			(xy 282.864102 -83.40385) (xy 282.891398 -83.355215) (xy 282.925484 -83.311072) (xy 282.965633 -83.272363)
			(xy 283.010991 -83.239912) (xy 283.060591 -83.214411) (xy 283.113375 -83.196404) (xy 283.168218 -83.186274)
			(xy 283.223952 -83.184237) (xy 283.279389 -83.190337) (xy 283.333346 -83.204443) (xy 283.384675 -83.226255)
			(xy 283.432281 -83.255309) (xy 283.475149 -83.290984) (xy 283.512366 -83.332521) (xy 283.543139 -83.379034)
			(xy 283.566811 -83.429531) (xy 283.582879 -83.482938) (xy 283.590999 -83.538114) (xy 283.591508 -83.566)
			(xy 283.590999 -83.593886) (xy 283.582879 -83.649062) (xy 283.566811 -83.702469) (xy 283.543139 -83.752966)
			(xy 283.512366 -83.799479) (xy 283.475149 -83.841016) (xy 283.432281 -83.876691) (xy 283.384675 -83.905745)
			(xy 283.333346 -83.927557) (xy 283.279389 -83.941663) (xy 283.223952 -83.947763) (xy 283.168218 -83.945726)
			(xy 283.113375 -83.935596) (xy 283.060591 -83.917589) (xy 283.010991 -83.892088) (xy 282.965633 -83.859637)
			(xy 282.925484 -83.820928) (xy 282.891398 -83.776785) (xy 282.864102 -83.72815) (xy 282.844179 -83.676059)
			(xy 282.832053 -83.621622) (xy 282.827982 -83.566) (xy 281.822262 -83.566) (xy 281.804541 -83.576815)
			(xy 281.753212 -83.598627) (xy 281.699255 -83.612733) (xy 281.643818 -83.618833) (xy 281.588084 -83.616796)
			(xy 281.533241 -83.606666) (xy 281.480457 -83.588659) (xy 281.430857 -83.563158) (xy 281.385499 -83.530707)
			(xy 281.34535 -83.491998) (xy 281.311264 -83.447855) (xy 281.283968 -83.39922) (xy 281.264045 -83.347129)
			(xy 281.251919 -83.292692) (xy 281.247848 -83.23707) (xy 274.84542 -83.23707) (xy 274.858888 -83.287319)
			(xy 274.866721 -83.346782) (xy 274.867116 -83.37677) (xy 274.867116 -84.24037) (xy 274.866649 -84.270356)
			(xy 274.858824 -84.329815) (xy 274.843304 -84.387744) (xy 274.820355 -84.443151) (xy 274.79037 -84.495088)
			(xy 274.753862 -84.542667) (xy 274.711455 -84.585072) (xy 274.663875 -84.621579) (xy 274.611936 -84.651563)
			(xy 274.556528 -84.674509) (xy 274.498599 -84.690027) (xy 274.43914 -84.69785) (xy 274.409154 -84.698332)
			(xy 274.408138 -84.698332) (xy 274.407122 -84.698332) (xy 274.406868 -84.698332) (xy 274.385597 -84.698089)
			(xy 274.343237 -84.694143) (xy 274.322286 -84.690458) (xy 274.320254 -84.690204) (xy 274.308062 -84.688934)
			(xy 274.29918 -84.688484) (xy 274.281983 -84.692959) (xy 274.267345 -84.703034) (xy 274.261834 -84.710016)
			(xy 274.258278 -84.71535) (xy 274.254214 -84.721954) (xy 274.252944 -84.72424) (xy 274.250912 -84.727034)
			(xy 274.250404 -84.727796) (xy 274.24761 -84.731606) (xy 274.245578 -84.739734) (xy 274.244569 -84.743909)
			(xy 274.243804 -84.752464) (xy 274.244054 -84.756752) (xy 274.250411 -84.836) (xy 282.827982 -84.836)
			(xy 282.832053 -84.780378) (xy 282.844179 -84.725941) (xy 282.864102 -84.67385) (xy 282.891398 -84.625215)
			(xy 282.925484 -84.581072) (xy 282.965633 -84.542363) (xy 283.010991 -84.509912) (xy 283.060591 -84.484411)
			(xy 283.113375 -84.466404) (xy 283.168218 -84.456274) (xy 283.223952 -84.454237) (xy 283.279389 -84.460337)
			(xy 283.333346 -84.474443) (xy 283.384675 -84.496255) (xy 283.432281 -84.525309) (xy 283.475149 -84.560984)
			(xy 283.512366 -84.602521) (xy 283.543139 -84.649034) (xy 283.566811 -84.699531) (xy 283.582879 -84.752938)
			(xy 283.590999 -84.808114) (xy 283.591508 -84.836) (xy 283.590999 -84.863886) (xy 283.582879 -84.919062)
			(xy 283.566811 -84.972469) (xy 283.543139 -85.022966) (xy 283.512366 -85.069479) (xy 283.475149 -85.111016)
			(xy 283.432281 -85.146691) (xy 283.384675 -85.175745) (xy 283.333346 -85.197557) (xy 283.279389 -85.211663)
			(xy 283.223952 -85.217763) (xy 283.168218 -85.215726) (xy 283.113375 -85.205596) (xy 283.060591 -85.187589)
			(xy 283.010991 -85.162088) (xy 282.965633 -85.129637) (xy 282.925484 -85.090928) (xy 282.891398 -85.046785)
			(xy 282.864102 -84.99815) (xy 282.844179 -84.946059) (xy 282.832053 -84.891622) (xy 282.827982 -84.836)
			(xy 274.250411 -84.836) (xy 274.295848 -85.40242) (xy 288.626802 -85.40242) (xy 288.630873 -85.346798)
			(xy 288.642999 -85.292361) (xy 288.662922 -85.24027) (xy 288.690218 -85.191635) (xy 288.724304 -85.147492)
			(xy 288.764453 -85.108783) (xy 288.809811 -85.076332) (xy 288.859411 -85.050831) (xy 288.912195 -85.032824)
			(xy 288.967038 -85.022694) (xy 289.022772 -85.020657) (xy 289.078209 -85.026757) (xy 289.132166 -85.040863)
			(xy 289.183495 -85.062675) (xy 289.231101 -85.091729) (xy 289.273969 -85.127404) (xy 289.311186 -85.168941)
			(xy 289.341959 -85.215454) (xy 289.365631 -85.265951) (xy 289.381699 -85.319358) (xy 289.389819 -85.374534)
			(xy 289.390328 -85.40242) (xy 289.389819 -85.430306) (xy 289.381699 -85.485482) (xy 289.365631 -85.538889)
			(xy 289.341959 -85.589386) (xy 289.311186 -85.635899) (xy 289.273969 -85.677436) (xy 289.231101 -85.713111)
			(xy 289.183495 -85.742165) (xy 289.132166 -85.763977) (xy 289.078209 -85.778083) (xy 289.022772 -85.784183)
			(xy 288.967038 -85.782146) (xy 288.912195 -85.772016) (xy 288.859411 -85.754009) (xy 288.809811 -85.728508)
			(xy 288.764453 -85.696057) (xy 288.724304 -85.657348) (xy 288.690218 -85.613205) (xy 288.662922 -85.56457)
			(xy 288.642999 -85.512479) (xy 288.630873 -85.458042) (xy 288.626802 -85.40242) (xy 274.295848 -85.40242)
			(xy 274.388351 -86.55558) (xy 274.52142 -86.55558) (xy 274.525491 -86.499958) (xy 274.537617 -86.445521)
			(xy 274.55754 -86.39343) (xy 274.584836 -86.344795) (xy 274.618922 -86.300652) (xy 274.659071 -86.261943)
			(xy 274.704429 -86.229492) (xy 274.754029 -86.203991) (xy 274.806813 -86.185984) (xy 274.861656 -86.175854)
			(xy 274.91739 -86.173817) (xy 274.972827 -86.179917) (xy 275.026784 -86.194023) (xy 275.078113 -86.215835)
			(xy 275.125719 -86.244889) (xy 275.168587 -86.280564) (xy 275.197658 -86.31301) (xy 275.364192 -86.31301)
			(xy 275.368263 -86.257388) (xy 275.380389 -86.202951) (xy 275.400312 -86.15086) (xy 275.427608 -86.102225)
			(xy 275.461694 -86.058082) (xy 275.501843 -86.019373) (xy 275.547201 -85.986922) (xy 275.596801 -85.961421)
			(xy 275.649585 -85.943414) (xy 275.704428 -85.933284) (xy 275.760162 -85.931247) (xy 275.815599 -85.937347)
			(xy 275.869556 -85.951453) (xy 275.920885 -85.973265) (xy 275.968491 -86.002319) (xy 276.011359 -86.037994)
			(xy 276.048576 -86.079531) (xy 276.079349 -86.126044) (xy 276.103021 -86.176541) (xy 276.119089 -86.229948)
			(xy 276.127209 -86.285124) (xy 276.127718 -86.31301) (xy 276.127209 -86.340896) (xy 276.119089 -86.396072)
			(xy 276.105641 -86.440772) (xy 277.126698 -86.440772) (xy 277.130769 -86.38515) (xy 277.142895 -86.330713)
			(xy 277.162818 -86.278622) (xy 277.190114 -86.229987) (xy 277.2242 -86.185844) (xy 277.264349 -86.147135)
			(xy 277.309707 -86.114684) (xy 277.359307 -86.089183) (xy 277.412091 -86.071176) (xy 277.466934 -86.061046)
			(xy 277.522668 -86.059009) (xy 277.578105 -86.065109) (xy 277.632062 -86.079215) (xy 277.683391 -86.101027)
			(xy 277.730997 -86.130081) (xy 277.773865 -86.165756) (xy 277.811082 -86.207293) (xy 277.841855 -86.253806)
			(xy 277.865527 -86.304303) (xy 277.881595 -86.35771) (xy 277.889715 -86.412886) (xy 277.890224 -86.440772)
			(xy 277.889715 -86.468658) (xy 277.887875 -86.481158) (xy 278.503886 -86.481158) (xy 278.507957 -86.425536)
			(xy 278.520083 -86.371099) (xy 278.540006 -86.319008) (xy 278.567302 -86.270373) (xy 278.601388 -86.22623)
			(xy 278.641537 -86.187521) (xy 278.686895 -86.15507) (xy 278.736495 -86.129569) (xy 278.789279 -86.111562)
			(xy 278.844122 -86.101432) (xy 278.899856 -86.099395) (xy 278.955293 -86.105495) (xy 278.957225 -86.106)
			(xy 282.827982 -86.106) (xy 282.832053 -86.050378) (xy 282.844179 -85.995941) (xy 282.864102 -85.94385)
			(xy 282.891398 -85.895215) (xy 282.925484 -85.851072) (xy 282.965633 -85.812363) (xy 283.010991 -85.779912)
			(xy 283.060591 -85.754411) (xy 283.113375 -85.736404) (xy 283.168218 -85.726274) (xy 283.223952 -85.724237)
			(xy 283.279389 -85.730337) (xy 283.333346 -85.744443) (xy 283.384675 -85.766255) (xy 283.432281 -85.795309)
			(xy 283.475149 -85.830984) (xy 283.512366 -85.872521) (xy 283.543139 -85.919034) (xy 283.566811 -85.969531)
			(xy 283.582879 -86.022938) (xy 283.590999 -86.078114) (xy 283.591508 -86.106) (xy 283.590999 -86.133886)
			(xy 283.589571 -86.143592) (xy 290.59708 -86.143592) (xy 290.601151 -86.08797) (xy 290.613277 -86.033533)
			(xy 290.6332 -85.981442) (xy 290.660496 -85.932807) (xy 290.694582 -85.888664) (xy 290.734731 -85.849955)
			(xy 290.780089 -85.817504) (xy 290.829689 -85.792003) (xy 290.882473 -85.773996) (xy 290.937316 -85.763866)
			(xy 290.99305 -85.761829) (xy 291.048487 -85.767929) (xy 291.102444 -85.782035) (xy 291.153773 -85.803847)
			(xy 291.201379 -85.832901) (xy 291.244247 -85.868576) (xy 291.281464 -85.910113) (xy 291.312237 -85.956626)
			(xy 291.335909 -86.007123) (xy 291.351977 -86.06053) (xy 291.360097 -86.115706) (xy 291.360606 -86.143592)
			(xy 291.360097 -86.171478) (xy 291.351977 -86.226654) (xy 291.335909 -86.280061) (xy 291.312237 -86.330558)
			(xy 291.281464 -86.377071) (xy 291.244247 -86.418608) (xy 291.201379 -86.454283) (xy 291.153773 -86.483337)
			(xy 291.102444 -86.505149) (xy 291.048487 -86.519255) (xy 290.99305 -86.525355) (xy 290.937316 -86.523318)
			(xy 290.882473 -86.513188) (xy 290.829689 -86.495181) (xy 290.780089 -86.46968) (xy 290.734731 -86.437229)
			(xy 290.694582 -86.39852) (xy 290.660496 -86.354377) (xy 290.6332 -86.305742) (xy 290.613277 -86.253651)
			(xy 290.601151 -86.199214) (xy 290.59708 -86.143592) (xy 283.589571 -86.143592) (xy 283.582879 -86.189062)
			(xy 283.566811 -86.242469) (xy 283.543139 -86.292966) (xy 283.512366 -86.339479) (xy 283.475149 -86.381016)
			(xy 283.432281 -86.416691) (xy 283.384675 -86.445745) (xy 283.333346 -86.467557) (xy 283.279389 -86.481663)
			(xy 283.223952 -86.487763) (xy 283.168218 -86.485726) (xy 283.113375 -86.475596) (xy 283.060591 -86.457589)
			(xy 283.010991 -86.432088) (xy 282.965633 -86.399637) (xy 282.925484 -86.360928) (xy 282.891398 -86.316785)
			(xy 282.864102 -86.26815) (xy 282.844179 -86.216059) (xy 282.832053 -86.161622) (xy 282.827982 -86.106)
			(xy 278.957225 -86.106) (xy 279.00925 -86.119601) (xy 279.060579 -86.141413) (xy 279.108185 -86.170467)
			(xy 279.151053 -86.206142) (xy 279.18827 -86.247679) (xy 279.219043 -86.294192) (xy 279.242715 -86.344689)
			(xy 279.258783 -86.398096) (xy 279.266903 -86.453272) (xy 279.267412 -86.481158) (xy 279.267101 -86.498176)
			(xy 279.88971 -86.498176) (xy 279.893781 -86.442554) (xy 279.905907 -86.388117) (xy 279.92583 -86.336026)
			(xy 279.953126 -86.287391) (xy 279.987212 -86.243248) (xy 280.027361 -86.204539) (xy 280.072719 -86.172088)
			(xy 280.122319 -86.146587) (xy 280.175103 -86.12858) (xy 280.229946 -86.11845) (xy 280.28568 -86.116413)
			(xy 280.341117 -86.122513) (xy 280.395074 -86.136619) (xy 280.446403 -86.158431) (xy 280.494009 -86.187485)
			(xy 280.536877 -86.22316) (xy 280.574094 -86.264697) (xy 280.604867 -86.31121) (xy 280.628539 -86.361707)
			(xy 280.644607 -86.415114) (xy 280.652727 -86.47029) (xy 280.653236 -86.498176) (xy 280.652727 -86.526062)
			(xy 280.644607 -86.581238) (xy 280.628539 -86.634645) (xy 280.604867 -86.685142) (xy 280.574094 -86.731655)
			(xy 280.536877 -86.773192) (xy 280.494009 -86.808867) (xy 280.446403 -86.837921) (xy 280.395074 -86.859733)
			(xy 280.341117 -86.873839) (xy 280.28568 -86.879939) (xy 280.229946 -86.877902) (xy 280.175103 -86.867772)
			(xy 280.122319 -86.849765) (xy 280.072719 -86.824264) (xy 280.027361 -86.791813) (xy 279.987212 -86.753104)
			(xy 279.953126 -86.708961) (xy 279.92583 -86.660326) (xy 279.905907 -86.608235) (xy 279.893781 -86.553798)
			(xy 279.88971 -86.498176) (xy 279.267101 -86.498176) (xy 279.266903 -86.509044) (xy 279.258783 -86.56422)
			(xy 279.242715 -86.617627) (xy 279.219043 -86.668124) (xy 279.18827 -86.714637) (xy 279.151053 -86.756174)
			(xy 279.108185 -86.791849) (xy 279.060579 -86.820903) (xy 279.00925 -86.842715) (xy 278.955293 -86.856821)
			(xy 278.899856 -86.862921) (xy 278.844122 -86.860884) (xy 278.789279 -86.850754) (xy 278.736495 -86.832747)
			(xy 278.686895 -86.807246) (xy 278.641537 -86.774795) (xy 278.601388 -86.736086) (xy 278.567302 -86.691943)
			(xy 278.540006 -86.643308) (xy 278.520083 -86.591217) (xy 278.507957 -86.53678) (xy 278.503886 -86.481158)
			(xy 277.887875 -86.481158) (xy 277.881595 -86.523834) (xy 277.865527 -86.577241) (xy 277.841855 -86.627738)
			(xy 277.811082 -86.674251) (xy 277.773865 -86.715788) (xy 277.730997 -86.751463) (xy 277.683391 -86.780517)
			(xy 277.632062 -86.802329) (xy 277.578105 -86.816435) (xy 277.522668 -86.822535) (xy 277.466934 -86.820498)
			(xy 277.412091 -86.810368) (xy 277.359307 -86.792361) (xy 277.309707 -86.76686) (xy 277.264349 -86.734409)
			(xy 277.2242 -86.6957) (xy 277.190114 -86.651557) (xy 277.162818 -86.602922) (xy 277.142895 -86.550831)
			(xy 277.130769 -86.496394) (xy 277.126698 -86.440772) (xy 276.105641 -86.440772) (xy 276.103021 -86.449479)
			(xy 276.079349 -86.499976) (xy 276.048576 -86.546489) (xy 276.011359 -86.588026) (xy 275.968491 -86.623701)
			(xy 275.920885 -86.652755) (xy 275.869556 -86.674567) (xy 275.815599 -86.688673) (xy 275.760162 -86.694773)
			(xy 275.704428 -86.692736) (xy 275.649585 -86.682606) (xy 275.596801 -86.664599) (xy 275.547201 -86.639098)
			(xy 275.501843 -86.606647) (xy 275.461694 -86.567938) (xy 275.427608 -86.523795) (xy 275.400312 -86.47516)
			(xy 275.380389 -86.423069) (xy 275.368263 -86.368632) (xy 275.364192 -86.31301) (xy 275.197658 -86.31301)
			(xy 275.205804 -86.322101) (xy 275.236577 -86.368614) (xy 275.260249 -86.419111) (xy 275.276317 -86.472518)
			(xy 275.284437 -86.527694) (xy 275.284946 -86.55558) (xy 275.284437 -86.583466) (xy 275.276317 -86.638642)
			(xy 275.260249 -86.692049) (xy 275.236577 -86.742546) (xy 275.205804 -86.789059) (xy 275.168587 -86.830596)
			(xy 275.125719 -86.866271) (xy 275.078113 -86.895325) (xy 275.026784 -86.917137) (xy 274.972827 -86.931243)
			(xy 274.91739 -86.937343) (xy 274.861656 -86.935306) (xy 274.806813 -86.925176) (xy 274.754029 -86.907169)
			(xy 274.704429 -86.881668) (xy 274.659071 -86.849217) (xy 274.618922 -86.810508) (xy 274.584836 -86.766365)
			(xy 274.55754 -86.71773) (xy 274.537617 -86.665639) (xy 274.525491 -86.611202) (xy 274.52142 -86.55558)
			(xy 274.388351 -86.55558) (xy 274.457668 -87.419688) (xy 274.458314 -87.425663) (xy 274.462035 -87.437086)
			(xy 274.465034 -87.442294) (xy 274.479766 -87.465916) (xy 274.48764 -87.474044) (xy 274.492466 -87.477092)
			(xy 274.515094 -87.492319) (xy 274.556196 -87.528169) (xy 274.591777 -87.569504) (xy 274.621115 -87.615482)
			(xy 274.64361 -87.665167) (xy 274.658807 -87.717547) (xy 274.666394 -87.771556) (xy 274.666219 -87.826096)
			(xy 274.658284 -87.880056) (xy 274.642751 -87.932337) (xy 274.619936 -87.981876) (xy 274.590304 -88.027664)
			(xy 274.554457 -88.068769) (xy 274.534122 -88.086946) (xy 274.532598 -88.088216) (xy 274.532344 -88.08847)
			(xy 274.524172 -88.096391) (xy 274.515081 -88.117223) (xy 274.514818 -88.128602) (xy 274.52574 -88.262206)
			(xy 274.527452 -88.271527) (xy 274.536749 -88.288028) (xy 274.551412 -88.300015) (xy 274.560284 -88.303354)
			(xy 274.658074 -88.328754) (xy 274.667534 -88.330327) (xy 274.68642 -88.327086) (xy 274.70278 -88.317109)
			(xy 274.708874 -88.309704) (xy 274.724104 -88.287426) (xy 274.759832 -88.246984) (xy 274.800895 -88.211971)
			(xy 274.846476 -88.183083) (xy 274.895667 -88.160894) (xy 274.947491 -88.145848) (xy 275.000916 -88.138241)
			(xy 275.027898 -88.137746) (xy 275.055154 -88.138209) (xy 275.109112 -88.145967) (xy 275.161416 -88.161324)
			(xy 275.211003 -88.183969) (xy 275.256862 -88.213441) (xy 275.29806 -88.249139) (xy 275.333758 -88.290337)
			(xy 275.36323 -88.336195) (xy 275.385875 -88.385782) (xy 275.401233 -88.438086) (xy 275.408991 -88.492044)
			(xy 275.408991 -88.546556) (xy 275.401233 -88.600514) (xy 275.385875 -88.652818) (xy 275.36323 -88.702405)
			(xy 275.333758 -88.748263) (xy 275.29806 -88.789461) (xy 275.256862 -88.825159) (xy 275.211003 -88.854631)
			(xy 275.161416 -88.877276) (xy 275.109112 -88.892633) (xy 275.055154 -88.900391) (xy 275.027898 -88.900762)
			(xy 275.001764 -88.900333) (xy 274.949985 -88.893198) (xy 274.899665 -88.879063) (xy 274.851745 -88.858191)
			(xy 274.807122 -88.830973) (xy 274.766633 -88.79792) (xy 274.748498 -88.779096) (xy 274.744434 -88.774778)
			(xy 274.740505 -88.77162) (xy 274.731678 -88.766756) (xy 274.726908 -88.765126) (xy 274.718077 -88.762805)
			(xy 274.699862 -88.763857) (xy 274.691348 -88.767158) (xy 274.60321 -88.80602) (xy 274.594245 -88.810481)
			(xy 274.580376 -88.824896) (xy 274.573048 -88.84351) (xy 274.57273 -88.853518) (xy 274.645274 -89.756996)
			(xy 277.128476 -89.756996) (xy 277.132547 -89.701374) (xy 277.144673 -89.646937) (xy 277.164596 -89.594846)
			(xy 277.191892 -89.546211) (xy 277.225978 -89.502068) (xy 277.266127 -89.463359) (xy 277.311485 -89.430908)
			(xy 277.361085 -89.405407) (xy 277.413869 -89.3874) (xy 277.468712 -89.37727) (xy 277.524446 -89.375233)
			(xy 277.579883 -89.381333) (xy 277.63384 -89.395439) (xy 277.685169 -89.417251) (xy 277.732775 -89.446305)
			(xy 277.775643 -89.48198) (xy 277.81286 -89.523517) (xy 277.843633 -89.57003) (xy 277.867305 -89.620527)
			(xy 277.883373 -89.673934) (xy 277.891493 -89.72911) (xy 277.892002 -89.756996) (xy 277.891863 -89.764616)
			(xy 278.724612 -89.764616) (xy 278.728683 -89.708994) (xy 278.740809 -89.654557) (xy 278.760732 -89.602466)
			(xy 278.788028 -89.553831) (xy 278.822114 -89.509688) (xy 278.862263 -89.470979) (xy 278.907621 -89.438528)
			(xy 278.957221 -89.413027) (xy 279.010005 -89.39502) (xy 279.064848 -89.38489) (xy 279.120582 -89.382853)
			(xy 279.176019 -89.388953) (xy 279.229976 -89.403059) (xy 279.281305 -89.424871) (xy 279.328911 -89.453925)
			(xy 279.371779 -89.4896) (xy 279.408996 -89.531137) (xy 279.439769 -89.57765) (xy 279.463441 -89.628147)
			(xy 279.479509 -89.681554) (xy 279.487629 -89.73673) (xy 279.488138 -89.764616) (xy 279.487674 -89.790016)
			(xy 280.29103 -89.790016) (xy 280.295101 -89.734394) (xy 280.307227 -89.679957) (xy 280.32715 -89.627866)
			(xy 280.354446 -89.579231) (xy 280.388532 -89.535088) (xy 280.428681 -89.496379) (xy 280.474039 -89.463928)
			(xy 280.523639 -89.438427) (xy 280.576423 -89.42042) (xy 280.631266 -89.41029) (xy 280.687 -89.408253)
			(xy 280.742437 -89.414353) (xy 280.796394 -89.428459) (xy 280.847723 -89.450271) (xy 280.895329 -89.479325)
			(xy 280.938197 -89.515) (xy 280.975414 -89.556537) (xy 281.006187 -89.60305) (xy 281.029859 -89.653547)
			(xy 281.045927 -89.706954) (xy 281.054047 -89.76213) (xy 281.054556 -89.790016) (xy 281.054047 -89.817902)
			(xy 281.045927 -89.873078) (xy 281.029859 -89.926485) (xy 281.006187 -89.976982) (xy 280.975414 -90.023495)
			(xy 280.938197 -90.065032) (xy 280.895329 -90.100707) (xy 280.847723 -90.129761) (xy 280.796394 -90.151573)
			(xy 280.742437 -90.165679) (xy 280.687 -90.171779) (xy 280.631266 -90.169742) (xy 280.576423 -90.159612)
			(xy 280.523639 -90.141605) (xy 280.474039 -90.116104) (xy 280.428681 -90.083653) (xy 280.388532 -90.044944)
			(xy 280.354446 -90.000801) (xy 280.32715 -89.952166) (xy 280.307227 -89.900075) (xy 280.295101 -89.845638)
			(xy 280.29103 -89.790016) (xy 279.487674 -89.790016) (xy 279.487629 -89.792502) (xy 279.479509 -89.847678)
			(xy 279.463441 -89.901085) (xy 279.439769 -89.951582) (xy 279.408996 -89.998095) (xy 279.371779 -90.039632)
			(xy 279.328911 -90.075307) (xy 279.281305 -90.104361) (xy 279.229976 -90.126173) (xy 279.176019 -90.140279)
			(xy 279.120582 -90.146379) (xy 279.064848 -90.144342) (xy 279.010005 -90.134212) (xy 278.957221 -90.116205)
			(xy 278.907621 -90.090704) (xy 278.862263 -90.058253) (xy 278.822114 -90.019544) (xy 278.788028 -89.975401)
			(xy 278.760732 -89.926766) (xy 278.740809 -89.874675) (xy 278.728683 -89.820238) (xy 278.724612 -89.764616)
			(xy 277.891863 -89.764616) (xy 277.891493 -89.784882) (xy 277.883373 -89.840058) (xy 277.867305 -89.893465)
			(xy 277.843633 -89.943962) (xy 277.81286 -89.990475) (xy 277.775643 -90.032012) (xy 277.732775 -90.067687)
			(xy 277.685169 -90.096741) (xy 277.63384 -90.118553) (xy 277.579883 -90.132659) (xy 277.524446 -90.138759)
			(xy 277.468712 -90.136722) (xy 277.413869 -90.126592) (xy 277.361085 -90.108585) (xy 277.311485 -90.083084)
			(xy 277.266127 -90.050633) (xy 277.225978 -90.011924) (xy 277.191892 -89.967781) (xy 277.164596 -89.919146)
			(xy 277.144673 -89.867055) (xy 277.132547 -89.812618) (xy 277.128476 -89.756996) (xy 274.645274 -89.756996)
			(xy 274.894802 -92.864686) (xy 275.011526 -94.31909) (xy 277.453596 -94.31909) (xy 277.457667 -94.263468)
			(xy 277.469793 -94.209031) (xy 277.489716 -94.15694) (xy 277.517012 -94.108305) (xy 277.551098 -94.064162)
			(xy 277.591247 -94.025453) (xy 277.636605 -93.993002) (xy 277.686205 -93.967501) (xy 277.738989 -93.949494)
			(xy 277.793832 -93.939364) (xy 277.849566 -93.937327) (xy 277.905003 -93.943427) (xy 277.95896 -93.957533)
			(xy 278.010289 -93.979345) (xy 278.057895 -94.008399) (xy 278.100763 -94.044074) (xy 278.13798 -94.085611)
			(xy 278.168753 -94.132124) (xy 278.192425 -94.182621) (xy 278.208493 -94.236028) (xy 278.216613 -94.291204)
			(xy 278.217122 -94.31909) (xy 278.216613 -94.346976) (xy 278.208493 -94.402152) (xy 278.192425 -94.455559)
			(xy 278.168753 -94.506056) (xy 278.13798 -94.552569) (xy 278.100763 -94.594106) (xy 278.057895 -94.629781)
			(xy 278.010289 -94.658835) (xy 277.95896 -94.680647) (xy 277.905003 -94.694753) (xy 277.849566 -94.700853)
			(xy 277.793832 -94.698816) (xy 277.738989 -94.688686) (xy 277.686205 -94.670679) (xy 277.636605 -94.645178)
			(xy 277.591247 -94.612727) (xy 277.551098 -94.574018) (xy 277.517012 -94.529875) (xy 277.489716 -94.48124)
			(xy 277.469793 -94.429149) (xy 277.457667 -94.374712) (xy 277.453596 -94.31909) (xy 275.011526 -94.31909)
			(xy 275.082364 -95.20174) (xy 276.739856 -95.20174) (xy 276.743927 -95.146118) (xy 276.756053 -95.091681)
			(xy 276.775976 -95.03959) (xy 276.803272 -94.990955) (xy 276.837358 -94.946812) (xy 276.877507 -94.908103)
			(xy 276.922865 -94.875652) (xy 276.972465 -94.850151) (xy 277.025249 -94.832144) (xy 277.080092 -94.822014)
			(xy 277.135826 -94.819977) (xy 277.191263 -94.826077) (xy 277.24522 -94.840183) (xy 277.296549 -94.861995)
			(xy 277.344155 -94.891049) (xy 277.387023 -94.926724) (xy 277.42424 -94.968261) (xy 277.455013 -95.014774)
			(xy 277.478685 -95.065271) (xy 277.494753 -95.118678) (xy 277.502873 -95.173854) (xy 277.503382 -95.20174)
			(xy 277.503141 -95.214948) (xy 279.474181 -95.214948) (xy 279.478136 -95.123111) (xy 279.489971 -95.031954)
			(xy 279.509598 -94.942151) (xy 279.536872 -94.854369) (xy 279.571592 -94.769255) (xy 279.6135 -94.687442)
			(xy 279.662286 -94.609534) (xy 279.717589 -94.536109) (xy 279.778999 -94.467709) (xy 279.846061 -94.404842)
			(xy 279.91828 -94.347972) (xy 279.99512 -94.297521) (xy 280.076013 -94.253862) (xy 280.160359 -94.217319)
			(xy 280.247535 -94.188162) (xy 280.336894 -94.166608) (xy 280.427775 -94.152814) (xy 280.519506 -94.146884)
			(xy 280.611407 -94.148862) (xy 280.702798 -94.158733) (xy 280.793002 -94.176423) (xy 280.881351 -94.201803)
			(xy 280.967191 -94.234683) (xy 281.049887 -94.274821) (xy 281.128827 -94.32192) (xy 281.203425 -94.37563)
			(xy 281.273131 -94.435554) (xy 281.337426 -94.501248) (xy 281.395837 -94.572226) (xy 281.447929 -94.647963)
			(xy 281.493318 -94.727898) (xy 281.531668 -94.811438) (xy 281.562693 -94.897966) (xy 281.586166 -94.986841)
			(xy 281.601912 -95.077405) (xy 281.609814 -95.168987) (xy 281.610308 -95.214948) (xy 281.609814 -95.260909)
			(xy 281.601912 -95.352491) (xy 281.586166 -95.443055) (xy 281.562693 -95.53193) (xy 281.531668 -95.618458)
			(xy 281.493318 -95.701998) (xy 281.447929 -95.781933) (xy 281.395837 -95.85767) (xy 281.337426 -95.928648)
			(xy 281.273131 -95.994342) (xy 281.203425 -96.054266) (xy 281.128827 -96.107976) (xy 281.049887 -96.155075)
			(xy 280.967191 -96.195213) (xy 280.881351 -96.228093) (xy 280.793002 -96.253473) (xy 280.702798 -96.271163)
			(xy 280.611407 -96.281034) (xy 280.519506 -96.283012) (xy 280.427775 -96.277082) (xy 280.336894 -96.263288)
			(xy 280.247535 -96.241734) (xy 280.160359 -96.212577) (xy 280.076013 -96.176034) (xy 279.99512 -96.132375)
			(xy 279.91828 -96.081924) (xy 279.846061 -96.025054) (xy 279.778999 -95.962187) (xy 279.717589 -95.893787)
			(xy 279.662286 -95.820362) (xy 279.6135 -95.742454) (xy 279.571592 -95.660641) (xy 279.536872 -95.575527)
			(xy 279.509598 -95.487745) (xy 279.489971 -95.397942) (xy 279.478136 -95.306785) (xy 279.474181 -95.214948)
			(xy 277.503141 -95.214948) (xy 277.502873 -95.229626) (xy 277.494753 -95.284802) (xy 277.478685 -95.338209)
			(xy 277.455013 -95.388706) (xy 277.42424 -95.435219) (xy 277.387023 -95.476756) (xy 277.344155 -95.512431)
			(xy 277.296549 -95.541485) (xy 277.24522 -95.563297) (xy 277.191263 -95.577403) (xy 277.135826 -95.583503)
			(xy 277.080092 -95.581466) (xy 277.025249 -95.571336) (xy 276.972465 -95.553329) (xy 276.922865 -95.527828)
			(xy 276.877507 -95.495377) (xy 276.837358 -95.456668) (xy 276.803272 -95.412525) (xy 276.775976 -95.36389)
			(xy 276.756053 -95.311799) (xy 276.743927 -95.257362) (xy 276.739856 -95.20174) (xy 275.082364 -95.20174)
			(xy 275.231154 -97.055686) (xy 283.805374 -97.055686) (xy 283.809445 -97.000064) (xy 283.821571 -96.945627)
			(xy 283.841494 -96.893536) (xy 283.86879 -96.844901) (xy 283.902876 -96.800758) (xy 283.943025 -96.762049)
			(xy 283.988383 -96.729598) (xy 284.037983 -96.704097) (xy 284.090767 -96.68609) (xy 284.14561 -96.67596)
			(xy 284.201344 -96.673923) (xy 284.256781 -96.680023) (xy 284.310738 -96.694129) (xy 284.362067 -96.715941)
			(xy 284.409673 -96.744995) (xy 284.452541 -96.78067) (xy 284.489758 -96.822207) (xy 284.520531 -96.86872)
			(xy 284.544203 -96.919217) (xy 284.560271 -96.972624) (xy 284.568391 -97.0278) (xy 284.5689 -97.055686)
			(xy 284.568391 -97.083572) (xy 284.560271 -97.138748) (xy 284.544203 -97.192155) (xy 284.520531 -97.242652)
			(xy 284.489758 -97.289165) (xy 284.452541 -97.330702) (xy 284.409673 -97.366377) (xy 284.362067 -97.395431)
			(xy 284.310738 -97.417243) (xy 284.256781 -97.431349) (xy 284.201344 -97.437449) (xy 284.14561 -97.435412)
			(xy 284.090767 -97.425282) (xy 284.037983 -97.407275) (xy 283.988383 -97.381774) (xy 283.943025 -97.349323)
			(xy 283.902876 -97.310614) (xy 283.86879 -97.266471) (xy 283.841494 -97.217836) (xy 283.821571 -97.165745)
			(xy 283.809445 -97.111308) (xy 283.805374 -97.055686) (xy 275.231154 -97.055686) (xy 275.481604 -100.17633)
			(xy 285.8389 -100.17633) (xy 285.8389 -99.31273) (xy 285.83939 -99.282746) (xy 285.847218 -99.22329)
			(xy 285.862739 -99.165365) (xy 285.885688 -99.109961) (xy 285.915672 -99.058027) (xy 285.952178 -99.010451)
			(xy 285.994583 -98.968046) (xy 286.042159 -98.93154) (xy 286.094093 -98.901556) (xy 286.149497 -98.878607)
			(xy 286.207422 -98.863086) (xy 286.266878 -98.855258) (xy 286.326846 -98.855258) (xy 286.386302 -98.863086)
			(xy 286.444227 -98.878607) (xy 286.499631 -98.901556) (xy 286.551565 -98.93154) (xy 286.599141 -98.968046)
			(xy 286.641546 -99.010451) (xy 286.678052 -99.058027) (xy 286.708036 -99.109961) (xy 286.730985 -99.165365)
			(xy 286.746506 -99.22329) (xy 286.754334 -99.282746) (xy 286.754824 -99.31273) (xy 286.754824 -100.17633)
			(xy 286.754334 -100.206314) (xy 286.746506 -100.26577) (xy 286.730985 -100.323695) (xy 286.708036 -100.379099)
			(xy 286.678052 -100.431033) (xy 286.641546 -100.478609) (xy 286.599141 -100.521014) (xy 286.551565 -100.55752)
			(xy 286.499631 -100.587504) (xy 286.444227 -100.610453) (xy 286.386302 -100.625974) (xy 286.326846 -100.633802)
			(xy 286.266878 -100.633802) (xy 286.207422 -100.625974) (xy 286.149497 -100.610453) (xy 286.094093 -100.587504)
			(xy 286.042159 -100.55752) (xy 285.994583 -100.521014) (xy 285.952178 -100.478609) (xy 285.915672 -100.431033)
			(xy 285.885688 -100.379099) (xy 285.862739 -100.323695) (xy 285.847218 -100.26577) (xy 285.83939 -100.206314)
			(xy 285.8389 -100.17633) (xy 275.481604 -100.17633) (xy 275.626073 -101.976428) (xy 283.9847 -101.976428)
			(xy 283.9847 -101.112828) (xy 283.98519 -101.082844) (xy 283.993018 -101.023388) (xy 284.008539 -100.965463)
			(xy 284.031488 -100.910059) (xy 284.061472 -100.858125) (xy 284.097978 -100.810549) (xy 284.140383 -100.768144)
			(xy 284.187959 -100.731638) (xy 284.239893 -100.701654) (xy 284.295297 -100.678705) (xy 284.353222 -100.663184)
			(xy 284.412678 -100.655356) (xy 284.472646 -100.655356) (xy 284.532102 -100.663184) (xy 284.590027 -100.678705)
			(xy 284.645431 -100.701654) (xy 284.697365 -100.731638) (xy 284.742632 -100.766372) (xy 289.797742 -100.766372)
			(xy 289.801813 -100.71075) (xy 289.813939 -100.656313) (xy 289.833862 -100.604222) (xy 289.861158 -100.555587)
			(xy 289.895244 -100.511444) (xy 289.935393 -100.472735) (xy 289.980751 -100.440284) (xy 290.030351 -100.414783)
			(xy 290.083135 -100.396776) (xy 290.137978 -100.386646) (xy 290.193712 -100.384609) (xy 290.249149 -100.390709)
			(xy 290.303106 -100.404815) (xy 290.354435 -100.426627) (xy 290.402041 -100.455681) (xy 290.444909 -100.491356)
			(xy 290.482126 -100.532893) (xy 290.512899 -100.579406) (xy 290.536571 -100.629903) (xy 290.552639 -100.68331)
			(xy 290.560759 -100.738486) (xy 290.561268 -100.766372) (xy 290.560759 -100.794258) (xy 290.552639 -100.849434)
			(xy 290.536571 -100.902841) (xy 290.512899 -100.953338) (xy 290.482126 -100.999851) (xy 290.444909 -101.041388)
			(xy 290.402041 -101.077063) (xy 290.354435 -101.106117) (xy 290.303106 -101.127929) (xy 290.249149 -101.142035)
			(xy 290.193712 -101.148135) (xy 290.137978 -101.146098) (xy 290.083135 -101.135968) (xy 290.030351 -101.117961)
			(xy 289.980751 -101.09246) (xy 289.935393 -101.060009) (xy 289.895244 -101.0213) (xy 289.861158 -100.977157)
			(xy 289.833862 -100.928522) (xy 289.813939 -100.876431) (xy 289.801813 -100.821994) (xy 289.797742 -100.766372)
			(xy 284.742632 -100.766372) (xy 284.744941 -100.768144) (xy 284.787346 -100.810549) (xy 284.823852 -100.858125)
			(xy 284.853836 -100.910059) (xy 284.876785 -100.965463) (xy 284.892306 -101.023388) (xy 284.900134 -101.082844)
			(xy 284.900624 -101.112828) (xy 284.900624 -101.976428) (xy 284.900134 -102.006412) (xy 284.892306 -102.065868)
			(xy 284.876785 -102.123793) (xy 284.853836 -102.179197) (xy 284.823852 -102.231131) (xy 284.787346 -102.278707)
			(xy 284.744941 -102.321112) (xy 284.697365 -102.357618) (xy 284.645431 -102.387602) (xy 284.590027 -102.410551)
			(xy 284.532102 -102.426072) (xy 284.472646 -102.4339) (xy 284.412678 -102.4339) (xy 284.353222 -102.426072)
			(xy 284.295297 -102.410551) (xy 284.239893 -102.387602) (xy 284.187959 -102.357618) (xy 284.140383 -102.321112)
			(xy 284.097978 -102.278707) (xy 284.061472 -102.231131) (xy 284.031488 -102.179197) (xy 284.008539 -102.123793)
			(xy 283.993018 -102.065868) (xy 283.98519 -102.006412) (xy 283.9847 -101.976428) (xy 275.626073 -101.976428)
			(xy 275.770521 -103.776272) (xy 285.8389 -103.776272) (xy 285.8389 -102.912672) (xy 285.83939 -102.882688)
			(xy 285.847218 -102.823232) (xy 285.862739 -102.765307) (xy 285.885688 -102.709903) (xy 285.915672 -102.657969)
			(xy 285.952178 -102.610393) (xy 285.994583 -102.567988) (xy 286.042159 -102.531482) (xy 286.094093 -102.501498)
			(xy 286.149497 -102.478549) (xy 286.207422 -102.463028) (xy 286.266878 -102.4552) (xy 286.326846 -102.4552)
			(xy 286.386302 -102.463028) (xy 286.444227 -102.478549) (xy 286.499631 -102.501498) (xy 286.551565 -102.531482)
			(xy 286.599141 -102.567988) (xy 286.641546 -102.610393) (xy 286.678052 -102.657969) (xy 286.708036 -102.709903)
			(xy 286.730985 -102.765307) (xy 286.746506 -102.823232) (xy 286.754334 -102.882688) (xy 286.754824 -102.912672)
			(xy 286.754824 -103.776272) (xy 286.754334 -103.806256) (xy 286.746506 -103.865712) (xy 286.730985 -103.923637)
			(xy 286.708036 -103.979041) (xy 286.678052 -104.030975) (xy 286.641546 -104.078551) (xy 286.599141 -104.120956)
			(xy 286.551565 -104.157462) (xy 286.499631 -104.187446) (xy 286.444227 -104.210395) (xy 286.386302 -104.225916)
			(xy 286.326846 -104.233744) (xy 286.266878 -104.233744) (xy 286.207422 -104.225916) (xy 286.149497 -104.210395)
			(xy 286.094093 -104.187446) (xy 286.042159 -104.157462) (xy 285.994583 -104.120956) (xy 285.952178 -104.078551)
			(xy 285.915672 -104.030975) (xy 285.885688 -103.979041) (xy 285.862739 -103.923637) (xy 285.847218 -103.865712)
			(xy 285.83939 -103.806256) (xy 285.8389 -103.776272) (xy 275.770521 -103.776272) (xy 275.806154 -104.220264)
			(xy 275.808948 -104.269794) (xy 275.848561 -105.57637) (xy 283.9847 -105.57637) (xy 283.9847 -104.71277)
			(xy 283.98519 -104.682786) (xy 283.993018 -104.62333) (xy 284.008539 -104.565405) (xy 284.031488 -104.510001)
			(xy 284.061472 -104.458067) (xy 284.097978 -104.410491) (xy 284.140383 -104.368086) (xy 284.187959 -104.33158)
			(xy 284.239893 -104.301596) (xy 284.295297 -104.278647) (xy 284.353222 -104.263126) (xy 284.412678 -104.255298)
			(xy 284.472646 -104.255298) (xy 284.532102 -104.263126) (xy 284.590027 -104.278647) (xy 284.645431 -104.301596)
			(xy 284.697365 -104.33158) (xy 284.744941 -104.368086) (xy 284.787346 -104.410491) (xy 284.823852 -104.458067)
			(xy 284.853836 -104.510001) (xy 284.876785 -104.565405) (xy 284.892306 -104.62333) (xy 284.900134 -104.682786)
			(xy 284.900624 -104.71277) (xy 284.900624 -105.57637) (xy 284.900134 -105.606354) (xy 284.892306 -105.66581)
			(xy 284.876785 -105.723735) (xy 284.853836 -105.779139) (xy 284.823852 -105.831073) (xy 284.787346 -105.878649)
			(xy 284.744941 -105.921054) (xy 284.697365 -105.95756) (xy 284.645431 -105.987544) (xy 284.590027 -106.010493)
			(xy 284.532102 -106.026014) (xy 284.472646 -106.033842) (xy 284.412678 -106.033842) (xy 284.353222 -106.026014)
			(xy 284.295297 -106.010493) (xy 284.239893 -105.987544) (xy 284.187959 -105.95756) (xy 284.140383 -105.921054)
			(xy 284.097978 -105.878649) (xy 284.061472 -105.831073) (xy 284.031488 -105.779139) (xy 284.008539 -105.723735)
			(xy 283.993018 -105.66581) (xy 283.98519 -105.606354) (xy 283.9847 -105.57637) (xy 275.848561 -105.57637)
			(xy 275.903129 -107.376214) (xy 285.8389 -107.376214) (xy 285.8389 -106.512614) (xy 285.83939 -106.48263)
			(xy 285.847218 -106.423174) (xy 285.862739 -106.365249) (xy 285.885688 -106.309845) (xy 285.915672 -106.257911)
			(xy 285.952178 -106.210335) (xy 285.994583 -106.16793) (xy 286.042159 -106.131424) (xy 286.094093 -106.10144)
			(xy 286.149497 -106.078491) (xy 286.207422 -106.06297) (xy 286.266878 -106.055142) (xy 286.326846 -106.055142)
			(xy 286.386302 -106.06297) (xy 286.444227 -106.078491) (xy 286.499631 -106.10144) (xy 286.551565 -106.131424)
			(xy 286.599141 -106.16793) (xy 286.641546 -106.210335) (xy 286.678052 -106.257911) (xy 286.708036 -106.309845)
			(xy 286.730985 -106.365249) (xy 286.746506 -106.423174) (xy 286.754334 -106.48263) (xy 286.754824 -106.512614)
			(xy 286.754824 -107.376214) (xy 286.754334 -107.406198) (xy 286.746506 -107.465654) (xy 286.730985 -107.523579)
			(xy 286.708036 -107.578983) (xy 286.678052 -107.630917) (xy 286.641546 -107.678493) (xy 286.599141 -107.720898)
			(xy 286.551565 -107.757404) (xy 286.499631 -107.787388) (xy 286.444227 -107.810337) (xy 286.386302 -107.825858)
			(xy 286.326846 -107.833686) (xy 286.266878 -107.833686) (xy 286.207422 -107.825858) (xy 286.149497 -107.810337)
			(xy 286.094093 -107.787388) (xy 286.042159 -107.757404) (xy 285.994583 -107.720898) (xy 285.952178 -107.678493)
			(xy 285.915672 -107.630917) (xy 285.885688 -107.578983) (xy 285.862739 -107.523579) (xy 285.847218 -107.465654)
			(xy 285.83939 -107.406198) (xy 285.8389 -107.376214) (xy 275.903129 -107.376214) (xy 275.957705 -109.176312)
			(xy 283.9847 -109.176312) (xy 283.9847 -108.312712) (xy 283.98519 -108.282728) (xy 283.993018 -108.223272)
			(xy 284.008539 -108.165347) (xy 284.031488 -108.109943) (xy 284.061472 -108.058009) (xy 284.097978 -108.010433)
			(xy 284.140383 -107.968028) (xy 284.187959 -107.931522) (xy 284.239893 -107.901538) (xy 284.295297 -107.878589)
			(xy 284.353222 -107.863068) (xy 284.412678 -107.85524) (xy 284.472646 -107.85524) (xy 284.532102 -107.863068)
			(xy 284.590027 -107.878589) (xy 284.645431 -107.901538) (xy 284.697365 -107.931522) (xy 284.744941 -107.968028)
			(xy 284.787346 -108.010433) (xy 284.823852 -108.058009) (xy 284.853836 -108.109943) (xy 284.876785 -108.165347)
			(xy 284.892306 -108.223272) (xy 284.900134 -108.282728) (xy 284.900624 -108.312712) (xy 284.900624 -109.176312)
			(xy 284.900134 -109.206296) (xy 284.892306 -109.265752) (xy 284.876785 -109.323677) (xy 284.853836 -109.379081)
			(xy 284.823852 -109.431015) (xy 284.787346 -109.478591) (xy 284.744941 -109.520996) (xy 284.697365 -109.557502)
			(xy 284.645431 -109.587486) (xy 284.590027 -109.610435) (xy 284.532102 -109.625956) (xy 284.472646 -109.633784)
			(xy 284.412678 -109.633784) (xy 284.353222 -109.625956) (xy 284.295297 -109.610435) (xy 284.239893 -109.587486)
			(xy 284.187959 -109.557502) (xy 284.140383 -109.520996) (xy 284.097978 -109.478591) (xy 284.061472 -109.431015)
			(xy 284.031488 -109.379081) (xy 284.008539 -109.323677) (xy 283.993018 -109.265752) (xy 283.98519 -109.206296)
			(xy 283.9847 -109.176312) (xy 275.957705 -109.176312) (xy 276.012281 -110.97641) (xy 285.8389 -110.97641)
			(xy 285.8389 -110.11281) (xy 285.83939 -110.082826) (xy 285.847218 -110.02337) (xy 285.862739 -109.965445)
			(xy 285.885688 -109.910041) (xy 285.915672 -109.858107) (xy 285.952178 -109.810531) (xy 285.994583 -109.768126)
			(xy 286.042159 -109.73162) (xy 286.094093 -109.701636) (xy 286.149497 -109.678687) (xy 286.207422 -109.663166)
			(xy 286.266878 -109.655338) (xy 286.326846 -109.655338) (xy 286.386302 -109.663166) (xy 286.444227 -109.678687)
			(xy 286.499631 -109.701636) (xy 286.551565 -109.73162) (xy 286.599141 -109.768126) (xy 286.641546 -109.810531)
			(xy 286.678052 -109.858107) (xy 286.708036 -109.910041) (xy 286.730985 -109.965445) (xy 286.746506 -110.02337)
			(xy 286.754334 -110.082826) (xy 286.754824 -110.11281) (xy 286.754824 -110.97641) (xy 286.754334 -111.006394)
			(xy 286.746506 -111.06585) (xy 286.730985 -111.123775) (xy 286.708036 -111.179179) (xy 286.678052 -111.231113)
			(xy 286.641546 -111.278689) (xy 286.599141 -111.321094) (xy 286.551565 -111.3576) (xy 286.499631 -111.387584)
			(xy 286.444227 -111.410533) (xy 286.386302 -111.426054) (xy 286.326846 -111.433882) (xy 286.266878 -111.433882)
			(xy 286.207422 -111.426054) (xy 286.149497 -111.410533) (xy 286.094093 -111.387584) (xy 286.042159 -111.3576)
			(xy 285.994583 -111.321094) (xy 285.952178 -111.278689) (xy 285.915672 -111.231113) (xy 285.885688 -111.179179)
			(xy 285.862739 -111.123775) (xy 285.847218 -111.06585) (xy 285.83939 -111.006394) (xy 285.8389 -110.97641)
			(xy 276.012281 -110.97641) (xy 276.066856 -112.776508) (xy 283.9847 -112.776508) (xy 283.9847 -111.912908)
			(xy 283.98519 -111.882924) (xy 283.993018 -111.823468) (xy 284.008539 -111.765543) (xy 284.031488 -111.710139)
			(xy 284.061472 -111.658205) (xy 284.097978 -111.610629) (xy 284.140383 -111.568224) (xy 284.187959 -111.531718)
			(xy 284.239893 -111.501734) (xy 284.295297 -111.478785) (xy 284.353222 -111.463264) (xy 284.412678 -111.455436)
			(xy 284.472646 -111.455436) (xy 284.532102 -111.463264) (xy 284.590027 -111.478785) (xy 284.645431 -111.501734)
			(xy 284.697365 -111.531718) (xy 284.744941 -111.568224) (xy 284.787346 -111.610629) (xy 284.823852 -111.658205)
			(xy 284.853836 -111.710139) (xy 284.876785 -111.765543) (xy 284.892306 -111.823468) (xy 284.900134 -111.882924)
			(xy 284.900624 -111.912908) (xy 284.900624 -112.776508) (xy 284.900134 -112.806492) (xy 284.892306 -112.865948)
			(xy 284.876785 -112.923873) (xy 284.853836 -112.979277) (xy 284.823852 -113.031211) (xy 284.787346 -113.078787)
			(xy 284.744941 -113.121192) (xy 284.697365 -113.157698) (xy 284.645431 -113.187682) (xy 284.590027 -113.210631)
			(xy 284.532102 -113.226152) (xy 284.472646 -113.23398) (xy 284.412678 -113.23398) (xy 284.353222 -113.226152)
			(xy 284.295297 -113.210631) (xy 284.239893 -113.187682) (xy 284.187959 -113.157698) (xy 284.140383 -113.121192)
			(xy 284.097978 -113.078787) (xy 284.061472 -113.031211) (xy 284.031488 -112.979277) (xy 284.008539 -112.923873)
			(xy 283.993018 -112.865948) (xy 283.98519 -112.806492) (xy 283.9847 -112.776508) (xy 276.066856 -112.776508)
			(xy 276.157741 -115.774216) (xy 288.047174 -115.774216) (xy 288.051245 -115.718594) (xy 288.063371 -115.664157)
			(xy 288.083294 -115.612066) (xy 288.11059 -115.563431) (xy 288.144676 -115.519288) (xy 288.184825 -115.480579)
			(xy 288.230183 -115.448128) (xy 288.279783 -115.422627) (xy 288.332567 -115.40462) (xy 288.38741 -115.39449)
			(xy 288.443144 -115.392453) (xy 288.498581 -115.398553) (xy 288.552538 -115.412659) (xy 288.603867 -115.434471)
			(xy 288.651473 -115.463525) (xy 288.694341 -115.4992) (xy 288.731558 -115.540737) (xy 288.762331 -115.58725)
			(xy 288.786003 -115.637747) (xy 288.802071 -115.691154) (xy 288.810191 -115.74633) (xy 288.8107 -115.774216)
			(xy 288.810191 -115.802102) (xy 288.802071 -115.857278) (xy 288.786003 -115.910685) (xy 288.762331 -115.961182)
			(xy 288.731558 -116.007695) (xy 288.694341 -116.049232) (xy 288.651473 -116.084907) (xy 288.603867 -116.113961)
			(xy 288.552538 -116.135773) (xy 288.498581 -116.149879) (xy 288.443144 -116.155979) (xy 288.38741 -116.153942)
			(xy 288.332567 -116.143812) (xy 288.279783 -116.125805) (xy 288.230183 -116.100304) (xy 288.184825 -116.067853)
			(xy 288.144676 -116.029144) (xy 288.11059 -115.985001) (xy 288.083294 -115.936366) (xy 288.063371 -115.884275)
			(xy 288.051245 -115.829838) (xy 288.047174 -115.774216) (xy 276.157741 -115.774216) (xy 276.232801 -118.249954)
			(xy 287.813748 -118.249954) (xy 287.817819 -118.194332) (xy 287.829945 -118.139895) (xy 287.849868 -118.087804)
			(xy 287.877164 -118.039169) (xy 287.91125 -117.995026) (xy 287.951399 -117.956317) (xy 287.996757 -117.923866)
			(xy 288.046357 -117.898365) (xy 288.099141 -117.880358) (xy 288.153984 -117.870228) (xy 288.209718 -117.868191)
			(xy 288.265155 -117.874291) (xy 288.319112 -117.888397) (xy 288.370441 -117.910209) (xy 288.418047 -117.939263)
			(xy 288.460915 -117.974938) (xy 288.498132 -118.016475) (xy 288.528905 -118.062988) (xy 288.552577 -118.113485)
			(xy 288.568645 -118.166892) (xy 288.576765 -118.222068) (xy 288.577274 -118.249954) (xy 288.576765 -118.27784)
			(xy 288.568645 -118.333016) (xy 288.552577 -118.386423) (xy 288.528905 -118.43692) (xy 288.498132 -118.483433)
			(xy 288.460915 -118.52497) (xy 288.418047 -118.560645) (xy 288.370441 -118.589699) (xy 288.319112 -118.611511)
			(xy 288.265155 -118.625617) (xy 288.209718 -118.631717) (xy 288.153984 -118.62968) (xy 288.099141 -118.61955)
			(xy 288.046357 -118.601543) (xy 287.996757 -118.576042) (xy 287.951399 -118.543591) (xy 287.91125 -118.504882)
			(xy 287.877164 -118.460739) (xy 287.849868 -118.412104) (xy 287.829945 -118.360013) (xy 287.817819 -118.305576)
			(xy 287.813748 -118.249954) (xy 276.232801 -118.249954) (xy 276.271736 -119.534178) (xy 276.272244 -119.563896)
			(xy 276.272244 -119.564912) (xy 276.27199 -119.574564) (xy 276.27199 -119.575072) (xy 276.266489 -120.086374)
			(xy 285.8389 -120.086374) (xy 285.8389 -119.222774) (xy 285.83939 -119.19279) (xy 285.847218 -119.133334)
			(xy 285.862739 -119.075409) (xy 285.885688 -119.020005) (xy 285.915672 -118.968071) (xy 285.952178 -118.920495)
			(xy 285.994583 -118.87809) (xy 286.042159 -118.841584) (xy 286.094093 -118.8116) (xy 286.149497 -118.788651)
			(xy 286.207422 -118.77313) (xy 286.266878 -118.765302) (xy 286.326846 -118.765302) (xy 286.386302 -118.77313)
			(xy 286.444227 -118.788651) (xy 286.499631 -118.8116) (xy 286.551565 -118.841584) (xy 286.599141 -118.87809)
			(xy 286.641546 -118.920495) (xy 286.678052 -118.968071) (xy 286.708036 -119.020005) (xy 286.730985 -119.075409)
			(xy 286.746506 -119.133334) (xy 286.754334 -119.19279) (xy 286.754824 -119.222774) (xy 286.754824 -120.086374)
			(xy 286.754334 -120.116358) (xy 286.746506 -120.175814) (xy 286.730985 -120.233739) (xy 286.708036 -120.289143)
			(xy 286.678052 -120.341077) (xy 286.641546 -120.388653) (xy 286.599141 -120.431058) (xy 286.551565 -120.467564)
			(xy 286.499631 -120.497548) (xy 286.444227 -120.520497) (xy 286.386302 -120.536018) (xy 286.326846 -120.543846)
			(xy 286.266878 -120.543846) (xy 286.207422 -120.536018) (xy 286.149497 -120.520497) (xy 286.094093 -120.497548)
			(xy 286.042159 -120.467564) (xy 285.994583 -120.431058) (xy 285.952178 -120.388653) (xy 285.915672 -120.341077)
			(xy 285.885688 -120.289143) (xy 285.862739 -120.233739) (xy 285.847218 -120.175814) (xy 285.83939 -120.116358)
			(xy 285.8389 -120.086374) (xy 276.266489 -120.086374) (xy 276.24712 -121.886472) (xy 283.9847 -121.886472)
			(xy 283.9847 -121.022872) (xy 283.98519 -120.992888) (xy 283.993018 -120.933432) (xy 284.008539 -120.875507)
			(xy 284.031488 -120.820103) (xy 284.061472 -120.768169) (xy 284.097978 -120.720593) (xy 284.140383 -120.678188)
			(xy 284.187959 -120.641682) (xy 284.239893 -120.611698) (xy 284.295297 -120.588749) (xy 284.353222 -120.573228)
			(xy 284.412678 -120.5654) (xy 284.472646 -120.5654) (xy 284.532102 -120.573228) (xy 284.590027 -120.588749)
			(xy 284.645431 -120.611698) (xy 284.697365 -120.641682) (xy 284.744941 -120.678188) (xy 284.787346 -120.720593)
			(xy 284.823852 -120.768169) (xy 284.853836 -120.820103) (xy 284.876785 -120.875507) (xy 284.892306 -120.933432)
			(xy 284.900134 -120.992888) (xy 284.900624 -121.022872) (xy 284.900624 -121.886472) (xy 284.900134 -121.916456)
			(xy 284.892306 -121.975912) (xy 284.876785 -122.033837) (xy 284.853836 -122.089241) (xy 284.823852 -122.141175)
			(xy 284.787346 -122.188751) (xy 284.744941 -122.231156) (xy 284.697365 -122.267662) (xy 284.645431 -122.297646)
			(xy 284.590027 -122.320595) (xy 284.532102 -122.336116) (xy 284.472646 -122.343944) (xy 284.412678 -122.343944)
			(xy 284.353222 -122.336116) (xy 284.295297 -122.320595) (xy 284.239893 -122.297646) (xy 284.187959 -122.267662)
			(xy 284.140383 -122.231156) (xy 284.097978 -122.188751) (xy 284.061472 -122.141175) (xy 284.031488 -122.089241)
			(xy 284.008539 -122.033837) (xy 283.993018 -121.975912) (xy 283.98519 -121.916456) (xy 283.9847 -121.886472)
			(xy 276.24712 -121.886472) (xy 276.227754 -123.686316) (xy 285.8389 -123.686316) (xy 285.8389 -122.822716)
			(xy 285.83939 -122.792732) (xy 285.847218 -122.733276) (xy 285.862739 -122.675351) (xy 285.885688 -122.619947)
			(xy 285.915672 -122.568013) (xy 285.952178 -122.520437) (xy 285.994583 -122.478032) (xy 286.042159 -122.441526)
			(xy 286.094093 -122.411542) (xy 286.149497 -122.388593) (xy 286.207422 -122.373072) (xy 286.266878 -122.365244)
			(xy 286.326846 -122.365244) (xy 286.386302 -122.373072) (xy 286.444227 -122.388593) (xy 286.499631 -122.411542)
			(xy 286.551565 -122.441526) (xy 286.599141 -122.478032) (xy 286.641546 -122.520437) (xy 286.678052 -122.568013)
			(xy 286.708036 -122.619947) (xy 286.730985 -122.675351) (xy 286.746506 -122.733276) (xy 286.754334 -122.792732)
			(xy 286.754824 -122.822716) (xy 286.754824 -123.686316) (xy 286.754334 -123.7163) (xy 286.746506 -123.775756)
			(xy 286.730985 -123.833681) (xy 286.708036 -123.889085) (xy 286.678052 -123.941019) (xy 286.641546 -123.988595)
			(xy 286.599141 -124.031) (xy 286.551565 -124.067506) (xy 286.499631 -124.09749) (xy 286.444227 -124.120439)
			(xy 286.386302 -124.13596) (xy 286.326846 -124.143788) (xy 286.266878 -124.143788) (xy 286.207422 -124.13596)
			(xy 286.149497 -124.120439) (xy 286.094093 -124.09749) (xy 286.042159 -124.067506) (xy 285.994583 -124.031)
			(xy 285.952178 -123.988595) (xy 285.915672 -123.941019) (xy 285.885688 -123.889085) (xy 285.862739 -123.833681)
			(xy 285.847218 -123.775756) (xy 285.83939 -123.7163) (xy 285.8389 -123.686316) (xy 276.227754 -123.686316)
			(xy 276.217888 -124.603256) (xy 276.2084 -125.486414) (xy 283.9847 -125.486414) (xy 283.9847 -124.622814)
			(xy 283.98519 -124.59283) (xy 283.993018 -124.533374) (xy 284.008539 -124.475449) (xy 284.031488 -124.420045)
			(xy 284.061472 -124.368111) (xy 284.097978 -124.320535) (xy 284.140383 -124.27813) (xy 284.187959 -124.241624)
			(xy 284.239893 -124.21164) (xy 284.295297 -124.188691) (xy 284.353222 -124.17317) (xy 284.412678 -124.165342)
			(xy 284.472646 -124.165342) (xy 284.532102 -124.17317) (xy 284.590027 -124.188691) (xy 284.645431 -124.21164)
			(xy 284.697365 -124.241624) (xy 284.744941 -124.27813) (xy 284.787346 -124.320535) (xy 284.823852 -124.368111)
			(xy 284.853836 -124.420045) (xy 284.876785 -124.475449) (xy 284.892306 -124.533374) (xy 284.900134 -124.59283)
			(xy 284.900624 -124.622814) (xy 284.900624 -125.486414) (xy 284.900134 -125.516398) (xy 284.892306 -125.575854)
			(xy 284.876785 -125.633779) (xy 284.853836 -125.689183) (xy 284.823852 -125.741117) (xy 284.787346 -125.788693)
			(xy 284.744941 -125.831098) (xy 284.697365 -125.867604) (xy 284.645431 -125.897588) (xy 284.590027 -125.920537)
			(xy 284.532102 -125.936058) (xy 284.472646 -125.943886) (xy 284.412678 -125.943886) (xy 284.353222 -125.936058)
			(xy 284.295297 -125.920537) (xy 284.239893 -125.897588) (xy 284.187959 -125.867604) (xy 284.140383 -125.831098)
			(xy 284.097978 -125.788693) (xy 284.061472 -125.741117) (xy 284.031488 -125.689183) (xy 284.008539 -125.633779)
			(xy 283.993018 -125.575854) (xy 283.98519 -125.516398) (xy 283.9847 -125.486414) (xy 276.2084 -125.486414)
			(xy 276.195028 -126.731014) (xy 276.175017 -128.589024) (xy 285.77997 -128.589024) (xy 285.784041 -128.533402)
			(xy 285.796167 -128.478965) (xy 285.81609 -128.426874) (xy 285.843386 -128.378239) (xy 285.877472 -128.334096)
			(xy 285.917621 -128.295387) (xy 285.962979 -128.262936) (xy 286.012579 -128.237435) (xy 286.065363 -128.219428)
			(xy 286.120206 -128.209298) (xy 286.17594 -128.207261) (xy 286.231377 -128.213361) (xy 286.285334 -128.227467)
			(xy 286.336663 -128.249279) (xy 286.384269 -128.278333) (xy 286.427137 -128.314008) (xy 286.464354 -128.355545)
			(xy 286.495127 -128.402058) (xy 286.518799 -128.452555) (xy 286.534867 -128.505962) (xy 286.542987 -128.561138)
			(xy 286.543496 -128.589024) (xy 286.542987 -128.61691) (xy 286.534867 -128.672086) (xy 286.518799 -128.725493)
			(xy 286.495127 -128.77599) (xy 286.464354 -128.822503) (xy 286.427137 -128.86404) (xy 286.384269 -128.899715)
			(xy 286.336663 -128.928769) (xy 286.285334 -128.950581) (xy 286.231377 -128.964687) (xy 286.17594 -128.970787)
			(xy 286.120206 -128.96875) (xy 286.065363 -128.95862) (xy 286.012579 -128.940613) (xy 285.962979 -128.915112)
			(xy 285.917621 -128.882661) (xy 285.877472 -128.843952) (xy 285.843386 -128.799809) (xy 285.81609 -128.751174)
			(xy 285.796167 -128.699083) (xy 285.784041 -128.644646) (xy 285.77997 -128.589024) (xy 276.175017 -128.589024)
			(xy 276.145858 -131.29641) (xy 285.8389 -131.29641) (xy 285.8389 -130.43281) (xy 285.83939 -130.402826)
			(xy 285.847218 -130.34337) (xy 285.862739 -130.285445) (xy 285.885688 -130.230041) (xy 285.915672 -130.178107)
			(xy 285.952178 -130.130531) (xy 285.994583 -130.088126) (xy 286.042159 -130.05162) (xy 286.094093 -130.021636)
			(xy 286.149497 -129.998687) (xy 286.207422 -129.983166) (xy 286.266878 -129.975338) (xy 286.326846 -129.975338)
			(xy 286.386302 -129.983166) (xy 286.444227 -129.998687) (xy 286.499631 -130.021636) (xy 286.551565 -130.05162)
			(xy 286.599141 -130.088126) (xy 286.641546 -130.130531) (xy 286.678052 -130.178107) (xy 286.708036 -130.230041)
			(xy 286.730985 -130.285445) (xy 286.746506 -130.34337) (xy 286.754334 -130.402826) (xy 286.754824 -130.43281)
			(xy 286.754824 -131.29641) (xy 286.754334 -131.326394) (xy 286.746506 -131.38585) (xy 286.730985 -131.443775)
			(xy 286.708036 -131.499179) (xy 286.678052 -131.551113) (xy 286.641546 -131.598689) (xy 286.599141 -131.641094)
			(xy 286.551565 -131.6776) (xy 286.499631 -131.707584) (xy 286.444227 -131.730533) (xy 286.386302 -131.746054)
			(xy 286.326846 -131.753882) (xy 286.266878 -131.753882) (xy 286.207422 -131.746054) (xy 286.149497 -131.730533)
			(xy 286.094093 -131.707584) (xy 286.042159 -131.6776) (xy 285.994583 -131.641094) (xy 285.952178 -131.598689)
			(xy 285.915672 -131.551113) (xy 285.885688 -131.499179) (xy 285.862739 -131.443775) (xy 285.847218 -131.38585)
			(xy 285.83939 -131.326394) (xy 285.8389 -131.29641) (xy 276.145858 -131.29641) (xy 276.12647 -133.096508)
			(xy 283.9847 -133.096508) (xy 283.9847 -132.232908) (xy 283.98519 -132.202924) (xy 283.993018 -132.143468)
			(xy 284.008539 -132.085543) (xy 284.031488 -132.030139) (xy 284.061472 -131.978205) (xy 284.097978 -131.930629)
			(xy 284.140383 -131.888224) (xy 284.187959 -131.851718) (xy 284.239893 -131.821734) (xy 284.295297 -131.798785)
			(xy 284.353222 -131.783264) (xy 284.412678 -131.775436) (xy 284.472646 -131.775436) (xy 284.532102 -131.783264)
			(xy 284.590027 -131.798785) (xy 284.645431 -131.821734) (xy 284.697365 -131.851718) (xy 284.744941 -131.888224)
			(xy 284.787346 -131.930629) (xy 284.823852 -131.978205) (xy 284.853836 -132.030139) (xy 284.876785 -132.085543)
			(xy 284.892306 -132.143468) (xy 284.900134 -132.202924) (xy 284.900624 -132.232908) (xy 284.900624 -133.096508)
			(xy 284.900134 -133.126492) (xy 284.892306 -133.185948) (xy 284.876785 -133.243873) (xy 284.853836 -133.299277)
			(xy 284.823852 -133.351211) (xy 284.787346 -133.398787) (xy 284.744941 -133.441192) (xy 284.697365 -133.477698)
			(xy 284.645431 -133.507682) (xy 284.590027 -133.530631) (xy 284.532102 -133.546152) (xy 284.472646 -133.55398)
			(xy 284.412678 -133.55398) (xy 284.353222 -133.546152) (xy 284.295297 -133.530631) (xy 284.239893 -133.507682)
			(xy 284.187959 -133.477698) (xy 284.140383 -133.441192) (xy 284.097978 -133.398787) (xy 284.061472 -133.351211)
			(xy 284.031488 -133.299277) (xy 284.008539 -133.243873) (xy 283.993018 -133.185948) (xy 283.98519 -133.126492)
			(xy 283.9847 -133.096508) (xy 276.12647 -133.096508) (xy 276.107085 -134.896352) (xy 285.8389 -134.896352)
			(xy 285.8389 -134.032752) (xy 285.83939 -134.002768) (xy 285.847218 -133.943312) (xy 285.862739 -133.885387)
			(xy 285.885688 -133.829983) (xy 285.915672 -133.778049) (xy 285.952178 -133.730473) (xy 285.994583 -133.688068)
			(xy 286.042159 -133.651562) (xy 286.094093 -133.621578) (xy 286.149497 -133.598629) (xy 286.207422 -133.583108)
			(xy 286.266878 -133.57528) (xy 286.326846 -133.57528) (xy 286.386302 -133.583108) (xy 286.444227 -133.598629)
			(xy 286.499631 -133.621578) (xy 286.551565 -133.651562) (xy 286.599141 -133.688068) (xy 286.641546 -133.730473)
			(xy 286.678052 -133.778049) (xy 286.708036 -133.829983) (xy 286.730985 -133.885387) (xy 286.746506 -133.943312)
			(xy 286.754334 -134.002768) (xy 286.754824 -134.032752) (xy 286.754824 -134.896352) (xy 286.754334 -134.926336)
			(xy 286.746506 -134.985792) (xy 286.730985 -135.043717) (xy 286.708036 -135.099121) (xy 286.678052 -135.151055)
			(xy 286.641546 -135.198631) (xy 286.599141 -135.241036) (xy 286.551565 -135.277542) (xy 286.499631 -135.307526)
			(xy 286.444227 -135.330475) (xy 286.386302 -135.345996) (xy 286.326846 -135.353824) (xy 286.266878 -135.353824)
			(xy 286.207422 -135.345996) (xy 286.149497 -135.330475) (xy 286.094093 -135.307526) (xy 286.042159 -135.277542)
			(xy 285.994583 -135.241036) (xy 285.952178 -135.198631) (xy 285.915672 -135.151055) (xy 285.885688 -135.099121)
			(xy 285.862739 -135.043717) (xy 285.847218 -134.985792) (xy 285.83939 -134.926336) (xy 285.8389 -134.896352)
			(xy 276.107085 -134.896352) (xy 276.087698 -136.69645) (xy 283.9847 -136.69645) (xy 283.9847 -135.83285)
			(xy 283.98519 -135.802866) (xy 283.993018 -135.74341) (xy 284.008539 -135.685485) (xy 284.031488 -135.630081)
			(xy 284.061472 -135.578147) (xy 284.097978 -135.530571) (xy 284.140383 -135.488166) (xy 284.187959 -135.45166)
			(xy 284.239893 -135.421676) (xy 284.295297 -135.398727) (xy 284.353222 -135.383206) (xy 284.412678 -135.375378)
			(xy 284.472646 -135.375378) (xy 284.532102 -135.383206) (xy 284.590027 -135.398727) (xy 284.645431 -135.421676)
			(xy 284.697365 -135.45166) (xy 284.744941 -135.488166) (xy 284.787346 -135.530571) (xy 284.823852 -135.578147)
			(xy 284.853836 -135.630081) (xy 284.876785 -135.685485) (xy 284.892306 -135.74341) (xy 284.900134 -135.802866)
			(xy 284.900624 -135.83285) (xy 284.900624 -136.69645) (xy 284.900134 -136.726434) (xy 284.892306 -136.78589)
			(xy 284.876785 -136.843815) (xy 284.853836 -136.899219) (xy 284.823852 -136.951153) (xy 284.787346 -136.998729)
			(xy 284.744941 -137.041134) (xy 284.697365 -137.07764) (xy 284.645431 -137.107624) (xy 284.590027 -137.130573)
			(xy 284.532102 -137.146094) (xy 284.472646 -137.153922) (xy 284.412678 -137.153922) (xy 284.353222 -137.146094)
			(xy 284.295297 -137.130573) (xy 284.239893 -137.107624) (xy 284.187959 -137.07764) (xy 284.140383 -137.041134)
			(xy 284.097978 -136.998729) (xy 284.061472 -136.951153) (xy 284.031488 -136.899219) (xy 284.008539 -136.843815)
			(xy 283.993018 -136.78589) (xy 283.98519 -136.726434) (xy 283.9847 -136.69645) (xy 276.087698 -136.69645)
			(xy 276.081236 -137.296398) (xy 276.081741 -137.307725) (xy 276.091236 -137.328284) (xy 276.099524 -137.336022)
			(xy 276.103193 -137.33895) (xy 276.111372 -137.343553) (xy 276.11578 -137.345166) (xy 276.161246 -137.36066)
			(xy 276.209252 -137.376916) (xy 276.219255 -137.379293) (xy 276.239635 -137.376727) (xy 276.257354 -137.366336)
			(xy 276.263862 -137.358374) (xy 276.282441 -137.334408) (xy 276.3249 -137.291113) (xy 276.372707 -137.253807)
			(xy 276.425022 -137.223142) (xy 276.48093 -137.199656) (xy 276.539449 -137.183761) (xy 276.599556 -137.175735)
			(xy 276.629876 -137.17524) (xy 276.630384 -137.17524) (xy 276.660353 -137.175708) (xy 276.719777 -137.18353)
			(xy 276.777672 -137.199042) (xy 276.833047 -137.221979) (xy 276.884953 -137.251948) (xy 276.932504 -137.288437)
			(xy 276.974884 -137.33082) (xy 277.011369 -137.378373) (xy 277.041335 -137.430282) (xy 277.064268 -137.485658)
			(xy 277.079776 -137.543554) (xy 277.087594 -137.602979) (xy 277.088092 -137.632948) (xy 277.088092 -138.496548)
			(xy 277.087602 -138.526516) (xy 277.082652 -138.564112) (xy 278.891236 -138.564112) (xy 278.895307 -138.50849)
			(xy 278.907433 -138.454053) (xy 278.927356 -138.401962) (xy 278.954652 -138.353327) (xy 278.988738 -138.309184)
			(xy 279.028887 -138.270475) (xy 279.074245 -138.238024) (xy 279.123845 -138.212523) (xy 279.176629 -138.194516)
			(xy 279.231472 -138.184386) (xy 279.287206 -138.182349) (xy 279.342643 -138.188449) (xy 279.3966 -138.202555)
			(xy 279.447929 -138.224367) (xy 279.495535 -138.253421) (xy 279.538403 -138.289096) (xy 279.57562 -138.330633)
			(xy 279.606393 -138.377146) (xy 279.630065 -138.427643) (xy 279.646133 -138.48105) (xy 279.654253 -138.536226)
			(xy 279.654762 -138.564112) (xy 279.654253 -138.591998) (xy 279.646133 -138.647174) (xy 279.630065 -138.700581)
			(xy 279.606393 -138.751078) (xy 279.57562 -138.797591) (xy 279.538403 -138.839128) (xy 279.495535 -138.874803)
			(xy 279.447929 -138.903857) (xy 279.3966 -138.925669) (xy 279.342643 -138.939775) (xy 279.287206 -138.945875)
			(xy 279.231472 -138.943838) (xy 279.176629 -138.933708) (xy 279.123845 -138.915701) (xy 279.074245 -138.8902)
			(xy 279.028887 -138.857749) (xy 278.988738 -138.81904) (xy 278.954652 -138.774897) (xy 278.927356 -138.726262)
			(xy 278.907433 -138.674171) (xy 278.895307 -138.619734) (xy 278.891236 -138.564112) (xy 277.082652 -138.564112)
			(xy 277.079779 -138.585938) (xy 277.064266 -138.643831) (xy 277.04133 -138.699204) (xy 277.011363 -138.75111)
			(xy 276.974876 -138.79866) (xy 276.932496 -138.84104) (xy 276.884946 -138.877527) (xy 276.83304 -138.907494)
			(xy 276.777667 -138.93043) (xy 276.719774 -138.945943) (xy 276.660352 -138.953766) (xy 276.600416 -138.953766)
			(xy 276.540994 -138.945943) (xy 276.483101 -138.93043) (xy 276.427728 -138.907494) (xy 276.375822 -138.877527)
			(xy 276.328272 -138.84104) (xy 276.285892 -138.79866) (xy 276.249405 -138.75111) (xy 276.219438 -138.699204)
			(xy 276.196502 -138.643831) (xy 276.180989 -138.585938) (xy 276.173166 -138.526516) (xy 276.172676 -138.496548)
			(xy 276.172676 -138.284458) (xy 276.172187 -138.274489) (xy 276.164566 -138.256064) (xy 276.150493 -138.241939)
			(xy 276.132097 -138.234251) (xy 276.12213 -138.233658) (xy 276.121114 -138.233658) (xy 276.111204 -138.234182)
			(xy 276.0929 -138.241796) (xy 276.078845 -138.255778) (xy 276.071135 -138.274043) (xy 276.070568 -138.28395)
			(xy 276.068282 -138.498326) (xy 276.062186 -139.05611) (xy 276.057106 -139.510516) (xy 276.059138 -139.512294)
			(xy 276.088094 -139.538202) (xy 276.095321 -139.544164) (xy 276.112773 -139.550937) (xy 276.12213 -139.55141)
			(xy 276.12721 -139.55141) (xy 276.12975 -139.551156) (xy 276.140068 -139.550093) (xy 276.16078 -139.548947)
			(xy 276.171152 -139.54887) (xy 276.196698 -139.549282) (xy 276.247334 -139.556104) (xy 276.296606 -139.56962)
			(xy 276.343636 -139.589587) (xy 276.387582 -139.615649) (xy 276.40788 -139.631166) (xy 276.412706 -139.634976)
			(xy 276.418802 -139.638024) (xy 276.430486 -139.641834) (xy 276.440392 -139.64285) (xy 276.461982 -139.64285)
			(xy 276.467423 -139.642989) (xy 276.478058 -139.645289) (xy 276.483064 -139.647422) (xy 276.497034 -139.653772)
			(xy 276.506201 -139.657456) (xy 276.525921 -139.658291) (xy 276.544506 -139.651644) (xy 276.552152 -139.64539)
			(xy 276.562566 -139.636246) (xy 276.583101 -139.619874) (xy 276.627809 -139.592317) (xy 276.675867 -139.571137)
			(xy 276.726371 -139.556733) (xy 276.77837 -139.549374) (xy 276.804628 -139.54887) (xy 276.806152 -139.54887)
			(xy 276.833228 -139.549347) (xy 276.886836 -139.557011) (xy 276.938822 -139.572179) (xy 276.98814 -139.594545)
			(xy 277.033801 -139.62366) (xy 277.074886 -139.658938) (xy 277.11057 -139.699672) (xy 277.140135 -139.745041)
			(xy 277.162989 -139.794136) (xy 277.17867 -139.845969) (xy 277.186866 -139.899498) (xy 277.18766 -139.926568)
			(xy 277.18766 -139.930886) (xy 277.187057 -139.960797) (xy 277.177689 -140.019882) (xy 277.159226 -140.076785)
			(xy 277.13212 -140.130115) (xy 277.115016 -140.15466) (xy 277.108666 -140.163042) (xy 277.104856 -140.167868)
			(xy 277.099522 -140.176504) (xy 277.099014 -140.17752) (xy 277.09655 -140.182845) (xy 277.093852 -140.194261)
			(xy 277.09368 -140.200126) (xy 277.09368 -140.221208) (xy 277.093539 -140.226648) (xy 277.091236 -140.237281)
			(xy 277.089108 -140.24229) (xy 277.082758 -140.25626) (xy 277.079083 -140.265427) (xy 277.078258 -140.285142)
			(xy 277.084903 -140.303721) (xy 277.09114 -140.311378) (xy 277.100284 -140.321792) (xy 277.116717 -140.342409)
			(xy 277.144358 -140.387303) (xy 277.165569 -140.43557) (xy 277.179948 -140.486292) (xy 277.187222 -140.53851)
			(xy 277.18766 -140.56487) (xy 277.18766 -140.565378) (xy 277.187198 -140.592631) (xy 277.179443 -140.646581)
			(xy 277.164089 -140.698879) (xy 277.141447 -140.748459) (xy 277.111979 -140.794311) (xy 277.076284 -140.835503)
			(xy 277.035091 -140.871194) (xy 276.989236 -140.900659) (xy 276.939655 -140.923298) (xy 276.887356 -140.938649)
			(xy 276.833405 -140.9464) (xy 276.806152 -140.946886) (xy 276.780605 -140.946474) (xy 276.729969 -140.939653)
			(xy 276.680695 -140.92614) (xy 276.633664 -140.906175) (xy 276.589715 -140.880117) (xy 276.569424 -140.86459)
			(xy 276.564598 -140.86078) (xy 276.55901 -140.85824) (xy 276.553676 -140.855446) (xy 276.5425 -140.852906)
			(xy 276.515322 -140.852906) (xy 276.509881 -140.852769) (xy 276.499245 -140.850472) (xy 276.49424 -140.848334)
			(xy 276.483064 -140.842746) (xy 276.473799 -140.838828) (xy 276.453735 -140.837689) (xy 276.434757 -140.844301)
			(xy 276.42693 -140.85062) (xy 276.426676 -140.85062) (xy 276.405505 -140.868885) (xy 276.35886 -140.899716)
			(xy 276.308226 -140.923432) (xy 276.254681 -140.939529) (xy 276.199363 -140.947665) (xy 276.171406 -140.948156)
			(xy 276.170898 -140.948156) (xy 276.157004 -140.948024) (xy 276.12929 -140.945992) (xy 276.115526 -140.944092)
			(xy 276.102318 -140.942314) (xy 276.07768 -140.951712) (xy 276.067266 -140.957808) (xy 276.064726 -140.95984)
			(xy 276.062948 -140.961364) (xy 276.052788 -140.97) (xy 276.050502 -140.972032) (xy 276.046184 -140.981176)
			(xy 276.04398 -140.986235) (xy 276.041555 -140.996997) (xy 276.041358 -141.002512) (xy 276.024017 -142.60068)
			(xy 283.80563 -142.60068) (xy 283.806093 -142.573275) (xy 283.813944 -142.51903) (xy 283.829482 -142.466469)
			(xy 283.852385 -142.416674) (xy 283.882183 -142.370671) (xy 283.899864 -142.349728) (xy 283.900118 -142.349474)
			(xy 283.905682 -142.342372) (xy 283.911942 -142.325467) (xy 283.91231 -142.316454) (xy 283.91231 -142.249144)
			(xy 283.91193 -142.240129) (xy 283.905698 -142.223212) (xy 283.900118 -142.216124) (xy 283.89961 -142.215616)
			(xy 283.881967 -142.194687) (xy 283.852255 -142.148714) (xy 283.82942 -142.098965) (xy 283.81393 -142.046464)
			(xy 283.806103 -141.992287) (xy 283.80563 -141.964918) (xy 283.806116 -141.937667) (xy 283.813872 -141.883719)
			(xy 283.829227 -141.831424) (xy 283.851869 -141.781847) (xy 283.881335 -141.735997) (xy 283.917026 -141.694806)
			(xy 283.958217 -141.659115) (xy 284.004067 -141.629649) (xy 284.053644 -141.607007) (xy 284.105939 -141.591652)
			(xy 284.159887 -141.583896) (xy 284.214389 -141.583896) (xy 284.268337 -141.591652) (xy 284.320632 -141.607007)
			(xy 284.370209 -141.629649) (xy 284.416059 -141.659115) (xy 284.45725 -141.694806) (xy 284.492941 -141.735997)
			(xy 284.522407 -141.781847) (xy 284.545049 -141.831424) (xy 284.560404 -141.883719) (xy 284.56816 -141.937667)
			(xy 284.568646 -141.964918) (xy 284.568187 -141.992323) (xy 284.560336 -142.046568) (xy 284.544798 -142.09913)
			(xy 284.521893 -142.148925) (xy 284.492094 -142.194927) (xy 284.474412 -142.21587) (xy 284.474158 -142.216124)
			(xy 284.46855 -142.223196) (xy 284.462317 -142.240124) (xy 284.461966 -142.249144) (xy 284.461966 -142.316454)
			(xy 284.462352 -142.325468) (xy 284.46858 -142.342385) (xy 284.474158 -142.349474) (xy 284.474666 -142.349982)
			(xy 284.492305 -142.370914) (xy 284.522018 -142.416887) (xy 284.544854 -142.466634) (xy 284.560345 -142.519135)
			(xy 284.568173 -142.573311) (xy 284.568646 -142.60068) (xy 284.56816 -142.627931) (xy 284.560404 -142.681879)
			(xy 284.545049 -142.734174) (xy 284.522407 -142.783751) (xy 284.492941 -142.829601) (xy 284.45725 -142.870792)
			(xy 284.416059 -142.906483) (xy 284.370209 -142.935949) (xy 284.320632 -142.958591) (xy 284.268337 -142.973946)
			(xy 284.214389 -142.981702) (xy 284.159887 -142.981702) (xy 284.105939 -142.973946) (xy 284.053644 -142.958591)
			(xy 284.004067 -142.935949) (xy 283.958217 -142.906483) (xy 283.917026 -142.870792) (xy 283.881335 -142.829601)
			(xy 283.851869 -142.783751) (xy 283.829227 -142.734174) (xy 283.813872 -142.681879) (xy 283.806116 -142.627931)
			(xy 283.80563 -142.60068) (xy 276.024017 -142.60068) (xy 276.006814 -144.186148) (xy 276.00656 -144.21231)
			(xy 276.005798 -144.27962) (xy 276.005993 -144.288514) (xy 276.011845 -144.305303) (xy 276.017228 -144.312386)
			(xy 276.067266 -144.367758) (xy 276.073542 -144.373458) (xy 276.088854 -144.380716) (xy 276.097238 -144.381982)
			(xy 276.098 -144.381982) (xy 276.109938 -144.383252) (xy 276.110192 -144.383252) (xy 276.118899 -144.383897)
			(xy 276.135906 -144.379999) (xy 276.143466 -144.375632) (xy 276.202648 -144.33423) (xy 276.208925 -144.329295)
			(xy 276.218261 -144.316352) (xy 276.220936 -144.30883) (xy 276.221698 -144.305274) (xy 276.228715 -144.277743)
			(xy 276.24979 -144.224982) (xy 276.278454 -144.17593) (xy 276.314075 -144.13167) (xy 276.355866 -144.093182)
			(xy 276.402901 -144.061315) (xy 276.454142 -144.036776) (xy 276.508455 -144.020106) (xy 276.564639 -144.011673)
			(xy 276.593046 -144.011142) (xy 276.5933 -144.011142) (xy 276.625012 -144.011798) (xy 276.687558 -144.022327)
			(xy 276.74751 -144.04303) (xy 276.775672 -144.057624) (xy 276.77618 -144.057878) (xy 276.782041 -144.060813)
			(xy 276.794772 -144.063906) (xy 276.801326 -144.063974) (xy 276.813772 -144.06372) (xy 276.854666 -144.03959)
			(xy 276.861187 -144.034838) (xy 276.871153 -144.02216) (xy 276.874224 -144.014698) (xy 276.874224 -143.999204)
			(xy 276.874765 -143.971991) (xy 276.882613 -143.918131) (xy 276.898037 -143.865934) (xy 276.920724 -143.816459)
			(xy 276.950213 -143.77071) (xy 276.985904 -143.729618) (xy 277.027074 -143.694016) (xy 277.072886 -143.664626)
			(xy 277.12241 -143.642047) (xy 277.174641 -143.626736) (xy 277.228518 -143.619005) (xy 277.255732 -143.618458)
			(xy 277.25878 -143.618458) (xy 277.286022 -143.618942) (xy 277.339951 -143.626689) (xy 277.39223 -143.642029)
			(xy 277.441795 -143.66465) (xy 277.487638 -143.694092) (xy 277.528827 -143.729755) (xy 277.564523 -143.770915)
			(xy 277.594002 -143.816735) (xy 277.616663 -143.866281) (xy 277.632045 -143.918548) (xy 277.639836 -143.972471)
			(xy 277.640288 -143.999712) (xy 277.640288 -144.00022) (xy 277.638764 -144.032732) (xy 277.63851 -144.036288)
			(xy 277.63851 -144.03832) (xy 277.638764 -144.041876) (xy 277.640288 -144.075658) (xy 277.640288 -144.076166)
			(xy 277.639837 -144.102887) (xy 277.632381 -144.155806) (xy 277.617623 -144.20717) (xy 277.595852 -144.255976)
			(xy 277.567492 -144.301273) (xy 277.533097 -144.342175) (xy 277.513542 -144.360392) (xy 277.505414 -144.367758)
			(xy 277.501096 -144.37741) (xy 277.497794 -144.384522) (xy 277.494492 -144.411192) (xy 277.494238 -144.412716)
			(xy 277.504144 -144.42821) (xy 277.518442 -144.451372) (xy 277.541042 -144.500888) (xy 277.556374 -144.553114)
			(xy 277.564125 -144.606989) (xy 277.564596 -144.634204) (xy 277.564088 -144.656048) (xy 277.564342 -144.66316)
			(xy 277.565657 -144.674735) (xy 277.567057 -144.697992) (xy 277.567136 -144.709642) (xy 277.567136 -144.710404)
			(xy 277.566647 -144.737825) (xy 277.558845 -144.792108) (xy 277.5434 -144.84473) (xy 277.520626 -144.894619)
			(xy 277.490987 -144.940761) (xy 277.455086 -144.982217) (xy 277.413651 -145.018144) (xy 277.367528 -145.047812)
			(xy 277.317653 -145.070617) (xy 277.265041 -145.086094) (xy 277.210762 -145.09393) (xy 277.183342 -145.094452)
			(xy 277.183088 -145.094452) (xy 277.172713 -145.094307) (xy 277.152001 -145.093038) (xy 277.141686 -145.091912)
			(xy 277.141432 -145.091912) (xy 277.131915 -145.091249) (xy 277.113506 -145.096199) (xy 277.105618 -145.101564)
			(xy 277.07463 -145.124678) (xy 277.074122 -145.124678) (xy 277.05304 -145.140172) (xy 277.050246 -145.14322)
			(xy 277.043134 -145.150332) (xy 277.034752 -145.165064) (xy 277.033228 -145.173192) (xy 277.027763 -145.198966)
			(xy 277.010692 -145.248809) (xy 276.986935 -145.295835) (xy 276.956944 -145.339152) (xy 276.921287 -145.377938)
			(xy 276.88064 -145.411458) (xy 276.835773 -145.439077) (xy 276.787538 -145.460271) (xy 276.736849 -145.474639)
			(xy 276.684667 -145.481906) (xy 276.658324 -145.48231) (xy 276.624288 -145.480786) (xy 276.613366 -145.479516)
			(xy 276.585847 -145.475732) (xy 276.532224 -145.461236) (xy 276.481267 -145.439125) (xy 276.434049 -145.409868)
			(xy 276.391567 -145.374081) (xy 276.354715 -145.332518) (xy 276.324272 -145.286056) (xy 276.312122 -145.261076)
			(xy 276.31136 -145.259298) (xy 276.309328 -145.255234) (xy 276.306026 -145.246852) (xy 276.299422 -145.239994)
			(xy 276.296492 -145.237056) (xy 276.289856 -145.232075) (xy 276.286214 -145.230088) (xy 276.249638 -145.214594)
			(xy 276.24913 -145.214086) (xy 276.229572 -145.206212) (xy 276.219158 -145.203672) (xy 276.211792 -145.202656)
			(xy 276.19579 -145.205704) (xy 276.191726 -145.207228) (xy 276.17039 -145.214086) (xy 276.161754 -145.216626)
			(xy 276.132544 -145.237962) (xy 276.127464 -145.245836) (xy 276.12721 -145.24609) (xy 276.103588 -145.283174)
			(xy 276.103588 -145.283682) (xy 276.101556 -145.28673) (xy 276.101556 -145.30578) (xy 276.100286 -145.338292)
			(xy 276.100032 -145.339562) (xy 276.099778 -145.343372) (xy 276.100286 -145.34769) (xy 276.100286 -145.348198)
			(xy 276.10054 -145.35023) (xy 276.10181 -145.38198) (xy 276.10181 -145.382234) (xy 276.101269 -145.41059)
			(xy 276.09284 -145.466672) (xy 276.076217 -145.520893) (xy 276.051764 -145.572062) (xy 276.020018 -145.619057)
			(xy 276.001226 -145.640298) (xy 276.000718 -145.640806) (xy 275.997416 -145.644616) (xy 275.991066 -145.66138)
			(xy 275.985732 -146.142456) (xy 275.979382 -146.72564) (xy 275.979382 -146.729196) (xy 275.980057 -146.740118)
			(xy 280.90622 -146.740118) (xy 280.90622 -146.739864) (xy 280.906655 -146.704463) (xy 280.915194 -146.634177)
			(xy 280.932143 -146.565433) (xy 280.957254 -146.499233) (xy 280.990161 -146.436543) (xy 281.030386 -146.378277)
			(xy 281.07734 -146.325283) (xy 281.13034 -146.278336) (xy 281.188612 -146.23812) (xy 281.251306 -146.205221)
			(xy 281.31751 -146.180119) (xy 281.386256 -146.16318) (xy 281.456543 -146.154651) (xy 281.491944 -146.15414)
			(xy 281.492198 -146.15414) (xy 281.525051 -146.154607) (xy 281.590344 -146.16197) (xy 281.654404 -146.176593)
			(xy 281.716425 -146.198291) (xy 281.775628 -146.226792) (xy 281.831271 -146.261739) (xy 281.882654 -146.302692)
			(xy 281.906218 -146.32559) (xy 282.376626 -146.795998) (xy 282.743654 -146.795998) (xy 282.747725 -146.740376)
			(xy 282.759851 -146.685939) (xy 282.779774 -146.633848) (xy 282.80707 -146.585213) (xy 282.841156 -146.54107)
			(xy 282.881305 -146.502361) (xy 282.926663 -146.46991) (xy 282.976263 -146.444409) (xy 283.029047 -146.426402)
			(xy 283.08389 -146.416272) (xy 283.139624 -146.414235) (xy 283.195061 -146.420335) (xy 283.249018 -146.434441)
			(xy 283.300347 -146.456253) (xy 283.347953 -146.485307) (xy 283.390821 -146.520982) (xy 283.428038 -146.562519)
			(xy 283.458811 -146.609032) (xy 283.482483 -146.659529) (xy 283.498551 -146.712936) (xy 283.506671 -146.768112)
			(xy 283.50718 -146.795998) (xy 283.506671 -146.823884) (xy 283.498551 -146.87906) (xy 283.482483 -146.932467)
			(xy 283.458811 -146.982964) (xy 283.428038 -147.029477) (xy 283.390821 -147.071014) (xy 283.347953 -147.106689)
			(xy 283.300347 -147.135743) (xy 283.249018 -147.157555) (xy 283.195061 -147.171661) (xy 283.139624 -147.177761)
			(xy 283.08389 -147.175724) (xy 283.029047 -147.165594) (xy 282.976263 -147.147587) (xy 282.926663 -147.122086)
			(xy 282.881305 -147.089635) (xy 282.841156 -147.050926) (xy 282.80707 -147.006783) (xy 282.779774 -146.958148)
			(xy 282.759851 -146.906057) (xy 282.747725 -146.85162) (xy 282.743654 -146.795998) (xy 282.376626 -146.795998)
			(xy 283.074618 -147.49399) (xy 283.09751 -147.517561) (xy 283.138478 -147.568935) (xy 283.173437 -147.624573)
			(xy 283.201947 -147.683775) (xy 283.223648 -147.745797) (xy 283.238269 -147.809859) (xy 283.245625 -147.875155)
			(xy 283.246068 -147.90801) (xy 283.246068 -149.581108) (xy 283.263086 -149.606762) (xy 283.277564 -149.612604)
			(xy 283.28695 -149.615967) (xy 283.306869 -149.615963) (xy 283.325281 -149.608364) (xy 283.332682 -149.601682)
			(xy 284.872938 -148.06168) (xy 284.879785 -148.054285) (xy 284.887499 -148.035682) (xy 284.887924 -148.025612)
			(xy 284.887924 -141.677644) (xy 284.887496 -141.667575) (xy 284.879779 -141.648976) (xy 284.872938 -141.641576)
			(xy 283.772864 -140.541756) (xy 283.749964 -140.518161) (xy 283.708967 -140.466754) (xy 283.673978 -140.411083)
			(xy 283.645435 -140.351848) (xy 283.623698 -140.289792) (xy 283.609039 -140.225694) (xy 283.601641 -140.160358)
			(xy 283.60116 -140.127482) (xy 283.601618 -140.092066) (xy 283.610158 -140.021751) (xy 283.627112 -139.952978)
			(xy 283.652232 -139.88675) (xy 283.685152 -139.824033) (xy 283.725392 -139.765741) (xy 283.772364 -139.712725)
			(xy 283.825385 -139.665757) (xy 283.883681 -139.625523) (xy 283.946401 -139.592609) (xy 284.012631 -139.567495)
			(xy 284.081406 -139.550548) (xy 284.151722 -139.542015) (xy 284.187138 -139.541504) (xy 284.220018 -139.541983)
			(xy 284.285365 -139.549344) (xy 284.349475 -139.563979) (xy 284.411542 -139.585704) (xy 284.470785 -139.614247)
			(xy 284.526457 -139.649247) (xy 284.577857 -139.690264) (xy 284.601412 -139.713208) (xy 285.887922 -140.999718)
			(xy 285.910828 -141.023276) (xy 285.951795 -141.074652) (xy 285.986753 -141.130293) (xy 286.01526 -141.189497)
			(xy 286.036959 -141.251521) (xy 286.051577 -141.315585) (xy 286.05893 -141.380883) (xy 286.059372 -141.413738)
			(xy 286.059372 -148.289518) (xy 286.058914 -148.322372) (xy 286.051549 -148.387665) (xy 286.036925 -148.451724)
			(xy 286.015225 -148.513745) (xy 285.986722 -148.572948) (xy 285.951774 -148.628591) (xy 285.91082 -148.679974)
			(xy 285.887922 -148.703538) (xy 285.428944 -149.162516) (xy 285.428436 -149.203918) (xy 285.44266 -149.218904)
			(xy 285.462412 -149.240354) (xy 285.495849 -149.288121) (xy 285.521631 -149.340418) (xy 285.53916 -149.396028)
			(xy 285.548027 -149.453656) (xy 285.548578 -149.48281) (xy 285.548123 -149.510181) (xy 285.540303 -149.56436)
			(xy 285.524812 -149.616864) (xy 285.501968 -149.666611) (xy 285.472241 -149.712577) (xy 285.454598 -149.733508)
			(xy 285.454344 -149.733762) (xy 285.448761 -149.74085) (xy 285.442513 -149.757766) (xy 285.442152 -149.766782)
			(xy 285.442152 -149.833838) (xy 285.442479 -149.842858) (xy 285.448746 -149.859775) (xy 285.454344 -149.866858)
			(xy 285.454598 -149.866858) (xy 285.454598 -149.867112) (xy 285.472209 -149.888067) (xy 285.501925 -149.934033)
			(xy 285.524767 -149.983775) (xy 285.540264 -150.036271) (xy 285.5481 -150.090442) (xy 285.548578 -150.11781)
			(xy 285.548092 -150.145061) (xy 285.540336 -150.199009) (xy 285.524981 -150.251304) (xy 285.502339 -150.300881)
			(xy 285.472873 -150.346731) (xy 285.437182 -150.387922) (xy 285.395991 -150.423613) (xy 285.350141 -150.453079)
			(xy 285.300564 -150.475721) (xy 285.248269 -150.491076) (xy 285.194321 -150.498832) (xy 285.139819 -150.498832)
			(xy 285.085871 -150.491076) (xy 285.033576 -150.475721) (xy 284.983999 -150.453079) (xy 284.938149 -150.423613)
			(xy 284.896958 -150.387922) (xy 284.861267 -150.346731) (xy 284.831801 -150.300881) (xy 284.809159 -150.251304)
			(xy 284.793804 -150.199009) (xy 284.786048 -150.145061) (xy 284.785562 -150.11781) (xy 284.786091 -150.088332)
			(xy 284.79516 -150.030077) (xy 284.813084 -149.973912) (xy 284.839437 -149.921173) (xy 284.873589 -149.873116)
			(xy 284.893766 -149.851618) (xy 284.900295 -149.844279) (xy 284.907741 -149.826122) (xy 284.908244 -149.816312)
			(xy 284.908244 -149.762972) (xy 284.903164 -149.7584) (xy 284.888178 -149.744176) (xy 284.846776 -149.744684)
			(xy 283.89199 -150.699216) (xy 283.885149 -150.706615) (xy 283.87743 -150.725215) (xy 283.877004 -150.735284)
			(xy 283.877004 -150.738078) (xy 283.877491 -150.749614) (xy 283.887457 -150.770417) (xy 283.905497 -150.784793)
			(xy 283.916628 -150.787862) (xy 283.942961 -150.794317) (xy 283.993643 -150.813562) (xy 284.04109 -150.839791)
			(xy 284.084343 -150.872475) (xy 284.122532 -150.910956) (xy 284.154885 -150.954457) (xy 284.180752 -151.002102)
			(xy 284.19961 -151.05293) (xy 284.21108 -151.105917) (xy 284.214929 -151.159994) (xy 284.211081 -151.214071)
			(xy 284.201791 -151.257) (xy 284.776924 -151.257) (xy 284.780995 -151.201378) (xy 284.793121 -151.146941)
			(xy 284.813044 -151.09485) (xy 284.84034 -151.046215) (xy 284.874426 -151.002072) (xy 284.914575 -150.963363)
			(xy 284.959933 -150.930912) (xy 285.009533 -150.905411) (xy 285.062317 -150.887404) (xy 285.11716 -150.877274)
			(xy 285.172894 -150.875237) (xy 285.228331 -150.881337) (xy 285.282288 -150.895443) (xy 285.333617 -150.917255)
			(xy 285.381223 -150.946309) (xy 285.424091 -150.981984) (xy 285.461308 -151.023521) (xy 285.492081 -151.070034)
			(xy 285.515753 -151.120531) (xy 285.531821 -151.173938) (xy 285.539941 -151.229114) (xy 285.54045 -151.257)
			(xy 285.539941 -151.284886) (xy 285.531821 -151.340062) (xy 285.515753 -151.393469) (xy 285.492081 -151.443966)
			(xy 285.461308 -151.490479) (xy 285.424091 -151.532016) (xy 285.381223 -151.567691) (xy 285.333617 -151.596745)
			(xy 285.282288 -151.618557) (xy 285.228331 -151.632663) (xy 285.172894 -151.638763) (xy 285.11716 -151.636726)
			(xy 285.062317 -151.626596) (xy 285.009533 -151.608589) (xy 284.959933 -151.583088) (xy 284.914575 -151.550637)
			(xy 284.874426 -151.511928) (xy 284.84034 -151.467785) (xy 284.813044 -151.41915) (xy 284.793121 -151.367059)
			(xy 284.780995 -151.312622) (xy 284.776924 -151.257) (xy 284.201791 -151.257) (xy 284.199614 -151.267058)
			(xy 284.180757 -151.317887) (xy 284.154892 -151.365532) (xy 284.12254 -151.409035) (xy 284.084352 -151.447517)
			(xy 284.0411 -151.480202) (xy 283.993655 -151.506433) (xy 283.942972 -151.52568) (xy 283.916628 -151.532082)
			(xy 283.905505 -151.535178) (xy 283.887457 -151.549535) (xy 283.877494 -151.570333) (xy 283.877004 -151.581866)
			(xy 283.877004 -152.538176) (xy 283.877492 -152.549712) (xy 283.887458 -152.570515) (xy 283.905497 -152.584891)
			(xy 283.916628 -152.58796) (xy 283.94296 -152.594418) (xy 283.993642 -152.613663) (xy 284.041088 -152.639892)
			(xy 284.084342 -152.672576) (xy 284.12253 -152.711057) (xy 284.154883 -152.754558) (xy 284.18075 -152.802203)
			(xy 284.199608 -152.853031) (xy 284.211078 -152.906017) (xy 284.214927 -152.960093) (xy 284.21108 -153.01417)
			(xy 284.199612 -153.067157) (xy 284.180755 -153.117985) (xy 284.154891 -153.165631) (xy 284.122538 -153.209133)
			(xy 284.084351 -153.247615) (xy 284.041099 -153.280301) (xy 283.993654 -153.306531) (xy 283.942972 -153.325778)
			(xy 283.916628 -153.33218) (xy 283.905505 -153.335278) (xy 283.887458 -153.349634) (xy 283.877494 -153.370431)
			(xy 283.877004 -153.381964) (xy 283.877004 -153.560018) (xy 284.649924 -153.560018) (xy 284.653995 -153.504396)
			(xy 284.666121 -153.449959) (xy 284.686044 -153.397868) (xy 284.71334 -153.349233) (xy 284.747426 -153.30509)
			(xy 284.787575 -153.266381) (xy 284.832933 -153.23393) (xy 284.882533 -153.208429) (xy 284.935317 -153.190422)
			(xy 284.99016 -153.180292) (xy 285.045894 -153.178255) (xy 285.101331 -153.184355) (xy 285.155288 -153.198461)
			(xy 285.206617 -153.220273) (xy 285.254223 -153.249327) (xy 285.297091 -153.285002) (xy 285.334308 -153.326539)
			(xy 285.365081 -153.373052) (xy 285.388753 -153.423549) (xy 285.404821 -153.476956) (xy 285.412941 -153.532132)
			(xy 285.41345 -153.560018) (xy 285.412941 -153.587904) (xy 285.404821 -153.64308) (xy 285.388753 -153.696487)
			(xy 285.365081 -153.746984) (xy 285.334308 -153.793497) (xy 285.297091 -153.835034) (xy 285.254223 -153.870709)
			(xy 285.206617 -153.899763) (xy 285.155288 -153.921575) (xy 285.101331 -153.935681) (xy 285.045894 -153.941781)
			(xy 284.99016 -153.939744) (xy 284.935317 -153.929614) (xy 284.882533 -153.911607) (xy 284.832933 -153.886106)
			(xy 284.787575 -153.853655) (xy 284.747426 -153.814946) (xy 284.71334 -153.770803) (xy 284.686044 -153.722168)
			(xy 284.666121 -153.670077) (xy 284.653995 -153.61564) (xy 284.649924 -153.560018) (xy 283.877004 -153.560018)
			(xy 283.877004 -153.709624) (xy 283.877317 -153.719069) (xy 283.884118 -153.736689) (xy 283.890212 -153.743914)
			(xy 283.910532 -153.766012) (xy 283.916703 -153.772317) (xy 283.932319 -153.780507) (xy 283.941012 -153.782014)
			(xy 283.968044 -153.786285) (xy 284.020631 -153.801428) (xy 284.070515 -153.82393) (xy 284.116671 -153.853329)
			(xy 284.158154 -153.889021) (xy 284.19411 -153.930275) (xy 284.223803 -153.976243) (xy 284.246624 -154.025982)
			(xy 284.262102 -154.078471) (xy 284.269922 -154.132633) (xy 284.269923 -154.187357) (xy 284.262104 -154.24152)
			(xy 284.246627 -154.29401) (xy 284.223808 -154.343749) (xy 284.194116 -154.389718) (xy 284.15816 -154.430972)
			(xy 284.116679 -154.466666) (xy 284.070523 -154.496066) (xy 284.02064 -154.518569) (xy 283.968053 -154.533714)
			(xy 283.941012 -154.537918) (xy 283.932345 -154.5395) (xy 283.91676 -154.547689) (xy 283.910532 -154.55392)
			(xy 283.890212 -154.576018) (xy 283.88421 -154.583295) (xy 283.87744 -154.600885) (xy 283.877004 -154.610308)
			(xy 283.877004 -154.958288) (xy 284.944056 -154.958288) (xy 284.948127 -154.902666) (xy 284.960253 -154.848229)
			(xy 284.980176 -154.796138) (xy 285.007472 -154.747503) (xy 285.041558 -154.70336) (xy 285.081707 -154.664651)
			(xy 285.127065 -154.6322) (xy 285.176665 -154.606699) (xy 285.229449 -154.588692) (xy 285.284292 -154.578562)
			(xy 285.340026 -154.576525) (xy 285.395463 -154.582625) (xy 285.44942 -154.596731) (xy 285.500749 -154.618543)
			(xy 285.548355 -154.647597) (xy 285.591223 -154.683272) (xy 285.62844 -154.724809) (xy 285.659213 -154.771322)
			(xy 285.682885 -154.821819) (xy 285.698953 -154.875226) (xy 285.707073 -154.930402) (xy 285.707582 -154.958288)
			(xy 285.707073 -154.986174) (xy 285.698953 -155.04135) (xy 285.682885 -155.094757) (xy 285.659213 -155.145254)
			(xy 285.62844 -155.191767) (xy 285.591223 -155.233304) (xy 285.548355 -155.268979) (xy 285.500749 -155.298033)
			(xy 285.44942 -155.319845) (xy 285.395463 -155.333951) (xy 285.340026 -155.340051) (xy 285.284292 -155.338014)
			(xy 285.229449 -155.327884) (xy 285.176665 -155.309877) (xy 285.127065 -155.284376) (xy 285.081707 -155.251925)
			(xy 285.041558 -155.213216) (xy 285.007472 -155.169073) (xy 284.980176 -155.120438) (xy 284.960253 -155.068347)
			(xy 284.948127 -155.01391) (xy 284.944056 -154.958288) (xy 283.877004 -154.958288) (xy 283.877004 -155.116022)
			(xy 283.877402 -155.125727) (xy 283.884589 -155.143754) (xy 283.890974 -155.151074) (xy 283.93898 -155.201874)
			(xy 283.945855 -155.208558) (xy 283.963222 -155.216652) (xy 283.972762 -155.217622) (xy 284.000147 -155.219788)
			(xy 284.053948 -155.230871) (xy 284.105603 -155.249557) (xy 284.154042 -155.275461) (xy 284.198265 -155.308046)
			(xy 284.237354 -155.346638) (xy 284.270503 -155.39044) (xy 284.297025 -155.438544) (xy 284.316371 -155.489955)
			(xy 284.328141 -155.54361) (xy 284.332092 -155.598398) (xy 284.328142 -155.653187) (xy 284.316372 -155.706842)
			(xy 284.297026 -155.758253) (xy 284.270505 -155.806357) (xy 284.237357 -155.850159) (xy 284.198267 -155.888752)
			(xy 284.154046 -155.921337) (xy 284.105606 -155.947241) (xy 284.053952 -155.965928) (xy 284.000151 -155.977011)
			(xy 283.972762 -155.979114) (xy 283.963232 -155.980122) (xy 283.945875 -155.988208) (xy 283.93898 -155.994862)
			(xy 283.890974 -156.045662) (xy 283.884629 -156.053007) (xy 283.877439 -156.071018) (xy 283.877004 -156.080714)
			(xy 283.877004 -156.544518) (xy 284.9278 -156.544518) (xy 284.931871 -156.488896) (xy 284.943997 -156.434459)
			(xy 284.96392 -156.382368) (xy 284.991216 -156.333733) (xy 285.025302 -156.28959) (xy 285.065451 -156.250881)
			(xy 285.110809 -156.21843) (xy 285.160409 -156.192929) (xy 285.213193 -156.174922) (xy 285.268036 -156.164792)
			(xy 285.32377 -156.162755) (xy 285.379207 -156.168855) (xy 285.433164 -156.182961) (xy 285.484493 -156.204773)
			(xy 285.532099 -156.233827) (xy 285.574967 -156.269502) (xy 285.612184 -156.311039) (xy 285.642957 -156.357552)
			(xy 285.666629 -156.408049) (xy 285.682697 -156.461456) (xy 285.690817 -156.516632) (xy 285.691326 -156.544518)
			(xy 285.690817 -156.572404) (xy 285.682697 -156.62758) (xy 285.666629 -156.680987) (xy 285.642957 -156.731484)
			(xy 285.612184 -156.777997) (xy 285.574967 -156.819534) (xy 285.532099 -156.855209) (xy 285.484493 -156.884263)
			(xy 285.433164 -156.906075) (xy 285.379207 -156.920181) (xy 285.32377 -156.926281) (xy 285.268036 -156.924244)
			(xy 285.213193 -156.914114) (xy 285.160409 -156.896107) (xy 285.110809 -156.870606) (xy 285.065451 -156.838155)
			(xy 285.025302 -156.799446) (xy 284.991216 -156.755303) (xy 284.96392 -156.706668) (xy 284.943997 -156.654577)
			(xy 284.931871 -156.60014) (xy 284.9278 -156.544518) (xy 283.877004 -156.544518) (xy 283.877004 -156.644086)
			(xy 283.877332 -156.653377) (xy 283.883924 -156.670748) (xy 283.896282 -156.684623) (xy 283.912778 -156.693174)
			(xy 283.921962 -156.694632) (xy 283.922216 -156.694632) (xy 283.949774 -156.698295) (xy 284.003501 -156.712573)
			(xy 284.054586 -156.734498) (xy 284.101948 -156.763606) (xy 284.144583 -156.799281) (xy 284.181587 -156.840767)
			(xy 284.212178 -156.887186) (xy 284.235706 -156.937553) (xy 284.251675 -156.990801) (xy 284.259744 -157.045804)
			(xy 284.259744 -157.101396) (xy 284.251675 -157.156399) (xy 284.235706 -157.209647) (xy 284.212178 -157.260014)
			(xy 284.181587 -157.306433) (xy 284.144583 -157.347919) (xy 284.101948 -157.383594) (xy 284.054586 -157.412702)
			(xy 284.003501 -157.434627) (xy 283.949774 -157.448905) (xy 283.922216 -157.452568) (xy 283.921962 -157.452568)
			(xy 283.912799 -157.45406) (xy 283.896357 -157.462647) (xy 283.88403 -157.476508) (xy 283.877421 -157.49384)
			(xy 283.877004 -157.503114) (xy 283.877004 -164.198554) (xy 283.876554 -164.231673) (xy 283.869043 -164.297485)
			(xy 283.854156 -164.36203) (xy 283.832084 -164.424484) (xy 283.803108 -164.484049) (xy 283.767599 -164.539966)
			(xy 283.726008 -164.591521) (xy 283.70276 -164.615114) (xy 283.695902 -164.621972) (xy 283.688028 -164.639244)
			(xy 283.684472 -164.717984) (xy 283.68448 -164.72744) (xy 283.69061 -164.745314) (xy 283.69641 -164.752782)
			(xy 283.718082 -164.779232) (xy 283.75576 -164.8363) (xy 283.786542 -164.897363) (xy 283.810011 -164.961594)
			(xy 283.825846 -165.028119) (xy 283.833834 -165.096034) (xy 283.834332 -165.130226) (xy 283.833889 -165.165642)
			(xy 283.825348 -165.235958) (xy 283.808393 -165.304732) (xy 283.783272 -165.370961) (xy 283.750351 -165.433678)
			(xy 283.71011 -165.49197) (xy 283.663136 -165.544987) (xy 283.610114 -165.591954) (xy 283.551817 -165.632188)
			(xy 283.489095 -165.665102) (xy 283.422863 -165.690215) (xy 283.354088 -165.707161) (xy 283.28377 -165.715694)
			(xy 283.248354 -165.716204) (xy 283.230574 -165.716204) (xy 283.197693 -165.71578) (xy 283.132344 -165.70841)
			(xy 283.068232 -165.693765) (xy 283.006165 -165.672031) (xy 282.946923 -165.64348) (xy 282.891252 -165.608472)
			(xy 282.839854 -165.567448) (xy 282.8163 -165.5445) (xy 282.24607 -164.97427) (xy 282.223156 -164.950719)
			(xy 282.18219 -164.899341) (xy 282.147234 -164.843699) (xy 282.118728 -164.784494) (xy 282.09703 -164.722468)
			(xy 282.082413 -164.658404) (xy 282.075061 -164.593106) (xy 282.07462 -164.56025) (xy 282.07462 -148.171916)
			(xy 282.074208 -148.161845) (xy 282.06648 -148.143246) (xy 282.059634 -148.135848) (xy 281.07767 -147.154138)
			(xy 281.054741 -147.130602) (xy 281.013776 -147.079221) (xy 280.978821 -147.023577) (xy 280.950317 -146.964368)
			(xy 280.928622 -146.902341) (xy 280.914008 -146.838274) (xy 280.906659 -146.772974) (xy 280.90622 -146.740118)
			(xy 275.980057 -146.740118) (xy 276.019006 -147.3708) (xy 276.368764 -153.05786) (xy 276.368764 -153.058876)
			(xy 276.523421 -155.0416) (xy 280.363674 -155.0416) (xy 280.367745 -154.985978) (xy 280.379871 -154.931541)
			(xy 280.399794 -154.87945) (xy 280.42709 -154.830815) (xy 280.461176 -154.786672) (xy 280.501325 -154.747963)
			(xy 280.546683 -154.715512) (xy 280.596283 -154.690011) (xy 280.649067 -154.672004) (xy 280.70391 -154.661874)
			(xy 280.759644 -154.659837) (xy 280.815081 -154.665937) (xy 280.869038 -154.680043) (xy 280.920367 -154.701855)
			(xy 280.967973 -154.730909) (xy 281.010841 -154.766584) (xy 281.048058 -154.808121) (xy 281.078831 -154.854634)
			(xy 281.102503 -154.905131) (xy 281.118571 -154.958538) (xy 281.126691 -155.013714) (xy 281.1272 -155.0416)
			(xy 281.126691 -155.069486) (xy 281.118571 -155.124662) (xy 281.102503 -155.178069) (xy 281.078831 -155.228566)
			(xy 281.048058 -155.275079) (xy 281.010841 -155.316616) (xy 280.967973 -155.352291) (xy 280.920367 -155.381345)
			(xy 280.869038 -155.403157) (xy 280.815081 -155.417263) (xy 280.759644 -155.423363) (xy 280.70391 -155.421326)
			(xy 280.649067 -155.411196) (xy 280.596283 -155.393189) (xy 280.546683 -155.367688) (xy 280.501325 -155.335237)
			(xy 280.461176 -155.296528) (xy 280.42709 -155.252385) (xy 280.399794 -155.20375) (xy 280.379871 -155.151659)
			(xy 280.367745 -155.097222) (xy 280.363674 -155.0416) (xy 276.523421 -155.0416) (xy 276.924627 -160.1851)
			(xy 277.724121 -160.1851) (xy 277.728076 -160.093263) (xy 277.739911 -160.002106) (xy 277.759538 -159.912303)
			(xy 277.786812 -159.824521) (xy 277.821532 -159.739407) (xy 277.86344 -159.657594) (xy 277.912226 -159.579686)
			(xy 277.967529 -159.506261) (xy 278.028939 -159.437861) (xy 278.096001 -159.374994) (xy 278.16822 -159.318124)
			(xy 278.24506 -159.267673) (xy 278.325953 -159.224014) (xy 278.410299 -159.187471) (xy 278.497475 -159.158314)
			(xy 278.586834 -159.13676) (xy 278.677715 -159.122966) (xy 278.769446 -159.117036) (xy 278.861347 -159.119014)
			(xy 278.952738 -159.128885) (xy 279.042942 -159.146575) (xy 279.131291 -159.171955) (xy 279.217131 -159.204835)
			(xy 279.299827 -159.244973) (xy 279.378767 -159.292072) (xy 279.453365 -159.345782) (xy 279.523071 -159.405706)
			(xy 279.587366 -159.4714) (xy 279.645777 -159.542378) (xy 279.697869 -159.618115) (xy 279.743258 -159.69805)
			(xy 279.781608 -159.78159) (xy 279.812633 -159.868118) (xy 279.836106 -159.956993) (xy 279.851852 -160.047557)
			(xy 279.859754 -160.139139) (xy 279.860248 -160.1851) (xy 279.859754 -160.231061) (xy 279.851852 -160.322643)
			(xy 279.836106 -160.413207) (xy 279.812633 -160.502082) (xy 279.781608 -160.58861) (xy 279.743258 -160.67215)
			(xy 279.697869 -160.752085) (xy 279.645777 -160.827822) (xy 279.587366 -160.8988) (xy 279.523071 -160.964494)
			(xy 279.453365 -161.024418) (xy 279.378767 -161.078128) (xy 279.299827 -161.125227) (xy 279.217131 -161.165365)
			(xy 279.131291 -161.198245) (xy 279.042942 -161.223625) (xy 278.952738 -161.241315) (xy 278.861347 -161.251186)
			(xy 278.769446 -161.253164) (xy 278.677715 -161.247234) (xy 278.586834 -161.23344) (xy 278.497475 -161.211886)
			(xy 278.410299 -161.182729) (xy 278.325953 -161.146186) (xy 278.24506 -161.102527) (xy 278.16822 -161.052076)
			(xy 278.096001 -160.995206) (xy 278.028939 -160.932339) (xy 277.967529 -160.863939) (xy 277.912226 -160.790514)
			(xy 277.86344 -160.712606) (xy 277.821532 -160.630793) (xy 277.786812 -160.545679) (xy 277.759538 -160.457897)
			(xy 277.739911 -160.368094) (xy 277.728076 -160.276937) (xy 277.724121 -160.1851) (xy 276.924627 -160.1851)
			(xy 277.565188 -168.397174) (xy 282.841698 -168.397174) (xy 282.845769 -168.341552) (xy 282.857895 -168.287115)
			(xy 282.877818 -168.235024) (xy 282.905114 -168.186389) (xy 282.9392 -168.142246) (xy 282.979349 -168.103537)
			(xy 283.024707 -168.071086) (xy 283.074307 -168.045585) (xy 283.127091 -168.027578) (xy 283.181934 -168.017448)
			(xy 283.237668 -168.015411) (xy 283.293105 -168.021511) (xy 283.347062 -168.035617) (xy 283.398391 -168.057429)
			(xy 283.445997 -168.086483) (xy 283.488865 -168.122158) (xy 283.526082 -168.163695) (xy 283.556855 -168.210208)
			(xy 283.580527 -168.260705) (xy 283.596595 -168.314112) (xy 283.604715 -168.369288) (xy 283.605224 -168.397174)
			(xy 283.604715 -168.42506) (xy 283.596595 -168.480236) (xy 283.580527 -168.533643) (xy 283.556855 -168.58414)
			(xy 283.526082 -168.630653) (xy 283.488865 -168.67219) (xy 283.445997 -168.707865) (xy 283.398391 -168.736919)
			(xy 283.347062 -168.758731) (xy 283.293105 -168.772837) (xy 283.237668 -168.778937) (xy 283.181934 -168.7769)
			(xy 283.127091 -168.76677) (xy 283.074307 -168.748763) (xy 283.024707 -168.723262) (xy 282.979349 -168.690811)
			(xy 282.9392 -168.652102) (xy 282.905114 -168.607959) (xy 282.877818 -168.559324) (xy 282.857895 -168.507233)
			(xy 282.845769 -168.452796) (xy 282.841698 -168.397174) (xy 277.565188 -168.397174) (xy 277.667659 -169.710862)
			(xy 281.061412 -169.710862) (xy 281.065483 -169.65524) (xy 281.077609 -169.600803) (xy 281.097532 -169.548712)
			(xy 281.124828 -169.500077) (xy 281.158914 -169.455934) (xy 281.199063 -169.417225) (xy 281.244421 -169.384774)
			(xy 281.294021 -169.359273) (xy 281.346805 -169.341266) (xy 281.401648 -169.331136) (xy 281.457382 -169.329099)
			(xy 281.512819 -169.335199) (xy 281.566776 -169.349305) (xy 281.618105 -169.371117) (xy 281.665711 -169.400171)
			(xy 281.708579 -169.435846) (xy 281.745796 -169.477383) (xy 281.776569 -169.523896) (xy 281.800241 -169.574393)
			(xy 281.816309 -169.6278) (xy 281.824429 -169.682976) (xy 281.824938 -169.710862) (xy 281.824429 -169.738748)
			(xy 281.816309 -169.793924) (xy 281.800241 -169.847331) (xy 281.776569 -169.897828) (xy 281.745796 -169.944341)
			(xy 281.708579 -169.985878) (xy 281.665711 -170.021553) (xy 281.618105 -170.050607) (xy 281.566776 -170.072419)
			(xy 281.512819 -170.086525) (xy 281.457382 -170.092625) (xy 281.401648 -170.090588) (xy 281.346805 -170.080458)
			(xy 281.294021 -170.062451) (xy 281.244421 -170.03695) (xy 281.199063 -170.004499) (xy 281.158914 -169.96579)
			(xy 281.124828 -169.921647) (xy 281.097532 -169.873012) (xy 281.077609 -169.820921) (xy 281.065483 -169.766484)
			(xy 281.061412 -169.710862) (xy 277.667659 -169.710862) (xy 278.040493 -174.490634) (xy 282.011372 -174.490634)
			(xy 282.015443 -174.435012) (xy 282.027569 -174.380575) (xy 282.047492 -174.328484) (xy 282.074788 -174.279849)
			(xy 282.108874 -174.235706) (xy 282.149023 -174.196997) (xy 282.194381 -174.164546) (xy 282.243981 -174.139045)
			(xy 282.296765 -174.121038) (xy 282.351608 -174.110908) (xy 282.407342 -174.108871) (xy 282.462779 -174.114971)
			(xy 282.516736 -174.129077) (xy 282.568065 -174.150889) (xy 282.615671 -174.179943) (xy 282.658539 -174.215618)
			(xy 282.695756 -174.257155) (xy 282.726529 -174.303668) (xy 282.750201 -174.354165) (xy 282.766269 -174.407572)
			(xy 282.774389 -174.462748) (xy 282.774898 -174.490634) (xy 282.774389 -174.51852) (xy 282.766269 -174.573696)
			(xy 282.750201 -174.627103) (xy 282.726529 -174.6776) (xy 282.695756 -174.724113) (xy 282.658539 -174.76565)
			(xy 282.615671 -174.801325) (xy 282.568065 -174.830379) (xy 282.516736 -174.852191) (xy 282.462779 -174.866297)
			(xy 282.407342 -174.872397) (xy 282.351608 -174.87036) (xy 282.296765 -174.86023) (xy 282.243981 -174.842223)
			(xy 282.194381 -174.816722) (xy 282.149023 -174.784271) (xy 282.108874 -174.745562) (xy 282.074788 -174.701419)
			(xy 282.047492 -174.652784) (xy 282.027569 -174.600693) (xy 282.015443 -174.546256) (xy 282.011372 -174.490634)
			(xy 278.040493 -174.490634) (xy 278.137179 -175.730154) (xy 283.157166 -175.730154) (xy 283.161237 -175.674532)
			(xy 283.173363 -175.620095) (xy 283.193286 -175.568004) (xy 283.220582 -175.519369) (xy 283.254668 -175.475226)
			(xy 283.294817 -175.436517) (xy 283.340175 -175.404066) (xy 283.389775 -175.378565) (xy 283.442559 -175.360558)
			(xy 283.497402 -175.350428) (xy 283.553136 -175.348391) (xy 283.608573 -175.354491) (xy 283.66253 -175.368597)
			(xy 283.713859 -175.390409) (xy 283.761465 -175.419463) (xy 283.804333 -175.455138) (xy 283.84155 -175.496675)
			(xy 283.872323 -175.543188) (xy 283.895995 -175.593685) (xy 283.912063 -175.647092) (xy 283.920183 -175.702268)
			(xy 283.920692 -175.730154) (xy 283.920183 -175.75804) (xy 283.912063 -175.813216) (xy 283.895995 -175.866623)
			(xy 283.872323 -175.91712) (xy 283.84155 -175.963633) (xy 283.804333 -176.00517) (xy 283.761465 -176.040845)
			(xy 283.713859 -176.069899) (xy 283.66253 -176.091711) (xy 283.608573 -176.105817) (xy 283.553136 -176.111917)
			(xy 283.497402 -176.10988) (xy 283.442559 -176.09975) (xy 283.389775 -176.081743) (xy 283.340175 -176.056242)
			(xy 283.294817 -176.023791) (xy 283.254668 -175.985082) (xy 283.220582 -175.940939) (xy 283.193286 -175.892304)
			(xy 283.173363 -175.840213) (xy 283.161237 -175.785776) (xy 283.157166 -175.730154) (xy 278.137179 -175.730154)
			(xy 278.449049 -179.728368) (xy 283.616652 -179.728368) (xy 283.620723 -179.672746) (xy 283.632849 -179.618309)
			(xy 283.652772 -179.566218) (xy 283.680068 -179.517583) (xy 283.714154 -179.47344) (xy 283.754303 -179.434731)
			(xy 283.799661 -179.40228) (xy 283.849261 -179.376779) (xy 283.902045 -179.358772) (xy 283.956888 -179.348642)
			(xy 284.012622 -179.346605) (xy 284.068059 -179.352705) (xy 284.122016 -179.366811) (xy 284.173345 -179.388623)
			(xy 284.220951 -179.417677) (xy 284.263819 -179.453352) (xy 284.301036 -179.494889) (xy 284.331809 -179.541402)
			(xy 284.355481 -179.591899) (xy 284.371549 -179.645306) (xy 284.379669 -179.700482) (xy 284.380178 -179.728368)
			(xy 284.379669 -179.756254) (xy 284.371549 -179.81143) (xy 284.355481 -179.864837) (xy 284.331809 -179.915334)
			(xy 284.301036 -179.961847) (xy 284.263819 -180.003384) (xy 284.220951 -180.039059) (xy 284.173345 -180.068113)
			(xy 284.122016 -180.089925) (xy 284.068059 -180.104031) (xy 284.012622 -180.110131) (xy 283.956888 -180.108094)
			(xy 283.902045 -180.097964) (xy 283.849261 -180.079957) (xy 283.799661 -180.054456) (xy 283.754303 -180.022005)
			(xy 283.714154 -179.983296) (xy 283.680068 -179.939153) (xy 283.652772 -179.890518) (xy 283.632849 -179.838427)
			(xy 283.620723 -179.78399) (xy 283.616652 -179.728368) (xy 278.449049 -179.728368) (xy 281.557984 -219.585286)
			(xy 281.775408 -222.373444) (xy 282.024836 -225.458528) (xy 282.116022 -226.586288) (xy 282.1686 -227.236528)
			(xy 282.185872 -227.446332) (xy 282.186634 -227.451158) (xy 282.189124 -227.460485) (xy 282.199954 -227.476446)
			(xy 282.215915 -227.487276) (xy 282.225242 -227.489766) (xy 282.22575 -227.489766) (xy 282.236164 -227.491036)
			(xy 284.555692 -227.491036) (xy 284.565248 -227.490643) (xy 284.583022 -227.483625) (xy 284.596948 -227.47054)
			(xy 284.601412 -227.46208) (xy 284.60192 -227.46081) (xy 284.60192 -227.460556) (xy 284.603952 -227.455984)
			(xy 284.604206 -227.455222) (xy 284.60573 -227.449634) (xy 284.828488 -223.179386) (xy 285.4198 -211.819744)
			(xy 286.02813 -200.129394) (xy 286.58566 -189.418722) (xy 286.663892 -187.917582) (xy 286.739584 -186.463686)
			(xy 286.739584 -186.458606) (xy 286.738314 -186.44743) (xy 286.710519 -186.435894) (xy 286.658424 -186.40577)
			(xy 286.611396 -186.368224) (xy 286.570484 -186.324092) (xy 286.536602 -186.274359) (xy 286.510505 -186.220135)
			(xy 286.492774 -186.162629) (xy 286.483807 -186.103123) (xy 286.483298 -186.073034) (xy 286.483805 -186.044108)
			(xy 286.492105 -185.986855) (xy 286.508524 -185.931383) (xy 286.532724 -185.878836) (xy 286.564204 -185.830299)
			(xy 286.602315 -185.786775) (xy 286.64627 -185.749162) (xy 286.695161 -185.718236) (xy 286.74798 -185.694636)
			(xy 286.775652 -185.686192) (xy 286.777771 -185.681818) (xy 286.780464 -185.672481) (xy 286.780986 -185.66765)
			(xy 288.800794 -146.861784) (xy 288.883598 -145.273268) (xy 288.91357 -144.69618) (xy 288.91357 -144.691608)
			(xy 288.913182 -144.683253) (xy 288.90773 -144.667451) (xy 288.902902 -144.66062) (xy 288.897568 -144.654016)
			(xy 288.884106 -144.645126) (xy 288.875216 -144.642586) (xy 288.848088 -144.635208) (xy 288.796195 -144.613582)
			(xy 288.748029 -144.584588) (xy 288.704629 -144.548853) (xy 288.666931 -144.507147) (xy 288.635748 -144.460369)
			(xy 288.611753 -144.409529) (xy 288.595463 -144.355722) (xy 288.587229 -144.300109) (xy 288.586672 -144.272)
			(xy 288.587137 -144.245311) (xy 288.594564 -144.192452) (xy 288.609274 -144.141141) (xy 288.630979 -144.092376)
			(xy 288.659259 -144.047105) (xy 288.693563 -144.006209) (xy 288.733223 -143.970485) (xy 288.777468 -143.940626)
			(xy 288.825438 -143.917213) (xy 288.876198 -143.900703) (xy 288.902394 -143.895572) (xy 288.906712 -143.89481)
			(xy 288.914332 -143.89227) (xy 288.923222 -143.888968) (xy 288.926778 -143.88719) (xy 288.933382 -143.883634)
			(xy 288.937704 -143.880893) (xy 288.945244 -143.873974) (xy 288.948368 -143.869918) (xy 288.9504 -143.86687)
			(xy 288.957004 -143.856202) (xy 288.957766 -143.84274) (xy 288.961576 -143.772128) (xy 288.963608 -143.733774)
			(xy 288.963862 -143.730726) (xy 288.963862 -143.730472) (xy 288.96564 -143.695166) (xy 288.976054 -143.494506)
			(xy 288.981896 -143.382746) (xy 288.982912 -143.36268) (xy 288.983928 -143.344392) (xy 288.983928 -143.340328)
			(xy 288.983257 -143.327684) (xy 288.97126 -143.305424) (xy 288.961068 -143.29791) (xy 288.95548 -143.294354)
			(xy 288.95294 -143.293084) (xy 288.928315 -143.280339) (xy 288.882706 -143.248807) (xy 288.84214 -143.211009)
			(xy 288.807469 -143.167739) (xy 288.779423 -143.119908) (xy 288.758593 -143.068522) (xy 288.745416 -143.014664)
			(xy 288.740171 -142.959465) (xy 288.742967 -142.904089) (xy 288.753745 -142.849699) (xy 288.77228 -142.797442)
			(xy 288.79818 -142.748416) (xy 288.830901 -142.703653) (xy 288.869753 -142.664095) (xy 288.913921 -142.630575)
			(xy 288.962473 -142.603797) (xy 288.988246 -142.593568) (xy 288.9885 -142.593568) (xy 288.991802 -142.592298)
			(xy 288.997898 -142.588996) (xy 289.005607 -142.584711) (xy 289.017649 -142.571838) (xy 289.02455 -142.555617)
			(xy 289.02533 -142.546832) (xy 289.026854 -142.5194) (xy 289.026854 -142.518892) (xy 289.034982 -142.352776)
			(xy 289.034982 -142.349982) (xy 289.034467 -142.340125) (xy 289.02694 -142.321899) (xy 289.013113 -142.30784)
			(xy 289.004248 -142.3035) (xy 288.99993 -142.301976) (xy 288.99739 -142.301214) (xy 288.971436 -142.293016)
			(xy 288.921979 -142.270291) (xy 288.876251 -142.240772) (xy 288.835179 -142.205058) (xy 288.799596 -142.163873)
			(xy 288.770224 -142.118051) (xy 288.747657 -142.068522) (xy 288.732353 -142.01629) (xy 288.724623 -141.962414)
			(xy 288.724086 -141.9352) (xy 288.724542 -141.908632) (xy 288.731896 -141.856008) (xy 288.746463 -141.804909)
			(xy 288.767963 -141.756317) (xy 288.795981 -141.711169) (xy 288.829978 -141.670333) (xy 288.8693 -141.634595)
			(xy 288.91319 -141.604644) (xy 288.960803 -141.581057) (xy 289.011222 -141.564286) (xy 289.037268 -141.559026)
			(xy 289.037522 -141.559026) (xy 289.041332 -141.558264) (xy 289.048526 -141.556099) (xy 289.061308 -141.548221)
			(xy 289.066478 -141.54277) (xy 289.07232 -141.536166) (xy 289.075368 -141.529054) (xy 289.076815 -141.525517)
			(xy 289.078723 -141.518117) (xy 289.079178 -141.514322) (xy 289.079178 -141.51229) (xy 289.08248 -141.45006)
			(xy 289.082734 -141.445996) (xy 289.083496 -141.43101) (xy 289.084512 -141.410944) (xy 289.086798 -141.367002)
			(xy 289.086947 -141.356233) (xy 289.079306 -141.336116) (xy 289.072066 -141.32814) (xy 289.05835 -141.314424)
			(xy 289.050984 -141.310614) (xy 289.042065 -141.306057) (xy 289.024658 -141.296145) (xy 289.016186 -141.290802)
			(xy 288.993551 -141.275655) (xy 288.952413 -141.239962) (xy 288.91677 -141.198782) (xy 288.887345 -141.152951)
			(xy 288.864736 -141.103402) (xy 288.849404 -141.051142) (xy 288.841659 -140.997232) (xy 288.84118 -140.97)
			(xy 288.841706 -140.941527) (xy 288.850161 -140.885213) (xy 288.866884 -140.830779) (xy 288.891504 -140.779431)
			(xy 288.923476 -140.732308) (xy 288.962089 -140.690454) (xy 289.00649 -140.654798) (xy 289.055692 -140.62613)
			(xy 289.081972 -140.615162) (xy 289.088576 -140.612368) (xy 289.093656 -140.608558) (xy 289.096504 -140.606346)
			(xy 289.101607 -140.601249) (xy 289.103816 -140.598398) (xy 289.115246 -140.583158) (xy 289.115246 -140.58265)
			(xy 289.119056 -140.57757) (xy 289.123329 -140.571412) (xy 289.128478 -140.557343) (xy 289.129216 -140.549884)
			(xy 289.134804 -140.445744) (xy 289.137344 -140.396722) (xy 289.140392 -140.336778) (xy 289.142932 -140.287248)
			(xy 289.15106 -140.132562) (xy 289.151822 -140.11656) (xy 289.152584 -140.104114) (xy 289.152584 -140.099288)
			(xy 289.152351 -140.092916) (xy 289.149132 -140.080584) (xy 289.146234 -140.074904) (xy 289.142932 -140.069062)
			(xy 289.125406 -140.04925) (xy 289.115246 -140.040614) (xy 289.109658 -140.037312) (xy 289.089338 -140.026644)
			(xy 289.08375 -140.025628) (xy 289.082734 -140.025374) (xy 289.08121 -140.02512) (xy 289.054993 -140.020104)
			(xy 289.004195 -140.003708) (xy 288.95618 -139.980388) (xy 288.911886 -139.950601) (xy 288.872178 -139.914929)
			(xy 288.837833 -139.874068) (xy 288.80952 -139.828817) (xy 288.787795 -139.78006) (xy 288.773081 -139.72875)
			(xy 288.765665 -139.675889) (xy 288.765234 -139.6492) (xy 288.765234 -139.639548) (xy 288.766758 -139.614148)
			(xy 288.767012 -139.611862) (xy 288.767012 -139.610338) (xy 288.76752 -139.606528) (xy 288.76752 -139.605766)
			(xy 288.770739 -139.581239) (xy 288.782697 -139.533236) (xy 288.800749 -139.487178) (xy 288.824596 -139.443835)
			(xy 288.838894 -139.423648) (xy 288.858198 -139.399518) (xy 288.858706 -139.39901) (xy 288.869374 -139.38631)
			(xy 288.872422 -139.37742) (xy 288.873928 -139.372358) (xy 288.875078 -139.361861) (xy 288.874708 -139.356592)
			(xy 288.873692 -139.345416) (xy 288.873692 -139.344908) (xy 288.86912 -139.283948) (xy 288.868594 -139.280353)
			(xy 288.86668 -139.273343) (xy 288.86531 -139.269978) (xy 288.860992 -139.261088) (xy 288.854388 -139.252452)
			(xy 288.850324 -139.24915) (xy 288.829447 -139.230927) (xy 288.792662 -139.189485) (xy 288.762254 -139.14316)
			(xy 288.738863 -139.092926) (xy 288.72298 -139.039837) (xy 288.71494 -138.98501) (xy 288.714434 -138.957304)
			(xy 288.714434 -138.95705) (xy 288.714894 -138.929796) (xy 288.722645 -138.875842) (xy 288.737998 -138.82354)
			(xy 288.760638 -138.773957) (xy 288.790105 -138.7281) (xy 288.825799 -138.686905) (xy 288.866994 -138.65121)
			(xy 288.91285 -138.621742) (xy 288.962433 -138.5991) (xy 289.014734 -138.583747) (xy 289.068688 -138.575995)
			(xy 289.095942 -138.575542) (xy 289.097974 -138.575542) (xy 289.129216 -138.576558) (xy 289.135058 -138.577066)
			(xy 289.138106 -138.57732) (xy 289.147504 -138.574272) (xy 289.152217 -138.572557) (xy 289.160919 -138.567572)
			(xy 289.164776 -138.564366) (xy 289.21964 -138.516614) (xy 289.22603 -138.510578) (xy 289.234593 -138.495244)
			(xy 289.236404 -138.486642) (xy 289.236912 -138.481054) (xy 289.255708 -138.122406) (xy 289.268916 -137.867898)
			(xy 289.277298 -137.703814) (xy 289.277437 -137.696871) (xy 289.27434 -137.683339) (xy 289.271202 -137.677144)
			(xy 289.266767 -137.66967) (xy 289.253919 -137.657983) (xy 289.246056 -137.654284) (xy 289.240976 -137.65276)
			(xy 289.227924 -137.648733) (xy 289.202374 -137.63907) (xy 289.189922 -137.633456) (xy 289.165482 -137.62162)
			(xy 289.11993 -137.592063) (xy 289.079024 -137.556351) (xy 289.043589 -137.515205) (xy 289.01434 -137.469454)
			(xy 288.991868 -137.42002) (xy 288.976625 -137.367902) (xy 288.968918 -137.314151) (xy 288.968434 -137.287)
			(xy 288.968944 -137.258853) (xy 288.977228 -137.20317) (xy 288.993602 -137.149309) (xy 289.017709 -137.098436)
			(xy 289.049028 -137.051657) (xy 289.086879 -137.009986) (xy 289.13044 -136.974327) (xy 289.178767 -136.945453)
			(xy 289.23081 -136.923992) (xy 289.257994 -136.916668) (xy 289.26409 -136.915144) (xy 289.284918 -136.903968)
			(xy 289.29076 -136.899142) (xy 289.295332 -136.89457) (xy 289.30981 -136.877806) (xy 289.31108 -136.876282)
			(xy 289.311334 -136.876028) (xy 289.311334 -136.875774) (xy 289.3187 -136.863582) (xy 289.322002 -136.851644)
			(xy 289.325812 -136.774428) (xy 289.336226 -136.574022) (xy 289.343084 -136.442958) (xy 289.346132 -136.3853)
			(xy 289.372294 -135.881364) (xy 289.415982 -135.035544) (xy 289.41543 -135.028105) (xy 289.410525 -135.014026)
			(xy 289.40633 -135.007858) (xy 289.40153 -135.001688) (xy 289.388991 -134.992367) (xy 289.381692 -134.98957)
			(xy 289.37839 -134.988554) (xy 289.351692 -134.9809) (xy 289.300685 -134.958931) (xy 289.253403 -134.929798)
			(xy 289.210844 -134.894117) (xy 289.173909 -134.852642) (xy 289.143378 -134.806249) (xy 289.119897 -134.755921)
			(xy 289.103961 -134.702719) (xy 289.095908 -134.647769) (xy 289.095434 -134.62) (xy 289.095512 -134.607262)
			(xy 289.097166 -134.581841) (xy 289.098736 -134.5692) (xy 289.102739 -134.542786) (xy 289.117171 -134.491347)
			(xy 289.138631 -134.442422) (xy 289.166701 -134.396966) (xy 289.200833 -134.355866) (xy 289.24036 -134.319924)
			(xy 289.284511 -134.289843) (xy 289.332424 -134.26621) (xy 289.383164 -134.249485) (xy 289.409378 -134.244334)
			(xy 289.418014 -134.24281) (xy 289.437318 -134.232142) (xy 289.446695 -134.225349) (xy 289.45859 -134.205512)
			(xy 289.460178 -134.194042) (xy 289.460432 -134.189724) (xy 289.460432 -134.189216) (xy 291.31768 -98.506788)
			(xy 293.08806 -64.48552) (xy 293.08806 -64.482472) (xy 293.080694 -62.45352) (xy 293.080261 -62.444618)
			(xy 293.074091 -62.427911) (xy 293.062589 -62.414315) (xy 293.05504 -62.409578) (xy 293.007288 -62.3824)
			(xy 293.006018 -62.381638) (xy 292.981888 -62.393322) (xy 292.980618 -62.39383) (xy 292.970204 -62.398148)
			(xy 292.96995 -62.398402) (xy 292.969442 -62.398656) (xy 292.967156 -62.399672) (xy 292.952396 -62.406126)
			(xy 292.922002 -62.416809) (xy 292.90645 -62.421008) (xy 292.902386 -62.422024) (xy 292.880501 -62.427044)
			(xy 292.835935 -62.432519) (xy 292.813486 -62.432946) (xy 292.809676 -62.432946) (xy 292.787036 -62.432551)
			(xy 292.742086 -62.427081) (xy 292.720014 -62.422024) (xy 292.71722 -62.421262) (xy 292.711124 -62.4205)
			(xy 292.698484 -62.419662) (xy 292.674915 -62.428863) (xy 292.666166 -62.438026) (xy 292.619938 -62.491874)
			(xy 292.619176 -62.492636) (xy 292.610794 -62.50178) (xy 292.605461 -62.508759) (xy 292.599486 -62.525262)
			(xy 292.59911 -62.534038) (xy 292.59911 -62.54877) (xy 292.601904 -62.563502) (xy 292.60419 -62.57163)
			(xy 292.604952 -62.573662) (xy 292.615751 -62.604965) (xy 292.627636 -62.670102) (xy 292.628574 -62.703202)
			(xy 292.628574 -62.708282) (xy 292.627933 -62.735426) (xy 292.619913 -62.789125) (xy 292.604361 -62.841144)
			(xy 292.58159 -62.890433) (xy 292.552062 -62.935995) (xy 292.516371 -62.976911) (xy 292.47524 -63.012352)
			(xy 292.429499 -63.041604) (xy 292.380073 -63.064075) (xy 292.32796 -63.079311) (xy 292.274213 -63.087004)
			(xy 292.247066 -63.087504) (xy 292.219816 -63.087016) (xy 292.165873 -63.079255) (xy 292.113582 -63.063897)
			(xy 292.064009 -63.041254) (xy 292.018164 -63.011787) (xy 291.976978 -62.976095) (xy 291.94129 -62.934906)
			(xy 291.911828 -62.889057) (xy 291.889189 -62.839482) (xy 291.873836 -62.78719) (xy 291.866081 -62.733246)
			(xy 291.865558 -62.705996) (xy 291.866038 -62.678825) (xy 291.873749 -62.625032) (xy 291.889015 -62.572878)
			(xy 291.911526 -62.523417) (xy 291.940827 -62.477651) (xy 291.976325 -62.436505) (xy 292.017302 -62.400812)
			(xy 292.062929 -62.371295) (xy 292.112282 -62.34855) (xy 292.164364 -62.333037) (xy 292.218119 -62.325071)
			(xy 292.245288 -62.324488) (xy 292.247828 -62.324488) (xy 292.2689 -62.324797) (xy 292.31078 -62.329508)
			(xy 292.331394 -62.333886) (xy 292.331902 -62.333886) (xy 292.339522 -62.335664) (xy 292.342824 -62.336426)
			(xy 292.347904 -62.336934) (xy 292.348412 -62.336934) (xy 292.357243 -62.337447) (xy 292.374396 -62.33317)
			(xy 292.38194 -62.328552) (xy 292.388544 -62.323218) (xy 292.449758 -62.252098) (xy 292.457083 -62.242704)
			(xy 292.46293 -62.219644) (xy 292.460934 -62.207902) (xy 292.458394 -62.198504) (xy 292.458394 -62.19825)
			(xy 292.457378 -62.196218) (xy 292.448445 -62.173271) (xy 292.435888 -62.125656) (xy 292.429563 -62.076821)
			(xy 292.429184 -62.0522) (xy 292.429184 -62.051438) (xy 292.430454 -62.021212) (xy 292.431216 -62.013338)
			(xy 292.434487 -61.985701) (xy 292.448013 -61.931718) (xy 292.469238 -61.880273) (xy 292.497714 -61.832459)
			(xy 292.532834 -61.789289) (xy 292.573855 -61.751681) (xy 292.619905 -61.720432) (xy 292.670007 -61.696206)
			(xy 292.723097 -61.679517) (xy 292.778048 -61.670719) (xy 292.805866 -61.66993) (xy 292.811454 -61.66993)
			(xy 292.844589 -61.670664) (xy 292.909854 -61.682164) (xy 292.941248 -61.69279) (xy 292.953186 -61.695584)
			(xy 292.96238 -61.696211) (xy 292.980223 -61.691662) (xy 292.987984 -61.686694) (xy 293.05758 -61.637418)
			(xy 293.064184 -61.631576) (xy 293.067232 -61.62802) (xy 293.071778 -61.621631) (xy 293.077075 -61.606884)
			(xy 293.077646 -61.599064) (xy 293.077392 -61.548518) (xy 293.075614 -60.998608) (xy 293.075614 -60.997084)
			(xy 293.07536 -60.99302) (xy 293.075614 -60.979558) (xy 293.077646 -60.845954) (xy 293.07282 -60.83808)
			(xy 293.05745 -60.812859) (xy 293.033838 -60.758724) (xy 293.018851 -60.701597) (xy 293.012848 -60.642843)
			(xy 293.015972 -60.583866) (xy 293.028147 -60.526074) (xy 293.049084 -60.47085) (xy 293.063168 -60.444888)
			(xy 293.077138 -60.422028) (xy 293.08044 -60.416948) (xy 293.082472 -60.410344) (xy 293.084504 -60.396374)
			(xy 293.110412 -58.728356) (xy 293.110426 -58.723966) (xy 293.109158 -58.715281) (xy 293.107872 -58.711084)
			(xy 293.104824 -58.702448) (xy 293.098728 -58.695336) (xy 293.081915 -58.674633) (xy 293.053628 -58.629419)
			(xy 293.031909 -58.580709) (xy 293.017183 -58.529449) (xy 293.009735 -58.476638) (xy 293.00932 -58.449972)
			(xy 293.00932 -58.449718) (xy 293.010844 -58.413904) (xy 293.01186 -58.40476) (xy 293.013522 -58.391475)
			(xy 293.018479 -58.365161) (xy 293.021766 -58.352182) (xy 293.03091 -58.317638) (xy 293.032688 -58.31205)
			(xy 293.033196 -58.31078) (xy 293.034212 -58.309256) (xy 293.034974 -58.307478) (xy 293.051992 -58.274204)
			(xy 293.053516 -58.27141) (xy 293.054024 -58.270394) (xy 293.058088 -58.263028) (xy 293.058088 -58.262774)
			(xy 293.066508 -58.248081) (xy 293.08559 -58.220102) (xy 293.096188 -58.206894) (xy 293.096696 -58.206386)
			(xy 293.09822 -58.204354) (xy 293.098728 -58.203592) (xy 293.101268 -58.201052) (xy 293.101776 -58.200544)
			(xy 293.103554 -58.198512) (xy 293.104316 -58.19775) (xy 293.105586 -58.196226) (xy 293.106856 -58.194702)
			(xy 293.112952 -58.187844) (xy 293.119556 -58.17108) (xy 293.120826 -58.084212) (xy 293.161212 -55.495444)
			(xy 293.161212 -55.492904) (xy 293.112952 -54.262274) (xy 292.945566 -49.986946) (xy 292.94485 -49.977954)
			(xy 292.937955 -49.961299) (xy 292.932104 -49.954434) (xy 292.925246 -49.947576) (xy 292.845998 -49.904904)
			(xy 292.845236 -49.90465) (xy 292.842442 -49.903126) (xy 292.83408 -49.899356) (xy 292.815854 -49.897408)
			(xy 292.806882 -49.899316) (xy 292.796722 -49.90211) (xy 292.790626 -49.905666) (xy 292.768707 -49.917966)
			(xy 292.722329 -49.937337) (xy 292.673809 -49.950452) (xy 292.623986 -49.957084) (xy 292.598856 -49.957482)
			(xy 292.573007 -49.957056) (xy 292.521779 -49.950105) (xy 292.47195 -49.936334) (xy 292.424422 -49.915994)
			(xy 292.380058 -49.889452) (xy 292.359588 -49.873662) (xy 292.359334 -49.873408) (xy 292.352476 -49.868074)
			(xy 292.344602 -49.86528) (xy 292.340423 -49.863874) (xy 292.331738 -49.862349) (xy 292.32733 -49.862232)
			(xy 292.308026 -49.862232) (xy 292.302585 -49.862094) (xy 292.29195 -49.859795) (xy 292.286944 -49.85766)
			(xy 292.276784 -49.852834) (xy 292.270756 -49.850337) (xy 292.257898 -49.848143) (xy 292.251384 -49.848516)
			(xy 292.24773 -49.848952) (xy 292.240592 -49.850744) (xy 292.23716 -49.852072) (xy 292.23081 -49.854612)
			(xy 292.209102 -49.874565) (xy 292.160764 -49.908324) (xy 292.107859 -49.934348) (xy 292.051614 -49.952032)
			(xy 291.993336 -49.960967) (xy 291.963856 -49.961546) (xy 291.963602 -49.961546) (xy 291.936378 -49.961063)
			(xy 291.882472 -49.953394) (xy 291.830171 -49.93825) (xy 291.780507 -49.915928) (xy 291.73446 -49.88687)
			(xy 291.713412 -49.869598) (xy 291.705792 -49.863502) (xy 291.700204 -49.862232) (xy 291.673026 -49.862232)
			(xy 291.667585 -49.862094) (xy 291.65695 -49.859795) (xy 291.651944 -49.85766) (xy 291.641784 -49.852834)
			(xy 291.635756 -49.850337) (xy 291.622898 -49.848143) (xy 291.616384 -49.848516) (xy 291.61273 -49.848952)
			(xy 291.605592 -49.850744) (xy 291.60216 -49.852072) (xy 291.59581 -49.854612) (xy 291.574102 -49.874565)
			(xy 291.525764 -49.908324) (xy 291.472859 -49.934348) (xy 291.416614 -49.952032) (xy 291.358336 -49.960967)
			(xy 291.328856 -49.961546) (xy 291.328602 -49.961546) (xy 291.301378 -49.961063) (xy 291.247472 -49.953394)
			(xy 291.195171 -49.93825) (xy 291.145507 -49.915928) (xy 291.09946 -49.88687) (xy 291.078412 -49.869598)
			(xy 291.070792 -49.863502) (xy 291.065204 -49.862232) (xy 291.038026 -49.862232) (xy 291.032585 -49.862094)
			(xy 291.02195 -49.859795) (xy 291.016944 -49.85766) (xy 291.002974 -49.85131) (xy 290.993806 -49.847626)
			(xy 290.974085 -49.846788) (xy 290.955497 -49.853431) (xy 290.947856 -49.859692) (xy 290.937442 -49.868836)
			(xy 290.916823 -49.885263) (xy 290.871926 -49.912893) (xy 290.823659 -49.934092) (xy 290.772937 -49.948461)
			(xy 290.720723 -49.955725) (xy 290.694364 -49.956212) (xy 290.693856 -49.956212) (xy 290.666607 -49.955723)
			(xy 290.612663 -49.947962) (xy 290.560373 -49.932602) (xy 290.510801 -49.909959) (xy 290.464955 -49.880491)
			(xy 290.42377 -49.844799) (xy 290.388083 -49.803609) (xy 290.35862 -49.757761) (xy 290.335982 -49.708186)
			(xy 290.320629 -49.655894) (xy 290.312874 -49.60195) (xy 290.312874 -49.54745) (xy 290.320629 -49.493506)
			(xy 290.335982 -49.441214) (xy 290.35862 -49.391639) (xy 290.388083 -49.345791) (xy 290.42377 -49.304601)
			(xy 290.464955 -49.268909) (xy 290.510801 -49.239441) (xy 290.560373 -49.216798) (xy 290.612663 -49.201438)
			(xy 290.666607 -49.193677) (xy 290.693856 -49.193196) (xy 290.69411 -49.193196) (xy 290.719622 -49.193616)
			(xy 290.770192 -49.200403) (xy 290.819407 -49.213869) (xy 290.866388 -49.233774) (xy 290.910298 -49.259762)
			(xy 290.930584 -49.275238) (xy 290.935918 -49.279556) (xy 290.9443 -49.283112) (xy 290.94684 -49.284128)
			(xy 290.950959 -49.285517) (xy 290.959513 -49.28705) (xy 290.963858 -49.287176) (xy 290.984686 -49.287176)
			(xy 290.990127 -49.287314) (xy 291.000763 -49.289612) (xy 291.005768 -49.291748) (xy 291.019738 -49.298098)
			(xy 291.025828 -49.30061) (xy 291.038815 -49.302798) (xy 291.045392 -49.302416) (xy 291.055044 -49.300638)
			(xy 291.064442 -49.292256) (xy 291.065204 -49.291748) (xy 291.065458 -49.291494) (xy 291.066728 -49.290224)
			(xy 291.088279 -49.27109) (xy 291.135986 -49.238761) (xy 291.18796 -49.213866) (xy 291.243051 -49.196954)
			(xy 291.300042 -49.1884) (xy 291.328856 -49.187862) (xy 291.356025 -49.188323) (xy 291.409826 -49.195943)
			(xy 291.462025 -49.211037) (xy 291.511589 -49.233308) (xy 291.557537 -49.262314) (xy 291.578538 -49.279556)
			(xy 291.583872 -49.28362) (xy 291.585904 -49.285398) (xy 291.598604 -49.287176) (xy 291.619686 -49.287176)
			(xy 291.625127 -49.287314) (xy 291.635763 -49.289612) (xy 291.640768 -49.291748) (xy 291.654738 -49.298098)
			(xy 291.660828 -49.30061) (xy 291.673815 -49.302798) (xy 291.680392 -49.302416) (xy 291.690044 -49.300638)
			(xy 291.699442 -49.292256) (xy 291.700204 -49.291748) (xy 291.700458 -49.291494) (xy 291.701728 -49.290224)
			(xy 291.723279 -49.27109) (xy 291.770986 -49.238761) (xy 291.82296 -49.213866) (xy 291.878051 -49.196954)
			(xy 291.935042 -49.1884) (xy 291.963856 -49.187862) (xy 291.991025 -49.188323) (xy 292.044826 -49.195943)
			(xy 292.097025 -49.211037) (xy 292.146589 -49.233308) (xy 292.192537 -49.262314) (xy 292.213538 -49.279556)
			(xy 292.218872 -49.28362) (xy 292.220904 -49.285398) (xy 292.233604 -49.287176) (xy 292.255194 -49.287176)
			(xy 292.265354 -49.288192) (xy 292.27145 -49.289462) (xy 292.324536 -49.289462) (xy 292.328947 -49.289375)
			(xy 292.337635 -49.287844) (xy 292.341808 -49.286414) (xy 292.349682 -49.28362) (xy 292.350952 -49.282604)
			(xy 292.35654 -49.278032) (xy 292.377131 -49.261809) (xy 292.421907 -49.234548) (xy 292.469982 -49.213647)
			(xy 292.520457 -49.199497) (xy 292.572391 -49.192363) (xy 292.598602 -49.191926) (xy 292.599364 -49.191926)
			(xy 292.628068 -49.192433) (xy 292.684832 -49.201009) (xy 292.739672 -49.217986) (xy 292.765734 -49.230026)
			(xy 292.770814 -49.232566) (xy 292.777672 -49.234344) (xy 292.787881 -49.236309) (xy 292.808344 -49.232771)
			(xy 292.817296 -49.227486) (xy 292.856412 -49.202086) (xy 292.85692 -49.202086) (xy 292.883336 -49.18456)
			(xy 292.885876 -49.182782) (xy 292.894948 -49.175231) (xy 292.905558 -49.15418) (xy 292.906196 -49.142396)
			(xy 292.906196 -48.984408) (xy 292.906196 -48.982376) (xy 292.822884 -46.85284) (xy 292.822884 -46.8503)
			(xy 291.886386 -39.919656) (xy 291.882623 -39.890264) (xy 291.878176 -39.83117) (xy 291.877496 -39.801546)
			(xy 291.872162 -39.470076) (xy 291.869622 -39.4589) (xy 291.867082 -39.454074) (xy 291.847835 -39.414111)
			(xy 291.815693 -39.331433) (xy 291.791026 -39.246225) (xy 291.774029 -39.159162) (xy 291.764835 -39.070933)
			(xy 291.763704 -39.026592) (xy 291.7571 -38.598094) (xy 291.7571 -38.59657) (xy 291.756084 -38.551358)
			(xy 291.756084 -38.548564) (xy 291.756084 -38.515798) (xy 291.756434 -38.476006) (xy 291.762697 -38.396669)
			(xy 291.775264 -38.318084) (xy 291.784278 -38.279324) (xy 291.786818 -38.269418) (xy 291.782754 -38.243764)
			(xy 291.780976 -38.232842) (xy 291.77107 -38.172136) (xy 291.765005 -38.132665) (xy 291.758524 -38.053064)
			(xy 291.758116 -38.013132) (xy 291.75837 -37.992812) (xy 291.758624 -37.981636) (xy 291.757862 -37.977064)
			(xy 291.752398 -37.941234) (xy 291.746045 -37.869026) (xy 291.745162 -37.832792) (xy 291.745162 -37.831268)
			(xy 291.744908 -37.818568) (xy 291.737542 -37.337238) (xy 291.737542 -37.336984) (xy 291.737288 -37.322252)
			(xy 291.737288 -37.320728) (xy 291.737894 -37.274261) (xy 291.746684 -37.181742) (xy 291.76404 -37.090442)
			(xy 291.776404 -37.045646) (xy 291.778182 -37.039296) (xy 291.779706 -36.960556) (xy 291.775134 -36.950396)
			(xy 291.770816 -36.940236) (xy 291.767514 -36.932362) (xy 291.746432 -36.908232) (xy 291.738304 -36.902644)
			(xy 291.718492 -36.892738) (xy 291.713167 -36.890272) (xy 291.701751 -36.88757) (xy 291.695886 -36.887404)
			(xy 291.681408 -36.887404) (xy 291.676582 -36.88842) (xy 291.675566 -36.888674) (xy 291.674042 -36.889182)
			(xy 291.644578 -36.894008) (xy 291.643562 -36.894008) (xy 291.633317 -36.895259) (xy 291.612731 -36.896781)
			(xy 291.602414 -36.897056) (xy 291.596064 -36.897056) (xy 291.568813 -36.896568) (xy 291.514867 -36.888807)
			(xy 291.462574 -36.87345) (xy 291.412998 -36.850807) (xy 291.367149 -36.821341) (xy 291.325959 -36.78565)
			(xy 291.290267 -36.744461) (xy 291.260799 -36.698613) (xy 291.238155 -36.649038) (xy 291.222795 -36.596745)
			(xy 291.215033 -36.542799) (xy 291.214556 -36.515548) (xy 291.215038 -36.488305) (xy 291.222782 -36.434373)
			(xy 291.23812 -36.38209) (xy 291.260739 -36.332522) (xy 291.29018 -36.286675) (xy 291.325843 -36.245483)
			(xy 291.367004 -36.209783) (xy 291.412825 -36.180301) (xy 291.462373 -36.157638) (xy 291.514642 -36.142254)
			(xy 291.568567 -36.134462) (xy 291.59581 -36.13404) (xy 291.606986 -36.13404) (xy 291.617654 -36.134802)
			(xy 291.63645 -36.127436) (xy 291.64407 -36.120578) (xy 291.646356 -36.118546) (xy 291.646864 -36.118038)
			(xy 291.69614 -36.073334) (xy 291.69906 -36.070459) (xy 291.704036 -36.063951) (xy 291.706046 -36.06038)
			(xy 291.71011 -36.053014) (xy 291.710364 -36.050474) (xy 291.711126 -36.044632) (xy 291.71138 -36.0426)
			(xy 291.712396 -36.034726) (xy 291.71265 -36.031424) (xy 291.712904 -36.030662) (xy 291.713158 -36.02863)
			(xy 291.714174 -36.019994) (xy 291.714174 -36.01974) (xy 291.718238 -35.987736) (xy 291.721194 -35.967543)
			(xy 291.728561 -35.927398) (xy 291.73297 -35.907472) (xy 291.739523 -35.879846) (xy 291.755407 -35.825328)
			(xy 291.76472 -35.798506) (xy 291.771318 -35.779971) (xy 291.785803 -35.743385) (xy 291.793676 -35.725354)
			(xy 291.794692 -35.723068) (xy 291.797994 -35.712908) (xy 291.800534 -35.701478) (xy 291.789358 -35.658806)
			(xy 291.786056 -35.64636) (xy 291.77234 -35.595052) (xy 291.761926 -35.55619) (xy 291.758918 -35.546815)
			(xy 291.747019 -35.531152) (xy 291.738812 -35.52571) (xy 291.680138 -35.490912) (xy 291.668708 -35.485832)
			(xy 291.650674 -35.490404) (xy 291.612228 -35.499569) (xy 291.534253 -35.512517) (xy 291.455497 -35.519246)
			(xy 291.415978 -35.519868) (xy 291.403024 -35.519868) (xy 291.356628 -35.518988) (xy 291.264295 -35.509669)
			(xy 291.173228 -35.491806) (xy 291.084215 -35.465556) (xy 290.998028 -35.431145) (xy 290.915414 -35.388871)
			(xy 290.875974 -35.36442) (xy 290.873942 -35.364928) (xy 290.869878 -35.36569) (xy 290.85288 -35.368566)
			(xy 290.818537 -35.371621) (xy 290.801298 -35.371786) (xy 290.80079 -35.371786) (xy 290.773538 -35.371322)
			(xy 290.71959 -35.363564) (xy 290.667294 -35.348207) (xy 290.617717 -35.325563) (xy 290.571866 -35.296095)
			(xy 290.530677 -35.260401) (xy 290.494986 -35.219208) (xy 290.465521 -35.173355) (xy 290.442882 -35.123776)
			(xy 290.427529 -35.071479) (xy 290.419776 -35.01753) (xy 290.419282 -34.990278) (xy 290.419282 -34.989008)
			(xy 290.419758 -34.964279) (xy 290.426318 -34.915255) (xy 290.43916 -34.86749) (xy 290.448238 -34.844482)
			(xy 290.450016 -34.840164) (xy 290.45662 -34.824162) (xy 290.45789 -34.818574) (xy 290.453318 -34.802826)
			(xy 290.440821 -34.758474) (xy 290.423111 -34.668039) (xy 290.413828 -34.576354) (xy 290.412932 -34.530284)
			(xy 290.412932 -34.519108) (xy 290.413508 -34.477574) (xy 290.420709 -34.394817) (xy 290.434763 -34.312943)
			(xy 290.455573 -34.232521) (xy 290.482994 -34.154107) (xy 290.499546 -34.11601) (xy 290.502594 -34.106358)
			(xy 290.50615 -34.091118) (xy 290.50615 -34.090102) (xy 290.502594 -34.074862) (xy 290.499546 -34.06521)
			(xy 290.482865 -34.026807) (xy 290.455254 -33.947757) (xy 290.434373 -33.866669) (xy 290.42037 -33.784115)
			(xy 290.413343 -33.700677) (xy 290.412932 -33.65881) (xy 290.412932 -33.658302) (xy 290.413203 -33.626014)
			(xy 290.4174 -33.561575) (xy 290.421314 -33.529524) (xy 290.424814 -33.504119) (xy 290.434089 -33.453675)
			(xy 290.439856 -33.428686) (xy 290.443874 -33.412172) (xy 290.452894 -33.379399) (xy 290.45789 -33.363154)
			(xy 290.456112 -33.35528) (xy 290.453826 -33.349692) (xy 290.444311 -33.328077) (xy 290.430089 -33.28304)
			(xy 290.421536 -33.236593) (xy 290.41979 -33.21304) (xy 290.41979 -33.208722) (xy 290.419282 -33.19018)
			(xy 290.419282 -33.18256) (xy 290.420276 -33.155663) (xy 290.428893 -33.102533) (xy 290.444892 -33.051142)
			(xy 290.467956 -33.00251) (xy 290.497627 -32.957603) (xy 290.533314 -32.917312) (xy 290.574311 -32.882437)
			(xy 290.619803 -32.853671) (xy 290.668886 -32.831584) (xy 290.720587 -32.816616) (xy 290.773878 -32.809063)
			(xy 290.80079 -32.808672) (xy 290.801044 -32.808672) (xy 290.815515 -32.808788) (xy 290.844375 -32.810953)
			(xy 290.858702 -32.81299) (xy 290.867523 -32.81399) (xy 290.884938 -32.810622) (xy 290.892738 -32.806386)
			(xy 290.931779 -32.783274) (xy 291.013283 -32.743405) (xy 291.09807 -32.7111) (xy 291.185439 -32.686625)
			(xy 291.274669 -32.670183) (xy 291.365024 -32.661909) (xy 291.41039 -32.661352) (xy 291.410644 -32.661352)
			(xy 291.455983 -32.66188) (xy 291.546286 -32.670136) (xy 291.635467 -32.68655) (xy 291.722792 -32.710985)
			(xy 291.807541 -32.74324) (xy 291.889015 -32.78305) (xy 291.928042 -32.806132) (xy 291.935768 -32.810393)
			(xy 291.953047 -32.813892) (xy 291.961824 -32.81299) (xy 291.97653 -32.810911) (xy 292.006154 -32.808751)
			(xy 292.021006 -32.808672) (xy 292.021768 -32.808672) (xy 292.052226 -32.809413) (xy 292.11233 -32.819371)
			(xy 292.141402 -32.828484) (xy 292.15207 -32.83204) (xy 292.163754 -32.831024) (xy 292.170698 -32.830104)
			(xy 292.183713 -32.824943) (xy 292.189408 -32.820864) (xy 292.212014 -32.804608) (xy 292.255956 -32.773112)
			(xy 292.259333 -32.770388) (xy 292.265213 -32.764008) (xy 292.26764 -32.760412) (xy 292.267894 -32.760158)
			(xy 292.267386 -32.741108) (xy 292.267386 -32.737806) (xy 292.267132 -32.722566) (xy 292.267132 -32.708596)
			(xy 292.268105 -32.66811) (xy 292.275805 -32.587485) (xy 292.290025 -32.507752) (xy 292.310671 -32.429436)
			(xy 292.337606 -32.353055) (xy 292.353746 -32.315912) (xy 292.356794 -32.30626) (xy 292.36035 -32.29102)
			(xy 292.36035 -32.290004) (xy 292.356794 -32.274764) (xy 292.353746 -32.265112) (xy 292.337065 -32.226709)
			(xy 292.309454 -32.147659) (xy 292.288573 -32.066571) (xy 292.27457 -31.984017) (xy 292.267543 -31.900579)
			(xy 292.267132 -31.858712) (xy 292.268656 -31.80461) (xy 292.269672 -31.785052) (xy 292.26891 -31.783782)
			(xy 292.252146 -31.763462) (xy 292.245796 -31.755588) (xy 292.241546 -31.751199) (xy 292.2314 -31.744402)
			(xy 292.22573 -31.742126) (xy 292.217856 -31.739332) (xy 292.208712 -31.7373) (xy 292.186868 -31.7373)
			(xy 292.181788 -31.738316) (xy 292.17874 -31.738824) (xy 292.171882 -31.740348) (xy 292.167564 -31.742126)
			(xy 292.145062 -31.751173) (xy 292.098328 -31.764139) (xy 292.050326 -31.771065) (xy 292.026086 -31.771844)
			(xy 292.019482 -31.771844) (xy 292.003207 -31.771663) (xy 291.970777 -31.768866) (xy 291.954712 -31.766256)
			(xy 291.944806 -31.764478) (xy 291.90482 -31.789197) (xy 291.821044 -31.83186) (xy 291.733627 -31.866453)
			(xy 291.643343 -31.89267) (xy 291.550993 -31.910277) (xy 291.457397 -31.91912) (xy 291.41039 -31.919672)
			(xy 291.364979 -31.919169) (xy 291.274532 -31.910937) (xy 291.185208 -31.894515) (xy 291.097747 -31.870039)
			(xy 291.012874 -31.837712) (xy 290.931292 -31.797801) (xy 290.89223 -31.774638) (xy 290.891976 -31.774638)
			(xy 290.88603 -31.771273) (xy 290.872895 -31.767531) (xy 290.866068 -31.767272) (xy 290.859718 -31.767272)
			(xy 290.856162 -31.76778) (xy 290.855146 -31.768034) (xy 290.853114 -31.768288) (xy 290.85286 -31.768288)
			(xy 290.849558 -31.768796) (xy 290.836858 -31.77032) (xy 290.836604 -31.77032) (xy 290.806886 -31.771844)
			(xy 290.80079 -31.771844) (xy 290.773538 -31.771358) (xy 290.71959 -31.7636) (xy 290.667294 -31.748244)
			(xy 290.617716 -31.725603) (xy 290.571864 -31.696137) (xy 290.530672 -31.660446) (xy 290.494978 -31.619257)
			(xy 290.465509 -31.573407) (xy 290.442865 -31.52383) (xy 290.427505 -31.471536) (xy 290.419744 -31.417588)
			(xy 290.419282 -31.390336) (xy 290.419282 -31.389066) (xy 290.419755 -31.364336) (xy 290.426307 -31.31531)
			(xy 290.439143 -31.267541) (xy 290.448238 -31.24454) (xy 290.450016 -31.240222) (xy 290.45662 -31.22422)
			(xy 290.45789 -31.218632) (xy 290.453318 -31.202884) (xy 290.440589 -31.157586) (xy 290.422704 -31.065204)
			(xy 290.413594 -30.971547) (xy 290.412932 -30.9245) (xy 290.412932 -30.91561) (xy 290.413532 -30.878397)
			(xy 290.419591 -30.804211) (xy 290.431168 -30.730684) (xy 290.439348 -30.694376) (xy 290.450714 -30.648428)
			(xy 290.480992 -30.558742) (xy 290.4998 -30.515306) (xy 290.501578 -30.511242) (xy 290.50615 -30.491176)
			(xy 290.50615 -30.49016) (xy 290.501578 -30.470094) (xy 290.4998 -30.46603) (xy 290.483073 -30.42756)
			(xy 290.455384 -30.348366) (xy 290.434447 -30.267126) (xy 290.420409 -30.184414) (xy 290.413372 -30.100815)
			(xy 290.412932 -30.058868) (xy 290.413388 -30.015527) (xy 290.420894 -29.929172) (xy 290.427918 -29.886402)
			(xy 290.432082 -29.863663) (xy 290.442246 -29.818559) (xy 290.448238 -29.796232) (xy 290.448238 -29.795724)
			(xy 290.45535 -29.772102) (xy 290.45535 -29.771594) (xy 290.458144 -29.76245) (xy 290.457636 -29.760672)
			(xy 290.456366 -29.755084) (xy 290.444662 -29.729286) (xy 290.428145 -29.6751) (xy 290.419806 -29.61907)
			(xy 290.419282 -29.590746) (xy 290.419282 -29.590238) (xy 290.419742 -29.562983) (xy 290.427495 -29.509027)
			(xy 290.442847 -29.456724) (xy 290.465488 -29.407139) (xy 290.494955 -29.36128) (xy 290.530648 -29.320082)
			(xy 290.571842 -29.284383) (xy 290.617697 -29.254911) (xy 290.667279 -29.232264) (xy 290.71958 -29.216905)
			(xy 290.773535 -29.209146) (xy 290.80079 -29.20873) (xy 290.801044 -29.20873) (xy 290.819838 -29.208962)
			(xy 290.857244 -29.21265) (xy 290.87572 -29.216096) (xy 290.875974 -29.216096) (xy 290.876736 -29.21635)
			(xy 290.916659 -29.191713) (xy 291.000293 -29.149195) (xy 291.087549 -29.114718) (xy 291.177657 -29.088585)
			(xy 291.269821 -29.07103) (xy 291.363226 -29.062205) (xy 291.410136 -29.061664) (xy 291.410644 -29.061664)
			(xy 291.457527 -29.062202) (xy 291.55088 -29.071003) (xy 291.642995 -29.088522) (xy 291.733061 -29.114606)
			(xy 291.820282 -29.149024) (xy 291.90389 -29.191473) (xy 291.94379 -29.216096) (xy 291.944044 -29.216096)
			(xy 291.944552 -29.215842) (xy 291.95014 -29.214826) (xy 291.967388 -29.211899) (xy 292.002242 -29.208851)
			(xy 292.019736 -29.20873) (xy 292.020752 -29.20873) (xy 292.046145 -29.209144) (xy 292.09648 -29.215893)
			(xy 292.121082 -29.222192) (xy 292.12286 -29.2227) (xy 292.12413 -29.222954) (xy 292.12794 -29.22397)
			(xy 292.14191 -29.228542) (xy 292.142418 -29.228542) (xy 292.147752 -29.230574) (xy 292.160452 -29.231844)
			(xy 292.166294 -29.231082) (xy 292.176962 -29.228288) (xy 292.189154 -29.221684) (xy 292.252146 -29.17571)
			(xy 292.252908 -29.175202) (xy 292.257734 -29.171646) (xy 292.264338 -29.165296) (xy 292.267894 -29.16047)
			(xy 292.267386 -29.137864) (xy 292.267386 -29.13761) (xy 292.267132 -29.122624) (xy 292.267132 -29.108654)
			(xy 292.268103 -29.068167) (xy 292.275798 -28.987541) (xy 292.290014 -28.907806) (xy 292.310656 -28.829488)
			(xy 292.337587 -28.753105) (xy 292.353746 -28.71597) (xy 292.356794 -28.706318) (xy 292.36035 -28.691078)
			(xy 292.36035 -28.690062) (xy 292.355778 -28.669996) (xy 292.354 -28.665932) (xy 292.337273 -28.627462)
			(xy 292.309583 -28.548268) (xy 292.288646 -28.467028) (xy 292.274609 -28.384316) (xy 292.267571 -28.300717)
			(xy 292.267132 -28.25877) (xy 292.267588 -28.215429) (xy 292.275094 -28.129074) (xy 292.282118 -28.086304)
			(xy 292.286282 -28.063565) (xy 292.296446 -28.018461) (xy 292.302438 -27.996134) (xy 292.302438 -27.995626)
			(xy 292.30955 -27.972004) (xy 292.30955 -27.971496) (xy 292.312344 -27.962352) (xy 292.310566 -27.954986)
			(xy 292.30828 -27.95016) (xy 292.298696 -27.928472) (xy 292.284361 -27.883273) (xy 292.27573 -27.836647)
			(xy 292.27399 -27.813) (xy 292.27399 -27.808682) (xy 292.273482 -27.79014) (xy 292.273482 -27.78252)
			(xy 292.274479 -27.755624) (xy 292.2831 -27.702499) (xy 292.299103 -27.651113) (xy 292.322169 -27.602486)
			(xy 292.35184 -27.557584) (xy 292.387528 -27.517297) (xy 292.428524 -27.482427) (xy 292.474014 -27.453664)
			(xy 292.523095 -27.43158) (xy 292.574792 -27.416614) (xy 292.62808 -27.409062) (xy 292.65499 -27.408632)
			(xy 292.671715 -27.40881) (xy 292.705038 -27.411731) (xy 292.721538 -27.414474) (xy 292.73119 -27.415998)
			(xy 292.783006 -27.385264) (xy 292.783514 -27.385264) (xy 292.79596 -27.378152) (xy 292.79977 -27.368754)
			(xy 292.819582 -27.295348) (xy 292.819328 -27.281632) (xy 292.81755 -27.275028) (xy 292.813232 -27.259534)
			(xy 292.810184 -27.2542) (xy 292.798488 -27.232664) (xy 292.78007 -27.187249) (xy 292.767609 -27.139853)
			(xy 292.761312 -27.091251) (xy 292.760908 -27.066748) (xy 292.760908 -27.057604) (xy 292.761162 -27.05354)
			(xy 292.761162 -27.052778) (xy 292.763448 -27.022552) (xy 292.766552 -26.998918) (xy 292.777899 -26.95262)
			(xy 292.794944 -26.908103) (xy 292.805866 -26.886916) (xy 292.818695 -26.863798) (xy 292.849764 -26.821021)
			(xy 292.886443 -26.782943) (xy 292.906958 -26.766266) (xy 292.90899 -26.764742) (xy 292.916102 -26.757884)
			(xy 292.929056 -26.742136) (xy 292.931596 -26.736802) (xy 292.934136 -26.725118) (xy 292.930072 -26.647394)
			(xy 292.929564 -26.634948) (xy 292.911276 -26.603452) (xy 292.906704 -26.59888) (xy 292.895528 -26.58745)
			(xy 292.889178 -26.583132) (xy 292.867279 -26.567859) (xy 292.827568 -26.532172) (xy 292.793217 -26.4913)
			(xy 292.764895 -26.446041) (xy 292.743157 -26.397276) (xy 292.728424 -26.345959) (xy 292.720986 -26.293089)
			(xy 292.720522 -26.266394) (xy 292.721008 -26.239143) (xy 292.728764 -26.185195) (xy 292.744119 -26.1329)
			(xy 292.766761 -26.083323) (xy 292.796227 -26.037473) (xy 292.831918 -25.996282) (xy 292.873109 -25.960591)
			(xy 292.918959 -25.931125) (xy 292.968536 -25.908483) (xy 293.020831 -25.893128) (xy 293.074779 -25.885372)
			(xy 293.129281 -25.885372) (xy 293.183229 -25.893128) (xy 293.235524 -25.908483) (xy 293.285101 -25.931125)
			(xy 293.330951 -25.960591) (xy 293.372142 -25.996282) (xy 293.407833 -26.037473) (xy 293.437299 -26.083323)
			(xy 293.459941 -26.1329) (xy 293.475296 -26.185195) (xy 293.483052 -26.239143) (xy 293.483538 -26.266394)
			(xy 293.482986 -26.295552) (xy 293.474115 -26.35319) (xy 293.456578 -26.408807) (xy 293.430784 -26.461109)
			(xy 293.397333 -26.508878) (xy 293.357004 -26.551002) (xy 293.334186 -26.569162) (xy 293.331392 -26.571194)
			(xy 293.324788 -26.577798) (xy 293.320216 -26.58364) (xy 293.316146 -26.589982) (xy 293.311499 -26.60431)
			(xy 293.311072 -26.611834) (xy 293.314882 -26.69667) (xy 293.319708 -26.706068) (xy 293.320724 -26.708354)
			(xy 293.329614 -26.72334) (xy 293.33317 -26.729182) (xy 293.348918 -26.745438) (xy 293.355268 -26.749756)
			(xy 293.377128 -26.764967) (xy 293.41678 -26.80052) (xy 293.451097 -26.841246) (xy 293.47941 -26.886353)
			(xy 293.501168 -26.934962) (xy 293.515948 -26.986127) (xy 293.523461 -27.038851) (xy 293.523924 -27.065478)
			(xy 293.523924 -27.072082) (xy 293.52302 -27.101372) (xy 293.513326 -27.159163) (xy 293.50462 -27.187144)
			(xy 293.503096 -27.191716) (xy 293.501826 -27.202892) (xy 293.501608 -27.206991) (xy 293.502366 -27.215163)
			(xy 293.50335 -27.219148) (xy 293.50589 -27.22626) (xy 293.506906 -27.228292) (xy 293.52621 -27.267154)
			(xy 293.534592 -27.283918) (xy 293.535354 -27.285696) (xy 293.537352 -27.289051) (xy 293.542199 -27.295173)
			(xy 293.545006 -27.297888) (xy 293.551356 -27.303476) (xy 293.563548 -27.307286) (xy 293.603302 -27.320238)
			(xy 293.658525 -27.342846) (xy 300.7233 -27.342846) (xy 300.7233 -26.479246) (xy 300.72379 -26.449262)
			(xy 300.731618 -26.389806) (xy 300.747139 -26.331881) (xy 300.770088 -26.276477) (xy 300.800072 -26.224543)
			(xy 300.836578 -26.176967) (xy 300.878983 -26.134562) (xy 300.926559 -26.098056) (xy 300.978493 -26.068072)
			(xy 301.033897 -26.045123) (xy 301.091822 -26.029602) (xy 301.151278 -26.021774) (xy 301.211246 -26.021774)
			(xy 301.270702 -26.029602) (xy 301.328627 -26.045123) (xy 301.384031 -26.068072) (xy 301.435965 -26.098056)
			(xy 301.483541 -26.134562) (xy 301.525946 -26.176967) (xy 301.562452 -26.224543) (xy 301.592436 -26.276477)
			(xy 301.615385 -26.331881) (xy 301.623156 -26.360882) (xy 303.28946 -26.360882) (xy 303.293531 -26.30526)
			(xy 303.305657 -26.250823) (xy 303.32558 -26.198732) (xy 303.352876 -26.150097) (xy 303.386962 -26.105954)
			(xy 303.427111 -26.067245) (xy 303.472469 -26.034794) (xy 303.522069 -26.009293) (xy 303.574853 -25.991286)
			(xy 303.629696 -25.981156) (xy 303.68543 -25.979119) (xy 303.740867 -25.985219) (xy 303.794824 -25.999325)
			(xy 303.846153 -26.021137) (xy 303.893759 -26.050191) (xy 303.936627 -26.085866) (xy 303.973844 -26.127403)
			(xy 304.004617 -26.173916) (xy 304.028289 -26.224413) (xy 304.044357 -26.27782) (xy 304.050525 -26.319734)
			(xy 309.041798 -26.319734) (xy 309.045869 -26.264112) (xy 309.057995 -26.209675) (xy 309.077918 -26.157584)
			(xy 309.105214 -26.108949) (xy 309.1393 -26.064806) (xy 309.179449 -26.026097) (xy 309.224807 -25.993646)
			(xy 309.274407 -25.968145) (xy 309.327191 -25.950138) (xy 309.382034 -25.940008) (xy 309.437768 -25.937971)
			(xy 309.493205 -25.944071) (xy 309.547162 -25.958177) (xy 309.598491 -25.979989) (xy 309.646097 -26.009043)
			(xy 309.675762 -26.03373) (xy 315.467744 -26.03373) (xy 315.471815 -25.978108) (xy 315.483941 -25.923671)
			(xy 315.503864 -25.87158) (xy 315.53116 -25.822945) (xy 315.565246 -25.778802) (xy 315.605395 -25.740093)
			(xy 315.650753 -25.707642) (xy 315.700353 -25.682141) (xy 315.753137 -25.664134) (xy 315.80798 -25.654004)
			(xy 315.863714 -25.651967) (xy 315.919151 -25.658067) (xy 315.973108 -25.672173) (xy 316.024437 -25.693985)
			(xy 316.072043 -25.723039) (xy 316.114911 -25.758714) (xy 316.152128 -25.800251) (xy 316.182901 -25.846764)
			(xy 316.206573 -25.897261) (xy 316.222641 -25.950668) (xy 316.230761 -26.005844) (xy 316.23127 -26.03373)
			(xy 316.230761 -26.061616) (xy 316.222641 -26.116792) (xy 316.206573 -26.170199) (xy 316.182901 -26.220696)
			(xy 316.152128 -26.267209) (xy 316.114911 -26.308746) (xy 316.072043 -26.344421) (xy 316.024437 -26.373475)
			(xy 315.973108 -26.395287) (xy 315.919151 -26.409393) (xy 315.863714 -26.415493) (xy 315.80798 -26.413456)
			(xy 315.753137 -26.403326) (xy 315.700353 -26.385319) (xy 315.650753 -26.359818) (xy 315.605395 -26.327367)
			(xy 315.565246 -26.288658) (xy 315.53116 -26.244515) (xy 315.503864 -26.19588) (xy 315.483941 -26.143789)
			(xy 315.471815 -26.089352) (xy 315.467744 -26.03373) (xy 309.675762 -26.03373) (xy 309.688965 -26.044718)
			(xy 309.726182 -26.086255) (xy 309.756955 -26.132768) (xy 309.780627 -26.183265) (xy 309.796695 -26.236672)
			(xy 309.804815 -26.291848) (xy 309.805324 -26.319734) (xy 309.804815 -26.34762) (xy 309.796695 -26.402796)
			(xy 309.780627 -26.456203) (xy 309.756955 -26.5067) (xy 309.726182 -26.553213) (xy 309.688965 -26.59475)
			(xy 309.646097 -26.630425) (xy 309.598491 -26.659479) (xy 309.547162 -26.681291) (xy 309.493205 -26.695397)
			(xy 309.437768 -26.701497) (xy 309.382034 -26.69946) (xy 309.327191 -26.68933) (xy 309.274407 -26.671323)
			(xy 309.224807 -26.645822) (xy 309.179449 -26.613371) (xy 309.1393 -26.574662) (xy 309.105214 -26.530519)
			(xy 309.077918 -26.481884) (xy 309.057995 -26.429793) (xy 309.045869 -26.375356) (xy 309.041798 -26.319734)
			(xy 304.050525 -26.319734) (xy 304.052477 -26.332996) (xy 304.052986 -26.360882) (xy 304.052477 -26.388768)
			(xy 304.044357 -26.443944) (xy 304.028289 -26.497351) (xy 304.004617 -26.547848) (xy 303.973844 -26.594361)
			(xy 303.936627 -26.635898) (xy 303.893759 -26.671573) (xy 303.846153 -26.700627) (xy 303.794824 -26.722439)
			(xy 303.740867 -26.736545) (xy 303.68543 -26.742645) (xy 303.629696 -26.740608) (xy 303.574853 -26.730478)
			(xy 303.522069 -26.712471) (xy 303.472469 -26.68697) (xy 303.427111 -26.654519) (xy 303.386962 -26.61581)
			(xy 303.352876 -26.571667) (xy 303.32558 -26.523032) (xy 303.305657 -26.470941) (xy 303.293531 -26.416504)
			(xy 303.28946 -26.360882) (xy 301.623156 -26.360882) (xy 301.630906 -26.389806) (xy 301.638734 -26.449262)
			(xy 301.639224 -26.479246) (xy 301.639224 -26.971244) (xy 305.05095 -26.971244) (xy 305.055021 -26.915622)
			(xy 305.067147 -26.861185) (xy 305.08707 -26.809094) (xy 305.114366 -26.760459) (xy 305.148452 -26.716316)
			(xy 305.188601 -26.677607) (xy 305.233959 -26.645156) (xy 305.283559 -26.619655) (xy 305.336343 -26.601648)
			(xy 305.391186 -26.591518) (xy 305.44692 -26.589481) (xy 305.502357 -26.595581) (xy 305.556314 -26.609687)
			(xy 305.607643 -26.631499) (xy 305.655249 -26.660553) (xy 305.698117 -26.696228) (xy 305.735334 -26.737765)
			(xy 305.766107 -26.784278) (xy 305.789779 -26.834775) (xy 305.805847 -26.888182) (xy 305.813967 -26.943358)
			(xy 305.814476 -26.971244) (xy 305.813967 -26.99913) (xy 305.805847 -27.054306) (xy 305.789779 -27.107713)
			(xy 305.766107 -27.15821) (xy 305.735334 -27.204723) (xy 305.698117 -27.24626) (xy 305.655249 -27.281935)
			(xy 305.607643 -27.310989) (xy 305.556314 -27.332801) (xy 305.502357 -27.346907) (xy 305.44692 -27.353007)
			(xy 305.391186 -27.35097) (xy 305.336343 -27.34084) (xy 305.283559 -27.322833) (xy 305.233959 -27.297332)
			(xy 305.188601 -27.264881) (xy 305.148452 -27.226172) (xy 305.114366 -27.182029) (xy 305.08707 -27.133394)
			(xy 305.067147 -27.081303) (xy 305.055021 -27.026866) (xy 305.05095 -26.971244) (xy 301.639224 -26.971244)
			(xy 301.639224 -27.342846) (xy 301.638734 -27.37283) (xy 301.630906 -27.432286) (xy 301.615385 -27.490211)
			(xy 301.592436 -27.545615) (xy 301.562452 -27.597549) (xy 301.525946 -27.645125) (xy 301.483541 -27.68753)
			(xy 301.435965 -27.724036) (xy 301.384031 -27.75402) (xy 301.328627 -27.776969) (xy 301.270702 -27.79249)
			(xy 301.211246 -27.800318) (xy 301.151278 -27.800318) (xy 301.091822 -27.79249) (xy 301.033897 -27.776969)
			(xy 300.978493 -27.75402) (xy 300.926559 -27.724036) (xy 300.878983 -27.68753) (xy 300.836578 -27.645125)
			(xy 300.800072 -27.597549) (xy 300.770088 -27.545615) (xy 300.747139 -27.490211) (xy 300.731618 -27.432286)
			(xy 300.72379 -27.37283) (xy 300.7233 -27.342846) (xy 293.658525 -27.342846) (xy 293.680687 -27.351919)
			(xy 293.755148 -27.389966) (xy 293.790878 -27.41168) (xy 293.799006 -27.41168) (xy 293.802816 -27.411172)
			(xy 293.80307 -27.411172) (xy 293.815262 -27.409902) (xy 293.816786 -27.409902) (xy 293.820342 -27.409394)
			(xy 293.84879 -27.408378) (xy 293.868094 -27.408886) (xy 293.877746 -27.409648) (xy 293.904755 -27.41218)
			(xy 293.957717 -27.423912) (xy 294.008484 -27.443024) (xy 294.056033 -27.469132) (xy 294.099407 -27.50171)
			(xy 294.137731 -27.540102) (xy 294.154352 -27.56154) (xy 294.156384 -27.56408) (xy 294.200781 -27.571473)
			(xy 294.288121 -27.593233) (xy 294.373147 -27.622772) (xy 294.455165 -27.659851) (xy 294.53351 -27.704168)
			(xy 294.607543 -27.755363) (xy 294.676664 -27.813019) (xy 294.708834 -27.844496) (xy 295.97881 -29.114242)
			(xy 303.0474 -29.114242) (xy 303.0474 -28.250642) (xy 303.04789 -28.220674) (xy 303.055713 -28.161252)
			(xy 303.071226 -28.103359) (xy 303.094162 -28.047986) (xy 303.124129 -27.99608) (xy 303.160616 -27.94853)
			(xy 303.202996 -27.90615) (xy 303.250546 -27.869663) (xy 303.302452 -27.839696) (xy 303.357825 -27.81676)
			(xy 303.415718 -27.801247) (xy 303.47514 -27.793424) (xy 303.535076 -27.793424) (xy 303.594498 -27.801247)
			(xy 303.652391 -27.81676) (xy 303.707764 -27.839696) (xy 303.75967 -27.869663) (xy 303.80722 -27.90615)
			(xy 303.8496 -27.94853) (xy 303.886087 -27.99608) (xy 303.916054 -28.047986) (xy 303.93899 -28.103359)
			(xy 303.954503 -28.161252) (xy 303.962326 -28.220674) (xy 303.962816 -28.250642) (xy 303.962816 -28.469082)
			(xy 307.952392 -28.469082) (xy 307.956463 -28.41346) (xy 307.968589 -28.359023) (xy 307.988512 -28.306932)
			(xy 308.015808 -28.258297) (xy 308.049894 -28.214154) (xy 308.090043 -28.175445) (xy 308.135401 -28.142994)
			(xy 308.185001 -28.117493) (xy 308.237785 -28.099486) (xy 308.292628 -28.089356) (xy 308.348362 -28.087319)
			(xy 308.403799 -28.093419) (xy 308.457756 -28.107525) (xy 308.509085 -28.129337) (xy 308.525141 -28.139136)
			(xy 312.597798 -28.139136) (xy 312.601869 -28.083514) (xy 312.613995 -28.029077) (xy 312.633918 -27.976986)
			(xy 312.661214 -27.928351) (xy 312.6953 -27.884208) (xy 312.735449 -27.845499) (xy 312.780807 -27.813048)
			(xy 312.830407 -27.787547) (xy 312.883191 -27.76954) (xy 312.938034 -27.75941) (xy 312.993768 -27.757373)
			(xy 313.049205 -27.763473) (xy 313.103162 -27.777579) (xy 313.154491 -27.799391) (xy 313.202097 -27.828445)
			(xy 313.244965 -27.86412) (xy 313.282182 -27.905657) (xy 313.312955 -27.95217) (xy 313.336627 -28.002667)
			(xy 313.352695 -28.056074) (xy 313.360815 -28.11125) (xy 313.361324 -28.139136) (xy 313.867798 -28.139136)
			(xy 313.871869 -28.083514) (xy 313.883995 -28.029077) (xy 313.903918 -27.976986) (xy 313.931214 -27.928351)
			(xy 313.9653 -27.884208) (xy 314.005449 -27.845499) (xy 314.050807 -27.813048) (xy 314.100407 -27.787547)
			(xy 314.153191 -27.76954) (xy 314.208034 -27.75941) (xy 314.263768 -27.757373) (xy 314.319205 -27.763473)
			(xy 314.373162 -27.777579) (xy 314.424491 -27.799391) (xy 314.472097 -27.828445) (xy 314.514965 -27.86412)
			(xy 314.552182 -27.905657) (xy 314.582955 -27.95217) (xy 314.606627 -28.002667) (xy 314.622695 -28.056074)
			(xy 314.630815 -28.11125) (xy 314.631324 -28.139136) (xy 314.630815 -28.167022) (xy 314.622695 -28.222198)
			(xy 314.606627 -28.275605) (xy 314.582955 -28.326102) (xy 314.552182 -28.372615) (xy 314.514965 -28.414152)
			(xy 314.472097 -28.449827) (xy 314.424491 -28.478881) (xy 314.373162 -28.500693) (xy 314.319205 -28.514799)
			(xy 314.263768 -28.520899) (xy 314.208034 -28.518862) (xy 314.153191 -28.508732) (xy 314.100407 -28.490725)
			(xy 314.050807 -28.465224) (xy 314.005449 -28.432773) (xy 313.9653 -28.394064) (xy 313.931214 -28.349921)
			(xy 313.903918 -28.301286) (xy 313.883995 -28.249195) (xy 313.871869 -28.194758) (xy 313.867798 -28.139136)
			(xy 313.361324 -28.139136) (xy 313.360815 -28.167022) (xy 313.352695 -28.222198) (xy 313.336627 -28.275605)
			(xy 313.312955 -28.326102) (xy 313.282182 -28.372615) (xy 313.244965 -28.414152) (xy 313.202097 -28.449827)
			(xy 313.154491 -28.478881) (xy 313.103162 -28.500693) (xy 313.049205 -28.514799) (xy 312.993768 -28.520899)
			(xy 312.938034 -28.518862) (xy 312.883191 -28.508732) (xy 312.830407 -28.490725) (xy 312.780807 -28.465224)
			(xy 312.735449 -28.432773) (xy 312.6953 -28.394064) (xy 312.661214 -28.349921) (xy 312.633918 -28.301286)
			(xy 312.613995 -28.249195) (xy 312.601869 -28.194758) (xy 312.597798 -28.139136) (xy 308.525141 -28.139136)
			(xy 308.556691 -28.158391) (xy 308.599559 -28.194066) (xy 308.636776 -28.235603) (xy 308.667549 -28.282116)
			(xy 308.691221 -28.332613) (xy 308.707289 -28.38602) (xy 308.715409 -28.441196) (xy 308.715918 -28.469082)
			(xy 308.715409 -28.496968) (xy 308.707289 -28.552144) (xy 308.691221 -28.605551) (xy 308.667549 -28.656048)
			(xy 308.636776 -28.702561) (xy 308.599559 -28.744098) (xy 308.556691 -28.779773) (xy 308.509085 -28.808827)
			(xy 308.457756 -28.830639) (xy 308.403799 -28.844745) (xy 308.348362 -28.850845) (xy 308.292628 -28.848808)
			(xy 308.237785 -28.838678) (xy 308.185001 -28.820671) (xy 308.135401 -28.79517) (xy 308.090043 -28.762719)
			(xy 308.049894 -28.72401) (xy 308.015808 -28.679867) (xy 307.988512 -28.631232) (xy 307.968589 -28.579141)
			(xy 307.956463 -28.524704) (xy 307.952392 -28.469082) (xy 303.962816 -28.469082) (xy 303.962816 -29.114242)
			(xy 303.962326 -29.14421) (xy 303.954503 -29.203632) (xy 303.93899 -29.261525) (xy 303.916054 -29.316898)
			(xy 303.886087 -29.368804) (xy 303.8496 -29.416354) (xy 303.80722 -29.458734) (xy 303.75967 -29.495221)
			(xy 303.707764 -29.525188) (xy 303.652391 -29.548124) (xy 303.594498 -29.563637) (xy 303.535076 -29.57146)
			(xy 303.47514 -29.57146) (xy 303.415718 -29.563637) (xy 303.357825 -29.548124) (xy 303.302452 -29.525188)
			(xy 303.250546 -29.495221) (xy 303.202996 -29.458734) (xy 303.160616 -29.416354) (xy 303.124129 -29.368804)
			(xy 303.094162 -29.316898) (xy 303.071226 -29.261525) (xy 303.055713 -29.203632) (xy 303.04789 -29.14421)
			(xy 303.0474 -29.114242) (xy 295.97881 -29.114242) (xy 296.110914 -29.246322) (xy 296.113962 -29.247846)
			(xy 296.11701 -29.24937) (xy 296.118026 -29.249878) (xy 296.144514 -29.263995) (xy 296.193074 -29.299269)
			(xy 296.235516 -29.341708) (xy 296.270792 -29.390266) (xy 296.284904 -29.416756) (xy 296.285412 -29.417772)
			(xy 296.286936 -29.42082) (xy 296.28846 -29.423868) (xy 296.40784 -29.543248) (xy 297.607736 -30.743398)
			(xy 297.632396 -30.768433) (xy 297.678541 -30.821441) (xy 297.699938 -30.849316) (xy 297.715088 -30.869693)
			(xy 297.743551 -30.911749) (xy 297.749039 -30.92069) (xy 305.689508 -30.92069) (xy 305.689508 -30.05709)
			(xy 305.689998 -30.027122) (xy 305.697821 -29.9677) (xy 305.713334 -29.909807) (xy 305.73627 -29.854434)
			(xy 305.766237 -29.802528) (xy 305.802724 -29.754978) (xy 305.845104 -29.712598) (xy 305.892654 -29.676111)
			(xy 305.94456 -29.646144) (xy 305.999933 -29.623208) (xy 306.057826 -29.607695) (xy 306.117248 -29.599872)
			(xy 306.177184 -29.599872) (xy 306.236606 -29.607695) (xy 306.294499 -29.623208) (xy 306.349872 -29.646144)
			(xy 306.401778 -29.676111) (xy 306.449328 -29.712598) (xy 306.491708 -29.754978) (xy 306.528195 -29.802528)
			(xy 306.558162 -29.854434) (xy 306.581098 -29.909807) (xy 306.596611 -29.9677) (xy 306.604434 -30.027122)
			(xy 306.604924 -30.05709) (xy 306.604924 -30.376876) (xy 311.088786 -30.376876) (xy 311.089326 -30.34796)
			(xy 311.098046 -30.290788) (xy 311.115298 -30.235588) (xy 311.140685 -30.183626) (xy 311.173626 -30.136091)
			(xy 311.213367 -30.094075) (xy 311.235852 -30.075886) (xy 311.244664 -30.068284) (xy 311.254843 -30.047379)
			(xy 311.25541 -30.035754) (xy 311.25541 -29.955998) (xy 311.254854 -29.944368) (xy 311.244677 -29.923459)
			(xy 311.235852 -29.915866) (xy 311.213342 -29.897706) (xy 311.173611 -29.855679) (xy 311.140676 -29.808137)
			(xy 311.115293 -29.75617) (xy 311.098042 -29.700967) (xy 311.089318 -29.643794) (xy 311.088786 -29.614876)
			(xy 311.089272 -29.587625) (xy 311.097028 -29.533677) (xy 311.112383 -29.481382) (xy 311.135025 -29.431805)
			(xy 311.164491 -29.385955) (xy 311.200182 -29.344764) (xy 311.241373 -29.309073) (xy 311.287223 -29.279607)
			(xy 311.3368 -29.256965) (xy 311.389095 -29.24161) (xy 311.443043 -29.233854) (xy 311.497545 -29.233854)
			(xy 311.551493 -29.24161) (xy 311.603788 -29.256965) (xy 311.653365 -29.279607) (xy 311.699215 -29.309073)
			(xy 311.740406 -29.344764) (xy 311.776097 -29.385955) (xy 311.805563 -29.431805) (xy 311.828205 -29.481382)
			(xy 311.84356 -29.533677) (xy 311.851316 -29.587625) (xy 311.851802 -29.614876) (xy 311.851266 -29.643792)
			(xy 311.84254 -29.700963) (xy 311.825286 -29.756161) (xy 311.799898 -29.808123) (xy 311.766957 -29.855657)
			(xy 311.72722 -29.897675) (xy 311.704736 -29.915866) (xy 311.695943 -29.923487) (xy 311.685754 -29.944378)
			(xy 311.685178 -29.955998) (xy 311.685178 -30.035754) (xy 311.685708 -30.047387) (xy 311.695904 -30.068295)
			(xy 311.704736 -30.075886) (xy 311.72722 -30.094076) (xy 311.766954 -30.136097) (xy 311.799892 -30.183632)
			(xy 311.82528 -30.235594) (xy 311.842536 -30.290791) (xy 311.851266 -30.34796) (xy 311.851802 -30.376876)
			(xy 314.128912 -30.376876) (xy 314.12948 -30.347961) (xy 314.138198 -30.290792) (xy 314.155446 -30.235594)
			(xy 314.180828 -30.183632) (xy 314.213763 -30.136097) (xy 314.253496 -30.094077) (xy 314.275978 -30.075886)
			(xy 314.284794 -30.068288) (xy 314.29497 -30.04738) (xy 314.295536 -30.035754) (xy 314.295536 -29.955998)
			(xy 314.295006 -29.944364) (xy 314.284813 -29.923453) (xy 314.275978 -29.915866) (xy 314.253474 -29.8977)
			(xy 314.213741 -29.855674) (xy 314.180805 -29.808134) (xy 314.15542 -29.756168) (xy 314.138168 -29.700966)
			(xy 314.129444 -29.643793) (xy 314.128912 -29.614876) (xy 314.129398 -29.587625) (xy 314.137154 -29.533677)
			(xy 314.152509 -29.481382) (xy 314.175151 -29.431805) (xy 314.204617 -29.385955) (xy 314.240308 -29.344764)
			(xy 314.281499 -29.309073) (xy 314.327349 -29.279607) (xy 314.376926 -29.256965) (xy 314.429221 -29.24161)
			(xy 314.483169 -29.233854) (xy 314.537671 -29.233854) (xy 314.591619 -29.24161) (xy 314.643914 -29.256965)
			(xy 314.693491 -29.279607) (xy 314.739341 -29.309073) (xy 314.780532 -29.344764) (xy 314.816223 -29.385955)
			(xy 314.845689 -29.431805) (xy 314.868331 -29.481382) (xy 314.883686 -29.533677) (xy 314.891442 -29.587625)
			(xy 314.891928 -29.614876) (xy 314.89142 -29.643794) (xy 314.882693 -29.700967) (xy 314.865434 -29.756167)
			(xy 314.840041 -29.808129) (xy 314.807094 -29.855662) (xy 314.76735 -29.897677) (xy 314.744862 -29.915866)
			(xy 314.736074 -29.923491) (xy 314.725881 -29.944378) (xy 314.725304 -29.955998) (xy 314.725304 -30.035754)
			(xy 314.725825 -30.047388) (xy 314.736026 -30.068298) (xy 314.744862 -30.075886) (xy 314.767331 -30.094095)
			(xy 314.807069 -30.136109) (xy 314.840011 -30.18364) (xy 314.865402 -30.235598) (xy 314.882661 -30.290793)
			(xy 314.891392 -30.347961) (xy 314.891928 -30.376876) (xy 314.891442 -30.404127) (xy 314.883686 -30.458075)
			(xy 314.868331 -30.51037) (xy 314.845689 -30.559947) (xy 314.816223 -30.605797) (xy 314.780532 -30.646988)
			(xy 314.739341 -30.682679) (xy 314.693491 -30.712145) (xy 314.643914 -30.734787) (xy 314.591619 -30.750142)
			(xy 314.537671 -30.757898) (xy 314.483169 -30.757898) (xy 314.429221 -30.750142) (xy 314.376926 -30.734787)
			(xy 314.327349 -30.712145) (xy 314.281499 -30.682679) (xy 314.240308 -30.646988) (xy 314.204617 -30.605797)
			(xy 314.175151 -30.559947) (xy 314.152509 -30.51037) (xy 314.137154 -30.458075) (xy 314.129398 -30.404127)
			(xy 314.128912 -30.376876) (xy 311.851802 -30.376876) (xy 311.851316 -30.404127) (xy 311.84356 -30.458075)
			(xy 311.828205 -30.51037) (xy 311.805563 -30.559947) (xy 311.776097 -30.605797) (xy 311.740406 -30.646988)
			(xy 311.699215 -30.682679) (xy 311.653365 -30.712145) (xy 311.603788 -30.734787) (xy 311.551493 -30.750142)
			(xy 311.497545 -30.757898) (xy 311.443043 -30.757898) (xy 311.389095 -30.750142) (xy 311.3368 -30.734787)
			(xy 311.287223 -30.712145) (xy 311.241373 -30.682679) (xy 311.200182 -30.646988) (xy 311.164491 -30.605797)
			(xy 311.135025 -30.559947) (xy 311.112383 -30.51037) (xy 311.097028 -30.458075) (xy 311.089272 -30.404127)
			(xy 311.088786 -30.376876) (xy 306.604924 -30.376876) (xy 306.604924 -30.92069) (xy 306.604434 -30.950658)
			(xy 306.596611 -31.01008) (xy 306.581098 -31.067973) (xy 306.558162 -31.123346) (xy 306.528195 -31.175252)
			(xy 306.491708 -31.222802) (xy 306.449328 -31.265182) (xy 306.401778 -31.301669) (xy 306.349872 -31.331636)
			(xy 306.294499 -31.354572) (xy 306.236606 -31.370085) (xy 306.177184 -31.377908) (xy 306.117248 -31.377908)
			(xy 306.057826 -31.370085) (xy 305.999933 -31.354572) (xy 305.94456 -31.331636) (xy 305.892654 -31.301669)
			(xy 305.845104 -31.265182) (xy 305.802724 -31.222802) (xy 305.766237 -31.175252) (xy 305.73627 -31.123346)
			(xy 305.713334 -31.067973) (xy 305.697821 -31.01008) (xy 305.689998 -30.950658) (xy 305.689508 -30.92069)
			(xy 297.749039 -30.92069) (xy 297.756834 -30.93339) (xy 297.75785 -30.935168) (xy 297.763946 -30.94355)
			(xy 297.777783 -30.958748) (xy 297.804334 -30.990127) (xy 297.817032 -31.006288) (xy 297.830135 -31.023208)
			(xy 297.855035 -31.058018) (xy 297.866816 -31.075884) (xy 297.883326 -31.1023) (xy 297.884342 -31.104332)
			(xy 297.885866 -31.106618) (xy 297.891962 -31.116778) (xy 297.90009 -31.130748) (xy 297.90009 -31.131002)
			(xy 297.906186 -31.142178) (xy 297.907202 -31.14421) (xy 297.919158 -31.166691) (xy 297.941012 -31.212689)
			(xy 297.95089 -31.236158) (xy 298.563172 -32.714184) (xy 303.0474 -32.714184) (xy 303.0474 -31.850584)
			(xy 303.04789 -31.820616) (xy 303.055713 -31.761194) (xy 303.071226 -31.703301) (xy 303.094162 -31.647928)
			(xy 303.124129 -31.596022) (xy 303.160616 -31.548472) (xy 303.202996 -31.506092) (xy 303.250546 -31.469605)
			(xy 303.302452 -31.439638) (xy 303.357825 -31.416702) (xy 303.415718 -31.401189) (xy 303.47514 -31.393366)
			(xy 303.535076 -31.393366) (xy 303.594498 -31.401189) (xy 303.652391 -31.416702) (xy 303.707764 -31.439638)
			(xy 303.75967 -31.469605) (xy 303.80722 -31.506092) (xy 303.8496 -31.548472) (xy 303.864494 -31.567882)
			(xy 311.198512 -31.567882) (xy 311.202583 -31.51226) (xy 311.214709 -31.457823) (xy 311.234632 -31.405732)
			(xy 311.261928 -31.357097) (xy 311.296014 -31.312954) (xy 311.336163 -31.274245) (xy 311.381521 -31.241794)
			(xy 311.431121 -31.216293) (xy 311.483905 -31.198286) (xy 311.538748 -31.188156) (xy 311.594482 -31.186119)
			(xy 311.649919 -31.192219) (xy 311.703876 -31.206325) (xy 311.755205 -31.228137) (xy 311.802811 -31.257191)
			(xy 311.845679 -31.292866) (xy 311.882896 -31.334403) (xy 311.913669 -31.380916) (xy 311.937341 -31.431413)
			(xy 311.953409 -31.48482) (xy 311.961529 -31.539996) (xy 311.962038 -31.567882) (xy 311.961529 -31.595768)
			(xy 311.953409 -31.650944) (xy 311.937341 -31.704351) (xy 311.930349 -31.719266) (xy 312.485276 -31.719266)
			(xy 312.489347 -31.663644) (xy 312.501473 -31.609207) (xy 312.521396 -31.557116) (xy 312.548692 -31.508481)
			(xy 312.582778 -31.464338) (xy 312.622927 -31.425629) (xy 312.668285 -31.393178) (xy 312.717885 -31.367677)
			(xy 312.770669 -31.34967) (xy 312.825512 -31.33954) (xy 312.881246 -31.337503) (xy 312.936683 -31.343603)
			(xy 312.99064 -31.357709) (xy 313.041969 -31.379521) (xy 313.089575 -31.408575) (xy 313.132443 -31.44425)
			(xy 313.16966 -31.485787) (xy 313.200433 -31.5323) (xy 313.224105 -31.582797) (xy 313.240173 -31.636204)
			(xy 313.244323 -31.664402) (xy 313.760864 -31.664402) (xy 313.764935 -31.60878) (xy 313.777061 -31.554343)
			(xy 313.796984 -31.502252) (xy 313.82428 -31.453617) (xy 313.858366 -31.409474) (xy 313.898515 -31.370765)
			(xy 313.943873 -31.338314) (xy 313.993473 -31.312813) (xy 314.046257 -31.294806) (xy 314.1011 -31.284676)
			(xy 314.156834 -31.282639) (xy 314.212271 -31.288739) (xy 314.266228 -31.302845) (xy 314.317557 -31.324657)
			(xy 314.365163 -31.353711) (xy 314.408031 -31.389386) (xy 314.445248 -31.430923) (xy 314.476021 -31.477436)
			(xy 314.499693 -31.527933) (xy 314.515761 -31.58134) (xy 314.523881 -31.636516) (xy 314.52439 -31.664402)
			(xy 314.523881 -31.692288) (xy 314.515761 -31.747464) (xy 314.506821 -31.777178) (xy 315.026038 -31.777178)
			(xy 315.030109 -31.721556) (xy 315.042235 -31.667119) (xy 315.062158 -31.615028) (xy 315.089454 -31.566393)
			(xy 315.12354 -31.52225) (xy 315.163689 -31.483541) (xy 315.209047 -31.45109) (xy 315.258647 -31.425589)
			(xy 315.311431 -31.407582) (xy 315.366274 -31.397452) (xy 315.422008 -31.395415) (xy 315.477445 -31.401515)
			(xy 315.531402 -31.415621) (xy 315.582731 -31.437433) (xy 315.630337 -31.466487) (xy 315.673205 -31.502162)
			(xy 315.710422 -31.543699) (xy 315.741195 -31.590212) (xy 315.764867 -31.640709) (xy 315.780935 -31.694116)
			(xy 315.789055 -31.749292) (xy 315.789564 -31.777178) (xy 315.789055 -31.805064) (xy 315.780935 -31.86024)
			(xy 315.764867 -31.913647) (xy 315.741195 -31.964144) (xy 315.710422 -32.010657) (xy 315.673205 -32.052194)
			(xy 315.630337 -32.087869) (xy 315.582731 -32.116923) (xy 315.531402 -32.138735) (xy 315.477445 -32.152841)
			(xy 315.422008 -32.158941) (xy 315.366274 -32.156904) (xy 315.311431 -32.146774) (xy 315.258647 -32.128767)
			(xy 315.209047 -32.103266) (xy 315.163689 -32.070815) (xy 315.12354 -32.032106) (xy 315.089454 -31.987963)
			(xy 315.062158 -31.939328) (xy 315.042235 -31.887237) (xy 315.030109 -31.8328) (xy 315.026038 -31.777178)
			(xy 314.506821 -31.777178) (xy 314.499693 -31.800871) (xy 314.476021 -31.851368) (xy 314.445248 -31.897881)
			(xy 314.408031 -31.939418) (xy 314.365163 -31.975093) (xy 314.317557 -32.004147) (xy 314.266228 -32.025959)
			(xy 314.212271 -32.040065) (xy 314.156834 -32.046165) (xy 314.1011 -32.044128) (xy 314.046257 -32.033998)
			(xy 313.993473 -32.015991) (xy 313.943873 -31.99049) (xy 313.898515 -31.958039) (xy 313.858366 -31.91933)
			(xy 313.82428 -31.875187) (xy 313.796984 -31.826552) (xy 313.777061 -31.774461) (xy 313.764935 -31.720024)
			(xy 313.760864 -31.664402) (xy 313.244323 -31.664402) (xy 313.248293 -31.69138) (xy 313.248802 -31.719266)
			(xy 313.248293 -31.747152) (xy 313.240173 -31.802328) (xy 313.224105 -31.855735) (xy 313.200433 -31.906232)
			(xy 313.16966 -31.952745) (xy 313.132443 -31.994282) (xy 313.089575 -32.029957) (xy 313.041969 -32.059011)
			(xy 312.99064 -32.080823) (xy 312.936683 -32.094929) (xy 312.881246 -32.101029) (xy 312.825512 -32.098992)
			(xy 312.770669 -32.088862) (xy 312.717885 -32.070855) (xy 312.668285 -32.045354) (xy 312.622927 -32.012903)
			(xy 312.582778 -31.974194) (xy 312.548692 -31.930051) (xy 312.521396 -31.881416) (xy 312.501473 -31.829325)
			(xy 312.489347 -31.774888) (xy 312.485276 -31.719266) (xy 311.930349 -31.719266) (xy 311.913669 -31.754848)
			(xy 311.882896 -31.801361) (xy 311.845679 -31.842898) (xy 311.802811 -31.878573) (xy 311.755205 -31.907627)
			(xy 311.703876 -31.929439) (xy 311.649919 -31.943545) (xy 311.594482 -31.949645) (xy 311.538748 -31.947608)
			(xy 311.483905 -31.937478) (xy 311.431121 -31.919471) (xy 311.381521 -31.89397) (xy 311.336163 -31.861519)
			(xy 311.296014 -31.82281) (xy 311.261928 -31.778667) (xy 311.234632 -31.730032) (xy 311.214709 -31.677941)
			(xy 311.202583 -31.623504) (xy 311.198512 -31.567882) (xy 303.864494 -31.567882) (xy 303.886087 -31.596022)
			(xy 303.916054 -31.647928) (xy 303.93899 -31.703301) (xy 303.954503 -31.761194) (xy 303.962326 -31.820616)
			(xy 303.962816 -31.850584) (xy 303.962816 -32.714184) (xy 303.962326 -32.744152) (xy 303.954503 -32.803574)
			(xy 303.93899 -32.861467) (xy 303.916054 -32.91684) (xy 303.886087 -32.968746) (xy 303.8496 -33.016296)
			(xy 303.80722 -33.058676) (xy 303.75967 -33.095163) (xy 303.707764 -33.12513) (xy 303.652391 -33.148066)
			(xy 303.594498 -33.163579) (xy 303.535076 -33.171402) (xy 303.47514 -33.171402) (xy 303.415718 -33.163579)
			(xy 303.357825 -33.148066) (xy 303.302452 -33.12513) (xy 303.250546 -33.095163) (xy 303.202996 -33.058676)
			(xy 303.160616 -33.016296) (xy 303.124129 -32.968746) (xy 303.094162 -32.91684) (xy 303.071226 -32.861467)
			(xy 303.055713 -32.803574) (xy 303.04789 -32.744152) (xy 303.0474 -32.714184) (xy 298.563172 -32.714184)
			(xy 298.56938 -32.72917) (xy 298.58589 -32.768794) (xy 298.612814 -32.833056) (xy 298.614392 -32.836676)
			(xy 298.618478 -32.843432) (xy 298.620942 -32.846518) (xy 298.626022 -32.852106) (xy 298.634658 -32.856932)
			(xy 298.635166 -32.857186) (xy 298.659824 -32.871564) (xy 298.704923 -32.906549) (xy 298.744303 -32.947865)
			(xy 298.777084 -32.994591) (xy 298.802533 -33.045681) (xy 298.820081 -33.099994) (xy 298.829338 -33.156317)
			(xy 298.830238 -33.184846) (xy 298.830238 -33.191704) (xy 298.829802 -33.217759) (xy 298.822668 -33.269379)
			(xy 298.816014 -33.294574) (xy 298.816014 -33.295082) (xy 298.814081 -33.303247) (xy 298.815122 -33.319984)
			(xy 298.818046 -33.327848) (xy 299.312073 -34.520886) (xy 305.689508 -34.520886) (xy 305.689508 -33.657286)
			(xy 305.689998 -33.627318) (xy 305.697821 -33.567896) (xy 305.713334 -33.510003) (xy 305.73627 -33.45463)
			(xy 305.766237 -33.402724) (xy 305.802724 -33.355174) (xy 305.845104 -33.312794) (xy 305.892654 -33.276307)
			(xy 305.94456 -33.24634) (xy 305.999933 -33.223404) (xy 306.057826 -33.207891) (xy 306.117248 -33.200068)
			(xy 306.177184 -33.200068) (xy 306.236606 -33.207891) (xy 306.294499 -33.223404) (xy 306.349872 -33.24634)
			(xy 306.401778 -33.276307) (xy 306.449328 -33.312794) (xy 306.491708 -33.355174) (xy 306.528195 -33.402724)
			(xy 306.558162 -33.45463) (xy 306.581098 -33.510003) (xy 306.596611 -33.567896) (xy 306.604434 -33.627318)
			(xy 306.604924 -33.657286) (xy 306.604924 -34.520886) (xy 306.604434 -34.550854) (xy 306.596611 -34.610276)
			(xy 306.581098 -34.668169) (xy 306.558162 -34.723542) (xy 306.528195 -34.775448) (xy 306.491708 -34.822998)
			(xy 306.449328 -34.865378) (xy 306.401778 -34.901865) (xy 306.349872 -34.931832) (xy 306.294499 -34.954768)
			(xy 306.236606 -34.970281) (xy 306.177184 -34.978104) (xy 306.117248 -34.978104) (xy 306.057826 -34.970281)
			(xy 305.999933 -34.954768) (xy 305.94456 -34.931832) (xy 305.892654 -34.901865) (xy 305.845104 -34.865378)
			(xy 305.802724 -34.822998) (xy 305.766237 -34.775448) (xy 305.73627 -34.723542) (xy 305.713334 -34.668169)
			(xy 305.697821 -34.610276) (xy 305.689998 -34.550854) (xy 305.689508 -34.520886) (xy 299.312073 -34.520886)
			(xy 299.620143 -35.264852) (xy 314.10224 -35.264852) (xy 314.106311 -35.20923) (xy 314.118437 -35.154793)
			(xy 314.13836 -35.102702) (xy 314.165656 -35.054067) (xy 314.199742 -35.009924) (xy 314.239891 -34.971215)
			(xy 314.285249 -34.938764) (xy 314.334849 -34.913263) (xy 314.387633 -34.895256) (xy 314.442476 -34.885126)
			(xy 314.49821 -34.883089) (xy 314.553647 -34.889189) (xy 314.607604 -34.903295) (xy 314.658933 -34.925107)
			(xy 314.706539 -34.954161) (xy 314.749407 -34.989836) (xy 314.786624 -35.031373) (xy 314.817397 -35.077886)
			(xy 314.841069 -35.128383) (xy 314.857137 -35.18179) (xy 314.865257 -35.236966) (xy 314.865766 -35.264852)
			(xy 314.865257 -35.292738) (xy 314.857137 -35.347914) (xy 314.841069 -35.401321) (xy 314.817397 -35.451818)
			(xy 314.786624 -35.498331) (xy 314.749407 -35.539868) (xy 314.706539 -35.575543) (xy 314.658933 -35.604597)
			(xy 314.607604 -35.626409) (xy 314.553647 -35.640515) (xy 314.49821 -35.646615) (xy 314.442476 -35.644578)
			(xy 314.387633 -35.634448) (xy 314.334849 -35.616441) (xy 314.285249 -35.59094) (xy 314.239891 -35.558489)
			(xy 314.199742 -35.51978) (xy 314.165656 -35.475637) (xy 314.13836 -35.427002) (xy 314.118437 -35.374911)
			(xy 314.106311 -35.320474) (xy 314.10224 -35.264852) (xy 299.620143 -35.264852) (xy 299.801788 -35.70351)
			(xy 299.873485 -35.876738) (xy 302.917096 -35.876738) (xy 302.921167 -35.821116) (xy 302.933293 -35.766679)
			(xy 302.953216 -35.714588) (xy 302.980512 -35.665953) (xy 303.014598 -35.62181) (xy 303.054747 -35.583101)
			(xy 303.100105 -35.55065) (xy 303.149705 -35.525149) (xy 303.202489 -35.507142) (xy 303.257332 -35.497012)
			(xy 303.313066 -35.494975) (xy 303.368503 -35.501075) (xy 303.42246 -35.515181) (xy 303.473789 -35.536993)
			(xy 303.521395 -35.566047) (xy 303.564263 -35.601722) (xy 303.60148 -35.643259) (xy 303.632253 -35.689772)
			(xy 303.655925 -35.740269) (xy 303.671993 -35.793676) (xy 303.680113 -35.848852) (xy 303.680622 -35.876738)
			(xy 306.988716 -35.876738) (xy 306.992787 -35.821116) (xy 307.004913 -35.766679) (xy 307.024836 -35.714588)
			(xy 307.052132 -35.665953) (xy 307.086218 -35.62181) (xy 307.126367 -35.583101) (xy 307.171725 -35.55065)
			(xy 307.221325 -35.525149) (xy 307.274109 -35.507142) (xy 307.328952 -35.497012) (xy 307.384686 -35.494975)
			(xy 307.440123 -35.501075) (xy 307.49408 -35.515181) (xy 307.545409 -35.536993) (xy 307.593015 -35.566047)
			(xy 307.635883 -35.601722) (xy 307.6731 -35.643259) (xy 307.703873 -35.689772) (xy 307.727545 -35.740269)
			(xy 307.743613 -35.793676) (xy 307.751733 -35.848852) (xy 307.752242 -35.876738) (xy 307.751733 -35.904624)
			(xy 307.743613 -35.9598) (xy 307.727545 -36.013207) (xy 307.703873 -36.063704) (xy 307.6731 -36.110217)
			(xy 307.635883 -36.151754) (xy 307.593015 -36.187429) (xy 307.545409 -36.216483) (xy 307.49408 -36.238295)
			(xy 307.440123 -36.252401) (xy 307.384686 -36.258501) (xy 307.328952 -36.256464) (xy 307.274109 -36.246334)
			(xy 307.221325 -36.228327) (xy 307.171725 -36.202826) (xy 307.126367 -36.170375) (xy 307.086218 -36.131666)
			(xy 307.052132 -36.087523) (xy 307.024836 -36.038888) (xy 307.004913 -35.986797) (xy 306.992787 -35.93236)
			(xy 306.988716 -35.876738) (xy 303.680622 -35.876738) (xy 303.680113 -35.904624) (xy 303.671993 -35.9598)
			(xy 303.655925 -36.013207) (xy 303.632253 -36.063704) (xy 303.60148 -36.110217) (xy 303.564263 -36.151754)
			(xy 303.521395 -36.187429) (xy 303.473789 -36.216483) (xy 303.42246 -36.238295) (xy 303.368503 -36.252401)
			(xy 303.313066 -36.258501) (xy 303.257332 -36.256464) (xy 303.202489 -36.246334) (xy 303.149705 -36.228327)
			(xy 303.100105 -36.202826) (xy 303.054747 -36.170375) (xy 303.014598 -36.131666) (xy 302.980512 -36.087523)
			(xy 302.953216 -36.038888) (xy 302.933293 -35.986797) (xy 302.921167 -35.93236) (xy 302.917096 -35.876738)
			(xy 299.873485 -35.876738) (xy 300.03496 -36.266882) (xy 300.06925 -36.349432) (xy 300.135729 -36.50996)
			(xy 304.813714 -36.50996) (xy 304.817785 -36.454338) (xy 304.829911 -36.399901) (xy 304.849834 -36.34781)
			(xy 304.87713 -36.299175) (xy 304.911216 -36.255032) (xy 304.951365 -36.216323) (xy 304.996723 -36.183872)
			(xy 305.046323 -36.158371) (xy 305.099107 -36.140364) (xy 305.15395 -36.130234) (xy 305.209684 -36.128197)
			(xy 305.265121 -36.134297) (xy 305.319078 -36.148403) (xy 305.370407 -36.170215) (xy 305.418013 -36.199269)
			(xy 305.460881 -36.234944) (xy 305.498098 -36.276481) (xy 305.528871 -36.322994) (xy 305.552543 -36.373491)
			(xy 305.568611 -36.426898) (xy 305.572536 -36.453572) (xy 308.128414 -36.453572) (xy 308.132485 -36.39795)
			(xy 308.144611 -36.343513) (xy 308.164534 -36.291422) (xy 308.19183 -36.242787) (xy 308.225916 -36.198644)
			(xy 308.266065 -36.159935) (xy 308.311423 -36.127484) (xy 308.361023 -36.101983) (xy 308.413807 -36.083976)
			(xy 308.46865 -36.073846) (xy 308.524384 -36.071809) (xy 308.579821 -36.077909) (xy 308.633778 -36.092015)
			(xy 308.685107 -36.113827) (xy 308.732713 -36.142881) (xy 308.775581 -36.178556) (xy 308.812798 -36.220093)
			(xy 308.843571 -36.266606) (xy 308.853107 -36.286948) (xy 315.40018 -36.286948) (xy 315.404251 -36.231326)
			(xy 315.416377 -36.176889) (xy 315.4363 -36.124798) (xy 315.463596 -36.076163) (xy 315.497682 -36.03202)
			(xy 315.537831 -35.993311) (xy 315.583189 -35.96086) (xy 315.632789 -35.935359) (xy 315.685573 -35.917352)
			(xy 315.740416 -35.907222) (xy 315.79615 -35.905185) (xy 315.851587 -35.911285) (xy 315.905544 -35.925391)
			(xy 315.956873 -35.947203) (xy 316.004479 -35.976257) (xy 316.047347 -36.011932) (xy 316.084564 -36.053469)
			(xy 316.115337 -36.099982) (xy 316.139009 -36.150479) (xy 316.155077 -36.203886) (xy 316.163197 -36.259062)
			(xy 316.163706 -36.286948) (xy 316.163197 -36.314834) (xy 316.155077 -36.37001) (xy 316.139009 -36.423417)
			(xy 316.115337 -36.473914) (xy 316.084564 -36.520427) (xy 316.047347 -36.561964) (xy 316.004479 -36.597639)
			(xy 315.956873 -36.626693) (xy 315.905544 -36.648505) (xy 315.851587 -36.662611) (xy 315.79615 -36.668711)
			(xy 315.740416 -36.666674) (xy 315.685573 -36.656544) (xy 315.632789 -36.638537) (xy 315.583189 -36.613036)
			(xy 315.537831 -36.580585) (xy 315.497682 -36.541876) (xy 315.463596 -36.497733) (xy 315.4363 -36.449098)
			(xy 315.416377 -36.397007) (xy 315.404251 -36.34257) (xy 315.40018 -36.286948) (xy 308.853107 -36.286948)
			(xy 308.867243 -36.317103) (xy 308.883311 -36.37051) (xy 308.891431 -36.425686) (xy 308.89194 -36.453572)
			(xy 308.891431 -36.481458) (xy 308.883311 -36.536634) (xy 308.867243 -36.590041) (xy 308.843571 -36.640538)
			(xy 308.812798 -36.687051) (xy 308.775581 -36.728588) (xy 308.732713 -36.764263) (xy 308.685107 -36.793317)
			(xy 308.633778 -36.815129) (xy 308.579821 -36.829235) (xy 308.524384 -36.835335) (xy 308.46865 -36.833298)
			(xy 308.413807 -36.823168) (xy 308.361023 -36.805161) (xy 308.311423 -36.77966) (xy 308.266065 -36.747209)
			(xy 308.225916 -36.7085) (xy 308.19183 -36.664357) (xy 308.164534 -36.615722) (xy 308.144611 -36.563631)
			(xy 308.132485 -36.509194) (xy 308.128414 -36.453572) (xy 305.572536 -36.453572) (xy 305.576731 -36.482074)
			(xy 305.57724 -36.50996) (xy 305.576731 -36.537846) (xy 305.568611 -36.593022) (xy 305.552543 -36.646429)
			(xy 305.528871 -36.696926) (xy 305.498098 -36.743439) (xy 305.460881 -36.784976) (xy 305.418013 -36.820651)
			(xy 305.370407 -36.849705) (xy 305.319078 -36.871517) (xy 305.265121 -36.885623) (xy 305.209684 -36.891723)
			(xy 305.15395 -36.889686) (xy 305.099107 -36.879556) (xy 305.046323 -36.861549) (xy 304.996723 -36.836048)
			(xy 304.951365 -36.803597) (xy 304.911216 -36.764888) (xy 304.87713 -36.720745) (xy 304.849834 -36.67211)
			(xy 304.829911 -36.620019) (xy 304.817785 -36.565582) (xy 304.813714 -36.50996) (xy 300.135729 -36.50996)
			(xy 300.231556 -36.741354) (xy 300.376082 -37.090604) (xy 300.390398 -37.125953) (xy 300.414174 -37.198424)
			(xy 300.42358 -37.235384) (xy 300.424088 -37.237924) (xy 300.424342 -37.23894) (xy 300.45025 -37.300916)
			(xy 300.471016 -37.351976) (xy 300.502452 -37.457631) (xy 300.505865 -37.47516) (xy 301.959008 -37.47516)
			(xy 301.963079 -37.419538) (xy 301.975205 -37.365101) (xy 301.995128 -37.31301) (xy 302.022424 -37.264375)
			(xy 302.05651 -37.220232) (xy 302.096659 -37.181523) (xy 302.142017 -37.149072) (xy 302.191617 -37.123571)
			(xy 302.244401 -37.105564) (xy 302.299244 -37.095434) (xy 302.354978 -37.093397) (xy 302.410415 -37.099497)
			(xy 302.464372 -37.113603) (xy 302.515701 -37.135415) (xy 302.563307 -37.164469) (xy 302.606175 -37.200144)
			(xy 302.643392 -37.241681) (xy 302.674165 -37.288194) (xy 302.697837 -37.338691) (xy 302.713905 -37.392098)
			(xy 302.722025 -37.447274) (xy 302.722534 -37.47516) (xy 302.722025 -37.503046) (xy 302.713905 -37.558222)
			(xy 302.697837 -37.611629) (xy 302.674165 -37.662126) (xy 302.674012 -37.662358) (xy 304.148234 -37.662358)
			(xy 304.152305 -37.606736) (xy 304.164431 -37.552299) (xy 304.184354 -37.500208) (xy 304.21165 -37.451573)
			(xy 304.245736 -37.40743) (xy 304.285885 -37.368721) (xy 304.331243 -37.33627) (xy 304.380843 -37.310769)
			(xy 304.433627 -37.292762) (xy 304.48847 -37.282632) (xy 304.544204 -37.280595) (xy 304.599641 -37.286695)
			(xy 304.653598 -37.300801) (xy 304.704927 -37.322613) (xy 304.752533 -37.351667) (xy 304.795401 -37.387342)
			(xy 304.832618 -37.428879) (xy 304.863391 -37.475392) (xy 304.887063 -37.525889) (xy 304.903131 -37.579296)
			(xy 304.911251 -37.634472) (xy 304.91176 -37.662358) (xy 304.911251 -37.690244) (xy 304.903131 -37.74542)
			(xy 304.894497 -37.774118) (xy 315.664594 -37.774118) (xy 315.668665 -37.718496) (xy 315.680791 -37.664059)
			(xy 315.700714 -37.611968) (xy 315.72801 -37.563333) (xy 315.762096 -37.51919) (xy 315.802245 -37.480481)
			(xy 315.847603 -37.44803) (xy 315.897203 -37.422529) (xy 315.949987 -37.404522) (xy 316.00483 -37.394392)
			(xy 316.060564 -37.392355) (xy 316.116001 -37.398455) (xy 316.169958 -37.412561) (xy 316.221287 -37.434373)
			(xy 316.268893 -37.463427) (xy 316.311761 -37.499102) (xy 316.348978 -37.540639) (xy 316.379751 -37.587152)
			(xy 316.403423 -37.637649) (xy 316.419491 -37.691056) (xy 316.427611 -37.746232) (xy 316.42812 -37.774118)
			(xy 316.427611 -37.802004) (xy 316.419491 -37.85718) (xy 316.403423 -37.910587) (xy 316.379751 -37.961084)
			(xy 316.348978 -38.007597) (xy 316.311761 -38.049134) (xy 316.268893 -38.084809) (xy 316.221287 -38.113863)
			(xy 316.169958 -38.135675) (xy 316.116001 -38.149781) (xy 316.060564 -38.155881) (xy 316.00483 -38.153844)
			(xy 315.949987 -38.143714) (xy 315.897203 -38.125707) (xy 315.847603 -38.100206) (xy 315.802245 -38.067755)
			(xy 315.762096 -38.029046) (xy 315.72801 -37.984903) (xy 315.700714 -37.936268) (xy 315.680791 -37.884177)
			(xy 315.668665 -37.82974) (xy 315.664594 -37.774118) (xy 304.894497 -37.774118) (xy 304.887063 -37.798827)
			(xy 304.863391 -37.849324) (xy 304.832618 -37.895837) (xy 304.795401 -37.937374) (xy 304.752533 -37.973049)
			(xy 304.704927 -38.002103) (xy 304.653598 -38.023915) (xy 304.599641 -38.038021) (xy 304.544204 -38.044121)
			(xy 304.48847 -38.042084) (xy 304.433627 -38.031954) (xy 304.380843 -38.013947) (xy 304.331243 -37.988446)
			(xy 304.285885 -37.955995) (xy 304.245736 -37.917286) (xy 304.21165 -37.873143) (xy 304.184354 -37.824508)
			(xy 304.164431 -37.772417) (xy 304.152305 -37.71798) (xy 304.148234 -37.662358) (xy 302.674012 -37.662358)
			(xy 302.643392 -37.708639) (xy 302.606175 -37.750176) (xy 302.563307 -37.785851) (xy 302.515701 -37.814905)
			(xy 302.464372 -37.836717) (xy 302.410415 -37.850823) (xy 302.354978 -37.856923) (xy 302.299244 -37.854886)
			(xy 302.244401 -37.844756) (xy 302.191617 -37.826749) (xy 302.142017 -37.801248) (xy 302.096659 -37.768797)
			(xy 302.05651 -37.730088) (xy 302.022424 -37.685945) (xy 301.995128 -37.63731) (xy 301.975205 -37.585219)
			(xy 301.963079 -37.530782) (xy 301.959008 -37.47516) (xy 300.505865 -37.47516) (xy 300.512988 -37.511736)
			(xy 300.520348 -37.555369) (xy 300.528233 -37.643511) (xy 300.528736 -37.687758) (xy 300.528736 -37.688266)
			(xy 300.528482 -37.704268) (xy 300.528482 -37.704522) (xy 300.51143 -38.729951) (xy 307.900797 -38.729951)
			(xy 307.900797 -38.675449) (xy 307.908554 -38.621501) (xy 307.92391 -38.569206) (xy 307.946553 -38.519629)
			(xy 307.97602 -38.47378) (xy 308.011714 -38.432591) (xy 308.052905 -38.396901) (xy 308.098758 -38.367437)
			(xy 308.148336 -38.344799) (xy 308.200632 -38.329447) (xy 308.254581 -38.321695) (xy 308.281832 -38.321234)
			(xy 308.310135 -38.321761) (xy 308.366122 -38.330104) (xy 308.420262 -38.346632) (xy 308.471363 -38.370981)
			(xy 308.518303 -38.402616) (xy 308.560051 -38.440842) (xy 308.59569 -38.48482) (xy 308.610508 -38.50894)
			(xy 308.618129 -38.520959) (xy 308.638743 -38.54056) (xy 308.66397 -38.553702) (xy 308.691846 -38.559364)
			(xy 308.720201 -38.557103) (xy 308.746828 -38.547096) (xy 308.769654 -38.530122) (xy 308.778656 -38.5191)
			(xy 308.796815 -38.496201) (xy 308.838984 -38.455739) (xy 308.886825 -38.422174) (xy 308.939222 -38.396291)
			(xy 308.994951 -38.378694) (xy 309.052711 -38.369794) (xy 309.081932 -38.36924) (xy 309.109185 -38.369632)
			(xy 309.163136 -38.377393) (xy 309.215434 -38.392753) (xy 309.265013 -38.415399) (xy 309.310865 -38.44487)
			(xy 309.352057 -38.480566) (xy 309.387749 -38.52176) (xy 309.417216 -38.567615) (xy 309.439858 -38.617196)
			(xy 309.455214 -38.669495) (xy 309.46297 -38.723447) (xy 309.46297 -38.777953) (xy 309.455214 -38.831905)
			(xy 309.439858 -38.884204) (xy 309.417216 -38.933785) (xy 309.387749 -38.97964) (xy 309.352057 -39.020834)
			(xy 309.310865 -39.05653) (xy 309.265013 -39.086001) (xy 309.215434 -39.108647) (xy 309.163136 -39.124007)
			(xy 309.109185 -39.131768) (xy 309.081932 -39.132256) (xy 309.053628 -39.131762) (xy 308.997639 -39.123413)
			(xy 308.943499 -39.106881) (xy 308.892397 -39.082526) (xy 308.845457 -39.050886) (xy 308.80371 -39.012654)
			(xy 308.768073 -38.968672) (xy 308.753256 -38.94455) (xy 308.745682 -38.932499) (xy 308.725058 -38.912898)
			(xy 308.699821 -38.899758) (xy 308.671936 -38.894101) (xy 308.643573 -38.896367) (xy 308.61694 -38.906382)
			(xy 308.594111 -38.923364) (xy 308.585108 -38.93439) (xy 308.566909 -38.957256) (xy 308.524749 -38.997721)
			(xy 308.476916 -39.03129) (xy 308.424527 -39.057179) (xy 308.368804 -39.074783) (xy 308.31105 -39.083692)
			(xy 308.281832 -39.08425) (xy 308.254581 -39.083705) (xy 308.200632 -39.075953) (xy 308.148336 -39.060601)
			(xy 308.098758 -39.037963) (xy 308.052905 -39.008499) (xy 308.011714 -38.972809) (xy 307.97602 -38.93162)
			(xy 307.946553 -38.885771) (xy 307.92391 -38.836194) (xy 307.908554 -38.783899) (xy 307.900797 -38.729951)
			(xy 300.51143 -38.729951) (xy 300.503844 -39.186104) (xy 300.502486 -39.233452) (xy 300.491926 -39.327591)
			(xy 300.482762 -39.374064) (xy 300.43501 -39.60241) (xy 300.357527 -39.97198) (xy 310.095644 -39.97198)
			(xy 310.099715 -39.916358) (xy 310.111841 -39.861921) (xy 310.131764 -39.80983) (xy 310.15906 -39.761195)
			(xy 310.193146 -39.717052) (xy 310.233295 -39.678343) (xy 310.278653 -39.645892) (xy 310.328253 -39.620391)
			(xy 310.381037 -39.602384) (xy 310.43588 -39.592254) (xy 310.491614 -39.590217) (xy 310.547051 -39.596317)
			(xy 310.601008 -39.610423) (xy 310.652337 -39.632235) (xy 310.699943 -39.661289) (xy 310.742811 -39.696964)
			(xy 310.780028 -39.738501) (xy 310.810801 -39.785014) (xy 310.834473 -39.835511) (xy 310.850541 -39.888918)
			(xy 310.858661 -39.944094) (xy 310.85917 -39.97198) (xy 310.858661 -39.999866) (xy 310.850541 -40.055042)
			(xy 310.834473 -40.108449) (xy 310.810801 -40.158946) (xy 310.780028 -40.205459) (xy 310.742811 -40.246996)
			(xy 310.699943 -40.282671) (xy 310.652337 -40.311725) (xy 310.601008 -40.333537) (xy 310.547051 -40.347643)
			(xy 310.491614 -40.353743) (xy 310.43588 -40.351706) (xy 310.381037 -40.341576) (xy 310.328253 -40.323569)
			(xy 310.278653 -40.298068) (xy 310.233295 -40.265617) (xy 310.193146 -40.226908) (xy 310.15906 -40.182765)
			(xy 310.131764 -40.13413) (xy 310.111841 -40.082039) (xy 310.099715 -40.027602) (xy 310.095644 -39.97198)
			(xy 300.357527 -39.97198) (xy 300.35119 -40.002206) (xy 300.193456 -40.756078) (xy 300.191626 -40.767635)
			(xy 300.197454 -40.79027) (xy 300.204632 -40.799512) (xy 300.208442 -40.803576) (xy 300.271942 -40.862758)
			(xy 300.278581 -40.868502) (xy 300.294678 -40.875472) (xy 300.312187 -40.876548) (xy 300.32071 -40.874442)
			(xy 300.346212 -40.867677) (xy 300.39847 -40.860418) (xy 300.42485 -40.859964) (xy 300.45359 -40.860481)
			(xy 300.510421 -40.869099) (xy 300.565315 -40.886145) (xy 300.617029 -40.911236) (xy 300.664394 -40.943802)
			(xy 300.685708 -40.963088) (xy 300.685962 -40.963342) (xy 300.689944 -40.966815) (xy 300.699035 -40.972192)
			(xy 300.703996 -40.97401) (xy 300.708003 -40.975293) (xy 300.7163 -40.976694) (xy 300.720506 -40.976804)
			(xy 300.789594 -40.976804) (xy 300.793803 -40.976724) (xy 300.802103 -40.975321) (xy 300.806104 -40.97401)
			(xy 300.81106 -40.972183) (xy 300.820143 -40.966798) (xy 300.824138 -40.963342) (xy 300.824392 -40.963088)
			(xy 300.845719 -40.943816) (xy 300.893081 -40.911247) (xy 300.944792 -40.886152) (xy 300.999683 -40.869096)
			(xy 301.05651 -40.860467) (xy 301.08525 -40.859964) (xy 301.112507 -40.860424) (xy 301.166468 -40.868175)
			(xy 301.218775 -40.883528) (xy 301.268365 -40.906169) (xy 301.314228 -40.935638) (xy 301.35543 -40.971335)
			(xy 301.391132 -41.012532) (xy 301.420607 -41.058391) (xy 301.443254 -41.107978) (xy 301.458614 -41.160284)
			(xy 301.466373 -41.214243) (xy 301.466373 -41.268757) (xy 301.458614 -41.322717) (xy 301.443254 -41.375022)
			(xy 301.420607 -41.424609) (xy 301.391132 -41.470468) (xy 301.35543 -41.511665) (xy 301.314228 -41.547362)
			(xy 301.268365 -41.576831) (xy 301.218775 -41.599472) (xy 301.166468 -41.614825) (xy 301.112507 -41.622576)
			(xy 301.08525 -41.62298) (xy 301.05651 -41.622463) (xy 300.999678 -41.613846) (xy 300.944783 -41.596801)
			(xy 300.893067 -41.571713) (xy 300.845699 -41.539149) (xy 300.824392 -41.519856) (xy 300.824138 -41.519602)
			(xy 300.820158 -41.516127) (xy 300.811068 -41.510745) (xy 300.806104 -41.508934) (xy 300.802096 -41.507653)
			(xy 300.7938 -41.506253) (xy 300.789594 -41.50614) (xy 300.720506 -41.50614) (xy 300.716297 -41.50622)
			(xy 300.707997 -41.507625) (xy 300.703996 -41.508934) (xy 300.699039 -41.510759) (xy 300.689952 -41.51614)
			(xy 300.685962 -41.519602) (xy 300.685708 -41.519856) (xy 300.66438 -41.539126) (xy 300.617017 -41.571691)
			(xy 300.565306 -41.596784) (xy 300.510416 -41.613837) (xy 300.453589 -41.622465) (xy 300.42485 -41.62298)
			(xy 300.39934 -41.622552) (xy 300.348774 -41.615752) (xy 300.299565 -41.602279) (xy 300.252588 -41.582373)
			(xy 300.208679 -41.55639) (xy 300.188376 -41.540938) (xy 300.181772 -41.535604) (xy 300.149514 -41.524174)
			(xy 300.145845 -41.524223) (xy 300.138579 -41.52525) (xy 300.135036 -41.526206) (xy 300.094904 -41.54043)
			(xy 300.050962 -41.555924) (xy 300.042928 -41.559182) (xy 300.029491 -41.570119) (xy 300.020419 -41.58488)
			(xy 300.018196 -41.593262) (xy 299.71492 -43.041062) (xy 299.659649 -43.305222) (xy 302.507142 -43.305222)
			(xy 302.507611 -43.277852) (xy 302.515426 -43.223672) (xy 302.530914 -43.171169) (xy 302.553756 -43.121422)
			(xy 302.58348 -43.075455) (xy 302.601122 -43.054524) (xy 302.601376 -43.05427) (xy 302.606948 -43.047174)
			(xy 302.613202 -43.030264) (xy 302.613568 -43.02125) (xy 302.613568 -42.954194) (xy 302.613221 -42.945176)
			(xy 302.606967 -42.928259) (xy 302.601376 -42.921174) (xy 302.601122 -42.921174) (xy 302.601122 -42.92092)
			(xy 302.583482 -42.899988) (xy 302.55377 -42.854016) (xy 302.530934 -42.804268) (xy 302.515443 -42.751767)
			(xy 302.507615 -42.697591) (xy 302.507142 -42.670222) (xy 302.507695 -42.641484) (xy 302.516313 -42.584659)
			(xy 302.533357 -42.529769) (xy 302.558441 -42.478057) (xy 302.590999 -42.430693) (xy 302.610266 -42.409364)
			(xy 302.61687 -42.402506) (xy 302.623982 -42.384472) (xy 302.623982 -42.295572) (xy 302.61687 -42.277538)
			(xy 302.610266 -42.27068) (xy 302.59102 -42.249333) (xy 302.558458 -42.201972) (xy 302.53337 -42.150263)
			(xy 302.516321 -42.095376) (xy 302.507697 -42.038553) (xy 302.507695 -41.981079) (xy 302.516313 -41.924255)
			(xy 302.533358 -41.869366) (xy 302.558442 -41.817655) (xy 302.590999 -41.770292) (xy 302.610266 -41.748964)
			(xy 302.61687 -41.742106) (xy 302.623982 -41.724072) (xy 302.623982 -41.635172) (xy 302.61687 -41.617138)
			(xy 302.610266 -41.61028) (xy 302.59101 -41.58894) (xy 302.558441 -41.541582) (xy 302.533345 -41.489874)
			(xy 302.516291 -41.434986) (xy 302.507665 -41.37816) (xy 302.507142 -41.349422) (xy 302.507628 -41.322171)
			(xy 302.515384 -41.268223) (xy 302.530739 -41.215928) (xy 302.553381 -41.166351) (xy 302.582847 -41.120501)
			(xy 302.618538 -41.07931) (xy 302.659729 -41.043619) (xy 302.705579 -41.014153) (xy 302.755156 -40.991511)
			(xy 302.807451 -40.976156) (xy 302.861399 -40.9684) (xy 302.915901 -40.9684) (xy 302.939022 -40.971724)
			(xy 310.79389 -40.971724) (xy 310.797961 -40.916102) (xy 310.810087 -40.861665) (xy 310.83001 -40.809574)
			(xy 310.857306 -40.760939) (xy 310.891392 -40.716796) (xy 310.931541 -40.678087) (xy 310.976899 -40.645636)
			(xy 311.026499 -40.620135) (xy 311.079283 -40.602128) (xy 311.134126 -40.591998) (xy 311.18986 -40.589961)
			(xy 311.245297 -40.596061) (xy 311.299254 -40.610167) (xy 311.350583 -40.631979) (xy 311.398189 -40.661033)
			(xy 311.441057 -40.696708) (xy 311.478274 -40.738245) (xy 311.509047 -40.784758) (xy 311.532719 -40.835255)
			(xy 311.548787 -40.888662) (xy 311.556907 -40.943838) (xy 311.557416 -40.971724) (xy 311.556907 -40.99961)
			(xy 311.548787 -41.054786) (xy 311.532719 -41.108193) (xy 311.509047 -41.15869) (xy 311.478274 -41.205203)
			(xy 311.441057 -41.24674) (xy 311.398189 -41.282415) (xy 311.350583 -41.311469) (xy 311.299254 -41.333281)
			(xy 311.245297 -41.347387) (xy 311.18986 -41.353487) (xy 311.134126 -41.35145) (xy 311.079283 -41.34132)
			(xy 311.026499 -41.323313) (xy 310.976899 -41.297812) (xy 310.931541 -41.265361) (xy 310.891392 -41.226652)
			(xy 310.857306 -41.182509) (xy 310.83001 -41.133874) (xy 310.810087 -41.081783) (xy 310.797961 -41.027346)
			(xy 310.79389 -40.971724) (xy 302.939022 -40.971724) (xy 302.969849 -40.976156) (xy 303.022144 -40.991511)
			(xy 303.071721 -41.014153) (xy 303.117571 -41.043619) (xy 303.158762 -41.07931) (xy 303.194453 -41.120501)
			(xy 303.223919 -41.166351) (xy 303.246561 -41.215928) (xy 303.261916 -41.268223) (xy 303.269672 -41.322171)
			(xy 303.270158 -41.349422) (xy 303.269632 -41.378161) (xy 303.261008 -41.434987) (xy 303.243957 -41.489877)
			(xy 303.218867 -41.541589) (xy 303.186303 -41.588952) (xy 303.167034 -41.61028) (xy 303.16043 -41.617138)
			(xy 303.153318 -41.635172) (xy 303.153318 -41.724072) (xy 303.16043 -41.742106) (xy 303.167034 -41.748964)
			(xy 303.186324 -41.770273) (xy 303.218884 -41.81764) (xy 303.24397 -41.869355) (xy 303.261016 -41.924248)
			(xy 303.269635 -41.981077) (xy 303.269633 -42.038555) (xy 303.261009 -42.095383) (xy 303.243958 -42.150275)
			(xy 303.218868 -42.201987) (xy 303.186304 -42.249352) (xy 303.167034 -42.27068) (xy 303.16043 -42.277538)
			(xy 303.153318 -42.295572) (xy 303.153318 -42.384472) (xy 303.16043 -42.402506) (xy 303.167034 -42.409364)
			(xy 303.186311 -42.430686) (xy 303.218877 -42.478049) (xy 303.243969 -42.529762) (xy 303.261018 -42.584654)
			(xy 303.269639 -42.641483) (xy 303.270158 -42.670222) (xy 303.269715 -42.697593) (xy 303.261893 -42.751774)
			(xy 303.246399 -42.804277) (xy 303.225842 -42.849038) (xy 305.091844 -42.849038) (xy 305.095915 -42.793416)
			(xy 305.108041 -42.738979) (xy 305.127964 -42.686888) (xy 305.15526 -42.638253) (xy 305.189346 -42.59411)
			(xy 305.229495 -42.555401) (xy 305.274853 -42.52295) (xy 305.324453 -42.497449) (xy 305.377237 -42.479442)
			(xy 305.43208 -42.469312) (xy 305.487814 -42.467275) (xy 305.543251 -42.473375) (xy 305.597208 -42.487481)
			(xy 305.648537 -42.509293) (xy 305.696143 -42.538347) (xy 305.739011 -42.574022) (xy 305.776228 -42.615559)
			(xy 305.807001 -42.662072) (xy 305.830673 -42.712569) (xy 305.846741 -42.765976) (xy 305.854861 -42.821152)
			(xy 305.855222 -42.84091) (xy 311.13298 -42.84091) (xy 311.137051 -42.785288) (xy 311.149177 -42.730851)
			(xy 311.1691 -42.67876) (xy 311.196396 -42.630125) (xy 311.230482 -42.585982) (xy 311.270631 -42.547273)
			(xy 311.315989 -42.514822) (xy 311.365589 -42.489321) (xy 311.418373 -42.471314) (xy 311.473216 -42.461184)
			(xy 311.52895 -42.459147) (xy 311.584387 -42.465247) (xy 311.638344 -42.479353) (xy 311.689673 -42.501165)
			(xy 311.737279 -42.530219) (xy 311.780147 -42.565894) (xy 311.817364 -42.607431) (xy 311.848137 -42.653944)
			(xy 311.871809 -42.704441) (xy 311.887877 -42.757848) (xy 311.895997 -42.813024) (xy 311.896506 -42.84091)
			(xy 311.895997 -42.868796) (xy 311.887877 -42.923972) (xy 311.871809 -42.977379) (xy 311.848137 -43.027876)
			(xy 311.817364 -43.074389) (xy 311.780147 -43.115926) (xy 311.737279 -43.151601) (xy 311.689673 -43.180655)
			(xy 311.638344 -43.202467) (xy 311.584387 -43.216573) (xy 311.52895 -43.222673) (xy 311.473216 -43.220636)
			(xy 311.418373 -43.210506) (xy 311.365589 -43.192499) (xy 311.315989 -43.166998) (xy 311.270631 -43.134547)
			(xy 311.230482 -43.095838) (xy 311.196396 -43.051695) (xy 311.1691 -43.00306) (xy 311.149177 -42.950969)
			(xy 311.137051 -42.896532) (xy 311.13298 -42.84091) (xy 305.855222 -42.84091) (xy 305.85537 -42.849038)
			(xy 305.854861 -42.876924) (xy 305.846741 -42.9321) (xy 305.830673 -42.985507) (xy 305.807001 -43.036004)
			(xy 305.776228 -43.082517) (xy 305.739011 -43.124054) (xy 305.696143 -43.159729) (xy 305.648537 -43.188783)
			(xy 305.597208 -43.210595) (xy 305.543251 -43.224701) (xy 305.487814 -43.230801) (xy 305.43208 -43.228764)
			(xy 305.377237 -43.218634) (xy 305.324453 -43.200627) (xy 305.274853 -43.175126) (xy 305.229495 -43.142675)
			(xy 305.189346 -43.103966) (xy 305.15526 -43.059823) (xy 305.127964 -43.011188) (xy 305.108041 -42.959097)
			(xy 305.095915 -42.90466) (xy 305.091844 -42.849038) (xy 303.225842 -42.849038) (xy 303.223552 -42.854024)
			(xy 303.193822 -42.899989) (xy 303.176178 -42.92092) (xy 303.175924 -42.921174) (xy 303.170333 -42.928257)
			(xy 303.164091 -42.945177) (xy 303.163732 -42.954194) (xy 303.163732 -43.02125) (xy 303.164106 -43.030265)
			(xy 303.170341 -43.047183) (xy 303.175924 -43.05427) (xy 303.176178 -43.05427) (xy 303.176178 -43.054524)
			(xy 303.193792 -43.075477) (xy 303.223508 -43.121444) (xy 303.246349 -43.171186) (xy 303.261846 -43.223682)
			(xy 303.269681 -43.277854) (xy 303.270158 -43.305222) (xy 303.269672 -43.332473) (xy 303.261916 -43.386421)
			(xy 303.246561 -43.438716) (xy 303.223919 -43.488293) (xy 303.194453 -43.534143) (xy 303.158762 -43.575334)
			(xy 303.117571 -43.611025) (xy 303.071721 -43.640491) (xy 303.022144 -43.663133) (xy 302.969849 -43.678488)
			(xy 302.915901 -43.686244) (xy 302.861399 -43.686244) (xy 302.807451 -43.678488) (xy 302.755156 -43.663133)
			(xy 302.705579 -43.640491) (xy 302.659729 -43.611025) (xy 302.618538 -43.575334) (xy 302.582847 -43.534143)
			(xy 302.553381 -43.488293) (xy 302.530739 -43.438716) (xy 302.515384 -43.386421) (xy 302.507628 -43.332473)
			(xy 302.507142 -43.305222) (xy 299.659649 -43.305222) (xy 299.569462 -43.73626) (xy 304.412902 -43.73626)
			(xy 304.416973 -43.680638) (xy 304.429099 -43.626201) (xy 304.449022 -43.57411) (xy 304.476318 -43.525475)
			(xy 304.510404 -43.481332) (xy 304.550553 -43.442623) (xy 304.595911 -43.410172) (xy 304.645511 -43.384671)
			(xy 304.698295 -43.366664) (xy 304.753138 -43.356534) (xy 304.808872 -43.354497) (xy 304.864309 -43.360597)
			(xy 304.918266 -43.374703) (xy 304.969595 -43.396515) (xy 305.017201 -43.425569) (xy 305.060069 -43.461244)
			(xy 305.097286 -43.502781) (xy 305.128059 -43.549294) (xy 305.136285 -43.566842) (xy 307.533292 -43.566842)
			(xy 307.537363 -43.51122) (xy 307.549489 -43.456783) (xy 307.569412 -43.404692) (xy 307.596708 -43.356057)
			(xy 307.630794 -43.311914) (xy 307.670943 -43.273205) (xy 307.716301 -43.240754) (xy 307.765901 -43.215253)
			(xy 307.818685 -43.197246) (xy 307.873528 -43.187116) (xy 307.929262 -43.185079) (xy 307.984699 -43.191179)
			(xy 308.038656 -43.205285) (xy 308.089985 -43.227097) (xy 308.137591 -43.256151) (xy 308.180459 -43.291826)
			(xy 308.217676 -43.333363) (xy 308.248449 -43.379876) (xy 308.272121 -43.430373) (xy 308.288189 -43.48378)
			(xy 308.296309 -43.538956) (xy 308.296818 -43.566842) (xy 308.296309 -43.594728) (xy 308.288189 -43.649904)
			(xy 308.272121 -43.703311) (xy 308.248449 -43.753808) (xy 308.217676 -43.800321) (xy 308.180459 -43.841858)
			(xy 308.162372 -43.85691) (xy 308.919624 -43.85691) (xy 308.923695 -43.801288) (xy 308.935821 -43.746851)
			(xy 308.955744 -43.69476) (xy 308.98304 -43.646125) (xy 309.017126 -43.601982) (xy 309.057275 -43.563273)
			(xy 309.102633 -43.530822) (xy 309.152233 -43.505321) (xy 309.205017 -43.487314) (xy 309.25986 -43.477184)
			(xy 309.315594 -43.475147) (xy 309.371031 -43.481247) (xy 309.424988 -43.495353) (xy 309.476317 -43.517165)
			(xy 309.523923 -43.546219) (xy 309.566791 -43.581894) (xy 309.604008 -43.623431) (xy 309.634781 -43.669944)
			(xy 309.658453 -43.720441) (xy 309.674521 -43.773848) (xy 309.682641 -43.829024) (xy 309.68315 -43.85691)
			(xy 309.682641 -43.884796) (xy 309.674521 -43.939972) (xy 309.658453 -43.993379) (xy 309.634781 -44.043876)
			(xy 309.604008 -44.090389) (xy 309.566791 -44.131926) (xy 309.523923 -44.167601) (xy 309.476317 -44.196655)
			(xy 309.424988 -44.218467) (xy 309.371031 -44.232573) (xy 309.315594 -44.238673) (xy 309.25986 -44.236636)
			(xy 309.205017 -44.226506) (xy 309.152233 -44.208499) (xy 309.102633 -44.182998) (xy 309.057275 -44.150547)
			(xy 309.017126 -44.111838) (xy 308.98304 -44.067695) (xy 308.955744 -44.01906) (xy 308.935821 -43.966969)
			(xy 308.923695 -43.912532) (xy 308.919624 -43.85691) (xy 308.162372 -43.85691) (xy 308.137591 -43.877533)
			(xy 308.089985 -43.906587) (xy 308.038656 -43.928399) (xy 307.984699 -43.942505) (xy 307.929262 -43.948605)
			(xy 307.873528 -43.946568) (xy 307.818685 -43.936438) (xy 307.765901 -43.918431) (xy 307.716301 -43.89293)
			(xy 307.670943 -43.860479) (xy 307.630794 -43.82177) (xy 307.596708 -43.777627) (xy 307.569412 -43.728992)
			(xy 307.549489 -43.676901) (xy 307.537363 -43.622464) (xy 307.533292 -43.566842) (xy 305.136285 -43.566842)
			(xy 305.151731 -43.599791) (xy 305.167799 -43.653198) (xy 305.175919 -43.708374) (xy 305.176428 -43.73626)
			(xy 305.175919 -43.764146) (xy 305.167799 -43.819322) (xy 305.151731 -43.872729) (xy 305.128059 -43.923226)
			(xy 305.097286 -43.969739) (xy 305.060069 -44.011276) (xy 305.017201 -44.046951) (xy 304.969595 -44.076005)
			(xy 304.918266 -44.097817) (xy 304.864309 -44.111923) (xy 304.808872 -44.118023) (xy 304.753138 -44.115986)
			(xy 304.698295 -44.105856) (xy 304.645511 -44.087849) (xy 304.595911 -44.062348) (xy 304.550553 -44.029897)
			(xy 304.510404 -43.991188) (xy 304.476318 -43.947045) (xy 304.449022 -43.89841) (xy 304.429099 -43.846319)
			(xy 304.416973 -43.791882) (xy 304.412902 -43.73626) (xy 299.569462 -43.73626) (xy 299.5549 -43.805856)
			(xy 299.280931 -45.114464) (xy 304.265328 -45.114464) (xy 304.269399 -45.058842) (xy 304.281525 -45.004405)
			(xy 304.301448 -44.952314) (xy 304.328744 -44.903679) (xy 304.36283 -44.859536) (xy 304.402979 -44.820827)
			(xy 304.448337 -44.788376) (xy 304.497937 -44.762875) (xy 304.550721 -44.744868) (xy 304.605564 -44.734738)
			(xy 304.661298 -44.732701) (xy 304.716735 -44.738801) (xy 304.770692 -44.752907) (xy 304.822021 -44.774719)
			(xy 304.869627 -44.803773) (xy 304.912495 -44.839448) (xy 304.942477 -44.87291) (xy 311.13298 -44.87291)
			(xy 311.137051 -44.817288) (xy 311.149177 -44.762851) (xy 311.1691 -44.71076) (xy 311.196396 -44.662125)
			(xy 311.230482 -44.617982) (xy 311.270631 -44.579273) (xy 311.315989 -44.546822) (xy 311.365589 -44.521321)
			(xy 311.418373 -44.503314) (xy 311.473216 -44.493184) (xy 311.52895 -44.491147) (xy 311.584387 -44.497247)
			(xy 311.638344 -44.511353) (xy 311.689673 -44.533165) (xy 311.737279 -44.562219) (xy 311.780147 -44.597894)
			(xy 311.817364 -44.639431) (xy 311.848137 -44.685944) (xy 311.871809 -44.736441) (xy 311.887877 -44.789848)
			(xy 311.895997 -44.845024) (xy 311.896506 -44.87291) (xy 311.895997 -44.900796) (xy 311.887877 -44.955972)
			(xy 311.871809 -45.009379) (xy 311.848137 -45.059876) (xy 311.817364 -45.106389) (xy 311.780147 -45.147926)
			(xy 311.737279 -45.183601) (xy 311.689673 -45.212655) (xy 311.638344 -45.234467) (xy 311.584387 -45.248573)
			(xy 311.52895 -45.254673) (xy 311.473216 -45.252636) (xy 311.418373 -45.242506) (xy 311.365589 -45.224499)
			(xy 311.315989 -45.198998) (xy 311.270631 -45.166547) (xy 311.230482 -45.127838) (xy 311.196396 -45.083695)
			(xy 311.1691 -45.03506) (xy 311.149177 -44.982969) (xy 311.137051 -44.928532) (xy 311.13298 -44.87291)
			(xy 304.942477 -44.87291) (xy 304.949712 -44.880985) (xy 304.980485 -44.927498) (xy 305.004157 -44.977995)
			(xy 305.020225 -45.031402) (xy 305.028345 -45.086578) (xy 305.028854 -45.114464) (xy 305.028345 -45.14235)
			(xy 305.020225 -45.197526) (xy 305.004157 -45.250933) (xy 304.980485 -45.30143) (xy 304.949712 -45.347943)
			(xy 304.94407 -45.35424) (xy 308.903622 -45.35424) (xy 308.907693 -45.298618) (xy 308.919819 -45.244181)
			(xy 308.939742 -45.19209) (xy 308.967038 -45.143455) (xy 309.001124 -45.099312) (xy 309.041273 -45.060603)
			(xy 309.086631 -45.028152) (xy 309.136231 -45.002651) (xy 309.189015 -44.984644) (xy 309.243858 -44.974514)
			(xy 309.299592 -44.972477) (xy 309.355029 -44.978577) (xy 309.408986 -44.992683) (xy 309.460315 -45.014495)
			(xy 309.507921 -45.043549) (xy 309.550789 -45.079224) (xy 309.588006 -45.120761) (xy 309.618779 -45.167274)
			(xy 309.642451 -45.217771) (xy 309.658519 -45.271178) (xy 309.666639 -45.326354) (xy 309.667148 -45.35424)
			(xy 309.666639 -45.382126) (xy 309.658519 -45.437302) (xy 309.642451 -45.490709) (xy 309.618779 -45.541206)
			(xy 309.588006 -45.587719) (xy 309.550789 -45.629256) (xy 309.507921 -45.664931) (xy 309.460315 -45.693985)
			(xy 309.408986 -45.715797) (xy 309.355029 -45.729903) (xy 309.299592 -45.736003) (xy 309.243858 -45.733966)
			(xy 309.189015 -45.723836) (xy 309.136231 -45.705829) (xy 309.086631 -45.680328) (xy 309.041273 -45.647877)
			(xy 309.001124 -45.609168) (xy 308.967038 -45.565025) (xy 308.939742 -45.51639) (xy 308.919819 -45.464299)
			(xy 308.907693 -45.409862) (xy 308.903622 -45.35424) (xy 304.94407 -45.35424) (xy 304.912495 -45.38948)
			(xy 304.869627 -45.425155) (xy 304.822021 -45.454209) (xy 304.770692 -45.476021) (xy 304.716735 -45.490127)
			(xy 304.661298 -45.496227) (xy 304.605564 -45.49419) (xy 304.550721 -45.48406) (xy 304.497937 -45.466053)
			(xy 304.448337 -45.440552) (xy 304.402979 -45.408101) (xy 304.36283 -45.369392) (xy 304.328744 -45.325249)
			(xy 304.301448 -45.276614) (xy 304.281525 -45.224523) (xy 304.269399 -45.170086) (xy 304.265328 -45.114464)
			(xy 299.280931 -45.114464) (xy 299.078325 -46.082204) (xy 302.25238 -46.082204) (xy 302.252881 -46.054953)
			(xy 302.260637 -46.001007) (xy 302.275991 -45.948713) (xy 302.298631 -45.899137) (xy 302.328096 -45.853287)
			(xy 302.363786 -45.812097) (xy 302.404974 -45.776405) (xy 302.450823 -45.746939) (xy 302.500398 -45.724297)
			(xy 302.552691 -45.708941) (xy 302.606637 -45.701183) (xy 302.633888 -45.700696) (xy 302.66079 -45.701167)
			(xy 302.71406 -45.708738) (xy 302.765738 -45.723715) (xy 302.8148 -45.745804) (xy 302.860272 -45.774565)
			(xy 302.901254 -45.809428) (xy 302.936932 -45.849703) (xy 302.95215 -45.871892) (xy 302.959262 -45.882814)
			(xy 302.982122 -45.894752) (xy 303.09439 -45.89272) (xy 303.116742 -45.879766) (xy 303.1236 -45.86859)
			(xy 303.138535 -45.844997) (xy 303.174212 -45.802046) (xy 303.215768 -45.764752) (xy 303.262316 -45.733914)
			(xy 303.312861 -45.710189) (xy 303.366324 -45.694084) (xy 303.421564 -45.685944) (xy 303.449482 -45.685456)
			(xy 303.476475 -45.685928) (xy 303.529923 -45.693531) (xy 303.581766 -45.708589) (xy 303.630971 -45.7308)
			(xy 303.676555 -45.759723) (xy 303.697386 -45.776896) (xy 303.705514 -45.784008) (xy 303.726088 -45.790104)
			(xy 303.811432 -45.779182) (xy 303.821983 -45.777433) (xy 303.840263 -45.766361) (xy 303.846738 -45.757846)
			(xy 303.862074 -45.736602) (xy 303.897664 -45.69815) (xy 303.938184 -45.664932) (xy 303.98287 -45.637575)
			(xy 304.030881 -45.616594) (xy 304.081312 -45.602384) (xy 304.133214 -45.595212) (xy 304.159412 -45.594778)
			(xy 304.186662 -45.595293) (xy 304.240606 -45.603051) (xy 304.292897 -45.618406) (xy 304.342471 -45.641047)
			(xy 304.388318 -45.670513) (xy 304.429506 -45.706203) (xy 304.465194 -45.747391) (xy 304.494659 -45.793239)
			(xy 304.517298 -45.842814) (xy 304.532652 -45.895106) (xy 304.540408 -45.94905) (xy 304.540408 -46.00355)
			(xy 304.532652 -46.057494) (xy 304.517298 -46.109786) (xy 304.494659 -46.159361) (xy 304.465194 -46.205209)
			(xy 304.429506 -46.246397) (xy 304.388318 -46.282087) (xy 304.342471 -46.311553) (xy 304.292897 -46.334194)
			(xy 304.240606 -46.349549) (xy 304.186662 -46.357307) (xy 304.159412 -46.357794) (xy 304.13242 -46.357314)
			(xy 304.078973 -46.349711) (xy 304.02713 -46.334654) (xy 303.977925 -46.312445) (xy 303.93234 -46.283525)
			(xy 303.911508 -46.266354) (xy 303.90338 -46.259242) (xy 303.882806 -46.253146) (xy 303.797462 -46.264068)
			(xy 303.786927 -46.265881) (xy 303.768641 -46.276909) (xy 303.762156 -46.285404) (xy 303.744546 -46.309706)
			(xy 303.702948 -46.352965) (xy 303.679352 -46.37151) (xy 303.671478 -46.377352) (xy 303.661064 -46.394878)
			(xy 303.647856 -46.485302) (xy 303.652682 -46.504606) (xy 303.658524 -46.51248) (xy 303.658524 -46.512734)
			(xy 303.676021 -46.537483) (xy 303.703826 -46.591333) (xy 303.722764 -46.648904) (xy 303.729968 -46.693836)
			(xy 308.876192 -46.693836) (xy 308.876678 -46.666585) (xy 308.884434 -46.612637) (xy 308.899789 -46.560342)
			(xy 308.922431 -46.510765) (xy 308.951897 -46.464915) (xy 308.987588 -46.423724) (xy 309.028779 -46.388033)
			(xy 309.074629 -46.358567) (xy 309.124206 -46.335925) (xy 309.176501 -46.32057) (xy 309.230449 -46.312814)
			(xy 309.284951 -46.312814) (xy 309.338899 -46.32057) (xy 309.391194 -46.335925) (xy 309.440771 -46.358567)
			(xy 309.486621 -46.388033) (xy 309.527812 -46.423724) (xy 309.563503 -46.464915) (xy 309.592969 -46.510765)
			(xy 309.615611 -46.560342) (xy 309.630966 -46.612637) (xy 309.638722 -46.666585) (xy 309.639208 -46.693836)
			(xy 309.638734 -46.720264) (xy 309.631425 -46.772611) (xy 309.616952 -46.823446) (xy 309.595593 -46.871793)
			(xy 309.582058 -46.894496) (xy 309.581804 -46.89475) (xy 309.576467 -46.904768) (xy 309.574212 -46.927318)
			(xy 309.577486 -46.938184) (xy 309.603648 -47.01286) (xy 309.608034 -47.023374) (xy 309.624121 -47.039463)
			(xy 309.634636 -47.043848) (xy 309.63489 -47.043848) (xy 309.659408 -47.052893) (xy 309.70586 -47.07684)
			(xy 309.74861 -47.106901) (xy 309.786861 -47.142512) (xy 309.819896 -47.183008) (xy 309.847098 -47.227631)
			(xy 309.867959 -47.275548) (xy 309.882088 -47.325863) (xy 309.889221 -47.377635) (xy 309.889652 -47.403766)
			(xy 309.889166 -47.431017) (xy 309.887643 -47.441612) (xy 311.161682 -47.441612) (xy 311.165753 -47.38599)
			(xy 311.177879 -47.331553) (xy 311.197802 -47.279462) (xy 311.225098 -47.230827) (xy 311.259184 -47.186684)
			(xy 311.299333 -47.147975) (xy 311.344691 -47.115524) (xy 311.394291 -47.090023) (xy 311.447075 -47.072016)
			(xy 311.501918 -47.061886) (xy 311.557652 -47.059849) (xy 311.613089 -47.065949) (xy 311.667046 -47.080055)
			(xy 311.718375 -47.101867) (xy 311.765981 -47.130921) (xy 311.808849 -47.166596) (xy 311.846066 -47.208133)
			(xy 311.876839 -47.254646) (xy 311.900511 -47.305143) (xy 311.916579 -47.35855) (xy 311.924699 -47.413726)
			(xy 311.925208 -47.441612) (xy 311.924699 -47.469498) (xy 311.916579 -47.524674) (xy 311.900511 -47.578081)
			(xy 311.876839 -47.628578) (xy 311.846066 -47.675091) (xy 311.808849 -47.716628) (xy 311.765981 -47.752303)
			(xy 311.718375 -47.781357) (xy 311.667046 -47.803169) (xy 311.613089 -47.817275) (xy 311.557652 -47.823375)
			(xy 311.501918 -47.821338) (xy 311.447075 -47.811208) (xy 311.394291 -47.793201) (xy 311.344691 -47.7677)
			(xy 311.299333 -47.735249) (xy 311.259184 -47.69654) (xy 311.225098 -47.652397) (xy 311.197802 -47.603762)
			(xy 311.177879 -47.551671) (xy 311.165753 -47.497234) (xy 311.161682 -47.441612) (xy 309.887643 -47.441612)
			(xy 309.88141 -47.484965) (xy 309.866055 -47.53726) (xy 309.843413 -47.586837) (xy 309.813947 -47.632687)
			(xy 309.778256 -47.673878) (xy 309.737065 -47.709569) (xy 309.691215 -47.739035) (xy 309.641638 -47.761677)
			(xy 309.589343 -47.777032) (xy 309.535395 -47.784788) (xy 309.480893 -47.784788) (xy 309.426945 -47.777032)
			(xy 309.37465 -47.761677) (xy 309.325073 -47.739035) (xy 309.279223 -47.709569) (xy 309.238032 -47.673878)
			(xy 309.202341 -47.632687) (xy 309.172875 -47.586837) (xy 309.150233 -47.53726) (xy 309.134878 -47.484965)
			(xy 309.127122 -47.431017) (xy 309.126636 -47.403766) (xy 309.127105 -47.377338) (xy 309.134415 -47.324991)
			(xy 309.148889 -47.274156) (xy 309.170251 -47.225809) (xy 309.183786 -47.203106) (xy 309.18404 -47.202852)
			(xy 309.189375 -47.192833) (xy 309.191634 -47.170284) (xy 309.188358 -47.159418) (xy 309.162196 -47.084742)
			(xy 309.157835 -47.074215) (xy 309.141731 -47.058131) (xy 309.131208 -47.053754) (xy 309.130954 -47.053754)
			(xy 309.106446 -47.044683) (xy 309.059994 -47.02074) (xy 309.017242 -46.990685) (xy 308.97899 -46.955078)
			(xy 308.945953 -46.914585) (xy 308.918749 -46.869964) (xy 308.897887 -46.822049) (xy 308.883757 -46.771736)
			(xy 308.876623 -46.719966) (xy 308.876192 -46.693836) (xy 303.729968 -46.693836) (xy 303.732358 -46.708745)
			(xy 303.732946 -46.739048) (xy 303.732467 -46.766299) (xy 303.724705 -46.820245) (xy 303.709346 -46.872537)
			(xy 303.686702 -46.922112) (xy 303.657234 -46.96796) (xy 303.621542 -47.009149) (xy 303.580352 -47.04484)
			(xy 303.534503 -47.074306) (xy 303.484928 -47.096949) (xy 303.432635 -47.112307) (xy 303.378689 -47.120068)
			(xy 303.351438 -47.120556) (xy 303.325405 -47.12008) (xy 303.273824 -47.112999) (xy 303.223683 -47.098976)
			(xy 303.175911 -47.078271) (xy 303.131395 -47.051269) (xy 303.1109 -47.035212) (xy 303.10315 -47.029459)
			(xy 303.084734 -47.023725) (xy 303.075086 -47.024036) (xy 302.99533 -47.030386) (xy 302.97755 -47.039022)
			(xy 302.9712 -47.046388) (xy 302.953042 -47.066056) (xy 302.912129 -47.100576) (xy 302.866796 -47.129042)
			(xy 302.81793 -47.150896) (xy 302.76649 -47.165709) (xy 302.713485 -47.17319) (xy 302.68672 -47.173642)
			(xy 302.659471 -47.173103) (xy 302.605527 -47.16535) (xy 302.553235 -47.149999) (xy 302.50366 -47.127363)
			(xy 302.457812 -47.097902) (xy 302.416622 -47.062216) (xy 302.38093 -47.021032) (xy 302.351463 -46.975187)
			(xy 302.328819 -46.925615) (xy 302.313461 -46.873326) (xy 302.305701 -46.819383) (xy 302.305212 -46.792134)
			(xy 302.305733 -46.76336) (xy 302.314385 -46.706465) (xy 302.331481 -46.651515) (xy 302.356636 -46.599755)
			(xy 302.389277 -46.552359) (xy 302.40859 -46.531022) (xy 302.415956 -46.523148) (xy 302.423068 -46.503336)
			(xy 302.415702 -46.40707) (xy 302.405796 -46.388274) (xy 302.397414 -46.38167) (xy 302.375228 -46.363447)
			(xy 302.336019 -46.321511) (xy 302.303533 -46.274175) (xy 302.278505 -46.222507) (xy 302.261499 -46.167672)
			(xy 302.252898 -46.110909) (xy 302.25238 -46.082204) (xy 299.078325 -46.082204) (xy 299.077634 -46.085506)
			(xy 298.61241 -48.30699) (xy 308.753762 -48.30699) (xy 308.757833 -48.251368) (xy 308.769959 -48.196931)
			(xy 308.789882 -48.14484) (xy 308.817178 -48.096205) (xy 308.851264 -48.052062) (xy 308.891413 -48.013353)
			(xy 308.936771 -47.980902) (xy 308.986371 -47.955401) (xy 309.039155 -47.937394) (xy 309.093998 -47.927264)
			(xy 309.149732 -47.925227) (xy 309.205169 -47.931327) (xy 309.259126 -47.945433) (xy 309.310455 -47.967245)
			(xy 309.358061 -47.996299) (xy 309.400929 -48.031974) (xy 309.438146 -48.073511) (xy 309.468919 -48.120024)
			(xy 309.492591 -48.170521) (xy 309.508659 -48.223928) (xy 309.516779 -48.279104) (xy 309.517288 -48.30699)
			(xy 309.516779 -48.334876) (xy 309.508659 -48.390052) (xy 309.492591 -48.443459) (xy 309.468919 -48.493956)
			(xy 309.438146 -48.540469) (xy 309.400929 -48.582006) (xy 309.358061 -48.617681) (xy 309.310455 -48.646735)
			(xy 309.259126 -48.668547) (xy 309.205169 -48.682653) (xy 309.149732 -48.688753) (xy 309.093998 -48.686716)
			(xy 309.039155 -48.676586) (xy 308.986371 -48.658579) (xy 308.936771 -48.633078) (xy 308.891413 -48.600627)
			(xy 308.851264 -48.561918) (xy 308.817178 -48.517775) (xy 308.789882 -48.46914) (xy 308.769959 -48.417049)
			(xy 308.757833 -48.362612) (xy 308.753762 -48.30699) (xy 298.61241 -48.30699) (xy 298.519004 -48.753014)
			(xy 305.368196 -48.753014) (xy 305.372267 -48.697392) (xy 305.384393 -48.642955) (xy 305.404316 -48.590864)
			(xy 305.431612 -48.542229) (xy 305.465698 -48.498086) (xy 305.505847 -48.459377) (xy 305.551205 -48.426926)
			(xy 305.600805 -48.401425) (xy 305.653589 -48.383418) (xy 305.708432 -48.373288) (xy 305.764166 -48.371251)
			(xy 305.819603 -48.377351) (xy 305.87356 -48.391457) (xy 305.924889 -48.413269) (xy 305.972495 -48.442323)
			(xy 306.015363 -48.477998) (xy 306.05258 -48.519535) (xy 306.083353 -48.566048) (xy 306.107025 -48.616545)
			(xy 306.123093 -48.669952) (xy 306.131213 -48.725128) (xy 306.131722 -48.753014) (xy 306.131213 -48.7809)
			(xy 306.123093 -48.836076) (xy 306.120649 -48.8442) (xy 306.387244 -48.8442) (xy 306.391315 -48.788578)
			(xy 306.403441 -48.734141) (xy 306.423364 -48.68205) (xy 306.45066 -48.633415) (xy 306.484746 -48.589272)
			(xy 306.524895 -48.550563) (xy 306.570253 -48.518112) (xy 306.619853 -48.492611) (xy 306.672637 -48.474604)
			(xy 306.72748 -48.464474) (xy 306.783214 -48.462437) (xy 306.838651 -48.468537) (xy 306.892608 -48.482643)
			(xy 306.943937 -48.504455) (xy 306.991543 -48.533509) (xy 307.034411 -48.569184) (xy 307.071628 -48.610721)
			(xy 307.102401 -48.657234) (xy 307.126073 -48.707731) (xy 307.142141 -48.761138) (xy 307.150261 -48.816314)
			(xy 307.15077 -48.8442) (xy 307.150261 -48.872086) (xy 307.147263 -48.89246) (xy 307.413912 -48.89246)
			(xy 307.417983 -48.836838) (xy 307.430109 -48.782401) (xy 307.450032 -48.73031) (xy 307.477328 -48.681675)
			(xy 307.511414 -48.637532) (xy 307.551563 -48.598823) (xy 307.596921 -48.566372) (xy 307.646521 -48.540871)
			(xy 307.699305 -48.522864) (xy 307.754148 -48.512734) (xy 307.809882 -48.510697) (xy 307.865319 -48.516797)
			(xy 307.919276 -48.530903) (xy 307.970605 -48.552715) (xy 308.018211 -48.581769) (xy 308.061079 -48.617444)
			(xy 308.098296 -48.658981) (xy 308.129069 -48.705494) (xy 308.152741 -48.755991) (xy 308.168809 -48.809398)
			(xy 308.176929 -48.864574) (xy 308.177438 -48.89246) (xy 308.176929 -48.920346) (xy 308.174491 -48.93691)
			(xy 311.13298 -48.93691) (xy 311.137051 -48.881288) (xy 311.149177 -48.826851) (xy 311.1691 -48.77476)
			(xy 311.196396 -48.726125) (xy 311.230482 -48.681982) (xy 311.270631 -48.643273) (xy 311.315989 -48.610822)
			(xy 311.365589 -48.585321) (xy 311.418373 -48.567314) (xy 311.473216 -48.557184) (xy 311.52895 -48.555147)
			(xy 311.584387 -48.561247) (xy 311.638344 -48.575353) (xy 311.689673 -48.597165) (xy 311.737279 -48.626219)
			(xy 311.780147 -48.661894) (xy 311.817364 -48.703431) (xy 311.848137 -48.749944) (xy 311.871809 -48.800441)
			(xy 311.887877 -48.853848) (xy 311.895997 -48.909024) (xy 311.896506 -48.93691) (xy 311.895997 -48.964796)
			(xy 311.887877 -49.019972) (xy 311.871809 -49.073379) (xy 311.848137 -49.123876) (xy 311.817364 -49.170389)
			(xy 311.780147 -49.211926) (xy 311.737279 -49.247601) (xy 311.689673 -49.276655) (xy 311.638344 -49.298467)
			(xy 311.584387 -49.312573) (xy 311.52895 -49.318673) (xy 311.473216 -49.316636) (xy 311.418373 -49.306506)
			(xy 311.365589 -49.288499) (xy 311.315989 -49.262998) (xy 311.270631 -49.230547) (xy 311.230482 -49.191838)
			(xy 311.196396 -49.147695) (xy 311.1691 -49.09906) (xy 311.149177 -49.046969) (xy 311.137051 -48.992532)
			(xy 311.13298 -48.93691) (xy 308.174491 -48.93691) (xy 308.168809 -48.975522) (xy 308.152741 -49.028929)
			(xy 308.129069 -49.079426) (xy 308.098296 -49.125939) (xy 308.061079 -49.167476) (xy 308.018211 -49.203151)
			(xy 307.970605 -49.232205) (xy 307.919276 -49.254017) (xy 307.865319 -49.268123) (xy 307.809882 -49.274223)
			(xy 307.754148 -49.272186) (xy 307.699305 -49.262056) (xy 307.646521 -49.244049) (xy 307.596921 -49.218548)
			(xy 307.551563 -49.186097) (xy 307.511414 -49.147388) (xy 307.477328 -49.103245) (xy 307.450032 -49.05461)
			(xy 307.430109 -49.002519) (xy 307.417983 -48.948082) (xy 307.413912 -48.89246) (xy 307.147263 -48.89246)
			(xy 307.142141 -48.927262) (xy 307.126073 -48.980669) (xy 307.102401 -49.031166) (xy 307.071628 -49.077679)
			(xy 307.034411 -49.119216) (xy 306.991543 -49.154891) (xy 306.943937 -49.183945) (xy 306.892608 -49.205757)
			(xy 306.838651 -49.219863) (xy 306.783214 -49.225963) (xy 306.72748 -49.223926) (xy 306.672637 -49.213796)
			(xy 306.619853 -49.195789) (xy 306.570253 -49.170288) (xy 306.524895 -49.137837) (xy 306.484746 -49.099128)
			(xy 306.45066 -49.054985) (xy 306.423364 -49.00635) (xy 306.403441 -48.954259) (xy 306.391315 -48.899822)
			(xy 306.387244 -48.8442) (xy 306.120649 -48.8442) (xy 306.107025 -48.889483) (xy 306.083353 -48.93998)
			(xy 306.05258 -48.986493) (xy 306.015363 -49.02803) (xy 305.972495 -49.063705) (xy 305.924889 -49.092759)
			(xy 305.87356 -49.114571) (xy 305.819603 -49.128677) (xy 305.764166 -49.134777) (xy 305.708432 -49.13274)
			(xy 305.653589 -49.12261) (xy 305.600805 -49.104603) (xy 305.551205 -49.079102) (xy 305.505847 -49.046651)
			(xy 305.465698 -49.007942) (xy 305.431612 -48.963799) (xy 305.404316 -48.915164) (xy 305.384393 -48.863073)
			(xy 305.372267 -48.808636) (xy 305.368196 -48.753014) (xy 298.519004 -48.753014) (xy 298.480226 -48.93818)
			(xy 298.47921 -48.948086) (xy 298.472572 -49.601953) (xy 316.312759 -49.601953) (xy 316.312759 -49.547447)
			(xy 316.320516 -49.493497) (xy 316.335872 -49.441199) (xy 316.358515 -49.391619) (xy 316.387983 -49.345766)
			(xy 316.423677 -49.304574) (xy 316.464869 -49.268881) (xy 316.510723 -49.239413) (xy 316.560303 -49.216771)
			(xy 316.6126 -49.201415) (xy 316.666551 -49.193659) (xy 316.693804 -49.193196) (xy 316.721174 -49.193661)
			(xy 316.775353 -49.201479) (xy 316.827856 -49.216968) (xy 316.877603 -49.23981) (xy 316.92357 -49.269535)
			(xy 316.944502 -49.287176) (xy 316.944756 -49.28743) (xy 316.951849 -49.293008) (xy 316.968761 -49.299259)
			(xy 316.977776 -49.299622) (xy 317.044832 -49.299622) (xy 317.05385 -49.299276) (xy 317.070767 -49.29302)
			(xy 317.077852 -49.28743) (xy 317.077852 -49.287176) (xy 317.078106 -49.287176) (xy 317.099039 -49.269535)
			(xy 317.145007 -49.239811) (xy 317.194753 -49.216965) (xy 317.247255 -49.201469) (xy 317.301433 -49.19364)
			(xy 317.356175 -49.19364) (xy 317.410353 -49.201469) (xy 317.462855 -49.216965) (xy 317.512601 -49.239811)
			(xy 317.558569 -49.269535) (xy 317.579502 -49.287176) (xy 317.579756 -49.28743) (xy 317.586849 -49.293008)
			(xy 317.603761 -49.299259) (xy 317.612776 -49.299622) (xy 317.679832 -49.299622) (xy 317.68885 -49.299276)
			(xy 317.705767 -49.29302) (xy 317.712852 -49.28743) (xy 317.712852 -49.287176) (xy 317.713106 -49.287176)
			(xy 317.734039 -49.269535) (xy 317.780007 -49.239811) (xy 317.829753 -49.216965) (xy 317.882255 -49.201469)
			(xy 317.936433 -49.19364) (xy 317.991175 -49.19364) (xy 318.045353 -49.201469) (xy 318.097855 -49.216965)
			(xy 318.147601 -49.239811) (xy 318.193569 -49.269535) (xy 318.214502 -49.287176) (xy 318.214756 -49.28743)
			(xy 318.221849 -49.293008) (xy 318.238761 -49.299259) (xy 318.247776 -49.299622) (xy 318.314832 -49.299622)
			(xy 318.32385 -49.299276) (xy 318.340767 -49.29302) (xy 318.347852 -49.28743) (xy 318.347852 -49.287176)
			(xy 318.348106 -49.287176) (xy 318.369022 -49.269517) (xy 318.415 -49.239809) (xy 318.464751 -49.216977)
			(xy 318.517255 -49.201491) (xy 318.571434 -49.193667) (xy 318.598804 -49.193196) (xy 318.626055 -49.193674)
			(xy 318.680003 -49.201431) (xy 318.732298 -49.216787) (xy 318.781875 -49.239428) (xy 318.827726 -49.268895)
			(xy 318.868916 -49.304587) (xy 318.904607 -49.345778) (xy 318.934074 -49.391628) (xy 318.956715 -49.441206)
			(xy 318.97207 -49.493501) (xy 318.979826 -49.547449) (xy 318.979826 -49.601951) (xy 318.97207 -49.655899)
			(xy 318.956715 -49.708194) (xy 318.934074 -49.757772) (xy 318.904607 -49.803622) (xy 318.868916 -49.844813)
			(xy 318.827726 -49.880505) (xy 318.781875 -49.909972) (xy 318.732298 -49.932613) (xy 318.680003 -49.947969)
			(xy 318.626055 -49.955726) (xy 318.598804 -49.956212) (xy 318.571434 -49.955741) (xy 318.517255 -49.947924)
			(xy 318.464752 -49.932436) (xy 318.415005 -49.909595) (xy 318.369038 -49.879872) (xy 318.348106 -49.862232)
			(xy 318.347852 -49.861978) (xy 318.340757 -49.856405) (xy 318.323846 -49.850151) (xy 318.314832 -49.849786)
			(xy 318.247776 -49.849786) (xy 318.238758 -49.850135) (xy 318.221842 -49.856389) (xy 318.214756 -49.861978)
			(xy 318.214502 -49.862232) (xy 318.193569 -49.879873) (xy 318.147601 -49.909597) (xy 318.097855 -49.932443)
			(xy 318.045353 -49.947939) (xy 317.991175 -49.955768) (xy 317.936433 -49.955768) (xy 317.882255 -49.947939)
			(xy 317.829753 -49.932443) (xy 317.780007 -49.909597) (xy 317.734039 -49.879873) (xy 317.713106 -49.862232)
			(xy 317.712852 -49.861978) (xy 317.705757 -49.856405) (xy 317.688846 -49.850151) (xy 317.679832 -49.849786)
			(xy 317.612776 -49.849786) (xy 317.603758 -49.850135) (xy 317.586842 -49.856389) (xy 317.579756 -49.861978)
			(xy 317.579756 -49.862232) (xy 317.579502 -49.862232) (xy 317.558569 -49.879873) (xy 317.512601 -49.909597)
			(xy 317.462855 -49.932443) (xy 317.410353 -49.947939) (xy 317.356175 -49.955768) (xy 317.301433 -49.955768)
			(xy 317.247255 -49.947939) (xy 317.194753 -49.932443) (xy 317.145007 -49.909597) (xy 317.099039 -49.879873)
			(xy 317.078106 -49.862232) (xy 317.077852 -49.861978) (xy 317.070757 -49.856405) (xy 317.053846 -49.850151)
			(xy 317.044832 -49.849786) (xy 316.977776 -49.849786) (xy 316.968758 -49.850135) (xy 316.951842 -49.856389)
			(xy 316.944756 -49.861978) (xy 316.944756 -49.862232) (xy 316.944502 -49.862232) (xy 316.923584 -49.879889)
			(xy 316.877607 -49.909597) (xy 316.827856 -49.932429) (xy 316.775352 -49.947916) (xy 316.721174 -49.95574)
			(xy 316.693804 -49.956212) (xy 316.666551 -49.955741) (xy 316.6126 -49.947985) (xy 316.560303 -49.932629)
			(xy 316.510723 -49.909987) (xy 316.464869 -49.880519) (xy 316.423677 -49.844826) (xy 316.387983 -49.803634)
			(xy 316.358515 -49.757781) (xy 316.335872 -49.708201) (xy 316.320516 -49.655903) (xy 316.312759 -49.601953)
			(xy 298.472572 -49.601953) (xy 298.463836 -50.462434) (xy 307.026054 -50.462434) (xy 307.030125 -50.406812)
			(xy 307.042251 -50.352375) (xy 307.062174 -50.300284) (xy 307.08947 -50.251649) (xy 307.123556 -50.207506)
			(xy 307.163705 -50.168797) (xy 307.209063 -50.136346) (xy 307.258663 -50.110845) (xy 307.311447 -50.092838)
			(xy 307.36629 -50.082708) (xy 307.422024 -50.080671) (xy 307.477461 -50.086771) (xy 307.531418 -50.100877)
			(xy 307.582747 -50.122689) (xy 307.630353 -50.151743) (xy 307.673221 -50.187418) (xy 307.710438 -50.228955)
			(xy 307.741211 -50.275468) (xy 307.764883 -50.325965) (xy 307.780951 -50.379372) (xy 307.789071 -50.434548)
			(xy 307.78958 -50.462434) (xy 307.789071 -50.49032) (xy 307.780951 -50.545496) (xy 307.764883 -50.598903)
			(xy 307.741211 -50.6494) (xy 307.710438 -50.695913) (xy 307.673221 -50.73745) (xy 307.630353 -50.773125)
			(xy 307.582747 -50.802179) (xy 307.531418 -50.823991) (xy 307.477461 -50.838097) (xy 307.422024 -50.844197)
			(xy 307.36629 -50.84216) (xy 307.311447 -50.83203) (xy 307.258663 -50.814023) (xy 307.209063 -50.788522)
			(xy 307.163705 -50.756071) (xy 307.123556 -50.717362) (xy 307.08947 -50.673219) (xy 307.062174 -50.624584)
			(xy 307.042251 -50.572493) (xy 307.030125 -50.518056) (xy 307.026054 -50.462434) (xy 298.463836 -50.462434)
			(xy 298.458181 -51.019456) (xy 308.949342 -51.019456) (xy 308.953413 -50.963834) (xy 308.965539 -50.909397)
			(xy 308.985462 -50.857306) (xy 309.012758 -50.808671) (xy 309.046844 -50.764528) (xy 309.086993 -50.725819)
			(xy 309.132351 -50.693368) (xy 309.181951 -50.667867) (xy 309.234735 -50.64986) (xy 309.289578 -50.63973)
			(xy 309.345312 -50.637693) (xy 309.400749 -50.643793) (xy 309.454706 -50.657899) (xy 309.506035 -50.679711)
			(xy 309.553641 -50.708765) (xy 309.596509 -50.74444) (xy 309.633726 -50.785977) (xy 309.664499 -50.83249)
			(xy 309.688171 -50.882987) (xy 309.704239 -50.936394) (xy 309.712359 -50.99157) (xy 309.712868 -51.019456)
			(xy 309.712359 -51.047342) (xy 309.704239 -51.102518) (xy 309.688171 -51.155925) (xy 309.664499 -51.206422)
			(xy 309.639643 -51.243992) (xy 317.332868 -51.243992) (xy 317.333313 -51.216621) (xy 317.341133 -51.16244)
			(xy 317.356626 -51.109936) (xy 317.379473 -51.06019) (xy 317.409204 -51.014224) (xy 317.426848 -50.993294)
			(xy 317.427102 -50.99304) (xy 317.432678 -50.985946) (xy 317.438931 -50.969035) (xy 317.439294 -50.96002)
			(xy 317.439294 -50.892964) (xy 317.438955 -50.883945) (xy 317.432695 -50.867028) (xy 317.427102 -50.859944)
			(xy 317.426848 -50.859944) (xy 317.426848 -50.85969) (xy 317.409198 -50.838766) (xy 317.379486 -50.792792)
			(xy 317.356652 -50.743042) (xy 317.341163 -50.69054) (xy 317.333339 -50.636362) (xy 317.332868 -50.608992)
			(xy 317.33337 -50.581742) (xy 317.341127 -50.527796) (xy 317.356482 -50.475503) (xy 317.379123 -50.425927)
			(xy 317.408587 -50.380078) (xy 317.444277 -50.338888) (xy 317.485465 -50.303197) (xy 317.531313 -50.27373)
			(xy 317.580888 -50.251088) (xy 317.63318 -50.235731) (xy 317.687126 -50.227971) (xy 317.714376 -50.227484)
			(xy 317.743294 -50.227988) (xy 317.800467 -50.236715) (xy 317.855668 -50.253974) (xy 317.90763 -50.279368)
			(xy 317.955163 -50.312316) (xy 317.997178 -50.352062) (xy 318.015366 -50.37455) (xy 318.022989 -50.38334)
			(xy 318.043878 -50.393531) (xy 318.055498 -50.394108) (xy 318.135254 -50.394108) (xy 318.146888 -50.393583)
			(xy 318.167797 -50.383384) (xy 318.175386 -50.37455) (xy 318.193572 -50.352063) (xy 318.235595 -50.31233)
			(xy 318.283131 -50.279393) (xy 318.335093 -50.254006) (xy 318.39029 -50.23675) (xy 318.44746 -50.22802)
			(xy 318.476376 -50.227484) (xy 318.503628 -50.227978) (xy 318.557577 -50.235731) (xy 318.609874 -50.251084)
			(xy 318.659454 -50.273723) (xy 318.705306 -50.303188) (xy 318.746499 -50.338878) (xy 318.782193 -50.380068)
			(xy 318.811662 -50.425918) (xy 318.834305 -50.475496) (xy 318.849662 -50.527791) (xy 318.85742 -50.58174)
			(xy 318.857884 -50.608992) (xy 318.857416 -50.635306) (xy 318.850182 -50.687435) (xy 318.835864 -50.738078)
			(xy 318.814731 -50.786277) (xy 318.787185 -50.83112) (xy 318.753746 -50.87176) (xy 318.734694 -50.889916)
			(xy 318.727283 -50.897429) (xy 318.718764 -50.916716) (xy 318.718184 -50.927254) (xy 318.718184 -51.00193)
			(xy 318.718742 -51.012476) (xy 318.727257 -51.031772) (xy 318.734694 -51.039268) (xy 318.753774 -51.057399)
			(xy 318.78723 -51.098034) (xy 318.814785 -51.142879) (xy 318.83592 -51.191085) (xy 318.850231 -51.241737)
			(xy 318.857449 -51.293874) (xy 318.857884 -51.320192) (xy 318.857437 -51.347446) (xy 318.849681 -51.401399)
			(xy 318.834324 -51.453698) (xy 318.811681 -51.50328) (xy 318.782212 -51.549134) (xy 318.746516 -51.590328)
			(xy 318.705321 -51.626021) (xy 318.659466 -51.655489) (xy 318.609883 -51.67813) (xy 318.557583 -51.693484)
			(xy 318.50363 -51.701238) (xy 318.476376 -51.7017) (xy 318.44871 -51.701207) (xy 318.39396 -51.693204)
			(xy 318.340938 -51.677384) (xy 318.290754 -51.654078) (xy 318.244459 -51.623774) (xy 318.203021 -51.587106)
			(xy 318.167309 -51.544842) (xy 318.152272 -51.521614) (xy 318.145658 -51.511919) (xy 318.12578 -51.499485)
			(xy 318.114172 -51.497738) (xy 318.034162 -51.489864) (xy 318.022523 -51.489212) (xy 318.000684 -51.497306)
			(xy 317.992252 -51.505358) (xy 317.991998 -51.505612) (xy 317.973903 -51.524179) (xy 317.933574 -51.556758)
			(xy 317.889202 -51.583573) (xy 317.841607 -51.604128) (xy 317.791665 -51.618045) (xy 317.740298 -51.625066)
			(xy 317.714376 -51.6255) (xy 317.687124 -51.625044) (xy 317.633175 -51.617285) (xy 317.580879 -51.601926)
			(xy 317.531301 -51.579281) (xy 317.48545 -51.549812) (xy 317.44426 -51.514117) (xy 317.408569 -51.472924)
			(xy 317.379103 -51.427071) (xy 317.356463 -51.377491) (xy 317.341109 -51.325194) (xy 317.333353 -51.271244)
			(xy 317.332868 -51.243992) (xy 309.639643 -51.243992) (xy 309.633726 -51.252935) (xy 309.596509 -51.294472)
			(xy 309.553641 -51.330147) (xy 309.506035 -51.359201) (xy 309.454706 -51.381013) (xy 309.400749 -51.395119)
			(xy 309.345312 -51.401219) (xy 309.289578 -51.399182) (xy 309.234735 -51.389052) (xy 309.181951 -51.371045)
			(xy 309.132351 -51.345544) (xy 309.086993 -51.313093) (xy 309.046844 -51.274384) (xy 309.012758 -51.230241)
			(xy 308.985462 -51.181606) (xy 308.965539 -51.129515) (xy 308.953413 -51.075078) (xy 308.949342 -51.019456)
			(xy 298.458181 -51.019456) (xy 298.447866 -52.035456) (xy 311.141108 -52.035456) (xy 311.145179 -51.979834)
			(xy 311.157305 -51.925397) (xy 311.177228 -51.873306) (xy 311.204524 -51.824671) (xy 311.23861 -51.780528)
			(xy 311.278759 -51.741819) (xy 311.324117 -51.709368) (xy 311.373717 -51.683867) (xy 311.426501 -51.66586)
			(xy 311.481344 -51.65573) (xy 311.537078 -51.653693) (xy 311.592515 -51.659793) (xy 311.646472 -51.673899)
			(xy 311.697801 -51.695711) (xy 311.745407 -51.724765) (xy 311.788275 -51.76044) (xy 311.825492 -51.801977)
			(xy 311.856265 -51.84849) (xy 311.879937 -51.898987) (xy 311.896005 -51.952394) (xy 311.904125 -52.00757)
			(xy 311.904634 -52.035456) (xy 311.904125 -52.063342) (xy 311.896005 -52.118518) (xy 311.879937 -52.171925)
			(xy 311.856265 -52.222422) (xy 311.825492 -52.268935) (xy 311.788275 -52.310472) (xy 311.745407 -52.346147)
			(xy 311.697801 -52.375201) (xy 311.646472 -52.397013) (xy 311.592515 -52.411119) (xy 311.537078 -52.417219)
			(xy 311.481344 -52.415182) (xy 311.426501 -52.405052) (xy 311.373717 -52.387045) (xy 311.324117 -52.361544)
			(xy 311.278759 -52.329093) (xy 311.23861 -52.290384) (xy 311.204524 -52.246241) (xy 311.177228 -52.197606)
			(xy 311.157305 -52.145515) (xy 311.145179 -52.091078) (xy 311.141108 -52.035456) (xy 298.447866 -52.035456)
			(xy 298.442126 -52.60086) (xy 298.442414 -52.609442) (xy 298.44799 -52.625671) (xy 298.453048 -52.63261)
			(xy 298.455334 -52.635404) (xy 298.473622 -52.658772) (xy 298.477261 -52.66288) (xy 298.485977 -52.669543)
			(xy 298.490894 -52.67198) (xy 298.495537 -52.67426) (xy 298.503853 -52.68041) (xy 298.507404 -52.684172)
			(xy 298.514756 -52.693126) (xy 298.521245 -52.715343) (xy 298.51985 -52.726844) (xy 298.51985 -52.727352)
			(xy 298.519088 -52.7304) (xy 298.519088 -52.730654) (xy 298.518326 -52.733956) (xy 298.486576 -52.822856)
			(xy 298.486576 -52.831238) (xy 298.485639 -52.861106) (xy 298.475655 -52.92002) (xy 298.456667 -52.976676)
			(xy 298.443396 -53.00345) (xy 298.441618 -53.006752) (xy 298.440112 -53.0106) (xy 298.438203 -53.01864)
			(xy 298.437808 -53.022754) (xy 298.435014 -53.274468) (xy 298.4373 -53.27904) (xy 298.451889 -53.307158)
			(xy 298.472575 -53.367028) (xy 298.483115 -53.429488) (xy 298.483782 -53.461158) (xy 298.483782 -53.46192)
			(xy 298.483528 -53.467) (xy 298.483528 -53.469032) (xy 298.482777 -53.491187) (xy 298.476788 -53.535112)
			(xy 298.47159 -53.556662) (xy 298.465431 -53.57944) (xy 298.448231 -53.62338) (xy 298.4373 -53.644292)
			(xy 298.434252 -53.650134) (xy 298.431204 -53.661564) (xy 298.430188 -53.754274) (xy 298.430188 -53.756052)
			(xy 298.428918 -53.866542) (xy 298.428929 -53.870339) (xy 298.429954 -53.877864) (xy 298.43095 -53.881528)
			(xy 298.432728 -53.887116) (xy 298.436538 -53.893466) (xy 298.449974 -53.916517) (xy 298.471164 -53.965483)
			(xy 298.485507 -54.016873) (xy 298.492738 -54.069735) (xy 298.49318 -54.096412) (xy 298.49318 -54.09692)
			(xy 298.492707 -54.123936) (xy 298.485249 -54.177452) (xy 298.470519 -54.229438) (xy 298.448796 -54.278911)
			(xy 298.435014 -54.302152) (xy 298.43222 -54.306724) (xy 298.426378 -54.325266) (xy 298.425413 -54.328807)
			(xy 298.424393 -54.336074) (xy 298.424346 -54.339744) (xy 298.422314 -54.523132) (xy 298.426632 -54.530498)
			(xy 298.440172 -54.553234) (xy 298.461538 -54.601645) (xy 298.476012 -54.652544) (xy 298.483319 -54.704954)
			(xy 298.483782 -54.731412) (xy 298.482766 -54.761384) (xy 298.480988 -54.77637) (xy 298.478991 -54.791102)
			(xy 300.376336 -54.791102) (xy 300.376794 -54.763731) (xy 300.384613 -54.709552) (xy 300.400103 -54.657048)
			(xy 300.422947 -54.607301) (xy 300.452674 -54.561335) (xy 300.470316 -54.540404) (xy 300.47057 -54.54015)
			(xy 300.47615 -54.533059) (xy 300.482399 -54.516145) (xy 300.482762 -54.50713) (xy 300.482762 -54.440074)
			(xy 300.482426 -54.431055) (xy 300.476165 -54.414138) (xy 300.47057 -54.407054) (xy 300.470316 -54.407054)
			(xy 300.470316 -54.4068) (xy 300.452678 -54.385865) (xy 300.422954 -54.339898) (xy 300.400109 -54.290152)
			(xy 300.384613 -54.23765) (xy 300.376784 -54.183472) (xy 300.376784 -54.128731) (xy 300.384612 -54.074553)
			(xy 300.400108 -54.022051) (xy 300.422952 -53.972305) (xy 300.452676 -53.926337) (xy 300.470316 -53.905404)
			(xy 300.47057 -53.90515) (xy 300.47615 -53.898059) (xy 300.482399 -53.881145) (xy 300.482762 -53.87213)
			(xy 300.482762 -53.805074) (xy 300.482426 -53.796055) (xy 300.476165 -53.779138) (xy 300.47057 -53.772054)
			(xy 300.470316 -53.772054) (xy 300.470316 -53.7718) (xy 300.452678 -53.750865) (xy 300.422954 -53.704898)
			(xy 300.400109 -53.655152) (xy 300.384613 -53.60265) (xy 300.376784 -53.548472) (xy 300.376784 -53.493731)
			(xy 300.384612 -53.439553) (xy 300.400108 -53.387051) (xy 300.422952 -53.337305) (xy 300.452676 -53.291337)
			(xy 300.470316 -53.270404) (xy 300.47057 -53.27015) (xy 300.47615 -53.263059) (xy 300.482399 -53.246145)
			(xy 300.482762 -53.23713) (xy 300.482762 -53.170074) (xy 300.482426 -53.161055) (xy 300.476165 -53.144138)
			(xy 300.47057 -53.137054) (xy 300.470316 -53.137054) (xy 300.470316 -53.1368) (xy 300.452666 -53.115877)
			(xy 300.422955 -53.069902) (xy 300.400121 -53.020152) (xy 300.384633 -52.967649) (xy 300.376808 -52.913472)
			(xy 300.376336 -52.886102) (xy 300.376822 -52.858851) (xy 300.384578 -52.804903) (xy 300.399933 -52.752608)
			(xy 300.422575 -52.703031) (xy 300.452041 -52.657181) (xy 300.487732 -52.61599) (xy 300.528923 -52.580299)
			(xy 300.574773 -52.550833) (xy 300.62435 -52.528191) (xy 300.676645 -52.512836) (xy 300.730593 -52.50508)
			(xy 300.785095 -52.50508) (xy 300.839043 -52.512836) (xy 300.891338 -52.528191) (xy 300.930442 -52.54605)
			(xy 305.879496 -52.54605) (xy 305.879496 -52.49155) (xy 305.887252 -52.437605) (xy 305.902607 -52.385313)
			(xy 305.925247 -52.335738) (xy 305.954712 -52.28989) (xy 305.990401 -52.248701) (xy 306.03159 -52.213012)
			(xy 306.077438 -52.183547) (xy 306.127013 -52.160907) (xy 306.179305 -52.145552) (xy 306.23325 -52.137796)
			(xy 306.2605 -52.13731) (xy 306.28787 -52.137774) (xy 306.34205 -52.145592) (xy 306.394553 -52.161081)
			(xy 306.4443 -52.183924) (xy 306.490266 -52.213649) (xy 306.511198 -52.23129) (xy 306.511452 -52.231544)
			(xy 306.518544 -52.237122) (xy 306.535457 -52.243373) (xy 306.544472 -52.243736) (xy 306.611528 -52.243736)
			(xy 306.620545 -52.243385) (xy 306.637462 -52.237132) (xy 306.644548 -52.231544) (xy 306.644548 -52.23129)
			(xy 306.644802 -52.23129) (xy 306.665735 -52.213649) (xy 306.711703 -52.183925) (xy 306.761449 -52.161079)
			(xy 306.813951 -52.145583) (xy 306.868129 -52.137754) (xy 306.922871 -52.137754) (xy 306.977049 -52.145583)
			(xy 307.029551 -52.161079) (xy 307.079297 -52.183925) (xy 307.125265 -52.213649) (xy 307.146198 -52.23129)
			(xy 307.146452 -52.231544) (xy 307.153544 -52.237122) (xy 307.170457 -52.243373) (xy 307.179472 -52.243736)
			(xy 307.246528 -52.243736) (xy 307.255545 -52.243385) (xy 307.272462 -52.237132) (xy 307.279548 -52.231544)
			(xy 307.279548 -52.23129) (xy 307.279802 -52.23129) (xy 307.300721 -52.213635) (xy 307.346698 -52.183926)
			(xy 307.396448 -52.161093) (xy 307.448952 -52.145606) (xy 307.50313 -52.137782) (xy 307.5305 -52.13731)
			(xy 307.557753 -52.13776) (xy 307.611703 -52.145517) (xy 307.664 -52.160873) (xy 307.71358 -52.183515)
			(xy 307.759432 -52.212982) (xy 307.800624 -52.248676) (xy 307.836318 -52.289868) (xy 307.865785 -52.33572)
			(xy 307.888427 -52.3853) (xy 307.903783 -52.437597) (xy 307.91154 -52.491547) (xy 307.91154 -52.546053)
			(xy 307.905595 -52.587398) (xy 308.955184 -52.587398) (xy 308.959255 -52.531776) (xy 308.971381 -52.477339)
			(xy 308.991304 -52.425248) (xy 309.0186 -52.376613) (xy 309.052686 -52.33247) (xy 309.092835 -52.293761)
			(xy 309.138193 -52.26131) (xy 309.187793 -52.235809) (xy 309.240577 -52.217802) (xy 309.29542 -52.207672)
			(xy 309.351154 -52.205635) (xy 309.406591 -52.211735) (xy 309.460548 -52.225841) (xy 309.511877 -52.247653)
			(xy 309.559483 -52.276707) (xy 309.602351 -52.312382) (xy 309.639568 -52.353919) (xy 309.670341 -52.400432)
			(xy 309.694013 -52.450929) (xy 309.710081 -52.504336) (xy 309.717677 -52.555952) (xy 316.783679 -52.555952)
			(xy 316.783679 -52.501448) (xy 316.791436 -52.447499) (xy 316.806792 -52.395203) (xy 316.829435 -52.345624)
			(xy 316.858903 -52.299773) (xy 316.894597 -52.258582) (xy 316.935789 -52.222891) (xy 316.981642 -52.193425)
			(xy 317.031221 -52.170785) (xy 317.083518 -52.155432) (xy 317.137468 -52.147678) (xy 317.16472 -52.147216)
			(xy 317.192091 -52.147666) (xy 317.246271 -52.155487) (xy 317.298774 -52.17098) (xy 317.348521 -52.193825)
			(xy 317.394487 -52.223553) (xy 317.415418 -52.241196) (xy 317.415672 -52.24145) (xy 317.422758 -52.247037)
			(xy 317.439675 -52.253282) (xy 317.448692 -52.253642) (xy 317.515748 -52.253642) (xy 317.524764 -52.253273)
			(xy 317.541682 -52.247035) (xy 317.548768 -52.24145) (xy 317.548768 -52.241196) (xy 317.549022 -52.241196)
			(xy 317.569972 -52.223579) (xy 317.61594 -52.193864) (xy 317.665683 -52.171024) (xy 317.71818 -52.155528)
			(xy 317.772352 -52.147693) (xy 317.79972 -52.147216) (xy 317.826972 -52.147655) (xy 317.880921 -52.155415)
			(xy 317.933217 -52.170772) (xy 317.982794 -52.193416) (xy 318.028645 -52.222885) (xy 318.069836 -52.258579)
			(xy 318.105527 -52.299771) (xy 318.134994 -52.345623) (xy 318.157635 -52.395202) (xy 318.17299 -52.447499)
			(xy 318.180746 -52.501448) (xy 318.180746 -52.555952) (xy 318.17299 -52.609901) (xy 318.157635 -52.662198)
			(xy 318.134994 -52.711777) (xy 318.105527 -52.757629) (xy 318.069836 -52.798821) (xy 318.028645 -52.834515)
			(xy 317.982794 -52.863984) (xy 317.933217 -52.886628) (xy 317.880921 -52.901985) (xy 317.826972 -52.909745)
			(xy 317.79972 -52.910232) (xy 317.772349 -52.909771) (xy 317.718169 -52.901954) (xy 317.665666 -52.886465)
			(xy 317.615919 -52.863622) (xy 317.569953 -52.833895) (xy 317.549022 -52.816252) (xy 317.548768 -52.815998)
			(xy 317.541666 -52.810434) (xy 317.524761 -52.804174) (xy 317.515748 -52.803806) (xy 317.448692 -52.803806)
			(xy 317.439675 -52.804158) (xy 317.422758 -52.810409) (xy 317.415672 -52.815998) (xy 317.415672 -52.816252)
			(xy 317.415418 -52.816252) (xy 317.394484 -52.833889) (xy 317.348512 -52.863603) (xy 317.298765 -52.88644)
			(xy 317.246265 -52.901931) (xy 317.192089 -52.909759) (xy 317.16472 -52.910232) (xy 317.137468 -52.909722)
			(xy 317.083518 -52.901968) (xy 317.031221 -52.886615) (xy 316.981642 -52.863975) (xy 316.935789 -52.834509)
			(xy 316.894597 -52.798818) (xy 316.858903 -52.757627) (xy 316.829435 -52.711776) (xy 316.806792 -52.662197)
			(xy 316.791436 -52.609901) (xy 316.783679 -52.555952) (xy 309.717677 -52.555952) (xy 309.718201 -52.559512)
			(xy 309.71871 -52.587398) (xy 309.718201 -52.615284) (xy 309.710081 -52.67046) (xy 309.694013 -52.723867)
			(xy 309.670341 -52.774364) (xy 309.639568 -52.820877) (xy 309.602351 -52.862414) (xy 309.559483 -52.898089)
			(xy 309.511877 -52.927143) (xy 309.460548 -52.948955) (xy 309.406591 -52.963061) (xy 309.351154 -52.969161)
			(xy 309.29542 -52.967124) (xy 309.240577 -52.956994) (xy 309.187793 -52.938987) (xy 309.138193 -52.913486)
			(xy 309.092835 -52.881035) (xy 309.052686 -52.842326) (xy 309.0186 -52.798183) (xy 308.991304 -52.749548)
			(xy 308.971381 -52.697457) (xy 308.959255 -52.64302) (xy 308.955184 -52.587398) (xy 307.905595 -52.587398)
			(xy 307.903783 -52.600003) (xy 307.888427 -52.6523) (xy 307.865785 -52.70188) (xy 307.836318 -52.747732)
			(xy 307.800624 -52.788924) (xy 307.759432 -52.824618) (xy 307.71358 -52.854085) (xy 307.664 -52.876727)
			(xy 307.611703 -52.892083) (xy 307.557753 -52.89984) (xy 307.5305 -52.900326) (xy 307.503129 -52.899878)
			(xy 307.448948 -52.892059) (xy 307.396444 -52.876566) (xy 307.346698 -52.85372) (xy 307.300732 -52.82399)
			(xy 307.279802 -52.806346) (xy 307.279548 -52.806092) (xy 307.272453 -52.800518) (xy 307.255543 -52.794264)
			(xy 307.246528 -52.7939) (xy 307.179472 -52.7939) (xy 307.170454 -52.794244) (xy 307.153537 -52.800501)
			(xy 307.146452 -52.806092) (xy 307.146198 -52.806346) (xy 307.125265 -52.823987) (xy 307.079297 -52.853711)
			(xy 307.029551 -52.876557) (xy 306.977049 -52.892053) (xy 306.922871 -52.899882) (xy 306.868129 -52.899882)
			(xy 306.813951 -52.892053) (xy 306.761449 -52.876557) (xy 306.711703 -52.853711) (xy 306.665735 -52.823987)
			(xy 306.644802 -52.806346) (xy 306.644548 -52.806092) (xy 306.637453 -52.800518) (xy 306.620543 -52.794264)
			(xy 306.611528 -52.7939) (xy 306.544472 -52.7939) (xy 306.535454 -52.794244) (xy 306.518537 -52.800501)
			(xy 306.511452 -52.806092) (xy 306.511452 -52.806346) (xy 306.511198 -52.806346) (xy 306.490271 -52.823991)
			(xy 306.444297 -52.853704) (xy 306.394549 -52.87654) (xy 306.342047 -52.892029) (xy 306.28787 -52.899854)
			(xy 306.2605 -52.900326) (xy 306.23325 -52.899804) (xy 306.179305 -52.892048) (xy 306.127013 -52.876693)
			(xy 306.077438 -52.854053) (xy 306.03159 -52.824588) (xy 305.990401 -52.788899) (xy 305.954712 -52.74771)
			(xy 305.925247 -52.701862) (xy 305.902607 -52.652287) (xy 305.887252 -52.599995) (xy 305.879496 -52.54605)
			(xy 300.930442 -52.54605) (xy 300.940915 -52.550833) (xy 300.986765 -52.580299) (xy 301.027956 -52.61599)
			(xy 301.063647 -52.657181) (xy 301.093113 -52.703031) (xy 301.115755 -52.752608) (xy 301.13111 -52.804903)
			(xy 301.138866 -52.858851) (xy 301.139352 -52.886102) (xy 301.138899 -52.913473) (xy 301.13108 -52.967653)
			(xy 301.115588 -53.020157) (xy 301.092743 -53.069903) (xy 301.063015 -53.115869) (xy 301.045372 -53.1368)
			(xy 301.045118 -53.137054) (xy 301.039547 -53.144151) (xy 301.033291 -53.16106) (xy 301.032926 -53.170074)
			(xy 301.032926 -53.23713) (xy 301.033263 -53.246149) (xy 301.039524 -53.263066) (xy 301.045118 -53.27015)
			(xy 301.045372 -53.27015) (xy 301.045372 -53.270404) (xy 301.063015 -53.291335) (xy 301.092739 -53.337303)
			(xy 301.115585 -53.38705) (xy 301.131081 -53.439552) (xy 301.138909 -53.493731) (xy 301.138909 -53.548472)
			(xy 301.13108 -53.602651) (xy 301.115584 -53.655153) (xy 301.092738 -53.704899) (xy 301.063013 -53.750867)
			(xy 301.046442 -53.77053) (xy 301.410624 -53.77053) (xy 301.411155 -53.741613) (xy 301.41988 -53.684442)
			(xy 301.437135 -53.629243) (xy 301.462524 -53.577282) (xy 301.495466 -53.529747) (xy 301.535205 -53.48773)
			(xy 301.55769 -53.46954) (xy 301.566468 -53.461904) (xy 301.576668 -53.441025) (xy 301.577248 -53.429408)
			(xy 301.577248 -53.349652) (xy 301.57674 -53.338016) (xy 301.566531 -53.317105) (xy 301.55769 -53.30952)
			(xy 301.535214 -53.29132) (xy 301.495479 -53.249302) (xy 301.462539 -53.201769) (xy 301.43715 -53.149809)
			(xy 301.419892 -53.094613) (xy 301.41116 -53.037445) (xy 301.410624 -53.00853) (xy 301.411083 -52.981276)
			(xy 301.418837 -52.927324) (xy 301.434191 -52.875024) (xy 301.456832 -52.825442) (xy 301.4863 -52.779587)
			(xy 301.521994 -52.738393) (xy 301.563188 -52.702699) (xy 301.609043 -52.673231) (xy 301.658626 -52.65059)
			(xy 301.710926 -52.635237) (xy 301.764878 -52.627483) (xy 301.792132 -52.627022) (xy 301.818447 -52.627461)
			(xy 301.870577 -52.634701) (xy 301.921221 -52.649025) (xy 301.96942 -52.670163) (xy 302.014262 -52.697714)
			(xy 302.0549 -52.731158) (xy 302.073056 -52.750212) (xy 302.08059 -52.757598) (xy 302.099861 -52.766131)
			(xy 302.110394 -52.766722) (xy 302.18507 -52.766722) (xy 302.195618 -52.766183) (xy 302.214913 -52.757654)
			(xy 302.222408 -52.750212) (xy 302.240569 -52.731162) (xy 302.281197 -52.697704) (xy 302.326036 -52.670144)
			(xy 302.374236 -52.649004) (xy 302.424883 -52.634686) (xy 302.477016 -52.627461) (xy 302.503332 -52.627022)
			(xy 302.530585 -52.627448) (xy 302.584537 -52.63521) (xy 302.636835 -52.65057) (xy 302.686414 -52.673218)
			(xy 302.732266 -52.70269) (xy 302.773456 -52.738388) (xy 302.809147 -52.779584) (xy 302.838612 -52.825441)
			(xy 302.861251 -52.875024) (xy 302.876603 -52.927324) (xy 302.884356 -52.981277) (xy 302.88484 -53.00853)
			(xy 302.884379 -53.036197) (xy 302.882148 -53.051456) (xy 311.141108 -53.051456) (xy 311.145179 -52.995834)
			(xy 311.157305 -52.941397) (xy 311.177228 -52.889306) (xy 311.204524 -52.840671) (xy 311.23861 -52.796528)
			(xy 311.278759 -52.757819) (xy 311.324117 -52.725368) (xy 311.373717 -52.699867) (xy 311.426501 -52.68186)
			(xy 311.481344 -52.67173) (xy 311.537078 -52.669693) (xy 311.592515 -52.675793) (xy 311.646472 -52.689899)
			(xy 311.697801 -52.711711) (xy 311.745407 -52.740765) (xy 311.788275 -52.77644) (xy 311.825492 -52.817977)
			(xy 311.856265 -52.86449) (xy 311.879937 -52.914987) (xy 311.896005 -52.968394) (xy 311.904125 -53.02357)
			(xy 311.904634 -53.051456) (xy 311.904125 -53.079342) (xy 311.896005 -53.134518) (xy 311.879937 -53.187925)
			(xy 311.856265 -53.238422) (xy 311.825492 -53.284935) (xy 311.788275 -53.326472) (xy 311.745407 -53.362147)
			(xy 311.697801 -53.391201) (xy 311.646472 -53.413013) (xy 311.592515 -53.427119) (xy 311.537078 -53.433219)
			(xy 311.481344 -53.431182) (xy 311.426501 -53.421052) (xy 311.373717 -53.403045) (xy 311.324117 -53.377544)
			(xy 311.278759 -53.345093) (xy 311.23861 -53.306384) (xy 311.204524 -53.262241) (xy 311.177228 -53.213606)
			(xy 311.157305 -53.161515) (xy 311.145179 -53.107078) (xy 311.141108 -53.051456) (xy 302.882148 -53.051456)
			(xy 302.876374 -53.09095) (xy 302.86055 -53.143974) (xy 302.83724 -53.194159) (xy 302.80693 -53.240454)
			(xy 302.770256 -53.28189) (xy 302.727985 -53.317599) (xy 302.704754 -53.332634) (xy 302.695064 -53.339255)
			(xy 302.682626 -53.359128) (xy 302.680878 -53.370734) (xy 302.673004 -53.450744) (xy 302.672366 -53.462382)
			(xy 302.680452 -53.484219) (xy 302.688498 -53.492654) (xy 302.688752 -53.492908) (xy 302.70731 -53.511012)
			(xy 302.739893 -53.551338) (xy 302.76671 -53.595707) (xy 302.787267 -53.643301) (xy 302.801185 -53.693242)
			(xy 302.808206 -53.744608) (xy 302.80864 -53.77053) (xy 302.80815 -53.797781) (xy 302.80039 -53.851726)
			(xy 302.785033 -53.904019) (xy 302.762391 -53.953594) (xy 302.732924 -53.999443) (xy 302.697234 -54.040632)
			(xy 302.656045 -54.076323) (xy 302.610196 -54.10579) (xy 302.560621 -54.128432) (xy 302.508328 -54.14379)
			(xy 302.454383 -54.15155) (xy 302.427132 -54.152038) (xy 302.399762 -54.151568) (xy 302.345582 -54.143754)
			(xy 302.293079 -54.128266) (xy 302.243332 -54.105425) (xy 302.197365 -54.0757) (xy 302.176434 -54.058058)
			(xy 302.17618 -54.057804) (xy 302.169103 -54.052203) (xy 302.152179 -54.045965) (xy 302.14316 -54.045612)
			(xy 302.076104 -54.045612) (xy 302.067087 -54.045968) (xy 302.05017 -54.052216) (xy 302.043084 -54.057804)
			(xy 302.043084 -54.058058) (xy 302.04283 -54.058058) (xy 302.021892 -54.07569) (xy 301.975922 -54.105404)
			(xy 301.926176 -54.128242) (xy 301.873676 -54.143735) (xy 301.819501 -54.151564) (xy 301.792132 -54.152038)
			(xy 301.764881 -54.151515) (xy 301.710934 -54.143763) (xy 301.658639 -54.128413) (xy 301.609061 -54.105776)
			(xy 301.563209 -54.076314) (xy 301.522017 -54.040627) (xy 301.486323 -53.99944) (xy 301.456854 -53.953593)
			(xy 301.434209 -53.904019) (xy 301.41885 -53.851727) (xy 301.411089 -53.797781) (xy 301.410624 -53.77053)
			(xy 301.046442 -53.77053) (xy 301.045372 -53.7718) (xy 301.045118 -53.772054) (xy 301.039547 -53.779151)
			(xy 301.033291 -53.79606) (xy 301.032926 -53.805074) (xy 301.032926 -53.87213) (xy 301.033263 -53.881149)
			(xy 301.039524 -53.898066) (xy 301.045118 -53.90515) (xy 301.045372 -53.90515) (xy 301.045372 -53.905404)
			(xy 301.063015 -53.926335) (xy 301.092739 -53.972303) (xy 301.115585 -54.02205) (xy 301.131081 -54.074552)
			(xy 301.138909 -54.128731) (xy 301.138909 -54.183472) (xy 301.13108 -54.237651) (xy 301.115584 -54.290153)
			(xy 301.101791 -54.320186) (xy 303.330356 -54.320186) (xy 303.3308 -54.292815) (xy 303.338621 -54.238634)
			(xy 303.354115 -54.18613) (xy 303.376962 -54.136384) (xy 303.406692 -54.090418) (xy 303.424336 -54.069488)
			(xy 303.42459 -54.069234) (xy 303.430167 -54.062141) (xy 303.43642 -54.045229) (xy 303.436782 -54.036214)
			(xy 303.436782 -53.969158) (xy 303.436401 -53.960143) (xy 303.43017 -53.943226) (xy 303.42459 -53.936138)
			(xy 303.424336 -53.936138) (xy 303.424336 -53.935884) (xy 303.406728 -53.914926) (xy 303.377011 -53.868961)
			(xy 303.354168 -53.81922) (xy 303.33867 -53.766725) (xy 303.330834 -53.712554) (xy 303.330356 -53.685186)
			(xy 303.330842 -53.657935) (xy 303.338598 -53.603987) (xy 303.353953 -53.551692) (xy 303.376595 -53.502115)
			(xy 303.406061 -53.456265) (xy 303.441752 -53.415074) (xy 303.482943 -53.379383) (xy 303.528793 -53.349917)
			(xy 303.57837 -53.327275) (xy 303.630665 -53.31192) (xy 303.684613 -53.304164) (xy 303.739115 -53.304164)
			(xy 303.793063 -53.31192) (xy 303.845358 -53.327275) (xy 303.894935 -53.349917) (xy 303.940785 -53.379383)
			(xy 303.981976 -53.415074) (xy 304.017667 -53.456265) (xy 304.043557 -53.496551) (xy 316.333364 -53.496551)
			(xy 316.333364 -53.442049) (xy 316.34112 -53.388101) (xy 316.356475 -53.335806) (xy 316.379115 -53.286228)
			(xy 316.40858 -53.240377) (xy 316.444271 -53.199186) (xy 316.48546 -53.163493) (xy 316.531309 -53.134025)
			(xy 316.580885 -53.111382) (xy 316.633179 -53.096025) (xy 316.687127 -53.088265) (xy 316.714378 -53.087778)
			(xy 316.741749 -53.088238) (xy 316.795929 -53.096054) (xy 316.848433 -53.111544) (xy 316.89818 -53.134387)
			(xy 316.944145 -53.164115) (xy 316.965076 -53.181758) (xy 316.96533 -53.182012) (xy 316.972431 -53.187577)
			(xy 316.989337 -53.193836) (xy 316.99835 -53.194204) (xy 317.065406 -53.194204) (xy 317.074423 -53.193849)
			(xy 317.09134 -53.1876) (xy 317.098426 -53.182012) (xy 317.098426 -53.181758) (xy 317.09868 -53.181758)
			(xy 317.119603 -53.164108) (xy 317.165579 -53.134399) (xy 317.215329 -53.111566) (xy 317.267831 -53.096077)
			(xy 317.322008 -53.088251) (xy 317.349378 -53.087778) (xy 317.376631 -53.088268) (xy 317.430582 -53.096022)
			(xy 317.482881 -53.111376) (xy 317.532462 -53.134016) (xy 317.578316 -53.163482) (xy 317.61951 -53.199175)
			(xy 317.655205 -53.240366) (xy 317.684674 -53.286219) (xy 317.707317 -53.335799) (xy 317.722673 -53.388096)
			(xy 317.730431 -53.442047) (xy 317.730431 -53.496553) (xy 317.722673 -53.550504) (xy 317.707317 -53.602801)
			(xy 317.684674 -53.652381) (xy 317.655205 -53.698234) (xy 317.61951 -53.739425) (xy 317.578316 -53.775118)
			(xy 317.532462 -53.804584) (xy 317.482881 -53.827224) (xy 317.430582 -53.842578) (xy 317.376631 -53.850332)
			(xy 317.349378 -53.850794) (xy 317.322007 -53.850342) (xy 317.267827 -53.842521) (xy 317.215324 -53.827029)
			(xy 317.165578 -53.804184) (xy 317.119611 -53.774457) (xy 317.09868 -53.756814) (xy 317.098426 -53.75656)
			(xy 317.09134 -53.750973) (xy 317.074423 -53.744728) (xy 317.065406 -53.744368) (xy 316.99835 -53.744368)
			(xy 316.989336 -53.744756) (xy 316.97242 -53.750983) (xy 316.96533 -53.75656) (xy 316.96533 -53.756814)
			(xy 316.965076 -53.756814) (xy 316.944128 -53.774433) (xy 316.898159 -53.804147) (xy 316.848416 -53.826987)
			(xy 316.795919 -53.842483) (xy 316.741746 -53.850317) (xy 316.714378 -53.850794) (xy 316.687127 -53.850335)
			(xy 316.633179 -53.842575) (xy 316.580885 -53.827218) (xy 316.531309 -53.804575) (xy 316.48546 -53.775107)
			(xy 316.444271 -53.739414) (xy 316.40858 -53.698223) (xy 316.379115 -53.652372) (xy 316.356475 -53.602794)
			(xy 316.34112 -53.550499) (xy 316.333364 -53.496551) (xy 304.043557 -53.496551) (xy 304.047133 -53.502115)
			(xy 304.069775 -53.551692) (xy 304.08513 -53.603987) (xy 304.092886 -53.657935) (xy 304.093372 -53.685186)
			(xy 304.092905 -53.712556) (xy 304.085088 -53.766736) (xy 304.0696 -53.819239) (xy 304.046758 -53.868986)
			(xy 304.017033 -53.914952) (xy 303.999392 -53.935884) (xy 303.999138 -53.936138) (xy 303.993564 -53.943233)
			(xy 303.987311 -53.960144) (xy 303.986946 -53.969158) (xy 303.986946 -54.036214) (xy 303.987286 -54.045233)
			(xy 303.993544 -54.06215) (xy 303.999138 -54.069234) (xy 303.999392 -54.069234) (xy 303.999392 -54.069488)
			(xy 304.017038 -54.090415) (xy 304.046749 -54.136389) (xy 304.069584 -54.186138) (xy 304.085073 -54.23864)
			(xy 304.092899 -54.292816) (xy 304.093372 -54.320186) (xy 304.092886 -54.347437) (xy 304.08513 -54.401385)
			(xy 304.069775 -54.45368) (xy 304.047133 -54.503257) (xy 304.017667 -54.549107) (xy 303.981976 -54.590298)
			(xy 303.940785 -54.625989) (xy 303.894935 -54.655455) (xy 303.845358 -54.678097) (xy 303.793063 -54.693452)
			(xy 303.739115 -54.701208) (xy 303.684613 -54.701208) (xy 303.630665 -54.693452) (xy 303.57837 -54.678097)
			(xy 303.528793 -54.655455) (xy 303.482943 -54.625989) (xy 303.441752 -54.590298) (xy 303.406061 -54.549107)
			(xy 303.376595 -54.503257) (xy 303.353953 -54.45368) (xy 303.338598 -54.401385) (xy 303.330842 -54.347437)
			(xy 303.330356 -54.320186) (xy 301.101791 -54.320186) (xy 301.092738 -54.339899) (xy 301.063013 -54.385867)
			(xy 301.045372 -54.4068) (xy 301.045118 -54.407054) (xy 301.039547 -54.414151) (xy 301.033291 -54.43106)
			(xy 301.032926 -54.440074) (xy 301.032926 -54.50713) (xy 301.033263 -54.516149) (xy 301.039524 -54.533066)
			(xy 301.045118 -54.54015) (xy 301.045372 -54.54015) (xy 301.045372 -54.540404) (xy 301.063022 -54.561327)
			(xy 301.092733 -54.607302) (xy 301.115567 -54.657052) (xy 301.131056 -54.709555) (xy 301.13888 -54.763732)
			(xy 301.138997 -54.770528) (xy 304.270918 -54.770528) (xy 304.271396 -54.743158) (xy 304.27921 -54.688979)
			(xy 304.294696 -54.636476) (xy 304.317536 -54.586729) (xy 304.347258 -54.540762) (xy 304.364898 -54.51983)
			(xy 304.365152 -54.519576) (xy 304.370761 -54.512505) (xy 304.376993 -54.495576) (xy 304.377344 -54.486556)
			(xy 304.377344 -54.4195) (xy 304.376999 -54.410482) (xy 304.370744 -54.393564) (xy 304.365152 -54.38648)
			(xy 304.364898 -54.38648) (xy 304.364898 -54.386226) (xy 304.347257 -54.365295) (xy 304.317546 -54.319322)
			(xy 304.29471 -54.269574) (xy 304.279219 -54.217073) (xy 304.271392 -54.162897) (xy 304.270918 -54.135528)
			(xy 304.271404 -54.108277) (xy 304.27916 -54.054329) (xy 304.294515 -54.002034) (xy 304.317157 -53.952457)
			(xy 304.346623 -53.906607) (xy 304.382314 -53.865416) (xy 304.423505 -53.829725) (xy 304.469355 -53.800259)
			(xy 304.518932 -53.777617) (xy 304.571227 -53.762262) (xy 304.625175 -53.754506) (xy 304.679677 -53.754506)
			(xy 304.733625 -53.762262) (xy 304.78592 -53.777617) (xy 304.835497 -53.800259) (xy 304.881347 -53.829725)
			(xy 304.922538 -53.865416) (xy 304.958229 -53.906607) (xy 304.987695 -53.952457) (xy 304.99277 -53.96357)
			(xy 308.971948 -53.96357) (xy 308.976019 -53.907948) (xy 308.988145 -53.853511) (xy 309.008068 -53.80142)
			(xy 309.035364 -53.752785) (xy 309.06945 -53.708642) (xy 309.109599 -53.669933) (xy 309.154957 -53.637482)
			(xy 309.204557 -53.611981) (xy 309.257341 -53.593974) (xy 309.312184 -53.583844) (xy 309.367918 -53.581807)
			(xy 309.423355 -53.587907) (xy 309.477312 -53.602013) (xy 309.528641 -53.623825) (xy 309.576247 -53.652879)
			(xy 309.619115 -53.688554) (xy 309.656332 -53.730091) (xy 309.687105 -53.776604) (xy 309.710777 -53.827101)
			(xy 309.726845 -53.880508) (xy 309.734965 -53.935684) (xy 309.735474 -53.96357) (xy 309.734965 -53.991456)
			(xy 309.726845 -54.046632) (xy 309.710777 -54.100039) (xy 309.687105 -54.150536) (xy 309.656332 -54.197049)
			(xy 309.619115 -54.238586) (xy 309.576247 -54.274261) (xy 309.528641 -54.303315) (xy 309.477312 -54.325127)
			(xy 309.423355 -54.339233) (xy 309.367918 -54.345333) (xy 309.312184 -54.343296) (xy 309.257341 -54.333166)
			(xy 309.204557 -54.315159) (xy 309.154957 -54.289658) (xy 309.109599 -54.257207) (xy 309.06945 -54.218498)
			(xy 309.035364 -54.174355) (xy 309.008068 -54.12572) (xy 308.988145 -54.073629) (xy 308.976019 -54.019192)
			(xy 308.971948 -53.96357) (xy 304.99277 -53.96357) (xy 305.010337 -54.002034) (xy 305.025692 -54.054329)
			(xy 305.033448 -54.108277) (xy 305.033934 -54.135528) (xy 305.0335 -54.1629) (xy 305.025677 -54.217081)
			(xy 305.010181 -54.269585) (xy 304.987332 -54.319331) (xy 304.957599 -54.365296) (xy 304.939954 -54.386226)
			(xy 304.9397 -54.38648) (xy 304.934116 -54.393568) (xy 304.927868 -54.410484) (xy 304.927508 -54.4195)
			(xy 304.927508 -54.486556) (xy 304.927885 -54.495571) (xy 304.934119 -54.512488) (xy 304.9397 -54.519576)
			(xy 304.939954 -54.519576) (xy 304.939954 -54.51983) (xy 304.957567 -54.540784) (xy 304.987284 -54.58675)
			(xy 305.010126 -54.636492) (xy 305.025623 -54.688988) (xy 305.033457 -54.74316) (xy 305.033934 -54.770528)
			(xy 305.033448 -54.797779) (xy 305.025692 -54.851727) (xy 305.010337 -54.904022) (xy 304.987695 -54.953599)
			(xy 304.964911 -54.989051) (xy 314.100968 -54.989051) (xy 314.100968 -54.934549) (xy 314.108724 -54.880603)
			(xy 314.124078 -54.828309) (xy 314.146718 -54.778732) (xy 314.176182 -54.732882) (xy 314.211871 -54.691691)
			(xy 314.253059 -54.655999) (xy 314.298907 -54.626531) (xy 314.348482 -54.603888) (xy 314.400775 -54.58853)
			(xy 314.454721 -54.58077) (xy 314.481972 -54.580282) (xy 314.510063 -54.580799) (xy 314.565639 -54.589022)
			(xy 314.619407 -54.605309) (xy 314.670205 -54.629308) (xy 314.716932 -54.6605) (xy 314.758578 -54.698209)
			(xy 314.794241 -54.741619) (xy 314.809124 -54.765448) (xy 314.814458 -54.774338) (xy 314.831476 -54.78653)
			(xy 314.924694 -54.80685) (xy 314.945268 -54.802532) (xy 314.953904 -54.79669) (xy 314.977965 -54.780685)
			(xy 315.029897 -54.755344) (xy 315.085056 -54.738119) (xy 315.142181 -54.729406) (xy 315.171074 -54.728872)
			(xy 315.198325 -54.729379) (xy 315.252274 -54.737132) (xy 315.304569 -54.752484) (xy 315.354148 -54.775122)
			(xy 315.4 -54.804586) (xy 315.441193 -54.840275) (xy 315.476887 -54.881463) (xy 315.506356 -54.927311)
			(xy 315.529 -54.976887) (xy 315.544358 -55.029181) (xy 315.552117 -55.083129) (xy 315.552582 -55.11038)
			(xy 315.552109 -55.13775) (xy 315.544293 -55.191929) (xy 315.528806 -55.244432) (xy 315.505966 -55.294179)
			(xy 315.476243 -55.340146) (xy 315.458602 -55.361078) (xy 315.458348 -55.361332) (xy 315.452778 -55.368429)
			(xy 315.446522 -55.385338) (xy 315.446156 -55.394352) (xy 315.446156 -55.461408) (xy 315.446497 -55.470427)
			(xy 315.452755 -55.487344) (xy 315.458348 -55.494428) (xy 315.458602 -55.494428) (xy 315.458602 -55.494682)
			(xy 315.476222 -55.515631) (xy 315.505945 -55.561597) (xy 315.52879 -55.611341) (xy 315.544287 -55.66384)
			(xy 315.552116 -55.718016) (xy 315.552119 -55.772754) (xy 315.544293 -55.826931) (xy 315.528801 -55.879431)
			(xy 315.50596 -55.929177) (xy 315.47624 -55.975145) (xy 315.458602 -55.996078) (xy 315.458348 -55.996332)
			(xy 315.452778 -56.003429) (xy 315.446522 -56.020338) (xy 315.446156 -56.029352) (xy 315.446156 -56.096408)
			(xy 315.446497 -56.105427) (xy 315.452755 -56.122344) (xy 315.458348 -56.129428) (xy 315.458602 -56.129428)
			(xy 315.458602 -56.129682) (xy 315.476246 -56.15061) (xy 315.505957 -56.196584) (xy 315.528792 -56.246332)
			(xy 315.544282 -56.298834) (xy 315.552109 -56.353011) (xy 315.552582 -56.38038) (xy 315.552096 -56.407631)
			(xy 315.54434 -56.461579) (xy 315.528985 -56.513874) (xy 315.506343 -56.563451) (xy 315.476877 -56.609301)
			(xy 315.441186 -56.650492) (xy 315.399995 -56.686183) (xy 315.354145 -56.715649) (xy 315.304568 -56.738291)
			(xy 315.252273 -56.753646) (xy 315.198325 -56.761402) (xy 315.143823 -56.761402) (xy 315.089875 -56.753646)
			(xy 315.03758 -56.738291) (xy 314.988003 -56.715649) (xy 314.942153 -56.686183) (xy 314.900962 -56.650492)
			(xy 314.865271 -56.609301) (xy 314.835805 -56.563451) (xy 314.813163 -56.513874) (xy 314.797808 -56.461579)
			(xy 314.790052 -56.407631) (xy 314.789566 -56.38038) (xy 314.790004 -56.353009) (xy 314.797826 -56.298828)
			(xy 314.813321 -56.246324) (xy 314.836169 -56.196577) (xy 314.865901 -56.150612) (xy 314.883546 -56.129682)
			(xy 314.8838 -56.129428) (xy 314.889381 -56.122338) (xy 314.895631 -56.105424) (xy 314.895992 -56.096408)
			(xy 314.895992 -56.029352) (xy 314.895612 -56.020337) (xy 314.88938 -56.00342) (xy 314.8838 -55.996332)
			(xy 314.883546 -55.996332) (xy 314.883546 -55.996078) (xy 314.865885 -55.975162) (xy 314.836159 -55.929191)
			(xy 314.813314 -55.879443) (xy 314.797819 -55.826938) (xy 314.789991 -55.772757) (xy 314.789994 -55.718013)
			(xy 314.797825 -55.663833) (xy 314.813325 -55.611329) (xy 314.836174 -55.561582) (xy 314.865903 -55.515614)
			(xy 314.883546 -55.494682) (xy 314.8838 -55.494428) (xy 314.889381 -55.487338) (xy 314.895631 -55.470424)
			(xy 314.895992 -55.461408) (xy 314.895992 -55.394352) (xy 314.895612 -55.385337) (xy 314.88938 -55.36842)
			(xy 314.8838 -55.361332) (xy 314.883546 -55.360824) (xy 314.872599 -55.348092) (xy 314.85276 -55.320999)
			(xy 314.843922 -55.306722) (xy 314.838588 -55.297832) (xy 314.82157 -55.28564) (xy 314.728352 -55.26532)
			(xy 314.707778 -55.269638) (xy 314.699142 -55.27548) (xy 314.675067 -55.291462) (xy 314.62314 -55.316809)
			(xy 314.567985 -55.33404) (xy 314.510864 -55.342761) (xy 314.481972 -55.343298) (xy 314.454721 -55.34283)
			(xy 314.400775 -55.33507) (xy 314.348482 -55.319712) (xy 314.298907 -55.297069) (xy 314.253059 -55.267601)
			(xy 314.211871 -55.231909) (xy 314.176182 -55.190718) (xy 314.146718 -55.144868) (xy 314.124078 -55.095291)
			(xy 314.108724 -55.042997) (xy 314.100968 -54.989051) (xy 304.964911 -54.989051) (xy 304.958229 -54.999449)
			(xy 304.922538 -55.04064) (xy 304.881347 -55.076331) (xy 304.835497 -55.105797) (xy 304.78592 -55.128439)
			(xy 304.733625 -55.143794) (xy 304.679677 -55.15155) (xy 304.625175 -55.15155) (xy 304.571227 -55.143794)
			(xy 304.518932 -55.128439) (xy 304.469355 -55.105797) (xy 304.423505 -55.076331) (xy 304.382314 -55.04064)
			(xy 304.346623 -54.999449) (xy 304.317157 -54.953599) (xy 304.294515 -54.904022) (xy 304.27916 -54.851727)
			(xy 304.271404 -54.797779) (xy 304.270918 -54.770528) (xy 301.138997 -54.770528) (xy 301.139352 -54.791102)
			(xy 301.138866 -54.818353) (xy 301.13111 -54.872301) (xy 301.115755 -54.924596) (xy 301.093113 -54.974173)
			(xy 301.063647 -55.020023) (xy 301.027956 -55.061214) (xy 300.986765 -55.096905) (xy 300.940915 -55.126371)
			(xy 300.891338 -55.149013) (xy 300.839043 -55.164368) (xy 300.785095 -55.172124) (xy 300.730593 -55.172124)
			(xy 300.676645 -55.164368) (xy 300.62435 -55.149013) (xy 300.574773 -55.126371) (xy 300.528923 -55.096905)
			(xy 300.487732 -55.061214) (xy 300.452041 -55.020023) (xy 300.422575 -54.974173) (xy 300.399933 -54.924596)
			(xy 300.384578 -54.872301) (xy 300.376822 -54.818353) (xy 300.376336 -54.791102) (xy 298.478991 -54.791102)
			(xy 298.477536 -54.801842) (xy 298.464663 -54.851608) (xy 298.445216 -54.89919) (xy 298.432728 -54.921658)
			(xy 298.425616 -54.933596) (xy 298.420536 -54.94147) (xy 298.417996 -54.945788) (xy 298.417488 -54.993794)
			(xy 298.409984 -55.722266) (xy 310.033922 -55.722266) (xy 310.037993 -55.666644) (xy 310.050119 -55.612207)
			(xy 310.070042 -55.560116) (xy 310.097338 -55.511481) (xy 310.131424 -55.467338) (xy 310.171573 -55.428629)
			(xy 310.216931 -55.396178) (xy 310.266531 -55.370677) (xy 310.319315 -55.35267) (xy 310.374158 -55.34254)
			(xy 310.429892 -55.340503) (xy 310.485329 -55.346603) (xy 310.539286 -55.360709) (xy 310.590615 -55.382521)
			(xy 310.638221 -55.411575) (xy 310.649367 -55.420851) (xy 312.424568 -55.420851) (xy 312.424568 -55.366349)
			(xy 312.432324 -55.312403) (xy 312.447678 -55.260109) (xy 312.470318 -55.210532) (xy 312.499782 -55.164682)
			(xy 312.535471 -55.123491) (xy 312.576659 -55.087799) (xy 312.622507 -55.058331) (xy 312.672082 -55.035688)
			(xy 312.724375 -55.02033) (xy 312.778321 -55.01257) (xy 312.805572 -55.012082) (xy 312.831887 -55.012507)
			(xy 312.884017 -55.019751) (xy 312.934661 -55.034079) (xy 312.982859 -55.05522) (xy 313.027702 -55.082773)
			(xy 313.06834 -55.116218) (xy 313.086496 -55.135272) (xy 313.094021 -55.14267) (xy 313.113298 -55.151197)
			(xy 313.123834 -55.151782) (xy 313.19851 -55.151782) (xy 313.209063 -55.151277) (xy 313.228358 -55.142725)
			(xy 313.235848 -55.135272) (xy 313.253982 -55.116195) (xy 313.294617 -55.082741) (xy 313.339462 -55.055185)
			(xy 313.387667 -55.034051) (xy 313.438318 -55.019738) (xy 313.490455 -55.012518) (xy 313.516772 -55.012082)
			(xy 313.544025 -55.012563) (xy 313.597978 -55.020317) (xy 313.650278 -55.03567) (xy 313.69986 -55.05831)
			(xy 313.745716 -55.087777) (xy 313.786911 -55.12347) (xy 313.822606 -55.164662) (xy 313.852076 -55.210515)
			(xy 313.87472 -55.260096) (xy 313.890077 -55.312395) (xy 313.897835 -55.366347) (xy 313.897835 -55.420853)
			(xy 313.890077 -55.474805) (xy 313.87472 -55.527104) (xy 313.852076 -55.576685) (xy 313.822606 -55.622538)
			(xy 313.786911 -55.66373) (xy 313.745716 -55.699423) (xy 313.69986 -55.72889) (xy 313.650278 -55.75153)
			(xy 313.597978 -55.766883) (xy 313.544025 -55.774637) (xy 313.516772 -55.775098) (xy 313.490457 -55.77465)
			(xy 313.438328 -55.767411) (xy 313.387685 -55.753088) (xy 313.339486 -55.731952) (xy 313.294643 -55.704403)
			(xy 313.254004 -55.670961) (xy 313.235848 -55.651908) (xy 313.228347 -55.644483) (xy 313.209051 -55.635972)
			(xy 313.19851 -55.635398) (xy 313.123834 -55.635398) (xy 313.113285 -55.635933) (xy 313.09399 -55.644464)
			(xy 313.086496 -55.651908) (xy 313.068337 -55.67096) (xy 313.027708 -55.704417) (xy 312.982868 -55.731976)
			(xy 312.934668 -55.753115) (xy 312.884021 -55.767433) (xy 312.831888 -55.774659) (xy 312.805572 -55.775098)
			(xy 312.778321 -55.77463) (xy 312.724375 -55.76687) (xy 312.672082 -55.751512) (xy 312.622507 -55.728869)
			(xy 312.576659 -55.699401) (xy 312.535471 -55.663709) (xy 312.499782 -55.622518) (xy 312.470318 -55.576668)
			(xy 312.447678 -55.527091) (xy 312.432324 -55.474797) (xy 312.424568 -55.420851) (xy 310.649367 -55.420851)
			(xy 310.681089 -55.44725) (xy 310.718306 -55.488787) (xy 310.749079 -55.5353) (xy 310.772751 -55.585797)
			(xy 310.788819 -55.639204) (xy 310.796939 -55.69438) (xy 310.797448 -55.722266) (xy 310.796939 -55.750152)
			(xy 310.788819 -55.805328) (xy 310.772751 -55.858735) (xy 310.749079 -55.909232) (xy 310.718306 -55.955745)
			(xy 310.681089 -55.997282) (xy 310.638221 -56.032957) (xy 310.590615 -56.062011) (xy 310.539286 -56.083823)
			(xy 310.485329 -56.097929) (xy 310.429892 -56.104029) (xy 310.374158 -56.101992) (xy 310.319315 -56.091862)
			(xy 310.266531 -56.073855) (xy 310.216931 -56.048354) (xy 310.171573 -56.015903) (xy 310.131424 -55.977194)
			(xy 310.097338 -55.933051) (xy 310.070042 -55.884416) (xy 310.050119 -55.832325) (xy 310.037993 -55.777888)
			(xy 310.033922 -55.722266) (xy 298.409984 -55.722266) (xy 298.401232 -56.571896) (xy 298.401265 -56.576032)
			(xy 298.402543 -56.584203) (xy 298.403772 -56.588152) (xy 298.406058 -56.59501) (xy 298.40936 -56.599836)
			(xy 298.409868 -56.600344) (xy 298.427197 -56.625015) (xy 298.454692 -56.678667) (xy 298.473429 -56.735968)
			(xy 298.482943 -56.795499) (xy 298.483528 -56.825642) (xy 298.483528 -56.835802) (xy 298.483274 -56.844438)
			(xy 298.483274 -56.844946) (xy 298.481603 -56.870161) (xy 298.472426 -56.919856) (xy 298.464986 -56.944006)
			(xy 298.456096 -56.968898) (xy 298.455588 -56.969914) (xy 298.455334 -56.97093) (xy 298.454826 -56.971438)
			(xy 298.447286 -56.989235) (xy 298.439976 -57.002934) (xy 305.763422 -57.002934) (xy 305.763924 -56.974842)
			(xy 305.772148 -56.919265) (xy 305.788436 -56.865495) (xy 305.812437 -56.814697) (xy 305.843631 -56.76797)
			(xy 305.881343 -56.726325) (xy 305.924757 -56.690664) (xy 305.948588 -56.675782) (xy 305.957478 -56.670448)
			(xy 305.96967 -56.65343) (xy 305.98999 -56.560212) (xy 305.985672 -56.539638) (xy 305.97983 -56.531002)
			(xy 305.963832 -56.506937) (xy 305.938488 -56.455006) (xy 305.921262 -56.399849) (xy 305.912546 -56.342724)
			(xy 305.912012 -56.313832) (xy 305.912485 -56.286579) (xy 305.920238 -56.232627) (xy 305.935591 -56.180329)
			(xy 305.958231 -56.130747) (xy 305.987698 -56.084893) (xy 306.023391 -56.043699) (xy 306.064583 -56.008005)
			(xy 306.110437 -55.978537) (xy 306.160017 -55.955895) (xy 306.212316 -55.940541) (xy 306.266267 -55.932786)
			(xy 306.29352 -55.932324) (xy 306.320891 -55.932772) (xy 306.375071 -55.940594) (xy 306.427575 -55.956087)
			(xy 306.477321 -55.978932) (xy 306.523287 -56.008661) (xy 306.544218 -56.026304) (xy 306.544472 -56.026558)
			(xy 306.551557 -56.032146) (xy 306.568475 -56.03839) (xy 306.577492 -56.03875) (xy 306.644548 -56.03875)
			(xy 306.653564 -56.038379) (xy 306.670481 -56.032142) (xy 306.677568 -56.026558) (xy 306.677568 -56.026304)
			(xy 306.677822 -56.026304) (xy 306.698755 -56.008663) (xy 306.744723 -55.978939) (xy 306.794469 -55.956093)
			(xy 306.846971 -55.940597) (xy 306.901149 -55.932768) (xy 306.955891 -55.932768) (xy 307.010069 -55.940597)
			(xy 307.062571 -55.956093) (xy 307.112317 -55.978939) (xy 307.158285 -56.008663) (xy 307.179218 -56.026304)
			(xy 307.179472 -56.026558) (xy 307.186557 -56.032146) (xy 307.203475 -56.03839) (xy 307.212492 -56.03875)
			(xy 307.279548 -56.03875) (xy 307.288564 -56.038379) (xy 307.305481 -56.032142) (xy 307.312568 -56.026558)
			(xy 307.312568 -56.026304) (xy 307.312822 -56.026304) (xy 307.333773 -56.008689) (xy 307.379741 -55.978973)
			(xy 307.429483 -55.956133) (xy 307.48198 -55.940636) (xy 307.536152 -55.932801) (xy 307.56352 -55.932324)
			(xy 307.590773 -55.932747) (xy 307.644723 -55.940507) (xy 307.697019 -55.955865) (xy 307.746598 -55.978509)
			(xy 307.79245 -56.007978) (xy 307.833641 -56.043673) (xy 307.869334 -56.084866) (xy 307.898801 -56.130719)
			(xy 307.921442 -56.180299) (xy 307.936798 -56.232597) (xy 307.944554 -56.286547) (xy 307.944554 -56.297068)
			(xy 308.286402 -56.297068) (xy 308.290473 -56.241446) (xy 308.302599 -56.187009) (xy 308.322522 -56.134918)
			(xy 308.349818 -56.086283) (xy 308.383904 -56.04214) (xy 308.424053 -56.003431) (xy 308.469411 -55.97098)
			(xy 308.519011 -55.945479) (xy 308.571795 -55.927472) (xy 308.626638 -55.917342) (xy 308.682372 -55.915305)
			(xy 308.737809 -55.921405) (xy 308.791766 -55.935511) (xy 308.843095 -55.957323) (xy 308.890701 -55.986377)
			(xy 308.933569 -56.022052) (xy 308.970786 -56.063589) (xy 309.001559 -56.110102) (xy 309.025231 -56.160599)
			(xy 309.041299 -56.214006) (xy 309.049419 -56.269182) (xy 309.049928 -56.297068) (xy 309.049419 -56.324954)
			(xy 309.041299 -56.38013) (xy 309.025231 -56.433537) (xy 309.001559 -56.484034) (xy 308.970786 -56.530547)
			(xy 308.933569 -56.572084) (xy 308.890701 -56.607759) (xy 308.843095 -56.636813) (xy 308.791766 -56.658625)
			(xy 308.737809 -56.672731) (xy 308.682372 -56.678831) (xy 308.626638 -56.676794) (xy 308.571795 -56.666664)
			(xy 308.519011 -56.648657) (xy 308.469411 -56.623156) (xy 308.424053 -56.590705) (xy 308.383904 -56.551996)
			(xy 308.349818 -56.507853) (xy 308.322522 -56.459218) (xy 308.302599 -56.407127) (xy 308.290473 -56.35269)
			(xy 308.286402 -56.297068) (xy 307.944554 -56.297068) (xy 307.944554 -56.341053) (xy 307.936798 -56.395003)
			(xy 307.921442 -56.447301) (xy 307.898801 -56.496881) (xy 307.869334 -56.542734) (xy 307.833641 -56.583927)
			(xy 307.79245 -56.619622) (xy 307.746598 -56.649091) (xy 307.697019 -56.671735) (xy 307.644723 -56.687093)
			(xy 307.590773 -56.694853) (xy 307.56352 -56.69534) (xy 307.536149 -56.694877) (xy 307.48197 -56.687061)
			(xy 307.429466 -56.671572) (xy 307.379719 -56.648729) (xy 307.333753 -56.619002) (xy 307.312822 -56.60136)
			(xy 307.312568 -56.601106) (xy 307.305466 -56.595542) (xy 307.288561 -56.589282) (xy 307.279548 -56.588914)
			(xy 307.212492 -56.588914) (xy 307.203474 -56.589264) (xy 307.186557 -56.595516) (xy 307.179472 -56.601106)
			(xy 307.179472 -56.60136) (xy 307.179218 -56.60136) (xy 307.158285 -56.619001) (xy 307.112317 -56.648725)
			(xy 307.062571 -56.671571) (xy 307.010069 -56.687067) (xy 306.955891 -56.694896) (xy 306.901149 -56.694896)
			(xy 306.846971 -56.687067) (xy 306.794469 -56.671571) (xy 306.744723 -56.648725) (xy 306.698755 -56.619001)
			(xy 306.677822 -56.60136) (xy 306.677568 -56.601106) (xy 306.670466 -56.595542) (xy 306.653561 -56.589282)
			(xy 306.644548 -56.588914) (xy 306.577492 -56.588914) (xy 306.568474 -56.589264) (xy 306.551557 -56.595516)
			(xy 306.544472 -56.601106) (xy 306.543964 -56.60136) (xy 306.531229 -56.612304) (xy 306.504138 -56.632145)
			(xy 306.489862 -56.640984) (xy 306.480972 -56.646318) (xy 306.46878 -56.663336) (xy 306.44846 -56.756554)
			(xy 306.452778 -56.777128) (xy 306.45862 -56.785764) (xy 306.474609 -56.809835) (xy 306.499954 -56.861764)
			(xy 306.517182 -56.91692) (xy 306.525901 -56.974042) (xy 306.526438 -57.002934) (xy 306.525952 -57.030185)
			(xy 306.518196 -57.084133) (xy 306.502841 -57.136428) (xy 306.480199 -57.186005) (xy 306.450733 -57.231855)
			(xy 306.415042 -57.273046) (xy 306.373851 -57.308737) (xy 306.328001 -57.338203) (xy 306.278424 -57.360845)
			(xy 306.226129 -57.3762) (xy 306.172181 -57.383956) (xy 306.117679 -57.383956) (xy 306.063731 -57.3762)
			(xy 306.011436 -57.360845) (xy 305.961859 -57.338203) (xy 305.916009 -57.308737) (xy 305.874818 -57.273046)
			(xy 305.839127 -57.231855) (xy 305.809661 -57.186005) (xy 305.787019 -57.136428) (xy 305.771664 -57.084133)
			(xy 305.763908 -57.030185) (xy 305.763422 -57.002934) (xy 298.439976 -57.002934) (xy 298.429088 -57.023337)
			(xy 298.418504 -57.03951) (xy 298.413424 -57.046876) (xy 298.406566 -57.05602) (xy 298.406566 -57.056274)
			(xy 298.402116 -57.062498) (xy 298.396822 -57.076846) (xy 298.396152 -57.084468) (xy 298.396152 -57.098946)
			(xy 298.395136 -57.195212) (xy 298.395136 -57.199276) (xy 298.40301 -57.22239) (xy 298.404328 -57.226039)
			(xy 298.407904 -57.232923) (xy 298.410122 -57.236106) (xy 298.427422 -57.260749) (xy 298.454857 -57.314343)
			(xy 298.473527 -57.371583) (xy 298.482967 -57.431046) (xy 298.483528 -57.46115) (xy 298.483528 -57.47131)
			(xy 298.482888 -57.48528) (xy 314.80582 -57.48528) (xy 314.809891 -57.429658) (xy 314.822017 -57.375221)
			(xy 314.84194 -57.32313) (xy 314.869236 -57.274495) (xy 314.903322 -57.230352) (xy 314.943471 -57.191643)
			(xy 314.988829 -57.159192) (xy 315.038429 -57.133691) (xy 315.091213 -57.115684) (xy 315.146056 -57.105554)
			(xy 315.20179 -57.103517) (xy 315.257227 -57.109617) (xy 315.311184 -57.123723) (xy 315.362513 -57.145535)
			(xy 315.410119 -57.174589) (xy 315.452987 -57.210264) (xy 315.490204 -57.251801) (xy 315.520977 -57.298314)
			(xy 315.544649 -57.348811) (xy 315.560717 -57.402218) (xy 315.568837 -57.457394) (xy 315.569346 -57.48528)
			(xy 315.568837 -57.513166) (xy 315.560717 -57.568342) (xy 315.544649 -57.621749) (xy 315.520977 -57.672246)
			(xy 315.490204 -57.718759) (xy 315.452987 -57.760296) (xy 315.410119 -57.795971) (xy 315.362513 -57.825025)
			(xy 315.311184 -57.846837) (xy 315.257227 -57.860943) (xy 315.20179 -57.867043) (xy 315.146056 -57.865006)
			(xy 315.091213 -57.854876) (xy 315.038429 -57.836869) (xy 314.988829 -57.811368) (xy 314.943471 -57.778917)
			(xy 314.903322 -57.740208) (xy 314.869236 -57.696065) (xy 314.84194 -57.64743) (xy 314.822017 -57.595339)
			(xy 314.809891 -57.540902) (xy 314.80582 -57.48528) (xy 298.482888 -57.48528) (xy 298.482125 -57.501947)
			(xy 298.470748 -57.562208) (xy 298.449867 -57.61987) (xy 298.42002 -57.673443) (xy 298.401486 -57.697878)
			(xy 298.398946 -57.70118) (xy 298.392088 -57.714134) (xy 298.389802 -57.724294) (xy 298.389548 -57.738518)
			(xy 298.389548 -57.755536) (xy 298.389294 -57.756044) (xy 298.389294 -57.757314) (xy 298.388532 -57.824624)
			(xy 298.388634 -57.829236) (xy 298.390297 -57.838309) (xy 298.391834 -57.842658) (xy 298.394628 -57.850532)
			(xy 298.395898 -57.85231) (xy 298.396152 -57.852564) (xy 298.39666 -57.85358) (xy 298.412688 -57.87372)
			(xy 298.439755 -57.917501) (xy 298.46069 -57.964523) (xy 298.475112 -58.013933) (xy 298.48276 -58.064834)
			(xy 298.483528 -58.090562) (xy 298.483528 -58.096658) (xy 298.48292 -58.126567) (xy 298.473541 -58.185647)
			(xy 298.455068 -58.242543) (xy 298.427953 -58.295864) (xy 298.410884 -58.320432) (xy 298.404534 -58.329068)
			(xy 298.400724 -58.333894) (xy 298.39539 -58.34253) (xy 298.394882 -58.343546) (xy 298.392422 -58.348872)
			(xy 298.389732 -58.360288) (xy 298.389548 -58.366152) (xy 298.389548 -58.387488) (xy 298.389395 -58.392723)
			(xy 298.387227 -58.402967) (xy 298.38523 -58.407808) (xy 298.384976 -58.40857) (xy 298.38269 -58.414412)
			(xy 298.382182 -58.452766) (xy 298.382266 -58.457442) (xy 298.38393 -58.466643) (xy 298.385484 -58.471054)
			(xy 298.388278 -58.478674) (xy 298.39412 -58.485786) (xy 298.413138 -58.509286) (xy 298.444268 -58.561105)
			(xy 298.466825 -58.61719) (xy 298.480243 -58.676133) (xy 298.480511 -58.679334) (xy 306.195222 -58.679334)
			(xy 306.195638 -58.653018) (xy 306.202883 -58.600887) (xy 306.217211 -58.550243) (xy 306.238353 -58.502044)
			(xy 306.265909 -58.457202) (xy 306.299356 -58.416565) (xy 306.318412 -58.39841) (xy 306.325813 -58.390888)
			(xy 306.334337 -58.371608) (xy 306.334922 -58.361072) (xy 306.334922 -58.286396) (xy 306.334402 -58.275845)
			(xy 306.32586 -58.256551) (xy 306.318412 -58.249058) (xy 306.299345 -58.230913) (xy 306.265889 -58.190282)
			(xy 306.238331 -58.145439) (xy 306.217194 -58.097236) (xy 306.20288 -58.046587) (xy 306.195658 -57.994451)
			(xy 306.195222 -57.968134) (xy 306.195708 -57.940883) (xy 306.203464 -57.886935) (xy 306.218819 -57.83464)
			(xy 306.241461 -57.785063) (xy 306.270927 -57.739213) (xy 306.306618 -57.698022) (xy 306.347809 -57.662331)
			(xy 306.393659 -57.632865) (xy 306.443236 -57.610223) (xy 306.495531 -57.594868) (xy 306.549479 -57.587112)
			(xy 306.603981 -57.587112) (xy 306.657929 -57.594868) (xy 306.710224 -57.610223) (xy 306.759801 -57.632865)
			(xy 306.805651 -57.662331) (xy 306.846842 -57.698022) (xy 306.882533 -57.739213) (xy 306.911999 -57.785063)
			(xy 306.934641 -57.83464) (xy 306.949996 -57.886935) (xy 306.957752 -57.940883) (xy 306.958238 -57.968134)
			(xy 306.957813 -57.99445) (xy 306.950572 -58.046581) (xy 306.943304 -58.072274) (xy 310.193434 -58.072274)
			(xy 310.197505 -58.016652) (xy 310.209631 -57.962215) (xy 310.229554 -57.910124) (xy 310.25685 -57.861489)
			(xy 310.290936 -57.817346) (xy 310.331085 -57.778637) (xy 310.376443 -57.746186) (xy 310.426043 -57.720685)
			(xy 310.478827 -57.702678) (xy 310.53367 -57.692548) (xy 310.589404 -57.690511) (xy 310.644841 -57.696611)
			(xy 310.698798 -57.710717) (xy 310.750127 -57.732529) (xy 310.797733 -57.761583) (xy 310.840601 -57.797258)
			(xy 310.877818 -57.838795) (xy 310.908591 -57.885308) (xy 310.932263 -57.935805) (xy 310.948331 -57.989212)
			(xy 310.956451 -58.044388) (xy 310.95696 -58.072274) (xy 310.95689 -58.076084) (xy 315.557914 -58.076084)
			(xy 315.561985 -58.020462) (xy 315.574111 -57.966025) (xy 315.594034 -57.913934) (xy 315.62133 -57.865299)
			(xy 315.655416 -57.821156) (xy 315.695565 -57.782447) (xy 315.740923 -57.749996) (xy 315.790523 -57.724495)
			(xy 315.843307 -57.706488) (xy 315.89815 -57.696358) (xy 315.953884 -57.694321) (xy 316.009321 -57.700421)
			(xy 316.063278 -57.714527) (xy 316.114607 -57.736339) (xy 316.162213 -57.765393) (xy 316.205081 -57.801068)
			(xy 316.242298 -57.842605) (xy 316.258634 -57.867296) (xy 317.842898 -57.867296) (xy 317.846969 -57.811674)
			(xy 317.859095 -57.757237) (xy 317.879018 -57.705146) (xy 317.906314 -57.656511) (xy 317.9404 -57.612368)
			(xy 317.980549 -57.573659) (xy 318.025907 -57.541208) (xy 318.075507 -57.515707) (xy 318.128291 -57.4977)
			(xy 318.183134 -57.48757) (xy 318.238868 -57.485533) (xy 318.294305 -57.491633) (xy 318.348262 -57.505739)
			(xy 318.399591 -57.527551) (xy 318.447197 -57.556605) (xy 318.490065 -57.59228) (xy 318.527282 -57.633817)
			(xy 318.558055 -57.68033) (xy 318.581727 -57.730827) (xy 318.597795 -57.784234) (xy 318.605915 -57.83941)
			(xy 318.606424 -57.867296) (xy 318.605915 -57.895182) (xy 318.597795 -57.950358) (xy 318.581727 -58.003765)
			(xy 318.558055 -58.054262) (xy 318.527282 -58.100775) (xy 318.490065 -58.142312) (xy 318.447197 -58.177987)
			(xy 318.399591 -58.207041) (xy 318.348262 -58.228853) (xy 318.294305 -58.242959) (xy 318.238868 -58.249059)
			(xy 318.183134 -58.247022) (xy 318.128291 -58.236892) (xy 318.075507 -58.218885) (xy 318.025907 -58.193384)
			(xy 317.980549 -58.160933) (xy 317.9404 -58.122224) (xy 317.906314 -58.078081) (xy 317.879018 -58.029446)
			(xy 317.859095 -57.977355) (xy 317.846969 -57.922918) (xy 317.842898 -57.867296) (xy 316.258634 -57.867296)
			(xy 316.273071 -57.889118) (xy 316.296743 -57.939615) (xy 316.312811 -57.993022) (xy 316.320931 -58.048198)
			(xy 316.32144 -58.076084) (xy 316.320931 -58.10397) (xy 316.312811 -58.159146) (xy 316.296743 -58.212553)
			(xy 316.273071 -58.26305) (xy 316.242298 -58.309563) (xy 316.205081 -58.3511) (xy 316.162213 -58.386775)
			(xy 316.114607 -58.415829) (xy 316.063278 -58.437641) (xy 316.009321 -58.451747) (xy 315.953884 -58.457847)
			(xy 315.89815 -58.45581) (xy 315.843307 -58.44568) (xy 315.790523 -58.427673) (xy 315.740923 -58.402172)
			(xy 315.695565 -58.369721) (xy 315.655416 -58.331012) (xy 315.62133 -58.286869) (xy 315.594034 -58.238234)
			(xy 315.574111 -58.186143) (xy 315.561985 -58.131706) (xy 315.557914 -58.076084) (xy 310.95689 -58.076084)
			(xy 310.956451 -58.10016) (xy 310.948331 -58.155336) (xy 310.932263 -58.208743) (xy 310.908591 -58.25924)
			(xy 310.877818 -58.305753) (xy 310.840601 -58.34729) (xy 310.797733 -58.382965) (xy 310.750127 -58.412019)
			(xy 310.698798 -58.433831) (xy 310.644841 -58.447937) (xy 310.589404 -58.454037) (xy 310.53367 -58.452)
			(xy 310.478827 -58.44187) (xy 310.426043 -58.423863) (xy 310.376443 -58.398362) (xy 310.331085 -58.365911)
			(xy 310.290936 -58.327202) (xy 310.25685 -58.283059) (xy 310.229554 -58.234424) (xy 310.209631 -58.182333)
			(xy 310.197505 -58.127896) (xy 310.193434 -58.072274) (xy 306.943304 -58.072274) (xy 306.936246 -58.097225)
			(xy 306.915106 -58.145424) (xy 306.887551 -58.190267) (xy 306.854104 -58.230904) (xy 306.835048 -58.249058)
			(xy 306.82767 -58.2566) (xy 306.819131 -58.275864) (xy 306.818538 -58.286396) (xy 306.818538 -58.361072)
			(xy 306.819058 -58.371623) (xy 306.827598 -58.390919) (xy 306.835048 -58.39841) (xy 306.854111 -58.416558)
			(xy 306.887565 -58.457191) (xy 306.915122 -58.502033) (xy 306.936259 -58.550235) (xy 306.939365 -58.561224)
			(xy 316.762128 -58.561224) (xy 316.766199 -58.505602) (xy 316.778325 -58.451165) (xy 316.798248 -58.399074)
			(xy 316.825544 -58.350439) (xy 316.85963 -58.306296) (xy 316.899779 -58.267587) (xy 316.945137 -58.235136)
			(xy 316.994737 -58.209635) (xy 317.047521 -58.191628) (xy 317.102364 -58.181498) (xy 317.158098 -58.179461)
			(xy 317.213535 -58.185561) (xy 317.267492 -58.199667) (xy 317.318821 -58.221479) (xy 317.366427 -58.250533)
			(xy 317.409295 -58.286208) (xy 317.446512 -58.327745) (xy 317.477285 -58.374258) (xy 317.500957 -58.424755)
			(xy 317.517025 -58.478162) (xy 317.525145 -58.533338) (xy 317.525654 -58.561224) (xy 317.525145 -58.58911)
			(xy 317.517025 -58.644286) (xy 317.500957 -58.697693) (xy 317.477285 -58.74819) (xy 317.446512 -58.794703)
			(xy 317.409295 -58.83624) (xy 317.366427 -58.871915) (xy 317.318821 -58.900969) (xy 317.267492 -58.922781)
			(xy 317.213535 -58.936887) (xy 317.158098 -58.942987) (xy 317.102364 -58.94095) (xy 317.047521 -58.93082)
			(xy 316.994737 -58.912813) (xy 316.945137 -58.887312) (xy 316.899779 -58.854861) (xy 316.85963 -58.816152)
			(xy 316.825544 -58.772009) (xy 316.798248 -58.723374) (xy 316.778325 -58.671283) (xy 316.766199 -58.616846)
			(xy 316.762128 -58.561224) (xy 306.939365 -58.561224) (xy 306.950575 -58.600883) (xy 306.9578 -58.653018)
			(xy 306.958238 -58.679334) (xy 306.957752 -58.706585) (xy 306.949996 -58.760533) (xy 306.934641 -58.812828)
			(xy 306.911999 -58.862405) (xy 306.882533 -58.908255) (xy 306.846842 -58.949446) (xy 306.805651 -58.985137)
			(xy 306.759801 -59.014603) (xy 306.710224 -59.037245) (xy 306.657929 -59.0526) (xy 306.603981 -59.060356)
			(xy 306.549479 -59.060356) (xy 306.495531 -59.0526) (xy 306.443236 -59.037245) (xy 306.393659 -59.014603)
			(xy 306.347809 -58.985137) (xy 306.306618 -58.949446) (xy 306.270927 -58.908255) (xy 306.241461 -58.862405)
			(xy 306.218819 -58.812828) (xy 306.203464 -58.760533) (xy 306.195708 -58.706585) (xy 306.195222 -58.679334)
			(xy 298.480511 -58.679334) (xy 298.482766 -58.706258) (xy 298.483988 -58.730492) (xy 298.481012 -58.778925)
			(xy 298.471903 -58.826587) (xy 298.464732 -58.849768) (xy 298.456384 -58.87416) (xy 298.434044 -58.920625)
			(xy 298.405664 -58.963666) (xy 298.38904 -58.983372) (xy 298.383706 -58.989468) (xy 298.382944 -58.99023)
			(xy 298.379896 -58.998612) (xy 298.378394 -59.002839) (xy 298.376737 -59.011654) (xy 298.376594 -59.016138)
			(xy 298.374976 -59.174634) (xy 315.292992 -59.174634) (xy 315.297063 -59.119012) (xy 315.309189 -59.064575)
			(xy 315.329112 -59.012484) (xy 315.356408 -58.963849) (xy 315.390494 -58.919706) (xy 315.430643 -58.880997)
			(xy 315.476001 -58.848546) (xy 315.525601 -58.823045) (xy 315.578385 -58.805038) (xy 315.633228 -58.794908)
			(xy 315.688962 -58.792871) (xy 315.744399 -58.798971) (xy 315.798356 -58.813077) (xy 315.849685 -58.834889)
			(xy 315.897291 -58.863943) (xy 315.940159 -58.899618) (xy 315.977376 -58.941155) (xy 316.008149 -58.987668)
			(xy 316.031821 -59.038165) (xy 316.047889 -59.091572) (xy 316.056009 -59.146748) (xy 316.056518 -59.174634)
			(xy 316.056009 -59.20252) (xy 316.047889 -59.257696) (xy 316.031821 -59.311103) (xy 316.008149 -59.3616)
			(xy 315.977376 -59.408113) (xy 315.940159 -59.44965) (xy 315.897291 -59.485325) (xy 315.849685 -59.514379)
			(xy 315.798356 -59.536191) (xy 315.744399 -59.550297) (xy 315.688962 -59.556397) (xy 315.633228 -59.55436)
			(xy 315.578385 -59.54423) (xy 315.525601 -59.526223) (xy 315.476001 -59.500722) (xy 315.430643 -59.468271)
			(xy 315.390494 -59.429562) (xy 315.356408 -59.385419) (xy 315.329112 -59.336784) (xy 315.309189 -59.284693)
			(xy 315.297063 -59.230256) (xy 315.292992 -59.174634) (xy 298.374976 -59.174634) (xy 298.366355 -60.01925)
			(xy 306.335684 -60.01925) (xy 306.335684 -59.96475) (xy 306.34344 -59.910804) (xy 306.358794 -59.858512)
			(xy 306.381433 -59.808936) (xy 306.410898 -59.763087) (xy 306.446587 -59.721898) (xy 306.487775 -59.686207)
			(xy 306.533622 -59.656741) (xy 306.583197 -59.634099) (xy 306.635489 -59.618743) (xy 306.689434 -59.610985)
			(xy 306.716684 -59.610498) (xy 306.744054 -59.610974) (xy 306.798233 -59.618789) (xy 306.850736 -59.634276)
			(xy 306.900483 -59.657116) (xy 306.94645 -59.686838) (xy 306.967382 -59.704478) (xy 306.967636 -59.704732)
			(xy 306.974734 -59.710301) (xy 306.991642 -59.716557) (xy 307.000656 -59.716924) (xy 307.067712 -59.716924)
			(xy 307.076729 -59.716567) (xy 307.093645 -59.710319) (xy 307.100732 -59.704732) (xy 307.100732 -59.704478)
			(xy 307.100986 -59.704478) (xy 307.121919 -59.686837) (xy 307.167887 -59.657113) (xy 307.217633 -59.634267)
			(xy 307.270135 -59.618771) (xy 307.324313 -59.610942) (xy 307.379055 -59.610942) (xy 307.433233 -59.618771)
			(xy 307.485735 -59.634267) (xy 307.535481 -59.657113) (xy 307.581449 -59.686837) (xy 307.602382 -59.704478)
			(xy 307.602636 -59.704732) (xy 307.609734 -59.710301) (xy 307.626642 -59.716557) (xy 307.635656 -59.716924)
			(xy 307.702712 -59.716924) (xy 307.711729 -59.716567) (xy 307.728645 -59.710319) (xy 307.735732 -59.704732)
			(xy 307.735732 -59.704478) (xy 307.735986 -59.704478) (xy 307.75691 -59.686829) (xy 307.802885 -59.657119)
			(xy 307.852635 -59.634285) (xy 307.905137 -59.618797) (xy 307.959314 -59.610971) (xy 307.986684 -59.610498)
			(xy 308.013938 -59.610948) (xy 308.067892 -59.618704) (xy 308.120192 -59.634058) (xy 308.169775 -59.6567)
			(xy 308.215631 -59.686168) (xy 308.256826 -59.721863) (xy 308.292522 -59.763056) (xy 308.321992 -59.808911)
			(xy 308.344636 -59.858493) (xy 308.359993 -59.910793) (xy 308.367751 -59.964746) (xy 308.367751 -60.019254)
			(xy 308.359993 -60.073207) (xy 308.344636 -60.125507) (xy 308.321992 -60.175089) (xy 308.292522 -60.220944)
			(xy 308.256826 -60.262137) (xy 308.215631 -60.297832) (xy 308.169775 -60.3273) (xy 308.120192 -60.349942)
			(xy 308.067892 -60.365296) (xy 308.013938 -60.373052) (xy 307.986684 -60.373514) (xy 307.959314 -60.373054)
			(xy 307.905134 -60.365234) (xy 307.852631 -60.349743) (xy 307.802885 -60.326901) (xy 307.756918 -60.297175)
			(xy 307.735986 -60.279534) (xy 307.735732 -60.27928) (xy 307.728642 -60.273698) (xy 307.711728 -60.267449)
			(xy 307.702712 -60.267088) (xy 307.635656 -60.267088) (xy 307.626642 -60.267474) (xy 307.609725 -60.273702)
			(xy 307.602636 -60.27928) (xy 307.602382 -60.279534) (xy 307.581449 -60.297175) (xy 307.535481 -60.326899)
			(xy 307.485735 -60.349745) (xy 307.433233 -60.365241) (xy 307.379055 -60.37307) (xy 307.324313 -60.37307)
			(xy 307.270135 -60.365241) (xy 307.217633 -60.349745) (xy 307.167887 -60.326899) (xy 307.121919 -60.297175)
			(xy 307.100986 -60.279534) (xy 307.100732 -60.27928) (xy 307.093642 -60.273698) (xy 307.076728 -60.267449)
			(xy 307.067712 -60.267088) (xy 307.000656 -60.267088) (xy 306.991642 -60.267474) (xy 306.974725 -60.273702)
			(xy 306.967636 -60.27928) (xy 306.967636 -60.279534) (xy 306.967382 -60.279534) (xy 306.946434 -60.297153)
			(xy 306.900465 -60.326867) (xy 306.850722 -60.349706) (xy 306.798225 -60.365202) (xy 306.744052 -60.373036)
			(xy 306.716684 -60.373514) (xy 306.689434 -60.373015) (xy 306.635489 -60.365257) (xy 306.583197 -60.349901)
			(xy 306.533622 -60.327259) (xy 306.487775 -60.297793) (xy 306.446587 -60.262102) (xy 306.410898 -60.220913)
			(xy 306.381433 -60.175064) (xy 306.358794 -60.125488) (xy 306.34344 -60.073196) (xy 306.335684 -60.01925)
			(xy 298.366355 -60.01925) (xy 298.360087 -60.633356) (xy 317.996822 -60.633356) (xy 318.000893 -60.577734)
			(xy 318.013019 -60.523297) (xy 318.032942 -60.471206) (xy 318.060238 -60.422571) (xy 318.094324 -60.378428)
			(xy 318.134473 -60.339719) (xy 318.179831 -60.307268) (xy 318.229431 -60.281767) (xy 318.282215 -60.26376)
			(xy 318.337058 -60.25363) (xy 318.392792 -60.251593) (xy 318.448229 -60.257693) (xy 318.502186 -60.271799)
			(xy 318.553515 -60.293611) (xy 318.601121 -60.322665) (xy 318.643989 -60.35834) (xy 318.681206 -60.399877)
			(xy 318.711979 -60.44639) (xy 318.735651 -60.496887) (xy 318.751719 -60.550294) (xy 318.759839 -60.60547)
			(xy 318.760348 -60.633356) (xy 318.759839 -60.661242) (xy 318.751719 -60.716418) (xy 318.735651 -60.769825)
			(xy 318.711979 -60.820322) (xy 318.681206 -60.866835) (xy 318.643989 -60.908372) (xy 318.601121 -60.944047)
			(xy 318.553515 -60.973101) (xy 318.502186 -60.994913) (xy 318.448229 -61.009019) (xy 318.392792 -61.015119)
			(xy 318.337058 -61.013082) (xy 318.282215 -61.002952) (xy 318.229431 -60.984945) (xy 318.179831 -60.959444)
			(xy 318.134473 -60.926993) (xy 318.094324 -60.888284) (xy 318.060238 -60.844141) (xy 318.032942 -60.795506)
			(xy 318.013019 -60.743415) (xy 318.000893 -60.688978) (xy 317.996822 -60.633356) (xy 298.360087 -60.633356)
			(xy 298.351365 -61.487812) (xy 316.504318 -61.487812) (xy 316.508389 -61.43219) (xy 316.520515 -61.377753)
			(xy 316.540438 -61.325662) (xy 316.567734 -61.277027) (xy 316.60182 -61.232884) (xy 316.641969 -61.194175)
			(xy 316.687327 -61.161724) (xy 316.736927 -61.136223) (xy 316.789711 -61.118216) (xy 316.844554 -61.108086)
			(xy 316.900288 -61.106049) (xy 316.955725 -61.112149) (xy 317.009682 -61.126255) (xy 317.061011 -61.148067)
			(xy 317.108617 -61.177121) (xy 317.151485 -61.212796) (xy 317.188702 -61.254333) (xy 317.219475 -61.300846)
			(xy 317.243147 -61.351343) (xy 317.259215 -61.40475) (xy 317.267335 -61.459926) (xy 317.267844 -61.487812)
			(xy 317.267335 -61.515698) (xy 317.259215 -61.570874) (xy 317.243147 -61.624281) (xy 317.219475 -61.674778)
			(xy 317.188702 -61.721291) (xy 317.151485 -61.762828) (xy 317.108617 -61.798503) (xy 317.061011 -61.827557)
			(xy 317.009682 -61.849369) (xy 316.955725 -61.863475) (xy 316.900288 -61.869575) (xy 316.844554 -61.867538)
			(xy 316.789711 -61.857408) (xy 316.736927 -61.839401) (xy 316.687327 -61.8139) (xy 316.641969 -61.781449)
			(xy 316.60182 -61.74274) (xy 316.567734 -61.698597) (xy 316.540438 -61.649962) (xy 316.520515 -61.597871)
			(xy 316.508389 -61.543434) (xy 316.504318 -61.487812) (xy 298.351365 -61.487812) (xy 298.344902 -62.121034)
			(xy 314.442092 -62.121034) (xy 314.446163 -62.065412) (xy 314.458289 -62.010975) (xy 314.478212 -61.958884)
			(xy 314.505508 -61.910249) (xy 314.539594 -61.866106) (xy 314.579743 -61.827397) (xy 314.625101 -61.794946)
			(xy 314.674701 -61.769445) (xy 314.727485 -61.751438) (xy 314.782328 -61.741308) (xy 314.838062 -61.739271)
			(xy 314.893499 -61.745371) (xy 314.947456 -61.759477) (xy 314.998785 -61.781289) (xy 315.046391 -61.810343)
			(xy 315.089259 -61.846018) (xy 315.126476 -61.887555) (xy 315.157249 -61.934068) (xy 315.180921 -61.984565)
			(xy 315.196989 -62.037972) (xy 315.205109 -62.093148) (xy 315.205618 -62.121034) (xy 315.205109 -62.14892)
			(xy 315.196989 -62.204096) (xy 315.180921 -62.257503) (xy 315.157249 -62.308) (xy 315.126476 -62.354513)
			(xy 315.089259 -62.39605) (xy 315.046391 -62.431725) (xy 314.998785 -62.460779) (xy 314.947456 -62.482591)
			(xy 314.893499 -62.496697) (xy 314.838062 -62.502797) (xy 314.782328 -62.50076) (xy 314.727485 -62.49063)
			(xy 314.674701 -62.472623) (xy 314.625101 -62.447122) (xy 314.579743 -62.414671) (xy 314.539594 -62.375962)
			(xy 314.505508 -62.331819) (xy 314.478212 -62.283184) (xy 314.458289 -62.231093) (xy 314.446163 -62.176656)
			(xy 314.442092 -62.121034) (xy 298.344902 -62.121034) (xy 298.333751 -63.21355) (xy 306.320688 -63.21355)
			(xy 306.320688 -63.15905) (xy 306.328444 -63.105104) (xy 306.343799 -63.05281) (xy 306.366439 -63.003235)
			(xy 306.395905 -62.957386) (xy 306.431595 -62.916197) (xy 306.472784 -62.880506) (xy 306.518633 -62.85104)
			(xy 306.568208 -62.8284) (xy 306.620502 -62.813045) (xy 306.674448 -62.805288) (xy 306.701698 -62.804802)
			(xy 306.729068 -62.805269) (xy 306.783247 -62.813086) (xy 306.83575 -62.828575) (xy 306.885497 -62.851417)
			(xy 306.931464 -62.881141) (xy 306.952396 -62.898782) (xy 306.95265 -62.899036) (xy 306.959744 -62.904612)
			(xy 306.976655 -62.910864) (xy 306.98567 -62.911228) (xy 307.052726 -62.911228) (xy 307.061743 -62.910878)
			(xy 307.07866 -62.904625) (xy 307.085746 -62.899036) (xy 307.085746 -62.898782) (xy 307.086 -62.898782)
			(xy 307.106933 -62.881141) (xy 307.152901 -62.851417) (xy 307.202647 -62.828571) (xy 307.255149 -62.813075)
			(xy 307.309327 -62.805246) (xy 307.364069 -62.805246) (xy 307.418247 -62.813075) (xy 307.470749 -62.828571)
			(xy 307.520495 -62.851417) (xy 307.566463 -62.881141) (xy 307.587396 -62.898782) (xy 307.58765 -62.899036)
			(xy 307.594744 -62.904612) (xy 307.611655 -62.910864) (xy 307.62067 -62.911228) (xy 307.687726 -62.911228)
			(xy 307.696743 -62.910878) (xy 307.71366 -62.904625) (xy 307.720746 -62.899036) (xy 307.720746 -62.898782)
			(xy 307.721 -62.898782) (xy 307.741919 -62.881127) (xy 307.787896 -62.851418) (xy 307.837647 -62.828585)
			(xy 307.89015 -62.813098) (xy 307.944328 -62.805274) (xy 307.971698 -62.804802) (xy 307.998952 -62.805245)
			(xy 308.052904 -62.813002) (xy 308.105204 -62.828358) (xy 308.154786 -62.851001) (xy 308.20064 -62.88047)
			(xy 308.241834 -62.916164) (xy 308.277529 -62.957358) (xy 308.306998 -63.003213) (xy 308.329641 -63.052794)
			(xy 308.33946 -63.086234) (xy 311.587386 -63.086234) (xy 311.591457 -63.030612) (xy 311.603583 -62.976175)
			(xy 311.623506 -62.924084) (xy 311.650802 -62.875449) (xy 311.684888 -62.831306) (xy 311.725037 -62.792597)
			(xy 311.770395 -62.760146) (xy 311.819995 -62.734645) (xy 311.872779 -62.716638) (xy 311.927622 -62.706508)
			(xy 311.983356 -62.704471) (xy 312.038793 -62.710571) (xy 312.09275 -62.724677) (xy 312.144079 -62.746489)
			(xy 312.191685 -62.775543) (xy 312.234553 -62.811218) (xy 312.27177 -62.852755) (xy 312.302543 -62.899268)
			(xy 312.326215 -62.949765) (xy 312.342283 -63.003172) (xy 312.350403 -63.058348) (xy 312.350912 -63.086234)
			(xy 312.350403 -63.11412) (xy 312.342283 -63.169296) (xy 312.326215 -63.222703) (xy 312.302543 -63.2732)
			(xy 312.30239 -63.273432) (xy 313.776612 -63.273432) (xy 313.780683 -63.21781) (xy 313.792809 -63.163373)
			(xy 313.812732 -63.111282) (xy 313.840028 -63.062647) (xy 313.874114 -63.018504) (xy 313.914263 -62.979795)
			(xy 313.959621 -62.947344) (xy 314.009221 -62.921843) (xy 314.062005 -62.903836) (xy 314.116848 -62.893706)
			(xy 314.172582 -62.891669) (xy 314.228019 -62.897769) (xy 314.281976 -62.911875) (xy 314.333305 -62.933687)
			(xy 314.380911 -62.962741) (xy 314.423779 -62.998416) (xy 314.460996 -63.039953) (xy 314.491769 -63.086466)
			(xy 314.515441 -63.136963) (xy 314.531509 -63.19037) (xy 314.539629 -63.245546) (xy 314.540138 -63.273432)
			(xy 314.539629 -63.301318) (xy 314.531509 -63.356494) (xy 314.515441 -63.409901) (xy 314.491769 -63.460398)
			(xy 314.460996 -63.506911) (xy 314.423779 -63.548448) (xy 314.380911 -63.584123) (xy 314.333305 -63.613177)
			(xy 314.281976 -63.634989) (xy 314.228019 -63.649095) (xy 314.172582 -63.655195) (xy 314.116848 -63.653158)
			(xy 314.062005 -63.643028) (xy 314.009221 -63.625021) (xy 313.959621 -63.59952) (xy 313.914263 -63.567069)
			(xy 313.874114 -63.52836) (xy 313.840028 -63.484217) (xy 313.812732 -63.435582) (xy 313.792809 -63.383491)
			(xy 313.780683 -63.329054) (xy 313.776612 -63.273432) (xy 312.30239 -63.273432) (xy 312.27177 -63.319713)
			(xy 312.234553 -63.36125) (xy 312.191685 -63.396925) (xy 312.144079 -63.425979) (xy 312.09275 -63.447791)
			(xy 312.038793 -63.461897) (xy 311.983356 -63.467997) (xy 311.927622 -63.46596) (xy 311.872779 -63.45583)
			(xy 311.819995 -63.437823) (xy 311.770395 -63.412322) (xy 311.725037 -63.379871) (xy 311.684888 -63.341162)
			(xy 311.650802 -63.297019) (xy 311.623506 -63.248384) (xy 311.603583 -63.196293) (xy 311.591457 -63.141856)
			(xy 311.587386 -63.086234) (xy 308.33946 -63.086234) (xy 308.344998 -63.105094) (xy 308.352755 -63.159046)
			(xy 308.352755 -63.213554) (xy 308.344998 -63.267506) (xy 308.329641 -63.319806) (xy 308.306998 -63.369387)
			(xy 308.277529 -63.415242) (xy 308.241834 -63.456436) (xy 308.20064 -63.49213) (xy 308.154786 -63.521599)
			(xy 308.105204 -63.544242) (xy 308.052904 -63.559598) (xy 307.998952 -63.567355) (xy 307.971698 -63.567818)
			(xy 307.944327 -63.567373) (xy 307.890146 -63.559553) (xy 307.837642 -63.54406) (xy 307.787895 -63.521213)
			(xy 307.74193 -63.491483) (xy 307.721 -63.473838) (xy 307.720746 -63.473584) (xy 307.713652 -63.468009)
			(xy 307.696741 -63.461756) (xy 307.687726 -63.461392) (xy 307.62067 -63.461392) (xy 307.611652 -63.461737)
			(xy 307.594735 -63.467993) (xy 307.58765 -63.473584) (xy 307.587396 -63.473838) (xy 307.566463 -63.491479)
			(xy 307.520495 -63.521203) (xy 307.470749 -63.544049) (xy 307.418247 -63.559545) (xy 307.364069 -63.567374)
			(xy 307.309327 -63.567374) (xy 307.255149 -63.559545) (xy 307.202647 -63.544049) (xy 307.152901 -63.521203)
			(xy 307.106933 -63.491479) (xy 307.086 -63.473838) (xy 307.085746 -63.473584) (xy 307.078652 -63.468009)
			(xy 307.061741 -63.461756) (xy 307.052726 -63.461392) (xy 306.98567 -63.461392) (xy 306.976652 -63.461737)
			(xy 306.959735 -63.467993) (xy 306.95265 -63.473584) (xy 306.95265 -63.473838) (xy 306.952396 -63.473838)
			(xy 306.931481 -63.491499) (xy 306.885503 -63.521206) (xy 306.835751 -63.544037) (xy 306.783247 -63.559524)
			(xy 306.729068 -63.567347) (xy 306.701698 -63.567818) (xy 306.674448 -63.567312) (xy 306.620502 -63.559555)
			(xy 306.568208 -63.5442) (xy 306.518633 -63.52156) (xy 306.472784 -63.492094) (xy 306.431595 -63.456403)
			(xy 306.395905 -63.415214) (xy 306.366439 -63.369365) (xy 306.343799 -63.31979) (xy 306.328444 -63.267496)
			(xy 306.320688 -63.21355) (xy 298.333751 -63.21355) (xy 298.321476 -64.416178) (xy 298.319952 -64.558418)
			(xy 298.319952 -65.100962) (xy 304.332384 -65.100962) (xy 304.336455 -65.04534) (xy 304.348581 -64.990903)
			(xy 304.368504 -64.938812) (xy 304.3958 -64.890177) (xy 304.429886 -64.846034) (xy 304.470035 -64.807325)
			(xy 304.515393 -64.774874) (xy 304.564993 -64.749373) (xy 304.617777 -64.731366) (xy 304.67262 -64.721236)
			(xy 304.728354 -64.719199) (xy 304.783791 -64.725299) (xy 304.837748 -64.739405) (xy 304.889077 -64.761217)
			(xy 304.936683 -64.790271) (xy 304.979551 -64.825946) (xy 305.016768 -64.867483) (xy 305.047541 -64.913996)
			(xy 305.071213 -64.964493) (xy 305.087281 -65.0179) (xy 305.095401 -65.073076) (xy 305.09591 -65.100962)
			(xy 305.095488 -65.124076) (xy 316.307214 -65.124076) (xy 316.311285 -65.068454) (xy 316.323411 -65.014017)
			(xy 316.343334 -64.961926) (xy 316.37063 -64.913291) (xy 316.404716 -64.869148) (xy 316.444865 -64.830439)
			(xy 316.490223 -64.797988) (xy 316.539823 -64.772487) (xy 316.592607 -64.75448) (xy 316.64745 -64.74435)
			(xy 316.703184 -64.742313) (xy 316.758621 -64.748413) (xy 316.812578 -64.762519) (xy 316.863907 -64.784331)
			(xy 316.911513 -64.813385) (xy 316.954381 -64.84906) (xy 316.991598 -64.890597) (xy 317.022371 -64.93711)
			(xy 317.046043 -64.987607) (xy 317.062111 -65.041014) (xy 317.070231 -65.09619) (xy 317.07074 -65.124076)
			(xy 317.070231 -65.151962) (xy 317.062111 -65.207138) (xy 317.046043 -65.260545) (xy 317.022371 -65.311042)
			(xy 316.991598 -65.357555) (xy 316.954381 -65.399092) (xy 316.911513 -65.434767) (xy 316.863907 -65.463821)
			(xy 316.812578 -65.485633) (xy 316.758621 -65.499739) (xy 316.703184 -65.505839) (xy 316.64745 -65.503802)
			(xy 316.592607 -65.493672) (xy 316.539823 -65.475665) (xy 316.490223 -65.450164) (xy 316.444865 -65.417713)
			(xy 316.404716 -65.379004) (xy 316.37063 -65.334861) (xy 316.343334 -65.286226) (xy 316.323411 -65.234135)
			(xy 316.311285 -65.179698) (xy 316.307214 -65.124076) (xy 305.095488 -65.124076) (xy 305.095401 -65.128848)
			(xy 305.087281 -65.184024) (xy 305.071213 -65.237431) (xy 305.047541 -65.287928) (xy 305.016768 -65.334441)
			(xy 304.979551 -65.375978) (xy 304.936683 -65.411653) (xy 304.889077 -65.440707) (xy 304.837748 -65.462519)
			(xy 304.783791 -65.476625) (xy 304.728354 -65.482725) (xy 304.67262 -65.480688) (xy 304.617777 -65.470558)
			(xy 304.564993 -65.452551) (xy 304.515393 -65.42705) (xy 304.470035 -65.394599) (xy 304.429886 -65.35589)
			(xy 304.3958 -65.311747) (xy 304.368504 -65.263112) (xy 304.348581 -65.211021) (xy 304.336455 -65.156584)
			(xy 304.332384 -65.100962) (xy 298.319952 -65.100962) (xy 298.319952 -65.511426) (xy 298.584872 -65.511426)
			(xy 298.588943 -65.455804) (xy 298.601069 -65.401367) (xy 298.620992 -65.349276) (xy 298.648288 -65.300641)
			(xy 298.682374 -65.256498) (xy 298.722523 -65.217789) (xy 298.767881 -65.185338) (xy 298.817481 -65.159837)
			(xy 298.870265 -65.14183) (xy 298.925108 -65.1317) (xy 298.980842 -65.129663) (xy 299.036279 -65.135763)
			(xy 299.090236 -65.149869) (xy 299.141565 -65.171681) (xy 299.189171 -65.200735) (xy 299.232039 -65.23641)
			(xy 299.269256 -65.277947) (xy 299.300029 -65.32446) (xy 299.323701 -65.374957) (xy 299.339769 -65.428364)
			(xy 299.347889 -65.48354) (xy 299.348398 -65.511426) (xy 299.347889 -65.539312) (xy 299.339769 -65.594488)
			(xy 299.323701 -65.647895) (xy 299.300029 -65.698392) (xy 299.269256 -65.744905) (xy 299.232039 -65.786442)
			(xy 299.189171 -65.822117) (xy 299.141565 -65.851171) (xy 299.090236 -65.872983) (xy 299.036279 -65.887089)
			(xy 298.980842 -65.893189) (xy 298.925108 -65.891152) (xy 298.870265 -65.881022) (xy 298.817481 -65.863015)
			(xy 298.767881 -65.837514) (xy 298.722523 -65.805063) (xy 298.682374 -65.766354) (xy 298.648288 -65.722211)
			(xy 298.620992 -65.673576) (xy 298.601069 -65.621485) (xy 298.588943 -65.567048) (xy 298.584872 -65.511426)
			(xy 298.319952 -65.511426) (xy 298.319952 -67.128949) (xy 298.566598 -67.128949) (xy 298.566598 -67.074451)
			(xy 298.574354 -67.020507) (xy 298.589708 -66.968216) (xy 298.612346 -66.918643) (xy 298.64181 -66.872796)
			(xy 298.677498 -66.831608) (xy 298.718684 -66.795918) (xy 298.76453 -66.766453) (xy 298.814103 -66.743812)
			(xy 298.866394 -66.728457) (xy 298.920337 -66.720699) (xy 298.947586 -66.720212) (xy 298.974956 -66.720683)
			(xy 299.029135 -66.728499) (xy 299.081638 -66.743987) (xy 299.131385 -66.766828) (xy 299.177352 -66.796551)
			(xy 299.198284 -66.814192) (xy 299.198538 -66.814446) (xy 299.205634 -66.820018) (xy 299.222544 -66.826272)
			(xy 299.231558 -66.826638) (xy 299.298614 -66.826638) (xy 299.307631 -66.82628) (xy 299.324547 -66.820032)
			(xy 299.331634 -66.814446) (xy 299.331634 -66.814192) (xy 299.331888 -66.814192) (xy 299.352813 -66.796544)
			(xy 299.398788 -66.766834) (xy 299.448537 -66.744) (xy 299.501039 -66.728511) (xy 299.555216 -66.720685)
			(xy 299.582586 -66.720212) (xy 299.609841 -66.720634) (xy 299.663796 -66.72839) (xy 299.716099 -66.743745)
			(xy 299.765683 -66.766388) (xy 299.811541 -66.795857) (xy 299.852737 -66.831553) (xy 299.888434 -66.872748)
			(xy 299.917905 -66.918605) (xy 299.94055 -66.968188) (xy 299.955907 -67.02049) (xy 299.963665 -67.074445)
			(xy 299.963665 -67.128955) (xy 299.955907 -67.18291) (xy 299.94055 -67.235212) (xy 299.917905 -67.284795)
			(xy 299.888434 -67.330652) (xy 299.852737 -67.371847) (xy 299.811541 -67.407543) (xy 299.765683 -67.437012)
			(xy 299.716099 -67.459655) (xy 299.663796 -67.47501) (xy 299.609841 -67.482766) (xy 299.582586 -67.483228)
			(xy 299.555215 -67.482788) (xy 299.501034 -67.474966) (xy 299.44853 -67.459472) (xy 299.398783 -67.436624)
			(xy 299.352818 -67.406893) (xy 299.331888 -67.389248) (xy 299.331634 -67.388994) (xy 299.324542 -67.383415)
			(xy 299.307629 -67.377164) (xy 299.298614 -67.376802) (xy 299.231558 -67.376802) (xy 299.222544 -67.377187)
			(xy 299.205627 -67.383415) (xy 299.198538 -67.388994) (xy 299.198538 -67.389248) (xy 299.198284 -67.389248)
			(xy 299.177324 -67.406853) (xy 299.13136 -67.436572) (xy 299.08162 -67.459415) (xy 299.029125 -67.474914)
			(xy 298.974953 -67.48275) (xy 298.947586 -67.483228) (xy 298.920337 -67.482701) (xy 298.866394 -67.474943)
			(xy 298.814103 -67.459588) (xy 298.76453 -67.436947) (xy 298.718684 -67.407482) (xy 298.677498 -67.371792)
			(xy 298.64181 -67.330604) (xy 298.612346 -67.284757) (xy 298.589708 -67.235184) (xy 298.574354 -67.182893)
			(xy 298.566598 -67.128949) (xy 298.319952 -67.128949) (xy 298.319952 -67.488054) (xy 302.979072 -67.488054)
			(xy 302.983143 -67.432432) (xy 302.995269 -67.377995) (xy 303.015192 -67.325904) (xy 303.042488 -67.277269)
			(xy 303.076574 -67.233126) (xy 303.116723 -67.194417) (xy 303.162081 -67.161966) (xy 303.211681 -67.136465)
			(xy 303.264465 -67.118458) (xy 303.319308 -67.108328) (xy 303.375042 -67.106291) (xy 303.430479 -67.112391)
			(xy 303.484436 -67.126497) (xy 303.535765 -67.148309) (xy 303.583371 -67.177363) (xy 303.626239 -67.213038)
			(xy 303.663456 -67.254575) (xy 303.694229 -67.301088) (xy 303.717901 -67.351585) (xy 303.733969 -67.404992)
			(xy 303.742089 -67.460168) (xy 303.742598 -67.488054) (xy 303.742089 -67.51594) (xy 303.738904 -67.537584)
			(xy 304.27117 -67.537584) (xy 304.275241 -67.481962) (xy 304.287367 -67.427525) (xy 304.30729 -67.375434)
			(xy 304.334586 -67.326799) (xy 304.368672 -67.282656) (xy 304.408821 -67.243947) (xy 304.454179 -67.211496)
			(xy 304.503779 -67.185995) (xy 304.556563 -67.167988) (xy 304.611406 -67.157858) (xy 304.66714 -67.155821)
			(xy 304.722577 -67.161921) (xy 304.776534 -67.176027) (xy 304.827863 -67.197839) (xy 304.875469 -67.226893)
			(xy 304.918337 -67.262568) (xy 304.955554 -67.304105) (xy 304.986327 -67.350618) (xy 305.009999 -67.401115)
			(xy 305.026067 -67.454522) (xy 305.034187 -67.509698) (xy 305.034696 -67.537584) (xy 305.034187 -67.56547)
			(xy 305.030142 -67.592956) (xy 305.545234 -67.592956) (xy 305.549305 -67.537334) (xy 305.561431 -67.482897)
			(xy 305.581354 -67.430806) (xy 305.60865 -67.382171) (xy 305.642736 -67.338028) (xy 305.682885 -67.299319)
			(xy 305.728243 -67.266868) (xy 305.777843 -67.241367) (xy 305.830627 -67.22336) (xy 305.88547 -67.21323)
			(xy 305.941204 -67.211193) (xy 305.996641 -67.217293) (xy 306.050598 -67.231399) (xy 306.101927 -67.253211)
			(xy 306.149533 -67.282265) (xy 306.192401 -67.31794) (xy 306.229618 -67.359477) (xy 306.260391 -67.40599)
			(xy 306.284063 -67.456487) (xy 306.300131 -67.509894) (xy 306.308248 -67.565047) (xy 308.646616 -67.565047)
			(xy 308.646616 -67.510553) (xy 308.654371 -67.456612) (xy 308.669724 -67.404325) (xy 308.692361 -67.354754)
			(xy 308.721822 -67.30891) (xy 308.757507 -67.267724) (xy 308.79869 -67.232036) (xy 308.844533 -67.202572)
			(xy 308.894102 -67.179932) (xy 308.946389 -67.164576) (xy 309.000329 -67.156818) (xy 309.027576 -67.15633)
			(xy 309.054946 -67.156803) (xy 309.109125 -67.164618) (xy 309.161628 -67.180105) (xy 309.211375 -67.202945)
			(xy 309.257342 -67.232669) (xy 309.278274 -67.25031) (xy 309.278528 -67.250564) (xy 309.285626 -67.256134)
			(xy 309.302534 -67.262389) (xy 309.311548 -67.262756) (xy 309.378604 -67.262756) (xy 309.387622 -67.26241)
			(xy 309.404539 -67.256156) (xy 309.411624 -67.250564) (xy 309.411624 -67.25031) (xy 309.411878 -67.25031)
			(xy 309.432809 -67.232669) (xy 309.478782 -67.202957) (xy 309.52853 -67.180122) (xy 309.581031 -67.164631)
			(xy 309.635207 -67.156804) (xy 309.662576 -67.15633) (xy 309.689833 -67.156715) (xy 309.743792 -67.16447)
			(xy 309.796098 -67.179826) (xy 309.845686 -67.202469) (xy 309.891547 -67.23194) (xy 309.932746 -67.267637)
			(xy 309.968446 -67.308834) (xy 309.997919 -67.354693) (xy 310.020566 -67.40428) (xy 310.035925 -67.456585)
			(xy 310.043683 -67.510543) (xy 310.043683 -67.565057) (xy 310.035925 -67.619015) (xy 310.020566 -67.67132)
			(xy 309.997919 -67.720907) (xy 309.968446 -67.766766) (xy 309.932746 -67.807963) (xy 309.891547 -67.84366)
			(xy 309.845686 -67.873131) (xy 309.796098 -67.895774) (xy 309.743792 -67.91113) (xy 309.689833 -67.918885)
			(xy 309.662576 -67.919346) (xy 309.635205 -67.918907) (xy 309.581024 -67.911085) (xy 309.52852 -67.89559)
			(xy 309.478773 -67.872742) (xy 309.432808 -67.843011) (xy 309.411878 -67.825366) (xy 309.411624 -67.825112)
			(xy 309.404534 -67.819531) (xy 309.38762 -67.81328) (xy 309.378604 -67.81292) (xy 309.311548 -67.81292)
			(xy 309.302533 -67.813296) (xy 309.285616 -67.81953) (xy 309.278528 -67.825112) (xy 309.278528 -67.825366)
			(xy 309.278274 -67.825366) (xy 309.25732 -67.842979) (xy 309.211354 -67.872696) (xy 309.161612 -67.895537)
			(xy 309.109116 -67.911034) (xy 309.054944 -67.918869) (xy 309.027576 -67.919346) (xy 309.000329 -67.918782)
			(xy 308.946389 -67.911024) (xy 308.894102 -67.895668) (xy 308.844533 -67.873028) (xy 308.79869 -67.843564)
			(xy 308.757507 -67.807876) (xy 308.721822 -67.76669) (xy 308.692361 -67.720846) (xy 308.669724 -67.671275)
			(xy 308.654371 -67.618988) (xy 308.646616 -67.565047) (xy 306.308248 -67.565047) (xy 306.308251 -67.56507)
			(xy 306.30876 -67.592956) (xy 306.308251 -67.620842) (xy 306.300131 -67.676018) (xy 306.284063 -67.729425)
			(xy 306.260391 -67.779922) (xy 306.229618 -67.826435) (xy 306.192401 -67.867972) (xy 306.149533 -67.903647)
			(xy 306.101927 -67.932701) (xy 306.050598 -67.954513) (xy 305.996641 -67.968619) (xy 305.941204 -67.974719)
			(xy 305.88547 -67.972682) (xy 305.830627 -67.962552) (xy 305.777843 -67.944545) (xy 305.728243 -67.919044)
			(xy 305.682885 -67.886593) (xy 305.642736 -67.847884) (xy 305.60865 -67.803741) (xy 305.581354 -67.755106)
			(xy 305.561431 -67.703015) (xy 305.549305 -67.648578) (xy 305.545234 -67.592956) (xy 305.030142 -67.592956)
			(xy 305.026067 -67.620646) (xy 305.009999 -67.674053) (xy 304.986327 -67.72455) (xy 304.955554 -67.771063)
			(xy 304.918337 -67.8126) (xy 304.875469 -67.848275) (xy 304.827863 -67.877329) (xy 304.776534 -67.899141)
			(xy 304.722577 -67.913247) (xy 304.66714 -67.919347) (xy 304.611406 -67.91731) (xy 304.556563 -67.90718)
			(xy 304.503779 -67.889173) (xy 304.454179 -67.863672) (xy 304.408821 -67.831221) (xy 304.368672 -67.792512)
			(xy 304.334586 -67.748369) (xy 304.30729 -67.699734) (xy 304.287367 -67.647643) (xy 304.275241 -67.593206)
			(xy 304.27117 -67.537584) (xy 303.738904 -67.537584) (xy 303.733969 -67.571116) (xy 303.717901 -67.624523)
			(xy 303.694229 -67.67502) (xy 303.663456 -67.721533) (xy 303.626239 -67.76307) (xy 303.583371 -67.798745)
			(xy 303.535765 -67.827799) (xy 303.484436 -67.849611) (xy 303.430479 -67.863717) (xy 303.375042 -67.869817)
			(xy 303.319308 -67.86778) (xy 303.264465 -67.85765) (xy 303.211681 -67.839643) (xy 303.162081 -67.814142)
			(xy 303.116723 -67.781691) (xy 303.076574 -67.742982) (xy 303.042488 -67.698839) (xy 303.015192 -67.650204)
			(xy 302.995269 -67.598113) (xy 302.983143 -67.543676) (xy 302.979072 -67.488054) (xy 298.319952 -67.488054)
			(xy 298.319952 -68.36791) (xy 298.318428 -68.419218) (xy 298.309719 -68.586604) (xy 300.825154 -68.586604)
			(xy 300.825609 -68.559233) (xy 300.833428 -68.505053) (xy 300.848919 -68.452549) (xy 300.871763 -68.402803)
			(xy 300.901491 -68.356837) (xy 300.919134 -68.335906) (xy 300.919388 -68.335652) (xy 300.924958 -68.328554)
			(xy 300.931215 -68.311646) (xy 300.93158 -68.302632) (xy 300.93158 -68.235576) (xy 300.931239 -68.226557)
			(xy 300.924981 -68.20964) (xy 300.919388 -68.202556) (xy 300.919134 -68.202556) (xy 300.919134 -68.202302)
			(xy 300.901488 -68.181376) (xy 300.871776 -68.135402) (xy 300.848941 -68.085653) (xy 300.833451 -68.033151)
			(xy 300.825626 -67.978974) (xy 300.825154 -67.951604) (xy 300.825681 -67.924355) (xy 300.833436 -67.87041)
			(xy 300.848789 -67.818119) (xy 300.871427 -67.768544) (xy 300.900889 -67.722695) (xy 300.936576 -67.681506)
			(xy 300.977762 -67.645815) (xy 301.023607 -67.616347) (xy 301.073179 -67.593704) (xy 301.125469 -67.578345)
			(xy 301.179413 -67.570584) (xy 301.206662 -67.570096) (xy 301.232977 -67.570523) (xy 301.285108 -67.577767)
			(xy 301.335751 -67.592094) (xy 301.38395 -67.613234) (xy 301.428792 -67.640787) (xy 301.46943 -67.674232)
			(xy 301.487586 -67.693286) (xy 301.495113 -67.700681) (xy 301.514389 -67.70921) (xy 301.524924 -67.709796)
			(xy 301.5996 -67.709796) (xy 301.610151 -67.709281) (xy 301.629447 -67.700736) (xy 301.636938 -67.693286)
			(xy 301.655079 -67.674216) (xy 301.695712 -67.640761) (xy 301.740556 -67.613204) (xy 301.788759 -67.592068)
			(xy 301.839409 -67.577754) (xy 301.891545 -67.570533) (xy 301.917862 -67.570096) (xy 301.945231 -67.570585)
			(xy 301.999409 -67.578398) (xy 302.051912 -67.593881) (xy 302.101659 -67.616718) (xy 302.147627 -67.646437)
			(xy 302.16856 -67.664076) (xy 302.168814 -67.66433) (xy 302.17589 -67.669932) (xy 302.192815 -67.676168)
			(xy 302.201834 -67.676522) (xy 302.26889 -67.676522) (xy 302.277906 -67.676155) (xy 302.294823 -67.669914)
			(xy 302.30191 -67.66433) (xy 302.30191 -67.664076) (xy 302.302164 -67.664076) (xy 302.323096 -67.646437)
			(xy 302.369069 -67.616726) (xy 302.418817 -67.59389) (xy 302.471317 -67.578399) (xy 302.525493 -67.57057)
			(xy 302.552862 -67.570096) (xy 302.580114 -67.570591) (xy 302.634064 -67.578343) (xy 302.686362 -67.593694)
			(xy 302.735942 -67.616332) (xy 302.781795 -67.645797) (xy 302.822989 -67.681487) (xy 302.858683 -67.722677)
			(xy 302.888151 -67.768528) (xy 302.910794 -67.818106) (xy 302.92615 -67.870403) (xy 302.933907 -67.924352)
			(xy 302.93437 -67.951604) (xy 302.933914 -67.978975) (xy 302.926095 -68.033154) (xy 302.910604 -68.085658)
			(xy 302.88776 -68.135405) (xy 302.858033 -68.181371) (xy 302.84039 -68.202302) (xy 302.840136 -68.202556)
			(xy 302.834554 -68.209645) (xy 302.828306 -68.22656) (xy 302.827944 -68.235576) (xy 302.827944 -68.302632)
			(xy 302.828276 -68.311652) (xy 302.83454 -68.328569) (xy 302.840136 -68.335652) (xy 302.84039 -68.335652)
			(xy 302.84039 -68.335906) (xy 302.858044 -68.356826) (xy 302.887754 -68.402802) (xy 302.910587 -68.452553)
			(xy 302.926075 -68.505056) (xy 302.933898 -68.559234) (xy 302.93437 -68.586604) (xy 302.933948 -68.613859)
			(xy 302.92619 -68.667813) (xy 302.910831 -68.720114) (xy 302.894199 -68.75653) (xy 306.370228 -68.75653)
			(xy 306.370705 -68.72916) (xy 306.378519 -68.674981) (xy 306.394005 -68.622478) (xy 306.416845 -68.572731)
			(xy 306.446567 -68.526764) (xy 306.464208 -68.505832) (xy 306.464462 -68.505578) (xy 306.470071 -68.498507)
			(xy 306.476303 -68.481578) (xy 306.476654 -68.472558) (xy 306.476654 -68.405502) (xy 306.476306 -68.396484)
			(xy 306.470053 -68.379567) (xy 306.464462 -68.372482) (xy 306.464208 -68.372482) (xy 306.464208 -68.372228)
			(xy 306.44657 -68.351295) (xy 306.416858 -68.305323) (xy 306.394021 -68.255575) (xy 306.37853 -68.203075)
			(xy 306.370702 -68.148899) (xy 306.370228 -68.12153) (xy 306.370683 -68.094276) (xy 306.378437 -68.040323)
			(xy 306.393791 -67.988023) (xy 306.416433 -67.938441) (xy 306.445901 -67.892586) (xy 306.481596 -67.851392)
			(xy 306.52279 -67.815697) (xy 306.568646 -67.78623) (xy 306.618229 -67.763589) (xy 306.670529 -67.748236)
			(xy 306.724482 -67.740483) (xy 306.751736 -67.740022) (xy 306.779107 -67.740462) (xy 306.833288 -67.748285)
			(xy 306.885791 -67.76378) (xy 306.935538 -67.786628) (xy 306.981503 -67.816358) (xy 307.002434 -67.834002)
			(xy 307.002688 -67.834256) (xy 307.009769 -67.83985) (xy 307.02669 -67.846091) (xy 307.035708 -67.846448)
			(xy 307.102764 -67.846448) (xy 307.11178 -67.846085) (xy 307.128698 -67.839843) (xy 307.135784 -67.834256)
			(xy 307.135784 -67.834002) (xy 307.136038 -67.834002) (xy 307.156983 -67.816379) (xy 307.202952 -67.786665)
			(xy 307.252696 -67.763825) (xy 307.305194 -67.748331) (xy 307.359368 -67.740498) (xy 307.386736 -67.740022)
			(xy 307.413051 -67.740458) (xy 307.465181 -67.747699) (xy 307.515825 -67.762023) (xy 307.564024 -67.783162)
			(xy 307.608867 -67.810713) (xy 307.649505 -67.844158) (xy 307.66766 -67.863212) (xy 307.675193 -67.8706)
			(xy 307.694464 -67.879132) (xy 307.704998 -67.879722) (xy 307.779674 -67.879722) (xy 307.790223 -67.879186)
			(xy 307.809518 -67.870655) (xy 307.817012 -67.863212) (xy 307.835171 -67.84416) (xy 307.8758 -67.810702)
			(xy 307.920639 -67.783142) (xy 307.968839 -67.762003) (xy 308.019486 -67.747685) (xy 308.07162 -67.74046)
			(xy 308.097936 -67.740022) (xy 308.12519 -67.740444) (xy 308.179141 -67.748207) (xy 308.231439 -67.763568)
			(xy 308.281018 -67.786215) (xy 308.32687 -67.815688) (xy 308.36806 -67.851386) (xy 308.403751 -67.892583)
			(xy 308.433216 -67.93844) (xy 308.455855 -67.988023) (xy 308.471207 -68.040324) (xy 308.47896 -68.094276)
			(xy 308.479444 -68.12153) (xy 308.479009 -68.148902) (xy 308.471186 -68.203082) (xy 308.45569 -68.255586)
			(xy 308.432841 -68.305333) (xy 308.403109 -68.351298) (xy 308.385464 -68.372228) (xy 308.38521 -68.372482)
			(xy 308.379626 -68.37957) (xy 308.373377 -68.396486) (xy 308.373018 -68.405502) (xy 308.373018 -68.472558)
			(xy 308.373391 -68.481573) (xy 308.379627 -68.498491) (xy 308.38521 -68.505578) (xy 308.385464 -68.505578)
			(xy 308.385464 -68.505832) (xy 308.403079 -68.526784) (xy 308.432796 -68.57275) (xy 308.455637 -68.622493)
			(xy 308.471133 -68.674989) (xy 308.478967 -68.729162) (xy 308.479444 -68.75653) (xy 308.47895 -68.78378)
			(xy 308.471191 -68.837726) (xy 308.455833 -68.890018) (xy 308.433191 -68.939593) (xy 308.403725 -68.985442)
			(xy 308.368035 -69.026631) (xy 308.326847 -69.062322) (xy 308.280999 -69.091789) (xy 308.231424 -69.114431)
			(xy 308.179132 -69.129789) (xy 308.125186 -69.13755) (xy 308.097936 -69.138038) (xy 308.07162 -69.137633)
			(xy 308.019488 -69.130388) (xy 307.968843 -69.116058) (xy 307.920644 -69.094914) (xy 307.875802 -69.067356)
			(xy 307.835166 -69.033905) (xy 307.817012 -69.014848) (xy 307.809481 -69.007457) (xy 307.790208 -68.998925)
			(xy 307.779674 -68.998338) (xy 307.704998 -68.998338) (xy 307.694445 -68.998841) (xy 307.675149 -69.007393)
			(xy 307.66766 -69.014848) (xy 307.649526 -69.033925) (xy 307.608891 -69.067378) (xy 307.564046 -69.094933)
			(xy 307.515841 -69.116068) (xy 307.46519 -69.130381) (xy 307.413053 -69.137602) (xy 307.386736 -69.138038)
			(xy 307.359366 -69.137566) (xy 307.305186 -69.129752) (xy 307.252683 -69.114265) (xy 307.202936 -69.091424)
			(xy 307.156969 -69.0617) (xy 307.136038 -69.044058) (xy 307.135784 -69.043804) (xy 307.128706 -69.038205)
			(xy 307.111783 -69.031966) (xy 307.102764 -69.031612) (xy 307.035708 -69.031612) (xy 307.026691 -69.03197)
			(xy 307.009774 -69.038217) (xy 307.002688 -69.043804) (xy 307.002688 -69.044058) (xy 307.002434 -69.044058)
			(xy 306.981495 -69.061688) (xy 306.935524 -69.091403) (xy 306.885779 -69.114241) (xy 306.83328 -69.129734)
			(xy 306.779105 -69.137564) (xy 306.751736 -69.138038) (xy 306.724485 -69.137511) (xy 306.670538 -69.12976)
			(xy 306.618243 -69.11441) (xy 306.568665 -69.091774) (xy 306.522814 -69.062312) (xy 306.481621 -69.026625)
			(xy 306.445927 -68.985439) (xy 306.416458 -68.939593) (xy 306.393813 -68.890018) (xy 306.378454 -68.837726)
			(xy 306.370693 -68.783781) (xy 306.370228 -68.75653) (xy 302.894199 -68.75653) (xy 302.888186 -68.769697)
			(xy 302.858714 -68.815552) (xy 302.823015 -68.856745) (xy 302.781818 -68.892439) (xy 302.73596 -68.921906)
			(xy 302.686375 -68.944546) (xy 302.634072 -68.959899) (xy 302.580117 -68.967651) (xy 302.552862 -68.968112)
			(xy 302.525493 -68.967607) (xy 302.471316 -68.959798) (xy 302.418813 -68.944318) (xy 302.369066 -68.921485)
			(xy 302.323097 -68.891769) (xy 302.302164 -68.874132) (xy 302.30191 -68.873878) (xy 302.294827 -68.868287)
			(xy 302.277907 -68.862044) (xy 302.26889 -68.861686) (xy 302.201834 -68.861686) (xy 302.192819 -68.862062)
			(xy 302.175902 -68.868297) (xy 302.168814 -68.873878) (xy 302.168814 -68.874132) (xy 302.16856 -68.874132)
			(xy 302.14762 -68.891761) (xy 302.101649 -68.921474) (xy 302.051903 -68.944311) (xy 301.999405 -68.959804)
			(xy 301.945231 -68.967636) (xy 301.917862 -68.968112) (xy 301.891547 -68.967666) (xy 301.839418 -68.960426)
			(xy 301.788775 -68.946103) (xy 301.740576 -68.924966) (xy 301.695733 -68.897417) (xy 301.655094 -68.863975)
			(xy 301.636938 -68.844922) (xy 301.629401 -68.837538) (xy 301.610133 -68.829003) (xy 301.5996 -68.828412)
			(xy 301.524924 -68.828412) (xy 301.514374 -68.828937) (xy 301.495078 -68.837475) (xy 301.487586 -68.844922)
			(xy 301.469435 -68.863982) (xy 301.428803 -68.897437) (xy 301.383962 -68.924995) (xy 301.335761 -68.946133)
			(xy 301.285113 -68.96045) (xy 301.232978 -68.967674) (xy 301.206662 -68.968112) (xy 301.17941 -68.967658)
			(xy 301.125461 -68.959896) (xy 301.073166 -68.944536) (xy 301.023589 -68.921891) (xy 300.977739 -68.892421)
			(xy 300.936549 -68.856726) (xy 300.900859 -68.815534) (xy 300.871393 -68.769681) (xy 300.848752 -68.720102)
			(xy 300.833397 -68.667805) (xy 300.82564 -68.613856) (xy 300.825154 -68.586604) (xy 298.309719 -68.586604)
			(xy 298.155223 -71.555864) (xy 303.394362 -71.555864) (xy 303.398433 -71.500242) (xy 303.410559 -71.445805)
			(xy 303.430482 -71.393714) (xy 303.457778 -71.345079) (xy 303.491864 -71.300936) (xy 303.532013 -71.262227)
			(xy 303.577371 -71.229776) (xy 303.626971 -71.204275) (xy 303.679755 -71.186268) (xy 303.734598 -71.176138)
			(xy 303.790332 -71.174101) (xy 303.845769 -71.180201) (xy 303.899726 -71.194307) (xy 303.951055 -71.216119)
			(xy 303.998661 -71.245173) (xy 304.041529 -71.280848) (xy 304.078746 -71.322385) (xy 304.109519 -71.368898)
			(xy 304.133191 -71.419395) (xy 304.149259 -71.472802) (xy 304.157379 -71.527978) (xy 304.157888 -71.555864)
			(xy 304.157379 -71.58375) (xy 304.15154 -71.623428) (xy 304.903376 -71.623428) (xy 304.907447 -71.567806)
			(xy 304.919573 -71.513369) (xy 304.939496 -71.461278) (xy 304.966792 -71.412643) (xy 305.000878 -71.3685)
			(xy 305.041027 -71.329791) (xy 305.086385 -71.29734) (xy 305.135985 -71.271839) (xy 305.188769 -71.253832)
			(xy 305.243612 -71.243702) (xy 305.299346 -71.241665) (xy 305.354783 -71.247765) (xy 305.40874 -71.261871)
			(xy 305.460069 -71.283683) (xy 305.507675 -71.312737) (xy 305.550543 -71.348412) (xy 305.58776 -71.389949)
			(xy 305.618533 -71.436462) (xy 305.642205 -71.486959) (xy 305.658273 -71.540366) (xy 305.666393 -71.595542)
			(xy 305.666902 -71.623428) (xy 305.666393 -71.651314) (xy 305.658273 -71.70649) (xy 305.642205 -71.759897)
			(xy 305.618533 -71.810394) (xy 305.58776 -71.856907) (xy 305.550543 -71.898444) (xy 305.507675 -71.934119)
			(xy 305.460069 -71.963173) (xy 305.40874 -71.984985) (xy 305.354783 -71.999091) (xy 305.299346 -72.005191)
			(xy 305.243612 -72.003154) (xy 305.188769 -71.993024) (xy 305.135985 -71.975017) (xy 305.086385 -71.949516)
			(xy 305.041027 -71.917065) (xy 305.000878 -71.878356) (xy 304.966792 -71.834213) (xy 304.939496 -71.785578)
			(xy 304.919573 -71.733487) (xy 304.907447 -71.67905) (xy 304.903376 -71.623428) (xy 304.15154 -71.623428)
			(xy 304.149259 -71.638926) (xy 304.133191 -71.692333) (xy 304.109519 -71.74283) (xy 304.078746 -71.789343)
			(xy 304.041529 -71.83088) (xy 303.998661 -71.866555) (xy 303.951055 -71.895609) (xy 303.899726 -71.917421)
			(xy 303.845769 -71.931527) (xy 303.790332 -71.937627) (xy 303.734598 -71.93559) (xy 303.679755 -71.92546)
			(xy 303.626971 -71.907453) (xy 303.577371 -71.881952) (xy 303.532013 -71.849501) (xy 303.491864 -71.810792)
			(xy 303.457778 -71.766649) (xy 303.430482 -71.718014) (xy 303.410559 -71.665923) (xy 303.398433 -71.611486)
			(xy 303.394362 -71.555864) (xy 298.155223 -71.555864) (xy 297.917108 -76.132182) (xy 297.902884 -76.40574)
			(xy 297.883072 -76.786486) (xy 297.877484 -76.894944) (xy 297.872912 -76.982828) (xy 297.873155 -76.991181)
			(xy 297.878468 -77.007017) (xy 297.883326 -77.013816) (xy 297.886882 -77.018388) (xy 297.907964 -77.035914)
			(xy 297.909234 -77.03693) (xy 297.955462 -77.075284) (xy 297.961587 -77.079654) (xy 297.97566 -77.084961)
			(xy 297.983148 -77.085698) (xy 297.99407 -77.085698) (xy 297.999658 -77.084428) (xy 298.01797 -77.080552)
			(xy 298.055121 -77.075971) (xy 298.073826 -77.075284) (xy 298.086272 -77.075284) (xy 298.113417 -77.075924)
			(xy 298.16712 -77.083942) (xy 298.219143 -77.099493) (xy 298.268436 -77.122263) (xy 298.314002 -77.151791)
			(xy 298.354922 -77.187481) (xy 298.390369 -77.228612) (xy 298.419626 -77.274353) (xy 298.442103 -77.32378)
			(xy 298.457344 -77.375894) (xy 298.465044 -77.429643) (xy 298.465494 -77.456792) (xy 298.465031 -77.484045)
			(xy 298.457275 -77.537996) (xy 298.44192 -77.590294) (xy 298.419277 -77.639874) (xy 298.389809 -77.685727)
			(xy 298.354115 -77.72692) (xy 298.312922 -77.762613) (xy 298.267069 -77.79208) (xy 298.217488 -77.814722)
			(xy 298.209851 -77.816964) (xy 299.312836 -77.816964) (xy 299.316907 -77.761342) (xy 299.329033 -77.706905)
			(xy 299.348956 -77.654814) (xy 299.376252 -77.606179) (xy 299.410338 -77.562036) (xy 299.450487 -77.523327)
			(xy 299.495845 -77.490876) (xy 299.545445 -77.465375) (xy 299.598229 -77.447368) (xy 299.653072 -77.437238)
			(xy 299.708806 -77.435201) (xy 299.764243 -77.441301) (xy 299.8182 -77.455407) (xy 299.869529 -77.477219)
			(xy 299.917135 -77.506273) (xy 299.960003 -77.541948) (xy 299.99722 -77.583485) (xy 300.027993 -77.629998)
			(xy 300.051665 -77.680495) (xy 300.067733 -77.733902) (xy 300.075853 -77.789078) (xy 300.076362 -77.816964)
			(xy 300.075853 -77.84485) (xy 300.067733 -77.900026) (xy 300.051665 -77.953433) (xy 300.027993 -78.00393)
			(xy 299.99722 -78.050443) (xy 299.960003 -78.09198) (xy 299.917135 -78.127655) (xy 299.869529 -78.156709)
			(xy 299.8182 -78.178521) (xy 299.764243 -78.192627) (xy 299.708806 -78.198727) (xy 299.653072 -78.19669)
			(xy 299.598229 -78.18656) (xy 299.545445 -78.168553) (xy 299.495845 -78.143052) (xy 299.450487 -78.110601)
			(xy 299.410338 -78.071892) (xy 299.376252 -78.027749) (xy 299.348956 -77.979114) (xy 299.329033 -77.927023)
			(xy 299.316907 -77.872586) (xy 299.312836 -77.816964) (xy 298.209851 -77.816964) (xy 298.16519 -77.830076)
			(xy 298.111239 -77.837832) (xy 298.083986 -77.8383) (xy 298.083224 -77.8383) (xy 298.052519 -77.837683)
			(xy 297.991902 -77.827854) (xy 297.962574 -77.818742) (xy 297.958764 -77.817472) (xy 297.944794 -77.814678)
			(xy 297.932094 -77.815694) (xy 297.918886 -77.820774) (xy 297.9166 -77.82179) (xy 297.874944 -77.84973)
			(xy 297.847258 -77.868272) (xy 297.837966 -77.875028) (xy 297.826202 -77.894734) (xy 297.824652 -77.906118)
			(xy 297.824652 -77.90815) (xy 297.779618 -78.773274) (xy 299.771306 -78.773274) (xy 299.775377 -78.717652)
			(xy 299.787503 -78.663215) (xy 299.807426 -78.611124) (xy 299.834722 -78.562489) (xy 299.868808 -78.518346)
			(xy 299.908957 -78.479637) (xy 299.954315 -78.447186) (xy 300.003915 -78.421685) (xy 300.056699 -78.403678)
			(xy 300.111542 -78.393548) (xy 300.167276 -78.391511) (xy 300.222713 -78.397611) (xy 300.27667 -78.411717)
			(xy 300.327999 -78.433529) (xy 300.375605 -78.462583) (xy 300.418473 -78.498258) (xy 300.45569 -78.539795)
			(xy 300.486463 -78.586308) (xy 300.510135 -78.636805) (xy 300.526203 -78.690212) (xy 300.534323 -78.745388)
			(xy 300.534832 -78.773274) (xy 300.534323 -78.80116) (xy 300.526203 -78.856336) (xy 300.510135 -78.909743)
			(xy 300.486463 -78.96024) (xy 300.45569 -79.006753) (xy 300.418473 -79.04829) (xy 300.375605 -79.083965)
			(xy 300.327999 -79.113019) (xy 300.27667 -79.134831) (xy 300.222713 -79.148937) (xy 300.167276 -79.155037)
			(xy 300.111542 -79.153) (xy 300.056699 -79.14287) (xy 300.003915 -79.124863) (xy 299.954315 -79.099362)
			(xy 299.908957 -79.066911) (xy 299.868808 -79.028202) (xy 299.834722 -78.984059) (xy 299.807426 -78.935424)
			(xy 299.787503 -78.883333) (xy 299.775377 -78.828896) (xy 299.771306 -78.773274) (xy 297.779618 -78.773274)
			(xy 297.752355 -79.297022) (xy 298.841412 -79.297022) (xy 298.845483 -79.2414) (xy 298.857609 -79.186963)
			(xy 298.877532 -79.134872) (xy 298.904828 -79.086237) (xy 298.938914 -79.042094) (xy 298.979063 -79.003385)
			(xy 299.024421 -78.970934) (xy 299.074021 -78.945433) (xy 299.126805 -78.927426) (xy 299.181648 -78.917296)
			(xy 299.237382 -78.915259) (xy 299.292819 -78.921359) (xy 299.346776 -78.935465) (xy 299.398105 -78.957277)
			(xy 299.445711 -78.986331) (xy 299.488579 -79.022006) (xy 299.525796 -79.063543) (xy 299.556569 -79.110056)
			(xy 299.580241 -79.160553) (xy 299.596309 -79.21396) (xy 299.604429 -79.269136) (xy 299.604938 -79.297022)
			(xy 299.604429 -79.324908) (xy 299.596309 -79.380084) (xy 299.580241 -79.433491) (xy 299.556569 -79.483988)
			(xy 299.525796 -79.530501) (xy 299.488579 -79.572038) (xy 299.445711 -79.607713) (xy 299.398105 -79.636767)
			(xy 299.346776 -79.658579) (xy 299.292819 -79.672685) (xy 299.237382 -79.678785) (xy 299.181648 -79.676748)
			(xy 299.126805 -79.666618) (xy 299.074021 -79.648611) (xy 299.024421 -79.62311) (xy 298.979063 -79.590659)
			(xy 298.938914 -79.55195) (xy 298.904828 -79.507807) (xy 298.877532 -79.459172) (xy 298.857609 -79.407081)
			(xy 298.845483 -79.352644) (xy 298.841412 -79.297022) (xy 297.752355 -79.297022) (xy 297.701372 -80.276446)
			(xy 299.688248 -80.276446) (xy 299.692319 -80.220824) (xy 299.704445 -80.166387) (xy 299.724368 -80.114296)
			(xy 299.751664 -80.065661) (xy 299.78575 -80.021518) (xy 299.825899 -79.982809) (xy 299.871257 -79.950358)
			(xy 299.920857 -79.924857) (xy 299.973641 -79.90685) (xy 300.028484 -79.89672) (xy 300.084218 -79.894683)
			(xy 300.139655 -79.900783) (xy 300.193612 -79.914889) (xy 300.244941 -79.936701) (xy 300.292547 -79.965755)
			(xy 300.335415 -80.00143) (xy 300.351969 -80.019906) (xy 304.700684 -80.019906) (xy 304.704755 -79.964284)
			(xy 304.716881 -79.909847) (xy 304.736804 -79.857756) (xy 304.7641 -79.809121) (xy 304.798186 -79.764978)
			(xy 304.838335 -79.726269) (xy 304.883693 -79.693818) (xy 304.933293 -79.668317) (xy 304.986077 -79.65031)
			(xy 305.04092 -79.64018) (xy 305.096654 -79.638143) (xy 305.152091 -79.644243) (xy 305.206048 -79.658349)
			(xy 305.257377 -79.680161) (xy 305.304983 -79.709215) (xy 305.347851 -79.74489) (xy 305.385068 -79.786427)
			(xy 305.415841 -79.83294) (xy 305.439513 -79.883437) (xy 305.455581 -79.936844) (xy 305.463701 -79.99202)
			(xy 305.46421 -80.019906) (xy 305.463701 -80.047792) (xy 305.455581 -80.102968) (xy 305.439513 -80.156375)
			(xy 305.415841 -80.206872) (xy 305.385068 -80.253385) (xy 305.347851 -80.294922) (xy 305.304983 -80.330597)
			(xy 305.257377 -80.359651) (xy 305.206048 -80.381463) (xy 305.152091 -80.395569) (xy 305.096654 -80.401669)
			(xy 305.04092 -80.399632) (xy 304.986077 -80.389502) (xy 304.933293 -80.371495) (xy 304.883693 -80.345994)
			(xy 304.838335 -80.313543) (xy 304.798186 -80.274834) (xy 304.7641 -80.230691) (xy 304.736804 -80.182056)
			(xy 304.716881 -80.129965) (xy 304.704755 -80.075528) (xy 304.700684 -80.019906) (xy 300.351969 -80.019906)
			(xy 300.372632 -80.042967) (xy 300.403405 -80.08948) (xy 300.427077 -80.139977) (xy 300.443145 -80.193384)
			(xy 300.451265 -80.24856) (xy 300.451774 -80.276446) (xy 300.451265 -80.304332) (xy 300.443145 -80.359508)
			(xy 300.427077 -80.412915) (xy 300.403405 -80.463412) (xy 300.372632 -80.509925) (xy 300.335415 -80.551462)
			(xy 300.292547 -80.587137) (xy 300.244941 -80.616191) (xy 300.193612 -80.638003) (xy 300.139655 -80.652109)
			(xy 300.084218 -80.658209) (xy 300.028484 -80.656172) (xy 299.973641 -80.646042) (xy 299.920857 -80.628035)
			(xy 299.871257 -80.602534) (xy 299.825899 -80.570083) (xy 299.78575 -80.531374) (xy 299.751664 -80.487231)
			(xy 299.724368 -80.438596) (xy 299.704445 -80.386505) (xy 299.692319 -80.332068) (xy 299.688248 -80.276446)
			(xy 297.701372 -80.276446) (xy 297.660146 -81.068418) (xy 298.049948 -81.068418) (xy 298.054019 -81.012796)
			(xy 298.066145 -80.958359) (xy 298.086068 -80.906268) (xy 298.113364 -80.857633) (xy 298.14745 -80.81349)
			(xy 298.187599 -80.774781) (xy 298.232957 -80.74233) (xy 298.282557 -80.716829) (xy 298.335341 -80.698822)
			(xy 298.390184 -80.688692) (xy 298.445918 -80.686655) (xy 298.501355 -80.692755) (xy 298.555312 -80.706861)
			(xy 298.606641 -80.728673) (xy 298.654247 -80.757727) (xy 298.697115 -80.793402) (xy 298.734332 -80.834939)
			(xy 298.765105 -80.881452) (xy 298.788777 -80.931949) (xy 298.804845 -80.985356) (xy 298.812965 -81.040532)
			(xy 298.813474 -81.068418) (xy 298.812965 -81.096304) (xy 298.804845 -81.15148) (xy 298.788777 -81.204887)
			(xy 298.765105 -81.255384) (xy 298.734332 -81.301897) (xy 298.697115 -81.343434) (xy 298.654247 -81.379109)
			(xy 298.606641 -81.408163) (xy 298.555312 -81.429975) (xy 298.501355 -81.444081) (xy 298.445918 -81.450181)
			(xy 298.390184 -81.448144) (xy 298.335341 -81.438014) (xy 298.282557 -81.420007) (xy 298.232957 -81.394506)
			(xy 298.187599 -81.362055) (xy 298.14745 -81.323346) (xy 298.113364 -81.279203) (xy 298.086068 -81.230568)
			(xy 298.066145 -81.178477) (xy 298.054019 -81.12404) (xy 298.049948 -81.068418) (xy 297.660146 -81.068418)
			(xy 297.594367 -82.332068) (xy 301.91024 -82.332068) (xy 301.914311 -82.276446) (xy 301.926437 -82.222009)
			(xy 301.94636 -82.169918) (xy 301.973656 -82.121283) (xy 302.007742 -82.07714) (xy 302.047891 -82.038431)
			(xy 302.093249 -82.00598) (xy 302.142849 -81.980479) (xy 302.195633 -81.962472) (xy 302.250476 -81.952342)
			(xy 302.30621 -81.950305) (xy 302.361647 -81.956405) (xy 302.415604 -81.970511) (xy 302.466933 -81.992323)
			(xy 302.514539 -82.021377) (xy 302.557407 -82.057052) (xy 302.594624 -82.098589) (xy 302.625397 -82.145102)
			(xy 302.649069 -82.195599) (xy 302.665137 -82.249006) (xy 302.672053 -82.296) (xy 303.351182 -82.296)
			(xy 303.355253 -82.240378) (xy 303.367379 -82.185941) (xy 303.387302 -82.13385) (xy 303.414598 -82.085215)
			(xy 303.448684 -82.041072) (xy 303.488833 -82.002363) (xy 303.534191 -81.969912) (xy 303.583791 -81.944411)
			(xy 303.636575 -81.926404) (xy 303.691418 -81.916274) (xy 303.747152 -81.914237) (xy 303.802589 -81.920337)
			(xy 303.856546 -81.934443) (xy 303.907875 -81.956255) (xy 303.955481 -81.985309) (xy 303.998349 -82.020984)
			(xy 304.035566 -82.062521) (xy 304.066339 -82.109034) (xy 304.090011 -82.159531) (xy 304.106079 -82.212938)
			(xy 304.114199 -82.268114) (xy 304.114708 -82.296) (xy 304.114199 -82.323886) (xy 304.106079 -82.379062)
			(xy 304.090011 -82.432469) (xy 304.066339 -82.482966) (xy 304.035566 -82.529479) (xy 303.998349 -82.571016)
			(xy 303.955481 -82.606691) (xy 303.907875 -82.635745) (xy 303.856546 -82.657557) (xy 303.802589 -82.671663)
			(xy 303.747152 -82.677763) (xy 303.691418 -82.675726) (xy 303.636575 -82.665596) (xy 303.583791 -82.647589)
			(xy 303.534191 -82.622088) (xy 303.488833 -82.589637) (xy 303.448684 -82.550928) (xy 303.414598 -82.506785)
			(xy 303.387302 -82.45815) (xy 303.367379 -82.406059) (xy 303.355253 -82.351622) (xy 303.351182 -82.296)
			(xy 302.672053 -82.296) (xy 302.673257 -82.304182) (xy 302.673766 -82.332068) (xy 302.673257 -82.359954)
			(xy 302.665137 -82.41513) (xy 302.649069 -82.468537) (xy 302.625397 -82.519034) (xy 302.594624 -82.565547)
			(xy 302.557407 -82.607084) (xy 302.514539 -82.642759) (xy 302.466933 -82.671813) (xy 302.415604 -82.693625)
			(xy 302.361647 -82.707731) (xy 302.30621 -82.713831) (xy 302.250476 -82.711794) (xy 302.195633 -82.701664)
			(xy 302.142849 -82.683657) (xy 302.093249 -82.658156) (xy 302.047891 -82.625705) (xy 302.007742 -82.586996)
			(xy 301.973656 -82.542853) (xy 301.94636 -82.494218) (xy 301.926437 -82.442127) (xy 301.914311 -82.38769)
			(xy 301.91024 -82.332068) (xy 297.594367 -82.332068) (xy 297.534076 -83.490308) (xy 297.490589 -84.325968)
			(xy 301.368966 -84.325968) (xy 301.373037 -84.270346) (xy 301.385163 -84.215909) (xy 301.405086 -84.163818)
			(xy 301.432382 -84.115183) (xy 301.466468 -84.07104) (xy 301.506617 -84.032331) (xy 301.551975 -83.99988)
			(xy 301.601575 -83.974379) (xy 301.654359 -83.956372) (xy 301.709202 -83.946242) (xy 301.764936 -83.944205)
			(xy 301.820373 -83.950305) (xy 301.87433 -83.964411) (xy 301.925659 -83.986223) (xy 301.973265 -84.015277)
			(xy 302.016133 -84.050952) (xy 302.05335 -84.092489) (xy 302.084123 -84.139002) (xy 302.107795 -84.189499)
			(xy 302.123863 -84.242906) (xy 302.131983 -84.298082) (xy 302.132492 -84.325968) (xy 302.131983 -84.353854)
			(xy 302.123863 -84.40903) (xy 302.107795 -84.462437) (xy 302.084123 -84.512934) (xy 302.05335 -84.559447)
			(xy 302.016133 -84.600984) (xy 301.973265 -84.636659) (xy 301.925659 -84.665713) (xy 301.87433 -84.687525)
			(xy 301.820373 -84.701631) (xy 301.764936 -84.707731) (xy 301.709202 -84.705694) (xy 301.654359 -84.695564)
			(xy 301.601575 -84.677557) (xy 301.551975 -84.652056) (xy 301.506617 -84.619605) (xy 301.466468 -84.580896)
			(xy 301.432382 -84.536753) (xy 301.405086 -84.488118) (xy 301.385163 -84.436027) (xy 301.373037 -84.38159)
			(xy 301.368966 -84.325968) (xy 297.490589 -84.325968) (xy 297.432588 -85.44052) (xy 299.277276 -85.44052)
			(xy 299.281347 -85.384898) (xy 299.293473 -85.330461) (xy 299.313396 -85.27837) (xy 299.340692 -85.229735)
			(xy 299.374778 -85.185592) (xy 299.414927 -85.146883) (xy 299.460285 -85.114432) (xy 299.509885 -85.088931)
			(xy 299.562669 -85.070924) (xy 299.617512 -85.060794) (xy 299.673246 -85.058757) (xy 299.728683 -85.064857)
			(xy 299.78264 -85.078963) (xy 299.833969 -85.100775) (xy 299.881575 -85.129829) (xy 299.924443 -85.165504)
			(xy 299.96166 -85.207041) (xy 299.992433 -85.253554) (xy 300.016105 -85.304051) (xy 300.032173 -85.357458)
			(xy 300.040293 -85.412634) (xy 300.040802 -85.44052) (xy 300.040293 -85.468406) (xy 300.032173 -85.523582)
			(xy 300.016105 -85.576989) (xy 299.992433 -85.627486) (xy 299.96166 -85.673999) (xy 299.924443 -85.715536)
			(xy 299.881575 -85.751211) (xy 299.833969 -85.780265) (xy 299.78264 -85.802077) (xy 299.728683 -85.816183)
			(xy 299.673246 -85.822283) (xy 299.617512 -85.820246) (xy 299.562669 -85.810116) (xy 299.509885 -85.792109)
			(xy 299.460285 -85.766608) (xy 299.414927 -85.734157) (xy 299.374778 -85.695448) (xy 299.340692 -85.651305)
			(xy 299.313396 -85.60267) (xy 299.293473 -85.550579) (xy 299.281347 -85.496142) (xy 299.277276 -85.44052)
			(xy 297.432588 -85.44052) (xy 297.072304 -92.363798) (xy 296.923896 -95.214948) (xy 303.839131 -95.214948)
			(xy 303.843086 -95.123111) (xy 303.854921 -95.031954) (xy 303.874548 -94.942151) (xy 303.901822 -94.854369)
			(xy 303.936542 -94.769255) (xy 303.97845 -94.687442) (xy 304.027236 -94.609534) (xy 304.082539 -94.536109)
			(xy 304.143949 -94.467709) (xy 304.211011 -94.404842) (xy 304.28323 -94.347972) (xy 304.36007 -94.297521)
			(xy 304.440963 -94.253862) (xy 304.525309 -94.217319) (xy 304.612485 -94.188162) (xy 304.701844 -94.166608)
			(xy 304.792725 -94.152814) (xy 304.884456 -94.146884) (xy 304.976357 -94.148862) (xy 305.067748 -94.158733)
			(xy 305.157952 -94.176423) (xy 305.246301 -94.201803) (xy 305.332141 -94.234683) (xy 305.414837 -94.274821)
			(xy 305.493777 -94.32192) (xy 305.568375 -94.37563) (xy 305.638081 -94.435554) (xy 305.702376 -94.501248)
			(xy 305.760787 -94.572226) (xy 305.812879 -94.647963) (xy 305.858268 -94.727898) (xy 305.896618 -94.811438)
			(xy 305.927643 -94.897966) (xy 305.951116 -94.986841) (xy 305.966862 -95.077405) (xy 305.974764 -95.168987)
			(xy 305.975258 -95.214948) (xy 305.974764 -95.260909) (xy 305.966862 -95.352491) (xy 305.951116 -95.443055)
			(xy 305.927643 -95.53193) (xy 305.896618 -95.618458) (xy 305.858268 -95.701998) (xy 305.812879 -95.781933)
			(xy 305.760787 -95.85767) (xy 305.702376 -95.928648) (xy 305.642675 -95.989648) (xy 307.763924 -95.989648)
			(xy 307.767995 -95.934026) (xy 307.780121 -95.879589) (xy 307.800044 -95.827498) (xy 307.82734 -95.778863)
			(xy 307.861426 -95.73472) (xy 307.901575 -95.696011) (xy 307.946933 -95.66356) (xy 307.996533 -95.638059)
			(xy 308.049317 -95.620052) (xy 308.10416 -95.609922) (xy 308.159894 -95.607885) (xy 308.215331 -95.613985)
			(xy 308.269288 -95.628091) (xy 308.320617 -95.649903) (xy 308.368223 -95.678957) (xy 308.411091 -95.714632)
			(xy 308.448308 -95.756169) (xy 308.479081 -95.802682) (xy 308.502753 -95.853179) (xy 308.518821 -95.906586)
			(xy 308.526941 -95.961762) (xy 308.52745 -95.989648) (xy 308.526941 -96.017534) (xy 308.518821 -96.07271)
			(xy 308.502753 -96.126117) (xy 308.479081 -96.176614) (xy 308.448308 -96.223127) (xy 308.411091 -96.264664)
			(xy 308.368223 -96.300339) (xy 308.320617 -96.329393) (xy 308.269288 -96.351205) (xy 308.215331 -96.365311)
			(xy 308.159894 -96.371411) (xy 308.10416 -96.369374) (xy 308.049317 -96.359244) (xy 307.996533 -96.341237)
			(xy 307.946933 -96.315736) (xy 307.901575 -96.283285) (xy 307.861426 -96.244576) (xy 307.82734 -96.200433)
			(xy 307.800044 -96.151798) (xy 307.780121 -96.099707) (xy 307.767995 -96.04527) (xy 307.763924 -95.989648)
			(xy 305.642675 -95.989648) (xy 305.638081 -95.994342) (xy 305.568375 -96.054266) (xy 305.493777 -96.107976)
			(xy 305.414837 -96.155075) (xy 305.332141 -96.195213) (xy 305.246301 -96.228093) (xy 305.157952 -96.253473)
			(xy 305.067748 -96.271163) (xy 304.976357 -96.281034) (xy 304.884456 -96.283012) (xy 304.792725 -96.277082)
			(xy 304.701844 -96.263288) (xy 304.612485 -96.241734) (xy 304.525309 -96.212577) (xy 304.440963 -96.176034)
			(xy 304.36007 -96.132375) (xy 304.28323 -96.081924) (xy 304.211011 -96.025054) (xy 304.143949 -95.962187)
			(xy 304.082539 -95.893787) (xy 304.027236 -95.820362) (xy 303.97845 -95.742454) (xy 303.936542 -95.660641)
			(xy 303.901822 -95.575527) (xy 303.874548 -95.487745) (xy 303.854921 -95.397942) (xy 303.843086 -95.306785)
			(xy 303.839131 -95.214948) (xy 296.923896 -95.214948) (xy 296.836134 -96.901) (xy 301.521874 -96.901)
			(xy 301.525945 -96.845378) (xy 301.538071 -96.790941) (xy 301.557994 -96.73885) (xy 301.58529 -96.690215)
			(xy 301.619376 -96.646072) (xy 301.659525 -96.607363) (xy 301.704883 -96.574912) (xy 301.754483 -96.549411)
			(xy 301.807267 -96.531404) (xy 301.86211 -96.521274) (xy 301.917844 -96.519237) (xy 301.973281 -96.525337)
			(xy 302.027238 -96.539443) (xy 302.078567 -96.561255) (xy 302.126173 -96.590309) (xy 302.169041 -96.625984)
			(xy 302.206258 -96.667521) (xy 302.237031 -96.714034) (xy 302.260703 -96.764531) (xy 302.276771 -96.817938)
			(xy 302.284891 -96.873114) (xy 302.2854 -96.901) (xy 302.284891 -96.928886) (xy 302.276771 -96.984062)
			(xy 302.260703 -97.037469) (xy 302.259546 -97.039938) (xy 306.92547 -97.039938) (xy 306.929541 -96.984316)
			(xy 306.941667 -96.929879) (xy 306.96159 -96.877788) (xy 306.988886 -96.829153) (xy 307.022972 -96.78501)
			(xy 307.063121 -96.746301) (xy 307.108479 -96.71385) (xy 307.158079 -96.688349) (xy 307.210863 -96.670342)
			(xy 307.265706 -96.660212) (xy 307.32144 -96.658175) (xy 307.376877 -96.664275) (xy 307.430834 -96.678381)
			(xy 307.482163 -96.700193) (xy 307.529769 -96.729247) (xy 307.572637 -96.764922) (xy 307.609854 -96.806459)
			(xy 307.640627 -96.852972) (xy 307.664299 -96.903469) (xy 307.680367 -96.956876) (xy 307.688487 -97.012052)
			(xy 307.688996 -97.039938) (xy 307.688487 -97.067824) (xy 307.680367 -97.123) (xy 307.664299 -97.176407)
			(xy 307.640627 -97.226904) (xy 307.609854 -97.273417) (xy 307.572637 -97.314954) (xy 307.529769 -97.350629)
			(xy 307.482163 -97.379683) (xy 307.430834 -97.401495) (xy 307.376877 -97.415601) (xy 307.32144 -97.421701)
			(xy 307.265706 -97.419664) (xy 307.210863 -97.409534) (xy 307.158079 -97.391527) (xy 307.108479 -97.366026)
			(xy 307.063121 -97.333575) (xy 307.022972 -97.294866) (xy 306.988886 -97.250723) (xy 306.96159 -97.202088)
			(xy 306.941667 -97.149997) (xy 306.929541 -97.09556) (xy 306.92547 -97.039938) (xy 302.259546 -97.039938)
			(xy 302.237031 -97.087966) (xy 302.206258 -97.134479) (xy 302.169041 -97.176016) (xy 302.126173 -97.211691)
			(xy 302.078567 -97.240745) (xy 302.027238 -97.262557) (xy 301.973281 -97.276663) (xy 301.917844 -97.282763)
			(xy 301.86211 -97.280726) (xy 301.807267 -97.270596) (xy 301.754483 -97.252589) (xy 301.704883 -97.227088)
			(xy 301.659525 -97.194637) (xy 301.619376 -97.155928) (xy 301.58529 -97.111785) (xy 301.557994 -97.06315)
			(xy 301.538071 -97.011059) (xy 301.525945 -96.956622) (xy 301.521874 -96.901) (xy 296.836134 -96.901)
			(xy 296.79766 -97.64014) (xy 306.118004 -97.64014) (xy 306.122075 -97.584518) (xy 306.134201 -97.530081)
			(xy 306.154124 -97.47799) (xy 306.18142 -97.429355) (xy 306.215506 -97.385212) (xy 306.255655 -97.346503)
			(xy 306.301013 -97.314052) (xy 306.350613 -97.288551) (xy 306.403397 -97.270544) (xy 306.45824 -97.260414)
			(xy 306.513974 -97.258377) (xy 306.569411 -97.264477) (xy 306.623368 -97.278583) (xy 306.674697 -97.300395)
			(xy 306.722303 -97.329449) (xy 306.765171 -97.365124) (xy 306.802388 -97.406661) (xy 306.833161 -97.453174)
			(xy 306.856833 -97.503671) (xy 306.872901 -97.557078) (xy 306.881021 -97.612254) (xy 306.88153 -97.64014)
			(xy 306.881021 -97.668026) (xy 306.872901 -97.723202) (xy 306.856833 -97.776609) (xy 306.833161 -97.827106)
			(xy 306.802388 -97.873619) (xy 306.765171 -97.915156) (xy 306.722303 -97.950831) (xy 306.674697 -97.979885)
			(xy 306.623368 -98.001697) (xy 306.569411 -98.015803) (xy 306.513974 -98.021903) (xy 306.45824 -98.019866)
			(xy 306.403397 -98.009736) (xy 306.350613 -97.991729) (xy 306.301013 -97.966228) (xy 306.255655 -97.933777)
			(xy 306.215506 -97.895068) (xy 306.18142 -97.850925) (xy 306.154124 -97.80229) (xy 306.134201 -97.750199)
			(xy 306.122075 -97.695762) (xy 306.118004 -97.64014) (xy 296.79766 -97.64014) (xy 296.770028 -98.171)
			(xy 307.763924 -98.171) (xy 307.767995 -98.115378) (xy 307.780121 -98.060941) (xy 307.800044 -98.00885)
			(xy 307.82734 -97.960215) (xy 307.861426 -97.916072) (xy 307.901575 -97.877363) (xy 307.946933 -97.844912)
			(xy 307.996533 -97.819411) (xy 308.049317 -97.801404) (xy 308.10416 -97.791274) (xy 308.159894 -97.789237)
			(xy 308.215331 -97.795337) (xy 308.269288 -97.809443) (xy 308.320617 -97.831255) (xy 308.368223 -97.860309)
			(xy 308.411091 -97.895984) (xy 308.448308 -97.937521) (xy 308.479081 -97.984034) (xy 308.502753 -98.034531)
			(xy 308.518821 -98.087938) (xy 308.526941 -98.143114) (xy 308.52745 -98.171) (xy 308.526941 -98.198886)
			(xy 308.518821 -98.254062) (xy 308.502753 -98.307469) (xy 308.479081 -98.357966) (xy 308.448308 -98.404479)
			(xy 308.411091 -98.446016) (xy 308.368223 -98.481691) (xy 308.320617 -98.510745) (xy 308.269288 -98.532557)
			(xy 308.215331 -98.546663) (xy 308.159894 -98.552763) (xy 308.10416 -98.550726) (xy 308.049317 -98.540596)
			(xy 307.996533 -98.522589) (xy 307.946933 -98.497088) (xy 307.901575 -98.464637) (xy 307.861426 -98.425928)
			(xy 307.82734 -98.381785) (xy 307.800044 -98.33315) (xy 307.780121 -98.281059) (xy 307.767995 -98.226622)
			(xy 307.763924 -98.171) (xy 296.770028 -98.171) (xy 296.688374 -99.739704) (xy 302.321974 -99.739704)
			(xy 302.326045 -99.684082) (xy 302.338171 -99.629645) (xy 302.358094 -99.577554) (xy 302.38539 -99.528919)
			(xy 302.419476 -99.484776) (xy 302.459625 -99.446067) (xy 302.504983 -99.413616) (xy 302.554583 -99.388115)
			(xy 302.607367 -99.370108) (xy 302.66221 -99.359978) (xy 302.717944 -99.357941) (xy 302.773381 -99.364041)
			(xy 302.827338 -99.378147) (xy 302.878667 -99.399959) (xy 302.926273 -99.429013) (xy 302.939456 -99.439984)
			(xy 307.509924 -99.439984) (xy 307.513995 -99.384362) (xy 307.526121 -99.329925) (xy 307.546044 -99.277834)
			(xy 307.57334 -99.229199) (xy 307.607426 -99.185056) (xy 307.647575 -99.146347) (xy 307.692933 -99.113896)
			(xy 307.742533 -99.088395) (xy 307.795317 -99.070388) (xy 307.85016 -99.060258) (xy 307.905894 -99.058221)
			(xy 307.961331 -99.064321) (xy 308.015288 -99.078427) (xy 308.066617 -99.100239) (xy 308.114223 -99.129293)
			(xy 308.157091 -99.164968) (xy 308.194308 -99.206505) (xy 308.225081 -99.253018) (xy 308.248753 -99.303515)
			(xy 308.264821 -99.356922) (xy 308.272941 -99.412098) (xy 308.27345 -99.439984) (xy 308.272941 -99.46787)
			(xy 308.264821 -99.523046) (xy 308.248753 -99.576453) (xy 308.225081 -99.62695) (xy 308.194308 -99.673463)
			(xy 308.157091 -99.715) (xy 308.114223 -99.750675) (xy 308.066617 -99.779729) (xy 308.015288 -99.801541)
			(xy 307.961331 -99.815647) (xy 307.905894 -99.821747) (xy 307.85016 -99.81971) (xy 307.795317 -99.80958)
			(xy 307.742533 -99.791573) (xy 307.692933 -99.766072) (xy 307.647575 -99.733621) (xy 307.607426 -99.694912)
			(xy 307.57334 -99.650769) (xy 307.546044 -99.602134) (xy 307.526121 -99.550043) (xy 307.513995 -99.495606)
			(xy 307.509924 -99.439984) (xy 302.939456 -99.439984) (xy 302.969141 -99.464688) (xy 303.006358 -99.506225)
			(xy 303.037131 -99.552738) (xy 303.060803 -99.603235) (xy 303.076871 -99.656642) (xy 303.084991 -99.711818)
			(xy 303.0855 -99.739704) (xy 303.084991 -99.76759) (xy 303.076871 -99.822766) (xy 303.060803 -99.876173)
			(xy 303.037131 -99.92667) (xy 303.006358 -99.973183) (xy 302.969141 -100.01472) (xy 302.938846 -100.039932)
			(xy 306.076856 -100.039932) (xy 306.080927 -99.98431) (xy 306.093053 -99.929873) (xy 306.112976 -99.877782)
			(xy 306.140272 -99.829147) (xy 306.174358 -99.785004) (xy 306.214507 -99.746295) (xy 306.259865 -99.713844)
			(xy 306.309465 -99.688343) (xy 306.362249 -99.670336) (xy 306.417092 -99.660206) (xy 306.472826 -99.658169)
			(xy 306.528263 -99.664269) (xy 306.58222 -99.678375) (xy 306.633549 -99.700187) (xy 306.681155 -99.729241)
			(xy 306.724023 -99.764916) (xy 306.76124 -99.806453) (xy 306.792013 -99.852966) (xy 306.815685 -99.903463)
			(xy 306.831753 -99.95687) (xy 306.839873 -100.012046) (xy 306.840382 -100.039932) (xy 306.839873 -100.067818)
			(xy 306.831753 -100.122994) (xy 306.815685 -100.176401) (xy 306.792013 -100.226898) (xy 306.76124 -100.273411)
			(xy 306.724023 -100.314948) (xy 306.681155 -100.350623) (xy 306.633549 -100.379677) (xy 306.58222 -100.401489)
			(xy 306.528263 -100.415595) (xy 306.472826 -100.421695) (xy 306.417092 -100.419658) (xy 306.362249 -100.409528)
			(xy 306.309465 -100.391521) (xy 306.259865 -100.36602) (xy 306.214507 -100.333569) (xy 306.174358 -100.29486)
			(xy 306.140272 -100.250717) (xy 306.112976 -100.202082) (xy 306.093053 -100.149991) (xy 306.080927 -100.095554)
			(xy 306.076856 -100.039932) (xy 302.938846 -100.039932) (xy 302.926273 -100.050395) (xy 302.878667 -100.079449)
			(xy 302.827338 -100.101261) (xy 302.773381 -100.115367) (xy 302.717944 -100.121467) (xy 302.66221 -100.11943)
			(xy 302.607367 -100.1093) (xy 302.554583 -100.091293) (xy 302.504983 -100.065792) (xy 302.459625 -100.033341)
			(xy 302.419476 -99.994632) (xy 302.38539 -99.950489) (xy 302.358094 -99.901854) (xy 302.338171 -99.849763)
			(xy 302.326045 -99.795326) (xy 302.321974 -99.739704) (xy 296.688374 -99.739704) (xy 296.610277 -101.240082)
			(xy 306.493924 -101.240082) (xy 306.497995 -101.18446) (xy 306.510121 -101.130023) (xy 306.530044 -101.077932)
			(xy 306.55734 -101.029297) (xy 306.591426 -100.985154) (xy 306.631575 -100.946445) (xy 306.676933 -100.913994)
			(xy 306.726533 -100.888493) (xy 306.779317 -100.870486) (xy 306.83416 -100.860356) (xy 306.889894 -100.858319)
			(xy 306.945331 -100.864419) (xy 306.999288 -100.878525) (xy 307.050617 -100.900337) (xy 307.098223 -100.929391)
			(xy 307.141091 -100.965066) (xy 307.178308 -101.006603) (xy 307.209081 -101.053116) (xy 307.216831 -101.069648)
			(xy 307.786276 -101.069648) (xy 307.790347 -101.014026) (xy 307.802473 -100.959589) (xy 307.822396 -100.907498)
			(xy 307.849692 -100.858863) (xy 307.883778 -100.81472) (xy 307.923927 -100.776011) (xy 307.969285 -100.74356)
			(xy 308.018885 -100.718059) (xy 308.071669 -100.700052) (xy 308.126512 -100.689922) (xy 308.182246 -100.687885)
			(xy 308.237683 -100.693985) (xy 308.29164 -100.708091) (xy 308.342969 -100.729903) (xy 308.390575 -100.758957)
			(xy 308.433443 -100.794632) (xy 308.47066 -100.836169) (xy 308.501433 -100.882682) (xy 308.525105 -100.933179)
			(xy 308.541173 -100.986586) (xy 308.549293 -101.041762) (xy 308.549802 -101.069648) (xy 308.549293 -101.097534)
			(xy 308.541173 -101.15271) (xy 308.525105 -101.206117) (xy 308.501433 -101.256614) (xy 308.47066 -101.303127)
			(xy 308.433443 -101.344664) (xy 308.390575 -101.380339) (xy 308.342969 -101.409393) (xy 308.29164 -101.431205)
			(xy 308.237683 -101.445311) (xy 308.182246 -101.451411) (xy 308.126512 -101.449374) (xy 308.071669 -101.439244)
			(xy 308.018885 -101.421237) (xy 307.969285 -101.395736) (xy 307.923927 -101.363285) (xy 307.883778 -101.324576)
			(xy 307.849692 -101.280433) (xy 307.822396 -101.231798) (xy 307.802473 -101.179707) (xy 307.790347 -101.12527)
			(xy 307.786276 -101.069648) (xy 307.216831 -101.069648) (xy 307.232753 -101.103613) (xy 307.248821 -101.15702)
			(xy 307.256941 -101.212196) (xy 307.25745 -101.240082) (xy 307.256941 -101.267968) (xy 307.248821 -101.323144)
			(xy 307.232753 -101.376551) (xy 307.209081 -101.427048) (xy 307.178308 -101.473561) (xy 307.141091 -101.515098)
			(xy 307.098223 -101.550773) (xy 307.050617 -101.579827) (xy 306.999288 -101.601639) (xy 306.945331 -101.615745)
			(xy 306.889894 -101.621845) (xy 306.83416 -101.619808) (xy 306.779317 -101.609678) (xy 306.726533 -101.591671)
			(xy 306.676933 -101.56617) (xy 306.631575 -101.533719) (xy 306.591426 -101.49501) (xy 306.55734 -101.450867)
			(xy 306.530044 -101.402232) (xy 306.510121 -101.350141) (xy 306.497995 -101.295704) (xy 306.493924 -101.240082)
			(xy 296.610277 -101.240082) (xy 296.545268 -102.489) (xy 307.001924 -102.489) (xy 307.005995 -102.433378)
			(xy 307.018121 -102.378941) (xy 307.038044 -102.32685) (xy 307.06534 -102.278215) (xy 307.099426 -102.234072)
			(xy 307.139575 -102.195363) (xy 307.184933 -102.162912) (xy 307.234533 -102.137411) (xy 307.287317 -102.119404)
			(xy 307.34216 -102.109274) (xy 307.397894 -102.107237) (xy 307.453331 -102.113337) (xy 307.507288 -102.127443)
			(xy 307.558617 -102.149255) (xy 307.606223 -102.178309) (xy 307.649091 -102.213984) (xy 307.686308 -102.255521)
			(xy 307.717081 -102.302034) (xy 307.740753 -102.352531) (xy 307.756821 -102.405938) (xy 307.764941 -102.461114)
			(xy 307.76545 -102.489) (xy 307.764941 -102.516886) (xy 307.756821 -102.572062) (xy 307.740753 -102.625469)
			(xy 307.717081 -102.675966) (xy 307.686308 -102.722479) (xy 307.649091 -102.764016) (xy 307.606223 -102.799691)
			(xy 307.558617 -102.828745) (xy 307.507288 -102.850557) (xy 307.453331 -102.864663) (xy 307.397894 -102.870763)
			(xy 307.34216 -102.868726) (xy 307.287317 -102.858596) (xy 307.234533 -102.840589) (xy 307.184933 -102.815088)
			(xy 307.139575 -102.782637) (xy 307.099426 -102.743928) (xy 307.06534 -102.699785) (xy 307.038044 -102.65115)
			(xy 307.018121 -102.599059) (xy 307.005995 -102.544622) (xy 307.001924 -102.489) (xy 296.545268 -102.489)
			(xy 296.472552 -103.886) (xy 307.509924 -103.886) (xy 307.513995 -103.830378) (xy 307.526121 -103.775941)
			(xy 307.546044 -103.72385) (xy 307.57334 -103.675215) (xy 307.607426 -103.631072) (xy 307.647575 -103.592363)
			(xy 307.692933 -103.559912) (xy 307.742533 -103.534411) (xy 307.795317 -103.516404) (xy 307.85016 -103.506274)
			(xy 307.905894 -103.504237) (xy 307.961331 -103.510337) (xy 308.015288 -103.524443) (xy 308.066617 -103.546255)
			(xy 308.114223 -103.575309) (xy 308.157091 -103.610984) (xy 308.194308 -103.652521) (xy 308.225081 -103.699034)
			(xy 308.248753 -103.749531) (xy 308.264821 -103.802938) (xy 308.272941 -103.858114) (xy 308.27345 -103.886)
			(xy 308.272941 -103.913886) (xy 308.264821 -103.969062) (xy 308.248753 -104.022469) (xy 308.225081 -104.072966)
			(xy 308.194308 -104.119479) (xy 308.157091 -104.161016) (xy 308.114223 -104.196691) (xy 308.066617 -104.225745)
			(xy 308.015288 -104.247557) (xy 307.961331 -104.261663) (xy 307.905894 -104.267763) (xy 307.85016 -104.265726)
			(xy 307.795317 -104.255596) (xy 307.742533 -104.237589) (xy 307.692933 -104.212088) (xy 307.647575 -104.179637)
			(xy 307.607426 -104.140928) (xy 307.57334 -104.096785) (xy 307.546044 -104.04815) (xy 307.526121 -103.996059)
			(xy 307.513995 -103.941622) (xy 307.509924 -103.886) (xy 296.472552 -103.886) (xy 296.299513 -107.210352)
			(xy 297.165012 -107.210352) (xy 297.169083 -107.15473) (xy 297.181209 -107.100293) (xy 297.201132 -107.048202)
			(xy 297.228428 -106.999567) (xy 297.262514 -106.955424) (xy 297.302663 -106.916715) (xy 297.348021 -106.884264)
			(xy 297.397621 -106.858763) (xy 297.450405 -106.840756) (xy 297.505248 -106.830626) (xy 297.560982 -106.828589)
			(xy 297.616419 -106.834689) (xy 297.670376 -106.848795) (xy 297.721705 -106.870607) (xy 297.769311 -106.899661)
			(xy 297.812179 -106.935336) (xy 297.849396 -106.976873) (xy 297.880169 -107.023386) (xy 297.903841 -107.073883)
			(xy 297.919909 -107.12729) (xy 297.928029 -107.182466) (xy 297.928538 -107.210352) (xy 297.928029 -107.238238)
			(xy 297.919909 -107.293414) (xy 297.903841 -107.346821) (xy 297.880169 -107.397318) (xy 297.849396 -107.443831)
			(xy 297.812179 -107.485368) (xy 297.769311 -107.521043) (xy 297.721705 -107.550097) (xy 297.670376 -107.571909)
			(xy 297.616419 -107.586015) (xy 297.560982 -107.592115) (xy 297.505248 -107.590078) (xy 297.450405 -107.579948)
			(xy 297.397621 -107.561941) (xy 297.348021 -107.53644) (xy 297.302663 -107.503989) (xy 297.262514 -107.46528)
			(xy 297.228428 -107.421137) (xy 297.201132 -107.372502) (xy 297.181209 -107.320411) (xy 297.169083 -107.265974)
			(xy 297.165012 -107.210352) (xy 296.299513 -107.210352) (xy 296.126712 -110.530132) (xy 302.62906 -110.530132)
			(xy 302.633131 -110.47451) (xy 302.645257 -110.420073) (xy 302.66518 -110.367982) (xy 302.692476 -110.319347)
			(xy 302.726562 -110.275204) (xy 302.766711 -110.236495) (xy 302.812069 -110.204044) (xy 302.861669 -110.178543)
			(xy 302.914453 -110.160536) (xy 302.969296 -110.150406) (xy 303.02503 -110.148369) (xy 303.080467 -110.154469)
			(xy 303.134424 -110.168575) (xy 303.185753 -110.190387) (xy 303.233359 -110.219441) (xy 303.276227 -110.255116)
			(xy 303.313444 -110.296653) (xy 303.344217 -110.343166) (xy 303.367889 -110.393663) (xy 303.383957 -110.44707)
			(xy 303.392077 -110.502246) (xy 303.392586 -110.530132) (xy 303.392077 -110.558018) (xy 303.383957 -110.613194)
			(xy 303.367889 -110.666601) (xy 303.344217 -110.717098) (xy 303.313444 -110.763611) (xy 303.276227 -110.805148)
			(xy 303.233359 -110.840823) (xy 303.185753 -110.869877) (xy 303.134424 -110.891689) (xy 303.080467 -110.905795)
			(xy 303.02503 -110.911895) (xy 302.969296 -110.909858) (xy 302.914453 -110.899728) (xy 302.861669 -110.881721)
			(xy 302.812069 -110.85622) (xy 302.766711 -110.823769) (xy 302.726562 -110.78506) (xy 302.692476 -110.740917)
			(xy 302.66518 -110.692282) (xy 302.645257 -110.640191) (xy 302.633131 -110.585754) (xy 302.62906 -110.530132)
			(xy 296.126712 -110.530132) (xy 296.084867 -111.334042) (xy 296.463972 -111.334042) (xy 296.468043 -111.27842)
			(xy 296.480169 -111.223983) (xy 296.500092 -111.171892) (xy 296.527388 -111.123257) (xy 296.561474 -111.079114)
			(xy 296.601623 -111.040405) (xy 296.646981 -111.007954) (xy 296.696581 -110.982453) (xy 296.749365 -110.964446)
			(xy 296.804208 -110.954316) (xy 296.859942 -110.952279) (xy 296.915379 -110.958379) (xy 296.969336 -110.972485)
			(xy 297.020665 -110.994297) (xy 297.068271 -111.023351) (xy 297.111139 -111.059026) (xy 297.148356 -111.100563)
			(xy 297.179129 -111.147076) (xy 297.202801 -111.197573) (xy 297.218869 -111.25098) (xy 297.226989 -111.306156)
			(xy 297.227498 -111.334042) (xy 297.226989 -111.361928) (xy 297.218869 -111.417104) (xy 297.202801 -111.470511)
			(xy 297.179129 -111.521008) (xy 297.148356 -111.567521) (xy 297.111139 -111.609058) (xy 297.068271 -111.644733)
			(xy 297.020665 -111.673787) (xy 296.969336 -111.695599) (xy 296.915379 -111.709705) (xy 296.859942 -111.715805)
			(xy 296.804208 -111.713768) (xy 296.749365 -111.703638) (xy 296.696581 -111.685631) (xy 296.646981 -111.66013)
			(xy 296.601623 -111.627679) (xy 296.561474 -111.58897) (xy 296.527388 -111.544827) (xy 296.500092 -111.496192)
			(xy 296.480169 -111.444101) (xy 296.468043 -111.389664) (xy 296.463972 -111.334042) (xy 296.084867 -111.334042)
			(xy 296.05623 -111.884206) (xy 302.56429 -111.884206) (xy 302.568361 -111.828584) (xy 302.580487 -111.774147)
			(xy 302.60041 -111.722056) (xy 302.627706 -111.673421) (xy 302.661792 -111.629278) (xy 302.701941 -111.590569)
			(xy 302.747299 -111.558118) (xy 302.796899 -111.532617) (xy 302.849683 -111.51461) (xy 302.904526 -111.50448)
			(xy 302.96026 -111.502443) (xy 303.015697 -111.508543) (xy 303.069654 -111.522649) (xy 303.120983 -111.544461)
			(xy 303.168589 -111.573515) (xy 303.211457 -111.60919) (xy 303.248674 -111.650727) (xy 303.279447 -111.69724)
			(xy 303.303119 -111.747737) (xy 303.319187 -111.801144) (xy 303.327307 -111.85632) (xy 303.327816 -111.884206)
			(xy 303.327307 -111.912092) (xy 303.319187 -111.967268) (xy 303.315138 -111.980726) (xy 306.101496 -111.980726)
			(xy 306.102037 -111.951988) (xy 306.110655 -111.895161) (xy 306.127701 -111.840271) (xy 306.152789 -111.788559)
			(xy 306.185351 -111.741195) (xy 306.20462 -111.719868) (xy 306.211224 -111.71301) (xy 306.218336 -111.694976)
			(xy 306.218336 -111.606076) (xy 306.211224 -111.588042) (xy 306.20462 -111.581184) (xy 306.185375 -111.559835)
			(xy 306.152809 -111.512476) (xy 306.127717 -111.460768) (xy 306.110665 -111.405881) (xy 306.10204 -111.349056)
			(xy 306.102037 -111.291581) (xy 306.110656 -111.234756) (xy 306.127703 -111.179867) (xy 306.15279 -111.128157)
			(xy 306.185351 -111.080795) (xy 306.20462 -111.059468) (xy 306.211224 -111.05261) (xy 306.218336 -111.034576)
			(xy 306.218336 -110.945676) (xy 306.211224 -110.927642) (xy 306.20462 -110.920784) (xy 306.185375 -110.899435)
			(xy 306.152809 -110.852076) (xy 306.127717 -110.800368) (xy 306.110665 -110.745481) (xy 306.10204 -110.688656)
			(xy 306.102037 -110.631181) (xy 306.110656 -110.574356) (xy 306.127703 -110.519467) (xy 306.15279 -110.467757)
			(xy 306.185351 -110.420395) (xy 306.20462 -110.399068) (xy 306.211224 -110.39221) (xy 306.218336 -110.374176)
			(xy 306.218336 -110.285276) (xy 306.211224 -110.267242) (xy 306.20462 -110.260384) (xy 306.185375 -110.239035)
			(xy 306.152809 -110.191676) (xy 306.127717 -110.139968) (xy 306.110665 -110.085081) (xy 306.10204 -110.028256)
			(xy 306.102037 -109.970781) (xy 306.110656 -109.913956) (xy 306.127703 -109.859067) (xy 306.15279 -109.807357)
			(xy 306.185351 -109.759995) (xy 306.20462 -109.738668) (xy 306.211224 -109.73181) (xy 306.218336 -109.713776)
			(xy 306.218336 -109.624876) (xy 306.211224 -109.606842) (xy 306.20462 -109.599984) (xy 306.185359 -109.578649)
			(xy 306.152792 -109.531289) (xy 306.127698 -109.479579) (xy 306.110645 -109.42469) (xy 306.102019 -109.367864)
			(xy 306.101496 -109.339126) (xy 306.10198 -109.311874) (xy 306.109733 -109.257923) (xy 306.125086 -109.205625)
			(xy 306.147726 -109.156045) (xy 306.177191 -109.110192) (xy 306.212883 -109.068999) (xy 306.254074 -109.033305)
			(xy 306.299926 -109.003836) (xy 306.349505 -108.981194) (xy 306.401802 -108.965838) (xy 306.455752 -108.958081)
			(xy 306.483004 -108.957618) (xy 306.509318 -108.958077) (xy 306.561447 -108.965313) (xy 306.612091 -108.979633)
			(xy 306.66029 -109.000767) (xy 306.705133 -109.028315) (xy 306.745772 -109.061755) (xy 306.763928 -109.080808)
			(xy 306.771436 -109.088225) (xy 306.790727 -109.09674) (xy 306.801266 -109.097318) (xy 306.875942 -109.097318)
			(xy 306.886489 -109.096766) (xy 306.905784 -109.088246) (xy 306.91328 -109.080808) (xy 306.931454 -109.061771)
			(xy 306.972079 -109.028312) (xy 307.016916 -109.00075) (xy 307.065113 -108.979608) (xy 307.115757 -108.965287)
			(xy 307.167889 -108.958059) (xy 307.194204 -108.957618) (xy 307.221458 -108.958052) (xy 307.275411 -108.96581)
			(xy 307.327711 -108.981168) (xy 307.377293 -109.003813) (xy 307.423148 -109.033283) (xy 307.464341 -109.06898)
			(xy 307.500035 -109.110176) (xy 307.529502 -109.156033) (xy 307.552143 -109.205617) (xy 307.567496 -109.257918)
			(xy 307.57525 -109.311872) (xy 307.575712 -109.339126) (xy 307.575201 -109.367865) (xy 307.566575 -109.424693)
			(xy 307.549522 -109.479584) (xy 307.524427 -109.531295) (xy 307.49186 -109.578657) (xy 307.472588 -109.599984)
			(xy 307.465984 -109.606842) (xy 307.458872 -109.624876) (xy 307.458872 -109.713776) (xy 307.465984 -109.73181)
			(xy 307.472588 -109.738668) (xy 307.491884 -109.759973) (xy 307.524447 -109.807339) (xy 307.549537 -109.859055)
			(xy 307.566584 -109.913949) (xy 307.575204 -109.970779) (xy 307.575201 -110.028259) (xy 307.566576 -110.085088)
			(xy 307.549523 -110.139981) (xy 307.524428 -110.191694) (xy 307.49186 -110.239057) (xy 307.472588 -110.260384)
			(xy 307.465984 -110.267242) (xy 307.458872 -110.285276) (xy 307.458872 -110.374176) (xy 307.465984 -110.39221)
			(xy 307.472588 -110.399068) (xy 307.491884 -110.420373) (xy 307.524447 -110.467739) (xy 307.549537 -110.519455)
			(xy 307.566584 -110.574349) (xy 307.575204 -110.631179) (xy 307.575201 -110.688659) (xy 307.566576 -110.745488)
			(xy 307.549523 -110.800381) (xy 307.524428 -110.852094) (xy 307.49186 -110.899457) (xy 307.472588 -110.920784)
			(xy 307.465984 -110.927642) (xy 307.458872 -110.945676) (xy 307.458872 -111.034576) (xy 307.465984 -111.05261)
			(xy 307.472588 -111.059468) (xy 307.491884 -111.080773) (xy 307.524447 -111.128139) (xy 307.549537 -111.179855)
			(xy 307.566584 -111.234749) (xy 307.575204 -111.291579) (xy 307.575201 -111.349059) (xy 307.566576 -111.405888)
			(xy 307.549523 -111.460781) (xy 307.524428 -111.512494) (xy 307.49186 -111.559857) (xy 307.472588 -111.581184)
			(xy 307.465984 -111.588042) (xy 307.458872 -111.606076) (xy 307.458872 -111.694976) (xy 307.465984 -111.71301)
			(xy 307.472588 -111.719868) (xy 307.491875 -111.741181) (xy 307.524438 -111.788547) (xy 307.549527 -111.840262)
			(xy 307.566574 -111.895156) (xy 307.575193 -111.951986) (xy 307.575712 -111.980726) (xy 307.575246 -112.007978)
			(xy 307.567486 -112.061926) (xy 307.552128 -112.114221) (xy 307.529484 -112.163798) (xy 307.500016 -112.209648)
			(xy 307.464322 -112.250838) (xy 307.42313 -112.286529) (xy 307.377279 -112.315995) (xy 307.3277 -112.338636)
			(xy 307.275404 -112.353991) (xy 307.221456 -112.361748) (xy 307.194204 -112.362234) (xy 307.167891 -112.361753)
			(xy 307.115763 -112.354519) (xy 307.065121 -112.340202) (xy 307.016922 -112.319072) (xy 306.972078 -112.291529)
			(xy 306.931438 -112.258094) (xy 306.91328 -112.239044) (xy 306.905762 -112.231638) (xy 306.886479 -112.223115)
			(xy 306.875942 -112.222534) (xy 306.801266 -112.222534) (xy 306.790717 -112.223075) (xy 306.771421 -112.231601)
			(xy 306.763928 -112.239044) (xy 306.74576 -112.258087) (xy 306.705132 -112.291544) (xy 306.660294 -112.319103)
			(xy 306.612096 -112.340244) (xy 306.561451 -112.354564) (xy 306.509319 -112.361793) (xy 306.483004 -112.362234)
			(xy 306.455754 -112.361719) (xy 306.401809 -112.353963) (xy 306.349516 -112.33861) (xy 306.299941 -112.315971)
			(xy 306.254091 -112.286508) (xy 306.212902 -112.250819) (xy 306.17721 -112.209633) (xy 306.147743 -112.163786)
			(xy 306.125101 -112.114212) (xy 306.109743 -112.061921) (xy 306.101984 -112.007976) (xy 306.101496 -111.980726)
			(xy 303.315138 -111.980726) (xy 303.303119 -112.020675) (xy 303.279447 -112.071172) (xy 303.248674 -112.117685)
			(xy 303.211457 -112.159222) (xy 303.168589 -112.194897) (xy 303.120983 -112.223951) (xy 303.069654 -112.245763)
			(xy 303.015697 -112.259869) (xy 302.96026 -112.265969) (xy 302.904526 -112.263932) (xy 302.849683 -112.253802)
			(xy 302.796899 -112.235795) (xy 302.747299 -112.210294) (xy 302.701941 -112.177843) (xy 302.661792 -112.139134)
			(xy 302.627706 -112.094991) (xy 302.60041 -112.046356) (xy 302.580487 -111.994265) (xy 302.568361 -111.939828)
			(xy 302.56429 -111.884206) (xy 296.05623 -111.884206) (xy 296.051986 -111.96574) (xy 296.051986 -112.091978)
			(xy 296.052805 -112.10365) (xy 296.063524 -112.124422) (xy 296.07256 -112.131856) (xy 296.145204 -112.177068)
			(xy 296.145712 -112.177068) (xy 296.15003 -112.179862) (xy 296.161206 -112.183672) (xy 296.166794 -112.18418)
			(xy 296.168318 -112.18418) (xy 296.169334 -112.184434) (xy 296.169588 -112.184434) (xy 296.175659 -112.184642)
			(xy 296.187605 -112.182457) (xy 296.19321 -112.180116) (xy 296.199306 -112.177068) (xy 296.202608 -112.17529)
			(xy 296.204132 -112.174274) (xy 296.231936 -112.160143) (xy 296.290998 -112.140117) (xy 296.352528 -112.129945)
			(xy 296.38371 -112.129316) (xy 296.390568 -112.129316) (xy 296.404347 -112.129648) (xy 296.431806 -112.132065)
			(xy 296.445432 -112.134142) (xy 296.472229 -112.138973) (xy 296.524193 -112.155229) (xy 296.57332 -112.178706)
			(xy 296.618612 -112.208926) (xy 296.65915 -112.245276) (xy 296.69411 -112.287018) (xy 296.722784 -112.333304)
			(xy 296.744588 -112.383196) (xy 296.759081 -112.43568) (xy 296.765424 -112.485424) (xy 298.851064 -112.485424)
			(xy 298.855135 -112.429802) (xy 298.867261 -112.375365) (xy 298.887184 -112.323274) (xy 298.91448 -112.274639)
			(xy 298.948566 -112.230496) (xy 298.988715 -112.191787) (xy 299.034073 -112.159336) (xy 299.083673 -112.133835)
			(xy 299.136457 -112.115828) (xy 299.1913 -112.105698) (xy 299.247034 -112.103661) (xy 299.302471 -112.109761)
			(xy 299.356428 -112.123867) (xy 299.407757 -112.145679) (xy 299.455363 -112.174733) (xy 299.498231 -112.210408)
			(xy 299.535448 -112.251945) (xy 299.566221 -112.298458) (xy 299.589893 -112.348955) (xy 299.605961 -112.402362)
			(xy 299.60884 -112.421924) (xy 301.65497 -112.421924) (xy 301.659041 -112.366302) (xy 301.671167 -112.311865)
			(xy 301.69109 -112.259774) (xy 301.718386 -112.211139) (xy 301.752472 -112.166996) (xy 301.792621 -112.128287)
			(xy 301.837979 -112.095836) (xy 301.887579 -112.070335) (xy 301.940363 -112.052328) (xy 301.995206 -112.042198)
			(xy 302.05094 -112.040161) (xy 302.106377 -112.046261) (xy 302.160334 -112.060367) (xy 302.211663 -112.082179)
			(xy 302.259269 -112.111233) (xy 302.302137 -112.146908) (xy 302.339354 -112.188445) (xy 302.370127 -112.234958)
			(xy 302.393799 -112.285455) (xy 302.409867 -112.338862) (xy 302.417987 -112.394038) (xy 302.418496 -112.421924)
			(xy 302.417987 -112.44981) (xy 302.409867 -112.504986) (xy 302.393799 -112.558393) (xy 302.370127 -112.60889)
			(xy 302.339354 -112.655403) (xy 302.302137 -112.69694) (xy 302.259269 -112.732615) (xy 302.211663 -112.761669)
			(xy 302.160334 -112.783481) (xy 302.106377 -112.797587) (xy 302.05094 -112.803687) (xy 301.995206 -112.80165)
			(xy 301.940363 -112.79152) (xy 301.887579 -112.773513) (xy 301.837979 -112.748012) (xy 301.792621 -112.715561)
			(xy 301.752472 -112.676852) (xy 301.718386 -112.632709) (xy 301.69109 -112.584074) (xy 301.671167 -112.531983)
			(xy 301.659041 -112.477546) (xy 301.65497 -112.421924) (xy 299.60884 -112.421924) (xy 299.614081 -112.457538)
			(xy 299.61459 -112.485424) (xy 299.614081 -112.51331) (xy 299.605961 -112.568486) (xy 299.589893 -112.621893)
			(xy 299.566221 -112.67239) (xy 299.535448 -112.718903) (xy 299.498231 -112.76044) (xy 299.455363 -112.796115)
			(xy 299.407757 -112.825169) (xy 299.356428 -112.846981) (xy 299.302471 -112.861087) (xy 299.247034 -112.867187)
			(xy 299.1913 -112.86515) (xy 299.136457 -112.85502) (xy 299.083673 -112.837013) (xy 299.034073 -112.811512)
			(xy 298.988715 -112.779061) (xy 298.948566 -112.740352) (xy 298.91448 -112.696209) (xy 298.887184 -112.647574)
			(xy 298.867261 -112.595483) (xy 298.855135 -112.541046) (xy 298.851064 -112.485424) (xy 296.765424 -112.485424)
			(xy 296.765968 -112.489691) (xy 296.765109 -112.544133) (xy 296.756522 -112.597899) (xy 296.740381 -112.6499)
			(xy 296.717014 -112.69908) (xy 296.686895 -112.744439) (xy 296.650636 -112.785057) (xy 296.63009 -112.802924)
			(xy 296.610519 -112.818827) (xy 296.567965 -112.845888) (xy 296.522221 -112.867113) (xy 296.474081 -112.882135)
			(xy 296.424384 -112.89069) (xy 296.399204 -112.892078) (xy 296.39895 -112.892078) (xy 296.387774 -112.892586)
			(xy 296.384472 -112.892586) (xy 296.355382 -112.892016) (xy 296.29788 -112.883148) (xy 296.242386 -112.865667)
			(xy 296.190184 -112.839977) (xy 296.166032 -112.823752) (xy 296.165524 -112.823498) (xy 296.162476 -112.821466)
			(xy 296.155872 -112.818164) (xy 296.149878 -112.815524) (xy 296.137016 -112.813074) (xy 296.130472 -112.813338)
			(xy 296.12844 -112.813592) (xy 296.117518 -112.815878) (xy 296.112692 -112.81791) (xy 296.112438 -112.81791)
			(xy 296.09288 -112.827308) (xy 296.092372 -112.827308) (xy 296.023538 -112.86109) (xy 296.020744 -112.864138)
			(xy 296.013632 -112.872774) (xy 296.00906 -112.88014) (xy 296.006774 -112.884966) (xy 296.004742 -112.895634)
			(xy 296.003726 -112.902746) (xy 295.98555 -113.251742) (xy 296.506136 -113.251742) (xy 296.510207 -113.19612)
			(xy 296.522333 -113.141683) (xy 296.542256 -113.089592) (xy 296.569552 -113.040957) (xy 296.603638 -112.996814)
			(xy 296.643787 -112.958105) (xy 296.689145 -112.925654) (xy 296.738745 -112.900153) (xy 296.791529 -112.882146)
			(xy 296.846372 -112.872016) (xy 296.902106 -112.869979) (xy 296.957543 -112.876079) (xy 297.0115 -112.890185)
			(xy 297.062829 -112.911997) (xy 297.110435 -112.941051) (xy 297.153303 -112.976726) (xy 297.164851 -112.989614)
			(xy 302.639982 -112.989614) (xy 302.644053 -112.933992) (xy 302.656179 -112.879555) (xy 302.676102 -112.827464)
			(xy 302.703398 -112.778829) (xy 302.737484 -112.734686) (xy 302.777633 -112.695977) (xy 302.822991 -112.663526)
			(xy 302.872591 -112.638025) (xy 302.925375 -112.620018) (xy 302.980218 -112.609888) (xy 303.035952 -112.607851)
			(xy 303.091389 -112.613951) (xy 303.145346 -112.628057) (xy 303.196675 -112.649869) (xy 303.244281 -112.678923)
			(xy 303.287149 -112.714598) (xy 303.324366 -112.756135) (xy 303.355139 -112.802648) (xy 303.378811 -112.853145)
			(xy 303.394879 -112.906552) (xy 303.402999 -112.961728) (xy 303.403508 -112.989614) (xy 303.402999 -113.0175)
			(xy 303.394879 -113.072676) (xy 303.378811 -113.126083) (xy 303.355139 -113.17658) (xy 303.324366 -113.223093)
			(xy 303.287149 -113.26463) (xy 303.244281 -113.300305) (xy 303.196675 -113.329359) (xy 303.145346 -113.351171)
			(xy 303.091389 -113.365277) (xy 303.035952 -113.371377) (xy 302.980218 -113.36934) (xy 302.925375 -113.35921)
			(xy 302.872591 -113.341203) (xy 302.822991 -113.315702) (xy 302.777633 -113.283251) (xy 302.737484 -113.244542)
			(xy 302.703398 -113.200399) (xy 302.676102 -113.151764) (xy 302.656179 -113.099673) (xy 302.644053 -113.045236)
			(xy 302.639982 -112.989614) (xy 297.164851 -112.989614) (xy 297.19052 -113.018263) (xy 297.221293 -113.064776)
			(xy 297.244965 -113.115273) (xy 297.261033 -113.16868) (xy 297.269153 -113.223856) (xy 297.269662 -113.251742)
			(xy 297.269153 -113.279628) (xy 297.261033 -113.334804) (xy 297.244965 -113.388211) (xy 297.22297 -113.43513)
			(xy 299.130718 -113.43513) (xy 299.134789 -113.379508) (xy 299.146915 -113.325071) (xy 299.166838 -113.27298)
			(xy 299.194134 -113.224345) (xy 299.22822 -113.180202) (xy 299.268369 -113.141493) (xy 299.313727 -113.109042)
			(xy 299.363327 -113.083541) (xy 299.416111 -113.065534) (xy 299.470954 -113.055404) (xy 299.526688 -113.053367)
			(xy 299.582125 -113.059467) (xy 299.636082 -113.073573) (xy 299.687411 -113.095385) (xy 299.735017 -113.124439)
			(xy 299.777885 -113.160114) (xy 299.815102 -113.201651) (xy 299.845875 -113.248164) (xy 299.869547 -113.298661)
			(xy 299.885615 -113.352068) (xy 299.893735 -113.407244) (xy 299.894244 -113.43513) (xy 299.894193 -113.437924)
			(xy 301.557688 -113.437924) (xy 301.561759 -113.382302) (xy 301.573885 -113.327865) (xy 301.593808 -113.275774)
			(xy 301.621104 -113.227139) (xy 301.65519 -113.182996) (xy 301.695339 -113.144287) (xy 301.740697 -113.111836)
			(xy 301.790297 -113.086335) (xy 301.843081 -113.068328) (xy 301.897924 -113.058198) (xy 301.953658 -113.056161)
			(xy 302.009095 -113.062261) (xy 302.063052 -113.076367) (xy 302.114381 -113.098179) (xy 302.161987 -113.127233)
			(xy 302.204855 -113.162908) (xy 302.242072 -113.204445) (xy 302.272845 -113.250958) (xy 302.296517 -113.301455)
			(xy 302.312585 -113.354862) (xy 302.320705 -113.410038) (xy 302.321214 -113.437924) (xy 302.320705 -113.46581)
			(xy 302.312585 -113.520986) (xy 302.296517 -113.574393) (xy 302.272845 -113.62489) (xy 302.242072 -113.671403)
			(xy 302.204855 -113.71294) (xy 302.161987 -113.748615) (xy 302.114381 -113.777669) (xy 302.063052 -113.799481)
			(xy 302.009095 -113.813587) (xy 301.953658 -113.819687) (xy 301.897924 -113.81765) (xy 301.843081 -113.80752)
			(xy 301.790297 -113.789513) (xy 301.740697 -113.764012) (xy 301.695339 -113.731561) (xy 301.65519 -113.692852)
			(xy 301.621104 -113.648709) (xy 301.593808 -113.600074) (xy 301.573885 -113.547983) (xy 301.561759 -113.493546)
			(xy 301.557688 -113.437924) (xy 299.894193 -113.437924) (xy 299.893735 -113.463016) (xy 299.885615 -113.518192)
			(xy 299.869547 -113.571599) (xy 299.845875 -113.622096) (xy 299.815102 -113.668609) (xy 299.777885 -113.710146)
			(xy 299.735017 -113.745821) (xy 299.687411 -113.774875) (xy 299.636082 -113.796687) (xy 299.582125 -113.810793)
			(xy 299.526688 -113.816893) (xy 299.470954 -113.814856) (xy 299.416111 -113.804726) (xy 299.363327 -113.786719)
			(xy 299.313727 -113.761218) (xy 299.268369 -113.728767) (xy 299.22822 -113.690058) (xy 299.194134 -113.645915)
			(xy 299.166838 -113.59728) (xy 299.146915 -113.545189) (xy 299.134789 -113.490752) (xy 299.130718 -113.43513)
			(xy 297.22297 -113.43513) (xy 297.221293 -113.438708) (xy 297.19052 -113.485221) (xy 297.153303 -113.526758)
			(xy 297.110435 -113.562433) (xy 297.062829 -113.591487) (xy 297.0115 -113.613299) (xy 296.957543 -113.627405)
			(xy 296.902106 -113.633505) (xy 296.846372 -113.631468) (xy 296.791529 -113.621338) (xy 296.738745 -113.603331)
			(xy 296.689145 -113.57783) (xy 296.643787 -113.545379) (xy 296.603638 -113.50667) (xy 296.569552 -113.462527)
			(xy 296.542256 -113.413892) (xy 296.522333 -113.361801) (xy 296.510207 -113.307364) (xy 296.506136 -113.251742)
			(xy 295.98555 -113.251742) (xy 295.916297 -114.581432) (xy 298.499528 -114.581432) (xy 298.503599 -114.52581)
			(xy 298.515725 -114.471373) (xy 298.535648 -114.419282) (xy 298.562944 -114.370647) (xy 298.59703 -114.326504)
			(xy 298.637179 -114.287795) (xy 298.682537 -114.255344) (xy 298.732137 -114.229843) (xy 298.784921 -114.211836)
			(xy 298.839764 -114.201706) (xy 298.895498 -114.199669) (xy 298.950935 -114.205769) (xy 299.004892 -114.219875)
			(xy 299.056221 -114.241687) (xy 299.103827 -114.270741) (xy 299.127082 -114.290094) (xy 302.560226 -114.290094)
			(xy 302.564297 -114.234472) (xy 302.576423 -114.180035) (xy 302.596346 -114.127944) (xy 302.623642 -114.079309)
			(xy 302.657728 -114.035166) (xy 302.697877 -113.996457) (xy 302.743235 -113.964006) (xy 302.792835 -113.938505)
			(xy 302.845619 -113.920498) (xy 302.900462 -113.910368) (xy 302.956196 -113.908331) (xy 303.011633 -113.914431)
			(xy 303.06559 -113.928537) (xy 303.116919 -113.950349) (xy 303.164525 -113.979403) (xy 303.207393 -114.015078)
			(xy 303.24461 -114.056615) (xy 303.275383 -114.103128) (xy 303.299055 -114.153625) (xy 303.315123 -114.207032)
			(xy 303.323243 -114.262208) (xy 303.323752 -114.290094) (xy 303.323243 -114.31798) (xy 303.315123 -114.373156)
			(xy 303.299055 -114.426563) (xy 303.275383 -114.47706) (xy 303.24461 -114.523573) (xy 303.207393 -114.56511)
			(xy 303.164525 -114.600785) (xy 303.116919 -114.629839) (xy 303.06559 -114.651651) (xy 303.011633 -114.665757)
			(xy 302.956196 -114.671857) (xy 302.900462 -114.66982) (xy 302.845619 -114.65969) (xy 302.792835 -114.641683)
			(xy 302.743235 -114.616182) (xy 302.697877 -114.583731) (xy 302.657728 -114.545022) (xy 302.623642 -114.500879)
			(xy 302.596346 -114.452244) (xy 302.576423 -114.400153) (xy 302.564297 -114.345716) (xy 302.560226 -114.290094)
			(xy 299.127082 -114.290094) (xy 299.146695 -114.306416) (xy 299.183912 -114.347953) (xy 299.214685 -114.394466)
			(xy 299.238357 -114.444963) (xy 299.254425 -114.49837) (xy 299.262545 -114.553546) (xy 299.263054 -114.581432)
			(xy 299.262545 -114.609318) (xy 299.254425 -114.664494) (xy 299.238357 -114.717901) (xy 299.214685 -114.768398)
			(xy 299.183912 -114.814911) (xy 299.146695 -114.856448) (xy 299.103827 -114.892123) (xy 299.056221 -114.921177)
			(xy 299.004892 -114.942989) (xy 298.950935 -114.957095) (xy 298.895498 -114.963195) (xy 298.839764 -114.961158)
			(xy 298.784921 -114.951028) (xy 298.732137 -114.933021) (xy 298.682537 -114.90752) (xy 298.637179 -114.875069)
			(xy 298.59703 -114.83636) (xy 298.562944 -114.792217) (xy 298.535648 -114.743582) (xy 298.515725 -114.691491)
			(xy 298.503599 -114.637054) (xy 298.499528 -114.581432) (xy 295.916297 -114.581432) (xy 295.90746 -114.751104)
			(xy 295.879617 -115.285774) (xy 299.130718 -115.285774) (xy 299.134789 -115.230152) (xy 299.146915 -115.175715)
			(xy 299.166838 -115.123624) (xy 299.194134 -115.074989) (xy 299.22822 -115.030846) (xy 299.268369 -114.992137)
			(xy 299.313727 -114.959686) (xy 299.363327 -114.934185) (xy 299.416111 -114.916178) (xy 299.470954 -114.906048)
			(xy 299.526688 -114.904011) (xy 299.582125 -114.910111) (xy 299.636082 -114.924217) (xy 299.687411 -114.946029)
			(xy 299.735017 -114.975083) (xy 299.777885 -115.010758) (xy 299.815102 -115.052295) (xy 299.845875 -115.098808)
			(xy 299.869547 -115.149305) (xy 299.885615 -115.202712) (xy 299.893735 -115.257888) (xy 299.894244 -115.285774)
			(xy 299.893735 -115.31366) (xy 299.886774 -115.360958) (xy 306.318412 -115.360958) (xy 306.318909 -115.333589)
			(xy 306.326719 -115.279411) (xy 306.342201 -115.226908) (xy 306.365036 -115.177161) (xy 306.394754 -115.131193)
			(xy 306.412392 -115.11026) (xy 306.412646 -115.110006) (xy 306.418242 -115.102926) (xy 306.424482 -115.086004)
			(xy 306.424838 -115.076986) (xy 306.424838 -115.00993) (xy 306.424458 -115.000916) (xy 306.418226 -114.983999)
			(xy 306.412646 -114.97691) (xy 306.412392 -114.97691) (xy 306.412392 -114.976656) (xy 306.394764 -114.955715)
			(xy 306.365051 -114.909744) (xy 306.342213 -114.859999) (xy 306.326719 -114.807501) (xy 306.318888 -114.753327)
			(xy 306.318412 -114.725958) (xy 306.318839 -114.698705) (xy 306.326602 -114.644754) (xy 306.341963 -114.592457)
			(xy 306.364611 -114.542878) (xy 306.394083 -114.497027) (xy 306.429781 -114.455837) (xy 306.470977 -114.420146)
			(xy 306.516833 -114.390681) (xy 306.566415 -114.368041) (xy 306.618715 -114.352688) (xy 306.672667 -114.344934)
			(xy 306.69992 -114.34445) (xy 306.727291 -114.344892) (xy 306.781472 -114.352714) (xy 306.833976 -114.368208)
			(xy 306.883722 -114.391055) (xy 306.929688 -114.420786) (xy 306.950618 -114.43843) (xy 306.950872 -114.438684)
			(xy 306.957964 -114.444263) (xy 306.974876 -114.450515) (xy 306.983892 -114.450876) (xy 307.050948 -114.450876)
			(xy 307.059963 -114.450499) (xy 307.07688 -114.444266) (xy 307.083968 -114.438684) (xy 307.083968 -114.43843)
			(xy 307.084222 -114.43843) (xy 307.105177 -114.420819) (xy 307.151143 -114.391102) (xy 307.200884 -114.36826)
			(xy 307.25338 -114.352762) (xy 307.307552 -114.344927) (xy 307.33492 -114.34445) (xy 307.36217 -114.344959)
			(xy 307.416115 -114.352717) (xy 307.468406 -114.368073) (xy 307.517981 -114.390713) (xy 307.563829 -114.420178)
			(xy 307.605018 -114.455866) (xy 307.640709 -114.497053) (xy 307.670176 -114.5429) (xy 307.69282 -114.592473)
			(xy 307.708178 -114.644764) (xy 307.715939 -114.698708) (xy 307.716428 -114.725958) (xy 307.715955 -114.753328)
			(xy 307.708141 -114.807508) (xy 307.692655 -114.860011) (xy 307.669814 -114.909758) (xy 307.64009 -114.955725)
			(xy 307.622448 -114.976656) (xy 307.622194 -114.97691) (xy 307.616596 -114.983989) (xy 307.610357 -115.000912)
			(xy 307.610002 -115.00993) (xy 307.610002 -115.076986) (xy 307.610365 -115.086002) (xy 307.616608 -115.102919)
			(xy 307.622194 -115.110006) (xy 307.622448 -115.110006) (xy 307.622448 -115.11026) (xy 307.640074 -115.131203)
			(xy 307.669789 -115.177172) (xy 307.692629 -115.226917) (xy 307.708123 -115.279415) (xy 307.715953 -115.333589)
			(xy 307.716428 -115.360958) (xy 307.715906 -115.388209) (xy 307.708155 -115.442157) (xy 307.692805 -115.494452)
			(xy 307.670169 -115.544031) (xy 307.640707 -115.589883) (xy 307.60502 -115.631076) (xy 307.563833 -115.66677)
			(xy 307.517985 -115.696239) (xy 307.46841 -115.718884) (xy 307.416117 -115.734242) (xy 307.362171 -115.742001)
			(xy 307.33492 -115.742466) (xy 307.30755 -115.741996) (xy 307.253371 -115.734181) (xy 307.200867 -115.718693)
			(xy 307.15112 -115.695852) (xy 307.105153 -115.666127) (xy 307.084222 -115.648486) (xy 307.083968 -115.648232)
			(xy 307.076872 -115.64266) (xy 307.059962 -115.636406) (xy 307.050948 -115.63604) (xy 306.983892 -115.63604)
			(xy 306.974874 -115.636384) (xy 306.957956 -115.64264) (xy 306.950872 -115.648232) (xy 306.950872 -115.648486)
			(xy 306.950618 -115.648486) (xy 306.929688 -115.666128) (xy 306.883715 -115.69584) (xy 306.833967 -115.718675)
			(xy 306.781466 -115.734166) (xy 306.727289 -115.741993) (xy 306.69992 -115.742466) (xy 306.672666 -115.742026)
			(xy 306.618712 -115.734271) (xy 306.566411 -115.718915) (xy 306.516828 -115.696272) (xy 306.470973 -115.666802)
			(xy 306.429779 -115.631106) (xy 306.394085 -115.58991) (xy 306.364618 -115.544053) (xy 306.341977 -115.494468)
			(xy 306.326625 -115.442167) (xy 306.318872 -115.388212) (xy 306.318412 -115.360958) (xy 299.886774 -115.360958)
			(xy 299.885615 -115.368836) (xy 299.869547 -115.422243) (xy 299.845875 -115.47274) (xy 299.815102 -115.519253)
			(xy 299.777885 -115.56079) (xy 299.735017 -115.596465) (xy 299.687411 -115.625519) (xy 299.636082 -115.647331)
			(xy 299.582125 -115.661437) (xy 299.526688 -115.667537) (xy 299.470954 -115.6655) (xy 299.416111 -115.65537)
			(xy 299.363327 -115.637363) (xy 299.313727 -115.611862) (xy 299.268369 -115.579411) (xy 299.22822 -115.540702)
			(xy 299.194134 -115.496559) (xy 299.166838 -115.447924) (xy 299.146915 -115.395833) (xy 299.134789 -115.341396)
			(xy 299.130718 -115.285774) (xy 295.879617 -115.285774) (xy 295.847502 -115.902486) (xy 296.391074 -115.902486)
			(xy 296.395145 -115.846864) (xy 296.407271 -115.792427) (xy 296.427194 -115.740336) (xy 296.45449 -115.691701)
			(xy 296.488576 -115.647558) (xy 296.528725 -115.608849) (xy 296.574083 -115.576398) (xy 296.623683 -115.550897)
			(xy 296.676467 -115.53289) (xy 296.73131 -115.52276) (xy 296.787044 -115.520723) (xy 296.842481 -115.526823)
			(xy 296.896438 -115.540929) (xy 296.947767 -115.562741) (xy 296.995373 -115.591795) (xy 297.038241 -115.62747)
			(xy 297.075458 -115.669007) (xy 297.106231 -115.71552) (xy 297.129903 -115.766017) (xy 297.145971 -115.819424)
			(xy 297.154091 -115.8746) (xy 297.1546 -115.902486) (xy 297.154091 -115.930372) (xy 297.145971 -115.985548)
			(xy 297.129903 -116.038955) (xy 297.106231 -116.089452) (xy 297.075458 -116.135965) (xy 297.038241 -116.177502)
			(xy 296.995373 -116.213177) (xy 296.947767 -116.242231) (xy 296.896438 -116.264043) (xy 296.842481 -116.278149)
			(xy 296.787044 -116.284249) (xy 296.73131 -116.282212) (xy 296.676467 -116.272082) (xy 296.623683 -116.254075)
			(xy 296.574083 -116.228574) (xy 296.528725 -116.196123) (xy 296.488576 -116.157414) (xy 296.45449 -116.113271)
			(xy 296.427194 -116.064636) (xy 296.407271 -116.012545) (xy 296.395145 -115.958108) (xy 296.391074 -115.902486)
			(xy 295.847502 -115.902486) (xy 295.819116 -116.44757) (xy 298.357034 -116.44757) (xy 298.361105 -116.391948)
			(xy 298.373231 -116.337511) (xy 298.393154 -116.28542) (xy 298.42045 -116.236785) (xy 298.454536 -116.192642)
			(xy 298.494685 -116.153933) (xy 298.540043 -116.121482) (xy 298.589643 -116.095981) (xy 298.642427 -116.077974)
			(xy 298.69727 -116.067844) (xy 298.753004 -116.065807) (xy 298.808441 -116.071907) (xy 298.862398 -116.086013)
			(xy 298.913727 -116.107825) (xy 298.961333 -116.136879) (xy 299.004201 -116.172554) (xy 299.041418 -116.214091)
			(xy 299.072191 -116.260604) (xy 299.095863 -116.311101) (xy 299.111931 -116.364508) (xy 299.120051 -116.419684)
			(xy 299.12056 -116.44757) (xy 299.120051 -116.475456) (xy 299.119781 -116.477288) (xy 303.504344 -116.477288)
			(xy 303.508415 -116.421666) (xy 303.520541 -116.367229) (xy 303.540464 -116.315138) (xy 303.56776 -116.266503)
			(xy 303.601846 -116.22236) (xy 303.641995 -116.183651) (xy 303.687353 -116.1512) (xy 303.736953 -116.125699)
			(xy 303.789737 -116.107692) (xy 303.84458 -116.097562) (xy 303.900314 -116.095525) (xy 303.955751 -116.101625)
			(xy 304.009708 -116.115731) (xy 304.061037 -116.137543) (xy 304.108643 -116.166597) (xy 304.151511 -116.202272)
			(xy 304.188728 -116.243809) (xy 304.219501 -116.290322) (xy 304.243173 -116.340819) (xy 304.259241 -116.394226)
			(xy 304.267361 -116.449402) (xy 304.26787 -116.477288) (xy 304.267361 -116.505174) (xy 304.259241 -116.56035)
			(xy 304.243173 -116.613757) (xy 304.219501 -116.664254) (xy 304.188728 -116.710767) (xy 304.151511 -116.752304)
			(xy 304.108643 -116.787979) (xy 304.061037 -116.817033) (xy 304.009708 -116.838845) (xy 303.955751 -116.852951)
			(xy 303.900314 -116.859051) (xy 303.84458 -116.857014) (xy 303.789737 -116.846884) (xy 303.736953 -116.828877)
			(xy 303.687353 -116.803376) (xy 303.641995 -116.770925) (xy 303.601846 -116.732216) (xy 303.56776 -116.688073)
			(xy 303.540464 -116.639438) (xy 303.520541 -116.587347) (xy 303.508415 -116.53291) (xy 303.504344 -116.477288)
			(xy 299.119781 -116.477288) (xy 299.111931 -116.530632) (xy 299.095863 -116.584039) (xy 299.072191 -116.634536)
			(xy 299.041418 -116.681049) (xy 299.004201 -116.722586) (xy 298.961333 -116.758261) (xy 298.913727 -116.787315)
			(xy 298.862398 -116.809127) (xy 298.808441 -116.823233) (xy 298.753004 -116.829333) (xy 298.69727 -116.827296)
			(xy 298.642427 -116.817166) (xy 298.589643 -116.799159) (xy 298.540043 -116.773658) (xy 298.494685 -116.741207)
			(xy 298.454536 -116.702498) (xy 298.42045 -116.658355) (xy 298.393154 -116.60972) (xy 298.373231 -116.557629)
			(xy 298.361105 -116.503192) (xy 298.357034 -116.44757) (xy 295.819116 -116.44757) (xy 295.752663 -117.723666)
			(xy 301.889666 -117.723666) (xy 301.893737 -117.668044) (xy 301.905863 -117.613607) (xy 301.925786 -117.561516)
			(xy 301.953082 -117.512881) (xy 301.987168 -117.468738) (xy 302.027317 -117.430029) (xy 302.072675 -117.397578)
			(xy 302.122275 -117.372077) (xy 302.175059 -117.35407) (xy 302.229902 -117.34394) (xy 302.285636 -117.341903)
			(xy 302.341073 -117.348003) (xy 302.39503 -117.362109) (xy 302.446359 -117.383921) (xy 302.493965 -117.412975)
			(xy 302.536833 -117.44865) (xy 302.57405 -117.490187) (xy 302.604823 -117.5367) (xy 302.628495 -117.587197)
			(xy 302.644563 -117.640604) (xy 302.652683 -117.69578) (xy 302.653192 -117.723666) (xy 302.652683 -117.751552)
			(xy 302.651628 -117.758718) (xy 306.675028 -117.758718) (xy 306.675028 -116.895118) (xy 306.675518 -116.86515)
			(xy 306.683341 -116.805728) (xy 306.698854 -116.747835) (xy 306.72179 -116.692462) (xy 306.751757 -116.640556)
			(xy 306.788244 -116.593006) (xy 306.830624 -116.550626) (xy 306.878174 -116.514139) (xy 306.93008 -116.484172)
			(xy 306.985453 -116.461236) (xy 307.043346 -116.445723) (xy 307.102768 -116.4379) (xy 307.162704 -116.4379)
			(xy 307.222126 -116.445723) (xy 307.280019 -116.461236) (xy 307.335392 -116.484172) (xy 307.387298 -116.514139)
			(xy 307.434848 -116.550626) (xy 307.477228 -116.593006) (xy 307.513715 -116.640556) (xy 307.543682 -116.692462)
			(xy 307.566618 -116.747835) (xy 307.582131 -116.805728) (xy 307.589954 -116.86515) (xy 307.590444 -116.895118)
			(xy 307.590444 -117.758718) (xy 307.589954 -117.788686) (xy 307.582131 -117.848108) (xy 307.566618 -117.906001)
			(xy 307.543682 -117.961374) (xy 307.513715 -118.01328) (xy 307.477228 -118.06083) (xy 307.434848 -118.10321)
			(xy 307.387298 -118.139697) (xy 307.335392 -118.169664) (xy 307.280019 -118.1926) (xy 307.222126 -118.208113)
			(xy 307.162704 -118.215936) (xy 307.102768 -118.215936) (xy 307.043346 -118.208113) (xy 306.985453 -118.1926)
			(xy 306.93008 -118.169664) (xy 306.878174 -118.139697) (xy 306.830624 -118.10321) (xy 306.788244 -118.06083)
			(xy 306.751757 -118.01328) (xy 306.72179 -117.961374) (xy 306.698854 -117.906001) (xy 306.683341 -117.848108)
			(xy 306.675518 -117.788686) (xy 306.675028 -117.758718) (xy 302.651628 -117.758718) (xy 302.644563 -117.806728)
			(xy 302.628495 -117.860135) (xy 302.604823 -117.910632) (xy 302.57405 -117.957145) (xy 302.536833 -117.998682)
			(xy 302.493965 -118.034357) (xy 302.446359 -118.063411) (xy 302.39503 -118.085223) (xy 302.341073 -118.099329)
			(xy 302.285636 -118.105429) (xy 302.229902 -118.103392) (xy 302.175059 -118.093262) (xy 302.122275 -118.075255)
			(xy 302.072675 -118.049754) (xy 302.027317 -118.017303) (xy 301.987168 -117.978594) (xy 301.953082 -117.934451)
			(xy 301.925786 -117.885816) (xy 301.905863 -117.833725) (xy 301.893737 -117.779288) (xy 301.889666 -117.723666)
			(xy 295.752663 -117.723666) (xy 295.73728 -118.019068) (xy 295.73728 -118.019576) (xy 295.736772 -118.031006)
			(xy 295.739566 -118.037864) (xy 295.748202 -118.050818) (xy 295.754298 -118.058184) (xy 295.775237 -118.080173)
			(xy 295.810721 -118.129441) (xy 295.838118 -118.183624) (xy 295.856765 -118.241407) (xy 295.866207 -118.301384)
			(xy 295.86682 -118.331742) (xy 295.86682 -118.331996) (xy 295.86629 -118.360927) (xy 295.85772 -118.41815)
			(xy 295.840769 -118.473473) (xy 295.815811 -118.525675) (xy 295.783395 -118.573605) (xy 295.744238 -118.616204)
			(xy 295.72204 -118.634764) (xy 295.7068 -118.64721) (xy 295.704006 -118.65864) (xy 295.697148 -118.788942)
			(xy 295.690036 -118.925594) (xy 295.681654 -119.086376) (xy 295.656637 -119.567198) (xy 298.799504 -119.567198)
			(xy 298.799504 -118.703598) (xy 298.799994 -118.67363) (xy 298.807817 -118.614208) (xy 298.82333 -118.556315)
			(xy 298.846266 -118.500942) (xy 298.876233 -118.449036) (xy 298.91272 -118.401486) (xy 298.9551 -118.359106)
			(xy 299.00265 -118.322619) (xy 299.054556 -118.292652) (xy 299.109929 -118.269716) (xy 299.167822 -118.254203)
			(xy 299.227244 -118.24638) (xy 299.28718 -118.24638) (xy 299.346602 -118.254203) (xy 299.404495 -118.269716)
			(xy 299.459868 -118.292652) (xy 299.511774 -118.322619) (xy 299.559324 -118.359106) (xy 299.601704 -118.401486)
			(xy 299.638191 -118.449036) (xy 299.668158 -118.500942) (xy 299.691094 -118.556315) (xy 299.706607 -118.614208)
			(xy 299.71443 -118.67363) (xy 299.71492 -118.703598) (xy 299.71492 -119.567198) (xy 299.71443 -119.597166)
			(xy 299.706607 -119.656588) (xy 299.691094 -119.714481) (xy 299.668158 -119.769854) (xy 299.638191 -119.82176)
			(xy 299.601704 -119.86931) (xy 299.559324 -119.91169) (xy 299.511774 -119.948177) (xy 299.459868 -119.978144)
			(xy 299.404495 -120.00108) (xy 299.346602 -120.016593) (xy 299.28718 -120.024416) (xy 299.227244 -120.024416)
			(xy 299.167822 -120.016593) (xy 299.109929 -120.00108) (xy 299.054556 -119.978144) (xy 299.00265 -119.948177)
			(xy 298.9551 -119.91169) (xy 298.91272 -119.86931) (xy 298.876233 -119.82176) (xy 298.846266 -119.769854)
			(xy 298.82333 -119.714481) (xy 298.807817 -119.656588) (xy 298.799994 -119.597166) (xy 298.799504 -119.567198)
			(xy 295.656637 -119.567198) (xy 295.563798 -121.351548) (xy 295.562978 -121.367296) (xy 296.945304 -121.367296)
			(xy 296.945304 -120.503696) (xy 296.945794 -120.473728) (xy 296.953617 -120.414306) (xy 296.96913 -120.356413)
			(xy 296.992066 -120.30104) (xy 297.022033 -120.249134) (xy 297.05852 -120.201584) (xy 297.1009 -120.159204)
			(xy 297.14845 -120.122717) (xy 297.200356 -120.09275) (xy 297.255729 -120.069814) (xy 297.313622 -120.054301)
			(xy 297.373044 -120.046478) (xy 297.43298 -120.046478) (xy 297.492402 -120.054301) (xy 297.550295 -120.069814)
			(xy 297.605668 -120.09275) (xy 297.657574 -120.122717) (xy 297.705124 -120.159204) (xy 297.747504 -120.201584)
			(xy 297.783991 -120.249134) (xy 297.813958 -120.30104) (xy 297.836894 -120.356413) (xy 297.852407 -120.414306)
			(xy 297.86023 -120.473728) (xy 297.86072 -120.503696) (xy 297.86072 -121.367296) (xy 297.86023 -121.397264)
			(xy 297.852407 -121.456686) (xy 297.836894 -121.514579) (xy 297.813958 -121.569952) (xy 297.783991 -121.621858)
			(xy 297.747504 -121.669408) (xy 297.705124 -121.711788) (xy 297.657574 -121.748275) (xy 297.605668 -121.778242)
			(xy 297.550295 -121.801178) (xy 297.492402 -121.816691) (xy 297.43298 -121.824514) (xy 297.373044 -121.824514)
			(xy 297.313622 -121.816691) (xy 297.255729 -121.801178) (xy 297.200356 -121.778242) (xy 297.14845 -121.748275)
			(xy 297.1009 -121.711788) (xy 297.05852 -121.669408) (xy 297.022033 -121.621858) (xy 296.992066 -121.569952)
			(xy 296.96913 -121.514579) (xy 296.953617 -121.456686) (xy 296.945794 -121.397264) (xy 296.945304 -121.367296)
			(xy 295.562978 -121.367296) (xy 295.497758 -122.61977) (xy 295.469171 -123.16714) (xy 298.799504 -123.16714)
			(xy 298.799504 -122.30354) (xy 298.799994 -122.273572) (xy 298.807817 -122.21415) (xy 298.82333 -122.156257)
			(xy 298.846266 -122.100884) (xy 298.876233 -122.048978) (xy 298.91272 -122.001428) (xy 298.9551 -121.959048)
			(xy 299.00265 -121.922561) (xy 299.054556 -121.892594) (xy 299.109929 -121.869658) (xy 299.167822 -121.854145)
			(xy 299.227244 -121.846322) (xy 299.28718 -121.846322) (xy 299.346602 -121.854145) (xy 299.404495 -121.869658)
			(xy 299.459868 -121.892594) (xy 299.511774 -121.922561) (xy 299.559324 -121.959048) (xy 299.601704 -122.001428)
			(xy 299.638191 -122.048978) (xy 299.668158 -122.100884) (xy 299.691094 -122.156257) (xy 299.706607 -122.21415)
			(xy 299.71443 -122.273572) (xy 299.71492 -122.30354) (xy 299.71492 -123.16714) (xy 299.71443 -123.197108)
			(xy 299.706607 -123.25653) (xy 299.691094 -123.314423) (xy 299.668158 -123.369796) (xy 299.638191 -123.421702)
			(xy 299.601704 -123.469252) (xy 299.559324 -123.511632) (xy 299.511774 -123.548119) (xy 299.459868 -123.578086)
			(xy 299.404495 -123.601022) (xy 299.346602 -123.616535) (xy 299.28718 -123.624358) (xy 299.227244 -123.624358)
			(xy 299.167822 -123.616535) (xy 299.109929 -123.601022) (xy 299.054556 -123.578086) (xy 299.00265 -123.548119)
			(xy 298.9551 -123.511632) (xy 298.91272 -123.469252) (xy 298.876233 -123.421702) (xy 298.846266 -123.369796)
			(xy 298.82333 -123.314423) (xy 298.807817 -123.25653) (xy 298.799994 -123.197108) (xy 298.799504 -123.16714)
			(xy 295.469171 -123.16714) (xy 295.458134 -123.378468) (xy 295.37544 -124.967238) (xy 296.945304 -124.967238)
			(xy 296.945304 -124.103638) (xy 296.945794 -124.07367) (xy 296.953617 -124.014248) (xy 296.96913 -123.956355)
			(xy 296.992066 -123.900982) (xy 297.022033 -123.849076) (xy 297.05852 -123.801526) (xy 297.1009 -123.759146)
			(xy 297.14845 -123.722659) (xy 297.200356 -123.692692) (xy 297.255729 -123.669756) (xy 297.313622 -123.654243)
			(xy 297.373044 -123.64642) (xy 297.43298 -123.64642) (xy 297.492402 -123.654243) (xy 297.550295 -123.669756)
			(xy 297.605668 -123.692692) (xy 297.657574 -123.722659) (xy 297.705124 -123.759146) (xy 297.747504 -123.801526)
			(xy 297.783991 -123.849076) (xy 297.813958 -123.900982) (xy 297.836894 -123.956355) (xy 297.852407 -124.014248)
			(xy 297.86023 -124.07367) (xy 297.86072 -124.103638) (xy 297.86072 -124.967238) (xy 297.86023 -124.997206)
			(xy 297.852407 -125.056628) (xy 297.836894 -125.114521) (xy 297.813958 -125.169894) (xy 297.783991 -125.2218)
			(xy 297.747504 -125.26935) (xy 297.705124 -125.31173) (xy 297.657574 -125.348217) (xy 297.605668 -125.378184)
			(xy 297.550295 -125.40112) (xy 297.492402 -125.416633) (xy 297.43298 -125.424456) (xy 297.373044 -125.424456)
			(xy 297.313622 -125.416633) (xy 297.255729 -125.40112) (xy 297.200356 -125.378184) (xy 297.14845 -125.348217)
			(xy 297.1009 -125.31173) (xy 297.05852 -125.26935) (xy 297.022033 -125.2218) (xy 296.992066 -125.169894)
			(xy 296.96913 -125.114521) (xy 296.953617 -125.056628) (xy 296.945794 -124.997206) (xy 296.945304 -124.967238)
			(xy 295.37544 -124.967238) (xy 295.073034 -130.777234) (xy 298.799504 -130.777234) (xy 298.799504 -129.913634)
			(xy 298.799994 -129.883666) (xy 298.807817 -129.824244) (xy 298.82333 -129.766351) (xy 298.846266 -129.710978)
			(xy 298.876233 -129.659072) (xy 298.91272 -129.611522) (xy 298.9551 -129.569142) (xy 299.00265 -129.532655)
			(xy 299.054556 -129.502688) (xy 299.109929 -129.479752) (xy 299.167822 -129.464239) (xy 299.227244 -129.456416)
			(xy 299.28718 -129.456416) (xy 299.346602 -129.464239) (xy 299.404495 -129.479752) (xy 299.459868 -129.502688)
			(xy 299.511774 -129.532655) (xy 299.559324 -129.569142) (xy 299.601704 -129.611522) (xy 299.638191 -129.659072)
			(xy 299.668158 -129.710978) (xy 299.691094 -129.766351) (xy 299.706607 -129.824244) (xy 299.71443 -129.883666)
			(xy 299.71492 -129.913634) (xy 299.71492 -130.777234) (xy 299.71443 -130.807202) (xy 299.706607 -130.866624)
			(xy 299.691094 -130.924517) (xy 299.668158 -130.97989) (xy 299.638191 -131.031796) (xy 299.601704 -131.079346)
			(xy 299.559324 -131.121726) (xy 299.511774 -131.158213) (xy 299.459868 -131.18818) (xy 299.404495 -131.211116)
			(xy 299.346602 -131.226629) (xy 299.28718 -131.234452) (xy 299.227244 -131.234452) (xy 299.167822 -131.226629)
			(xy 299.109929 -131.211116) (xy 299.054556 -131.18818) (xy 299.00265 -131.158213) (xy 298.9551 -131.121726)
			(xy 298.91272 -131.079346) (xy 298.876233 -131.031796) (xy 298.846266 -130.97989) (xy 298.82333 -130.924517)
			(xy 298.807817 -130.866624) (xy 298.799994 -130.807202) (xy 298.799504 -130.777234) (xy 295.073034 -130.777234)
			(xy 294.97934 -132.577332) (xy 296.945304 -132.577332) (xy 296.945304 -131.713732) (xy 296.945794 -131.683764)
			(xy 296.953617 -131.624342) (xy 296.96913 -131.566449) (xy 296.992066 -131.511076) (xy 297.022033 -131.45917)
			(xy 297.05852 -131.41162) (xy 297.1009 -131.36924) (xy 297.14845 -131.332753) (xy 297.200356 -131.302786)
			(xy 297.255729 -131.27985) (xy 297.313622 -131.264337) (xy 297.373044 -131.256514) (xy 297.43298 -131.256514)
			(xy 297.492402 -131.264337) (xy 297.550295 -131.27985) (xy 297.605668 -131.302786) (xy 297.657574 -131.332753)
			(xy 297.705124 -131.36924) (xy 297.747504 -131.41162) (xy 297.783991 -131.45917) (xy 297.813958 -131.511076)
			(xy 297.836894 -131.566449) (xy 297.852407 -131.624342) (xy 297.86023 -131.683764) (xy 297.86072 -131.713732)
			(xy 297.86072 -132.577332) (xy 297.86023 -132.6073) (xy 297.852407 -132.666722) (xy 297.836894 -132.724615)
			(xy 297.813958 -132.779988) (xy 297.783991 -132.831894) (xy 297.747504 -132.879444) (xy 297.705124 -132.921824)
			(xy 297.657574 -132.958311) (xy 297.605668 -132.988278) (xy 297.550295 -133.011214) (xy 297.492402 -133.026727)
			(xy 297.43298 -133.03455) (xy 297.373044 -133.03455) (xy 297.313622 -133.026727) (xy 297.255729 -133.011214)
			(xy 297.200356 -132.988278) (xy 297.14845 -132.958311) (xy 297.1009 -132.921824) (xy 297.05852 -132.879444)
			(xy 297.022033 -132.831894) (xy 296.992066 -132.779988) (xy 296.96913 -132.724615) (xy 296.953617 -132.666722)
			(xy 296.945794 -132.6073) (xy 296.945304 -132.577332) (xy 294.97934 -132.577332) (xy 294.88566 -134.377176)
			(xy 298.799504 -134.377176) (xy 298.799504 -133.513576) (xy 298.799994 -133.483608) (xy 298.807817 -133.424186)
			(xy 298.82333 -133.366293) (xy 298.846266 -133.31092) (xy 298.876233 -133.259014) (xy 298.91272 -133.211464)
			(xy 298.9551 -133.169084) (xy 299.00265 -133.132597) (xy 299.054556 -133.10263) (xy 299.109929 -133.079694)
			(xy 299.167822 -133.064181) (xy 299.227244 -133.056358) (xy 299.28718 -133.056358) (xy 299.346602 -133.064181)
			(xy 299.404495 -133.079694) (xy 299.459868 -133.10263) (xy 299.511774 -133.132597) (xy 299.559324 -133.169084)
			(xy 299.601704 -133.211464) (xy 299.638191 -133.259014) (xy 299.668158 -133.31092) (xy 299.691094 -133.366293)
			(xy 299.706607 -133.424186) (xy 299.71443 -133.483608) (xy 299.71492 -133.513576) (xy 299.71492 -134.377176)
			(xy 299.71443 -134.407144) (xy 299.706607 -134.466566) (xy 299.691094 -134.524459) (xy 299.668158 -134.579832)
			(xy 299.638191 -134.631738) (xy 299.601704 -134.679288) (xy 299.559324 -134.721668) (xy 299.511774 -134.758155)
			(xy 299.459868 -134.788122) (xy 299.404495 -134.811058) (xy 299.346602 -134.826571) (xy 299.28718 -134.834394)
			(xy 299.227244 -134.834394) (xy 299.167822 -134.826571) (xy 299.109929 -134.811058) (xy 299.054556 -134.788122)
			(xy 299.00265 -134.758155) (xy 298.9551 -134.721668) (xy 298.91272 -134.679288) (xy 298.876233 -134.631738)
			(xy 298.846266 -134.579832) (xy 298.82333 -134.524459) (xy 298.807817 -134.466566) (xy 298.799994 -134.407144)
			(xy 298.799504 -134.377176) (xy 294.88566 -134.377176) (xy 294.791966 -136.177274) (xy 296.945304 -136.177274)
			(xy 296.945304 -135.313674) (xy 296.945794 -135.283706) (xy 296.953617 -135.224284) (xy 296.96913 -135.166391)
			(xy 296.992066 -135.111018) (xy 297.022033 -135.059112) (xy 297.05852 -135.011562) (xy 297.1009 -134.969182)
			(xy 297.14845 -134.932695) (xy 297.200356 -134.902728) (xy 297.255729 -134.879792) (xy 297.313622 -134.864279)
			(xy 297.373044 -134.856456) (xy 297.43298 -134.856456) (xy 297.492402 -134.864279) (xy 297.550295 -134.879792)
			(xy 297.605668 -134.902728) (xy 297.657574 -134.932695) (xy 297.705124 -134.969182) (xy 297.747504 -135.011562)
			(xy 297.783991 -135.059112) (xy 297.813958 -135.111018) (xy 297.836894 -135.166391) (xy 297.852407 -135.224284)
			(xy 297.86023 -135.283706) (xy 297.86072 -135.313674) (xy 297.86072 -136.177274) (xy 297.86023 -136.207242)
			(xy 297.852407 -136.266664) (xy 297.836894 -136.324557) (xy 297.813958 -136.37993) (xy 297.783991 -136.431836)
			(xy 297.747504 -136.479386) (xy 297.705124 -136.521766) (xy 297.657574 -136.558253) (xy 297.605668 -136.58822)
			(xy 297.550295 -136.611156) (xy 297.492402 -136.626669) (xy 297.43298 -136.634492) (xy 297.373044 -136.634492)
			(xy 297.313622 -136.626669) (xy 297.255729 -136.611156) (xy 297.200356 -136.58822) (xy 297.14845 -136.558253)
			(xy 297.1009 -136.521766) (xy 297.05852 -136.479386) (xy 297.022033 -136.431836) (xy 296.992066 -136.37993)
			(xy 296.96913 -136.324557) (xy 296.953617 -136.266664) (xy 296.945794 -136.207242) (xy 296.945304 -136.177274)
			(xy 294.791966 -136.177274) (xy 294.791384 -136.18845) (xy 294.760904 -136.776968) (xy 294.737536 -137.225786)
			(xy 294.72509 -137.465562) (xy 294.724328 -137.48004) (xy 294.724074 -137.483088) (xy 294.724074 -137.489946)
			(xy 294.724531 -137.495034) (xy 294.727223 -137.504886) (xy 294.729408 -137.509504) (xy 294.738044 -137.526268)
			(xy 294.739914 -137.529665) (xy 294.744501 -137.535918) (xy 294.747188 -137.538714) (xy 294.752522 -137.544048)
			(xy 294.774994 -137.561758) (xy 294.814885 -137.602774) (xy 294.848214 -137.649279) (xy 294.874236 -137.700234)
			(xy 294.892369 -137.7545) (xy 294.902208 -137.810862) (xy 294.903398 -137.83945) (xy 294.903398 -137.84834)
			(xy 294.902944 -137.87706) (xy 294.894463 -137.933868) (xy 294.877565 -137.988764) (xy 294.85263 -138.040507)
			(xy 294.820221 -138.087929) (xy 294.781072 -138.129957) (xy 294.736066 -138.165644) (xy 294.711374 -138.180318)
			(xy 294.708072 -138.182096) (xy 294.700706 -138.188192) (xy 294.694654 -138.194653) (xy 294.687101 -138.210653)
			(xy 294.685974 -138.219434) (xy 294.679878 -138.33094) (xy 294.672258 -138.478768) (xy 294.672258 -138.481054)
			(xy 294.67247 -138.487865) (xy 294.676065 -138.501004) (xy 294.67937 -138.506962) (xy 294.683434 -138.51382)
			(xy 294.69334 -138.523218) (xy 294.69969 -138.526774) (xy 294.700198 -138.527028) (xy 294.726133 -138.541353)
			(xy 294.773627 -138.576772) (xy 294.815085 -138.619097) (xy 294.849512 -138.667315) (xy 294.876083 -138.720269)
			(xy 294.894162 -138.776689) (xy 294.903316 -138.835225) (xy 294.903906 -138.864848) (xy 294.903408 -138.892881)
			(xy 294.895197 -138.948342) (xy 294.87896 -139.002005) (xy 294.855046 -139.052714) (xy 294.82397 -139.099379)
			(xy 294.7864 -139.140994) (xy 294.743145 -139.176664) (xy 294.695136 -139.205622) (xy 294.669464 -139.216892)
			(xy 294.668956 -139.217146) (xy 294.662606 -139.21994) (xy 294.649906 -139.229846) (xy 294.642458 -139.236469)
			(xy 294.633035 -139.254016) (xy 294.631618 -139.263882) (xy 294.563833 -140.565451) (xy 295.630578 -140.565451)
			(xy 295.630578 -140.510949) (xy 295.638334 -140.457001) (xy 295.653689 -140.404706) (xy 295.676331 -140.355129)
			(xy 295.705797 -140.309279) (xy 295.741488 -140.268088) (xy 295.782679 -140.232397) (xy 295.828529 -140.202931)
			(xy 295.878106 -140.180289) (xy 295.930401 -140.164934) (xy 295.984349 -140.157178) (xy 296.0116 -140.156692)
			(xy 296.03897 -140.15716) (xy 296.093149 -140.164978) (xy 296.145652 -140.180466) (xy 296.195399 -140.203308)
			(xy 296.241366 -140.233031) (xy 296.262298 -140.250672) (xy 296.262552 -140.250926) (xy 296.269646 -140.256502)
			(xy 296.286557 -140.262754) (xy 296.295572 -140.263118) (xy 296.362628 -140.263118) (xy 296.371646 -140.262771)
			(xy 296.388563 -140.256516) (xy 296.395648 -140.250926) (xy 296.395648 -140.250672) (xy 296.395902 -140.250672)
			(xy 296.416819 -140.233014) (xy 296.462796 -140.203306) (xy 296.512548 -140.180474) (xy 296.565052 -140.164987)
			(xy 296.61923 -140.157164) (xy 296.6466 -140.156692) (xy 296.673851 -140.157178) (xy 296.727799 -140.164934)
			(xy 296.780094 -140.180289) (xy 296.829671 -140.202931) (xy 296.875521 -140.232397) (xy 296.916712 -140.268088)
			(xy 296.952403 -140.309279) (xy 296.981869 -140.355129) (xy 297.004511 -140.404706) (xy 297.019866 -140.457001)
			(xy 297.027622 -140.510949) (xy 297.027622 -140.565451) (xy 297.019866 -140.619399) (xy 297.004511 -140.671694)
			(xy 296.981869 -140.721271) (xy 296.952403 -140.767121) (xy 296.916712 -140.808312) (xy 296.875521 -140.844003)
			(xy 296.829671 -140.873469) (xy 296.780094 -140.896111) (xy 296.727799 -140.911466) (xy 296.673851 -140.919222)
			(xy 296.6466 -140.919708) (xy 296.61923 -140.91924) (xy 296.565051 -140.911422) (xy 296.512548 -140.895934)
			(xy 296.462801 -140.873092) (xy 296.416834 -140.843369) (xy 296.395902 -140.825728) (xy 296.395648 -140.825474)
			(xy 296.388554 -140.819898) (xy 296.371643 -140.813646) (xy 296.362628 -140.813282) (xy 296.295572 -140.813282)
			(xy 296.286554 -140.813629) (xy 296.269637 -140.819884) (xy 296.262552 -140.825474) (xy 296.262552 -140.825728)
			(xy 296.262298 -140.825728) (xy 296.241381 -140.843386) (xy 296.195404 -140.873094) (xy 296.145652 -140.895926)
			(xy 296.093148 -140.911413) (xy 296.03897 -140.919236) (xy 296.0116 -140.919708) (xy 295.984349 -140.919222)
			(xy 295.930401 -140.911466) (xy 295.878106 -140.896111) (xy 295.828529 -140.873469) (xy 295.782679 -140.844003)
			(xy 295.741488 -140.808312) (xy 295.705797 -140.767121) (xy 295.676331 -140.721271) (xy 295.653689 -140.671694)
			(xy 295.638334 -140.619399) (xy 295.630578 -140.565451) (xy 294.563833 -140.565451) (xy 294.411674 -143.48714)
			(xy 298.799504 -143.48714) (xy 298.799504 -142.62354) (xy 298.799994 -142.593572) (xy 298.807817 -142.53415)
			(xy 298.82333 -142.476257) (xy 298.846266 -142.420884) (xy 298.876233 -142.368978) (xy 298.91272 -142.321428)
			(xy 298.9551 -142.279048) (xy 299.00265 -142.242561) (xy 299.054556 -142.212594) (xy 299.109929 -142.189658)
			(xy 299.167822 -142.174145) (xy 299.227244 -142.166322) (xy 299.28718 -142.166322) (xy 299.346602 -142.174145)
			(xy 299.404495 -142.189658) (xy 299.459868 -142.212594) (xy 299.511774 -142.242561) (xy 299.559324 -142.279048)
			(xy 299.601704 -142.321428) (xy 299.638191 -142.368978) (xy 299.668158 -142.420884) (xy 299.691094 -142.476257)
			(xy 299.706607 -142.53415) (xy 299.71443 -142.593572) (xy 299.71492 -142.62354) (xy 299.71492 -143.48714)
			(xy 299.71443 -143.517108) (xy 299.706607 -143.57653) (xy 299.691094 -143.634423) (xy 299.668158 -143.689796)
			(xy 299.638191 -143.741702) (xy 299.601704 -143.789252) (xy 299.559324 -143.831632) (xy 299.511774 -143.868119)
			(xy 299.459868 -143.898086) (xy 299.404495 -143.921022) (xy 299.346602 -143.936535) (xy 299.28718 -143.944358)
			(xy 299.227244 -143.944358) (xy 299.167822 -143.936535) (xy 299.109929 -143.921022) (xy 299.054556 -143.898086)
			(xy 299.00265 -143.868119) (xy 298.9551 -143.831632) (xy 298.91272 -143.789252) (xy 298.876233 -143.741702)
			(xy 298.846266 -143.689796) (xy 298.82333 -143.634423) (xy 298.807817 -143.57653) (xy 298.799994 -143.517108)
			(xy 298.799504 -143.48714) (xy 294.411674 -143.48714) (xy 294.36568 -144.370298) (xy 294.31794 -145.287238)
			(xy 296.945304 -145.287238) (xy 296.945304 -144.423638) (xy 296.945794 -144.39367) (xy 296.953617 -144.334248)
			(xy 296.96913 -144.276355) (xy 296.992066 -144.220982) (xy 297.022033 -144.169076) (xy 297.05852 -144.121526)
			(xy 297.1009 -144.079146) (xy 297.14845 -144.042659) (xy 297.200356 -144.012692) (xy 297.255729 -143.989756)
			(xy 297.313622 -143.974243) (xy 297.373044 -143.96642) (xy 297.43298 -143.96642) (xy 297.492402 -143.974243)
			(xy 297.550295 -143.989756) (xy 297.605668 -144.012692) (xy 297.657574 -144.042659) (xy 297.705124 -144.079146)
			(xy 297.747504 -144.121526) (xy 297.783991 -144.169076) (xy 297.813958 -144.220982) (xy 297.836894 -144.276355)
			(xy 297.852407 -144.334248) (xy 297.86023 -144.39367) (xy 297.86072 -144.423638) (xy 297.86072 -145.287238)
			(xy 297.86023 -145.317206) (xy 297.852407 -145.376628) (xy 297.836894 -145.434521) (xy 297.813958 -145.489894)
			(xy 297.783991 -145.5418) (xy 297.747504 -145.58935) (xy 297.705124 -145.63173) (xy 297.657574 -145.668217)
			(xy 297.605668 -145.698184) (xy 297.550295 -145.72112) (xy 297.492402 -145.736633) (xy 297.43298 -145.744456)
			(xy 297.373044 -145.744456) (xy 297.313622 -145.736633) (xy 297.255729 -145.72112) (xy 297.200356 -145.698184)
			(xy 297.14845 -145.668217) (xy 297.1009 -145.63173) (xy 297.05852 -145.58935) (xy 297.022033 -145.5418)
			(xy 296.992066 -145.489894) (xy 296.96913 -145.434521) (xy 296.953617 -145.376628) (xy 296.945794 -145.317206)
			(xy 296.945304 -145.287238) (xy 294.31794 -145.287238) (xy 294.224218 -147.087336) (xy 298.799504 -147.087336)
			(xy 298.799504 -146.223736) (xy 298.799994 -146.193768) (xy 298.807817 -146.134346) (xy 298.82333 -146.076453)
			(xy 298.846266 -146.02108) (xy 298.876233 -145.969174) (xy 298.91272 -145.921624) (xy 298.9551 -145.879244)
			(xy 299.00265 -145.842757) (xy 299.054556 -145.81279) (xy 299.109929 -145.789854) (xy 299.167822 -145.774341)
			(xy 299.227244 -145.766518) (xy 299.28718 -145.766518) (xy 299.346602 -145.774341) (xy 299.404495 -145.789854)
			(xy 299.459868 -145.81279) (xy 299.511774 -145.842757) (xy 299.559324 -145.879244) (xy 299.601704 -145.921624)
			(xy 299.638191 -145.969174) (xy 299.668158 -146.02108) (xy 299.691094 -146.076453) (xy 299.706607 -146.134346)
			(xy 299.71443 -146.193768) (xy 299.71492 -146.223736) (xy 299.71492 -147.087336) (xy 299.71443 -147.117304)
			(xy 299.706607 -147.176726) (xy 299.691094 -147.234619) (xy 299.668158 -147.289992) (xy 299.638191 -147.341898)
			(xy 299.601704 -147.389448) (xy 299.559324 -147.431828) (xy 299.511774 -147.468315) (xy 299.459868 -147.498282)
			(xy 299.404495 -147.521218) (xy 299.346602 -147.536731) (xy 299.28718 -147.544554) (xy 299.227244 -147.544554)
			(xy 299.167822 -147.536731) (xy 299.109929 -147.521218) (xy 299.054556 -147.498282) (xy 299.00265 -147.468315)
			(xy 298.9551 -147.431828) (xy 298.91272 -147.389448) (xy 298.876233 -147.341898) (xy 298.846266 -147.289992)
			(xy 298.82333 -147.234619) (xy 298.807817 -147.176726) (xy 298.799994 -147.117304) (xy 298.799504 -147.087336)
			(xy 294.224218 -147.087336) (xy 294.203628 -147.482814) (xy 294.19296 -147.688554) (xy 294.130583 -148.887434)
			(xy 296.945304 -148.887434) (xy 296.945304 -148.023834) (xy 296.945794 -147.993866) (xy 296.953617 -147.934444)
			(xy 296.96913 -147.876551) (xy 296.992066 -147.821178) (xy 297.022033 -147.769272) (xy 297.05852 -147.721722)
			(xy 297.1009 -147.679342) (xy 297.14845 -147.642855) (xy 297.200356 -147.612888) (xy 297.255729 -147.589952)
			(xy 297.313622 -147.574439) (xy 297.373044 -147.566616) (xy 297.43298 -147.566616) (xy 297.492402 -147.574439)
			(xy 297.550295 -147.589952) (xy 297.605668 -147.612888) (xy 297.657574 -147.642855) (xy 297.705124 -147.679342)
			(xy 297.747504 -147.721722) (xy 297.783991 -147.769272) (xy 297.813958 -147.821178) (xy 297.836894 -147.876551)
			(xy 297.852407 -147.934444) (xy 297.86023 -147.993866) (xy 297.86072 -148.023834) (xy 297.86072 -148.887434)
			(xy 297.86023 -148.917402) (xy 297.852407 -148.976824) (xy 297.836894 -149.034717) (xy 297.813958 -149.09009)
			(xy 297.783991 -149.141996) (xy 297.747504 -149.189546) (xy 297.705124 -149.231926) (xy 297.657574 -149.268413)
			(xy 297.605668 -149.29838) (xy 297.550295 -149.321316) (xy 297.492402 -149.336829) (xy 297.43298 -149.344652)
			(xy 297.373044 -149.344652) (xy 297.313622 -149.336829) (xy 297.255729 -149.321316) (xy 297.200356 -149.29838)
			(xy 297.14845 -149.268413) (xy 297.1009 -149.231926) (xy 297.05852 -149.189546) (xy 297.022033 -149.141996)
			(xy 296.992066 -149.09009) (xy 296.96913 -149.034717) (xy 296.953617 -148.976824) (xy 296.945794 -148.917402)
			(xy 296.945304 -148.887434) (xy 294.130583 -148.887434) (xy 294.036938 -150.687278) (xy 298.799504 -150.687278)
			(xy 298.799504 -149.823678) (xy 298.799994 -149.79371) (xy 298.807817 -149.734288) (xy 298.82333 -149.676395)
			(xy 298.846266 -149.621022) (xy 298.876233 -149.569116) (xy 298.91272 -149.521566) (xy 298.9551 -149.479186)
			(xy 299.00265 -149.442699) (xy 299.054556 -149.412732) (xy 299.109929 -149.389796) (xy 299.167822 -149.374283)
			(xy 299.227244 -149.36646) (xy 299.28718 -149.36646) (xy 299.346602 -149.374283) (xy 299.404495 -149.389796)
			(xy 299.459868 -149.412732) (xy 299.511774 -149.442699) (xy 299.559324 -149.479186) (xy 299.601704 -149.521566)
			(xy 299.638191 -149.569116) (xy 299.668158 -149.621022) (xy 299.691094 -149.676395) (xy 299.706607 -149.734288)
			(xy 299.71443 -149.79371) (xy 299.71492 -149.823678) (xy 299.71492 -150.687278) (xy 299.71443 -150.717246)
			(xy 299.706607 -150.776668) (xy 299.691094 -150.834561) (xy 299.668158 -150.889934) (xy 299.638191 -150.94184)
			(xy 299.601704 -150.98939) (xy 299.559324 -151.03177) (xy 299.511774 -151.068257) (xy 299.459868 -151.098224)
			(xy 299.404495 -151.12116) (xy 299.346602 -151.136673) (xy 299.28718 -151.144496) (xy 299.227244 -151.144496)
			(xy 299.167822 -151.136673) (xy 299.109929 -151.12116) (xy 299.054556 -151.098224) (xy 299.00265 -151.068257)
			(xy 298.9551 -151.03177) (xy 298.91272 -150.98939) (xy 298.876233 -150.94184) (xy 298.846266 -150.889934)
			(xy 298.82333 -150.834561) (xy 298.807817 -150.776668) (xy 298.799994 -150.717246) (xy 298.799504 -150.687278)
			(xy 294.036938 -150.687278) (xy 293.986204 -151.662384) (xy 293.943331 -152.487376) (xy 296.945304 -152.487376)
			(xy 296.945304 -151.623776) (xy 296.945794 -151.593808) (xy 296.953617 -151.534386) (xy 296.96913 -151.476493)
			(xy 296.992066 -151.42112) (xy 297.022033 -151.369214) (xy 297.05852 -151.321664) (xy 297.1009 -151.279284)
			(xy 297.14845 -151.242797) (xy 297.200356 -151.21283) (xy 297.255729 -151.189894) (xy 297.313622 -151.174381)
			(xy 297.373044 -151.166558) (xy 297.43298 -151.166558) (xy 297.492402 -151.174381) (xy 297.550295 -151.189894)
			(xy 297.605668 -151.21283) (xy 297.657574 -151.242797) (xy 297.705124 -151.279284) (xy 297.747504 -151.321664)
			(xy 297.783991 -151.369214) (xy 297.813958 -151.42112) (xy 297.836894 -151.476493) (xy 297.852407 -151.534386)
			(xy 297.86023 -151.593808) (xy 297.86072 -151.623776) (xy 297.86072 -152.487376) (xy 297.86023 -152.517344)
			(xy 297.852407 -152.576766) (xy 297.836894 -152.634659) (xy 297.813958 -152.690032) (xy 297.783991 -152.741938)
			(xy 297.747504 -152.789488) (xy 297.705124 -152.831868) (xy 297.657574 -152.868355) (xy 297.605668 -152.898322)
			(xy 297.550295 -152.921258) (xy 297.492402 -152.936771) (xy 297.43298 -152.944594) (xy 297.373044 -152.944594)
			(xy 297.313622 -152.936771) (xy 297.255729 -152.921258) (xy 297.200356 -152.898322) (xy 297.14845 -152.868355)
			(xy 297.1009 -152.831868) (xy 297.05852 -152.789488) (xy 297.022033 -152.741938) (xy 296.992066 -152.690032)
			(xy 296.96913 -152.634659) (xy 296.953617 -152.576766) (xy 296.945794 -152.517344) (xy 296.945304 -152.487376)
			(xy 293.943331 -152.487376) (xy 293.888922 -153.534364) (xy 293.849707 -154.28722) (xy 298.799504 -154.28722)
			(xy 298.799504 -153.42362) (xy 298.799994 -153.393652) (xy 298.807817 -153.33423) (xy 298.82333 -153.276337)
			(xy 298.846266 -153.220964) (xy 298.876233 -153.169058) (xy 298.91272 -153.121508) (xy 298.9551 -153.079128)
			(xy 299.00265 -153.042641) (xy 299.054556 -153.012674) (xy 299.109929 -152.989738) (xy 299.167822 -152.974225)
			(xy 299.227244 -152.966402) (xy 299.28718 -152.966402) (xy 299.346602 -152.974225) (xy 299.404495 -152.989738)
			(xy 299.459868 -153.012674) (xy 299.511774 -153.042641) (xy 299.559324 -153.079128) (xy 299.601704 -153.121508)
			(xy 299.638191 -153.169058) (xy 299.668158 -153.220964) (xy 299.691094 -153.276337) (xy 299.706607 -153.33423)
			(xy 299.71443 -153.393652) (xy 299.71492 -153.42362) (xy 299.71492 -154.28722) (xy 299.71443 -154.317188)
			(xy 299.706607 -154.37661) (xy 299.691094 -154.434503) (xy 299.668158 -154.489876) (xy 299.638191 -154.541782)
			(xy 299.601704 -154.589332) (xy 299.559324 -154.631712) (xy 299.511774 -154.668199) (xy 299.459868 -154.698166)
			(xy 299.404495 -154.721102) (xy 299.346602 -154.736615) (xy 299.28718 -154.744438) (xy 299.227244 -154.744438)
			(xy 299.167822 -154.736615) (xy 299.109929 -154.721102) (xy 299.054556 -154.698166) (xy 299.00265 -154.668199)
			(xy 298.9551 -154.631712) (xy 298.91272 -154.589332) (xy 298.876233 -154.541782) (xy 298.846266 -154.489876)
			(xy 298.82333 -154.434503) (xy 298.807817 -154.37661) (xy 298.799994 -154.317188) (xy 298.799504 -154.28722)
			(xy 293.849707 -154.28722) (xy 293.833804 -154.592528) (xy 293.819326 -154.869896) (xy 293.773098 -155.759404)
			(xy 293.75604 -156.087318) (xy 296.945304 -156.087318) (xy 296.945304 -155.223718) (xy 296.945794 -155.19375)
			(xy 296.953617 -155.134328) (xy 296.96913 -155.076435) (xy 296.992066 -155.021062) (xy 297.022033 -154.969156)
			(xy 297.05852 -154.921606) (xy 297.1009 -154.879226) (xy 297.14845 -154.842739) (xy 297.200356 -154.812772)
			(xy 297.255729 -154.789836) (xy 297.313622 -154.774323) (xy 297.373044 -154.7665) (xy 297.43298 -154.7665)
			(xy 297.492402 -154.774323) (xy 297.550295 -154.789836) (xy 297.605668 -154.812772) (xy 297.657574 -154.842739)
			(xy 297.705124 -154.879226) (xy 297.747504 -154.921606) (xy 297.783991 -154.969156) (xy 297.813958 -155.021062)
			(xy 297.836894 -155.076435) (xy 297.852407 -155.134328) (xy 297.86023 -155.19375) (xy 297.86072 -155.223718)
			(xy 297.86072 -156.087318) (xy 297.86023 -156.117286) (xy 297.852407 -156.176708) (xy 297.836894 -156.234601)
			(xy 297.813958 -156.289974) (xy 297.783991 -156.34188) (xy 297.747504 -156.38943) (xy 297.705124 -156.43181)
			(xy 297.657574 -156.468297) (xy 297.605668 -156.498264) (xy 297.550295 -156.5212) (xy 297.492402 -156.536713)
			(xy 297.43298 -156.544536) (xy 297.373044 -156.544536) (xy 297.313622 -156.536713) (xy 297.255729 -156.5212)
			(xy 297.200356 -156.498264) (xy 297.14845 -156.468297) (xy 297.1009 -156.43181) (xy 297.05852 -156.38943)
			(xy 297.022033 -156.34188) (xy 296.992066 -156.289974) (xy 296.96913 -156.234601) (xy 296.953617 -156.176708)
			(xy 296.945794 -156.117286) (xy 296.945304 -156.087318) (xy 293.75604 -156.087318) (xy 293.746936 -156.262324)
			(xy 293.731442 -156.558234) (xy 293.731188 -156.564076) (xy 293.730172 -156.582364) (xy 293.730172 -156.587444)
			(xy 293.730859 -156.598892) (xy 293.740872 -156.619489) (xy 293.749476 -156.627068) (xy 293.752778 -156.629608)
			(xy 293.816786 -156.67736) (xy 293.821104 -156.679392) (xy 293.822628 -156.680154) (xy 293.827953 -156.682618)
			(xy 293.839369 -156.685316) (xy 293.845234 -156.685488) (xy 293.865046 -156.685488) (xy 293.87292 -156.682948)
			(xy 293.902006 -156.673945) (xy 293.962112 -156.664246) (xy 293.992554 -156.663644) (xy 294.019809 -156.664127)
			(xy 294.073764 -156.671878) (xy 294.126067 -156.687228) (xy 294.175653 -156.709866) (xy 294.221513 -156.73933)
			(xy 294.262712 -156.775021) (xy 294.298413 -156.816212) (xy 294.327889 -156.862064) (xy 294.350539 -156.911645)
			(xy 294.365902 -156.963944) (xy 294.373667 -157.017897) (xy 294.374062 -157.045152) (xy 294.626536 -157.045152)
			(xy 294.630607 -156.98953) (xy 294.642733 -156.935093) (xy 294.662656 -156.883002) (xy 294.689952 -156.834367)
			(xy 294.724038 -156.790224) (xy 294.764187 -156.751515) (xy 294.809545 -156.719064) (xy 294.859145 -156.693563)
			(xy 294.911929 -156.675556) (xy 294.966772 -156.665426) (xy 295.022506 -156.663389) (xy 295.077943 -156.669489)
			(xy 295.1319 -156.683595) (xy 295.183229 -156.705407) (xy 295.230835 -156.734461) (xy 295.273703 -156.770136)
			(xy 295.31092 -156.811673) (xy 295.341693 -156.858186) (xy 295.365365 -156.908683) (xy 295.381433 -156.96209)
			(xy 295.389553 -157.017266) (xy 295.390062 -157.045152) (xy 295.389553 -157.073038) (xy 295.381433 -157.128214)
			(xy 295.365365 -157.181621) (xy 295.341693 -157.232118) (xy 295.31092 -157.278631) (xy 295.273703 -157.320168)
			(xy 295.230835 -157.355843) (xy 295.183229 -157.384897) (xy 295.1319 -157.406709) (xy 295.077943 -157.420815)
			(xy 295.022506 -157.426915) (xy 294.966772 -157.424878) (xy 294.911929 -157.414748) (xy 294.859145 -157.396741)
			(xy 294.809545 -157.37124) (xy 294.764187 -157.338789) (xy 294.724038 -157.30008) (xy 294.689952 -157.255937)
			(xy 294.662656 -157.207302) (xy 294.642733 -157.155211) (xy 294.630607 -157.100774) (xy 294.626536 -157.045152)
			(xy 294.374062 -157.045152) (xy 294.373603 -157.071978) (xy 294.366082 -157.125101) (xy 294.351195 -157.176646)
			(xy 294.329236 -157.225599) (xy 294.300637 -157.270994) (xy 294.265963 -157.311936) (xy 294.225896 -157.347619)
			(xy 294.181227 -157.377339) (xy 294.132836 -157.40051) (xy 294.081677 -157.416675) (xy 294.028758 -157.425516)
			(xy 294.001952 -157.42666) (xy 293.982902 -157.42666) (xy 293.957135 -157.425567) (xy 293.906228 -157.417302)
			(xy 293.856898 -157.402258) (xy 293.833296 -157.391862) (xy 293.829486 -157.390084) (xy 293.828724 -157.38983)
			(xy 293.816278 -157.386782) (xy 293.806998 -157.385318) (xy 293.78849 -157.388441) (xy 293.78021 -157.392878)
			(xy 293.734998 -157.419294) (xy 293.708328 -157.435042) (xy 293.701202 -157.439698) (xy 293.690186 -157.452659)
			(xy 293.686738 -157.460442) (xy 293.683944 -157.468062) (xy 293.542531 -160.1851) (xy 302.088817 -160.1851)
			(xy 302.092773 -160.093241) (xy 302.10461 -160.002062) (xy 302.124242 -159.912238) (xy 302.151523 -159.824435)
			(xy 302.186251 -159.739302) (xy 302.228169 -159.657469) (xy 302.276967 -159.579542) (xy 302.332282 -159.506099)
			(xy 302.393707 -159.437683) (xy 302.460786 -159.374801) (xy 302.533021 -159.317918) (xy 302.60988 -159.267455)
			(xy 302.690792 -159.223786) (xy 302.775158 -159.187234) (xy 302.862354 -159.15807) (xy 302.951735 -159.13651)
			(xy 303.042638 -159.122714) (xy 303.134391 -159.116782) (xy 303.226313 -159.118761) (xy 303.317726 -159.128634)
			(xy 303.407951 -159.146329) (xy 303.496322 -159.171714) (xy 303.582182 -159.204602) (xy 303.664898 -159.24475)
			(xy 303.743856 -159.291859) (xy 303.818473 -159.345582) (xy 303.888194 -159.40552) (xy 303.952505 -159.47123)
			(xy 304.01093 -159.542226) (xy 304.063035 -159.61798) (xy 304.108434 -159.697934) (xy 304.146793 -159.781494)
			(xy 304.177826 -159.868043) (xy 304.201304 -159.956939) (xy 304.217054 -160.047524) (xy 304.224958 -160.139128)
			(xy 304.225452 -160.1851) (xy 304.224958 -160.231072) (xy 304.217054 -160.322676) (xy 304.201304 -160.413261)
			(xy 304.177826 -160.502157) (xy 304.146793 -160.588706) (xy 304.108434 -160.672266) (xy 304.063035 -160.75222)
			(xy 304.01093 -160.827974) (xy 303.952505 -160.89897) (xy 303.888194 -160.96468) (xy 303.818473 -161.024618)
			(xy 303.743856 -161.078341) (xy 303.664898 -161.12545) (xy 303.582182 -161.165598) (xy 303.496322 -161.198486)
			(xy 303.407951 -161.223871) (xy 303.317726 -161.241566) (xy 303.226313 -161.251439) (xy 303.134391 -161.253418)
			(xy 303.042638 -161.247486) (xy 302.951735 -161.23369) (xy 302.862354 -161.21213) (xy 302.775158 -161.182966)
			(xy 302.690792 -161.146414) (xy 302.60988 -161.102745) (xy 302.533021 -161.052282) (xy 302.460786 -160.995399)
			(xy 302.393707 -160.932517) (xy 302.332282 -160.864101) (xy 302.276967 -160.790658) (xy 302.228169 -160.712731)
			(xy 302.186251 -160.630898) (xy 302.151523 -160.545765) (xy 302.124242 -160.457962) (xy 302.10461 -160.368138)
			(xy 302.092773 -160.276959) (xy 302.088817 -160.1851) (xy 293.542531 -160.1851) (xy 293.203162 -166.705534)
			(xy 293.311832 -166.705534) (xy 293.315903 -166.649912) (xy 293.328029 -166.595475) (xy 293.347952 -166.543384)
			(xy 293.375248 -166.494749) (xy 293.409334 -166.450606) (xy 293.449483 -166.411897) (xy 293.494841 -166.379446)
			(xy 293.544441 -166.353945) (xy 293.597225 -166.335938) (xy 293.652068 -166.325808) (xy 293.707802 -166.323771)
			(xy 293.763239 -166.329871) (xy 293.817196 -166.343977) (xy 293.868525 -166.365789) (xy 293.916131 -166.394843)
			(xy 293.958999 -166.430518) (xy 293.996216 -166.472055) (xy 294.026989 -166.518568) (xy 294.050661 -166.569065)
			(xy 294.066729 -166.622472) (xy 294.074849 -166.677648) (xy 294.075358 -166.705534) (xy 294.327832 -166.705534)
			(xy 294.331903 -166.649912) (xy 294.344029 -166.595475) (xy 294.363952 -166.543384) (xy 294.391248 -166.494749)
			(xy 294.425334 -166.450606) (xy 294.465483 -166.411897) (xy 294.510841 -166.379446) (xy 294.560441 -166.353945)
			(xy 294.613225 -166.335938) (xy 294.668068 -166.325808) (xy 294.723802 -166.323771) (xy 294.779239 -166.329871)
			(xy 294.833196 -166.343977) (xy 294.884525 -166.365789) (xy 294.932131 -166.394843) (xy 294.974999 -166.430518)
			(xy 295.012216 -166.472055) (xy 295.042989 -166.518568) (xy 295.066661 -166.569065) (xy 295.082729 -166.622472)
			(xy 295.090849 -166.677648) (xy 295.091358 -166.705534) (xy 295.343832 -166.705534) (xy 295.347903 -166.649912)
			(xy 295.360029 -166.595475) (xy 295.379952 -166.543384) (xy 295.407248 -166.494749) (xy 295.441334 -166.450606)
			(xy 295.481483 -166.411897) (xy 295.526841 -166.379446) (xy 295.576441 -166.353945) (xy 295.629225 -166.335938)
			(xy 295.684068 -166.325808) (xy 295.739802 -166.323771) (xy 295.795239 -166.329871) (xy 295.849196 -166.343977)
			(xy 295.900525 -166.365789) (xy 295.948131 -166.394843) (xy 295.990999 -166.430518) (xy 296.028216 -166.472055)
			(xy 296.058989 -166.518568) (xy 296.082661 -166.569065) (xy 296.098729 -166.622472) (xy 296.106849 -166.677648)
			(xy 296.107358 -166.705534) (xy 296.106849 -166.73342) (xy 296.098729 -166.788596) (xy 296.082661 -166.842003)
			(xy 296.058989 -166.8925) (xy 296.028216 -166.939013) (xy 295.990999 -166.98055) (xy 295.948131 -167.016225)
			(xy 295.900525 -167.045279) (xy 295.849196 -167.067091) (xy 295.795239 -167.081197) (xy 295.739802 -167.087297)
			(xy 295.684068 -167.08526) (xy 295.629225 -167.07513) (xy 295.576441 -167.057123) (xy 295.526841 -167.031622)
			(xy 295.481483 -166.999171) (xy 295.441334 -166.960462) (xy 295.407248 -166.916319) (xy 295.379952 -166.867684)
			(xy 295.360029 -166.815593) (xy 295.347903 -166.761156) (xy 295.343832 -166.705534) (xy 295.091358 -166.705534)
			(xy 295.090849 -166.73342) (xy 295.082729 -166.788596) (xy 295.066661 -166.842003) (xy 295.042989 -166.8925)
			(xy 295.012216 -166.939013) (xy 294.974999 -166.98055) (xy 294.932131 -167.016225) (xy 294.884525 -167.045279)
			(xy 294.833196 -167.067091) (xy 294.779239 -167.081197) (xy 294.723802 -167.087297) (xy 294.668068 -167.08526)
			(xy 294.613225 -167.07513) (xy 294.560441 -167.057123) (xy 294.510841 -167.031622) (xy 294.465483 -166.999171)
			(xy 294.425334 -166.960462) (xy 294.391248 -166.916319) (xy 294.363952 -166.867684) (xy 294.344029 -166.815593)
			(xy 294.331903 -166.761156) (xy 294.327832 -166.705534) (xy 294.075358 -166.705534) (xy 294.074849 -166.73342)
			(xy 294.066729 -166.788596) (xy 294.050661 -166.842003) (xy 294.026989 -166.8925) (xy 293.996216 -166.939013)
			(xy 293.958999 -166.98055) (xy 293.916131 -167.016225) (xy 293.868525 -167.045279) (xy 293.817196 -167.067091)
			(xy 293.763239 -167.081197) (xy 293.707802 -167.087297) (xy 293.652068 -167.08526) (xy 293.597225 -167.07513)
			(xy 293.544441 -167.057123) (xy 293.494841 -167.031622) (xy 293.449483 -166.999171) (xy 293.409334 -166.960462)
			(xy 293.375248 -166.916319) (xy 293.347952 -166.867684) (xy 293.328029 -166.815593) (xy 293.315903 -166.761156)
			(xy 293.311832 -166.705534) (xy 293.203162 -166.705534) (xy 293.071042 -169.24401) (xy 293.063676 -169.385488)
			(xy 292.910579 -172.329348) (xy 294.047924 -172.329348) (xy 294.051995 -172.273726) (xy 294.064121 -172.219289)
			(xy 294.084044 -172.167198) (xy 294.11134 -172.118563) (xy 294.145426 -172.07442) (xy 294.185575 -172.035711)
			(xy 294.230933 -172.00326) (xy 294.280533 -171.977759) (xy 294.333317 -171.959752) (xy 294.38816 -171.949622)
			(xy 294.443894 -171.947585) (xy 294.499331 -171.953685) (xy 294.553288 -171.967791) (xy 294.604617 -171.989603)
			(xy 294.652223 -172.018657) (xy 294.695091 -172.054332) (xy 294.732308 -172.095869) (xy 294.763081 -172.142382)
			(xy 294.786753 -172.192879) (xy 294.802821 -172.246286) (xy 294.810941 -172.301462) (xy 294.81145 -172.329348)
			(xy 294.811186 -172.343826) (xy 294.985184 -172.343826) (xy 294.989255 -172.288204) (xy 295.001381 -172.233767)
			(xy 295.021304 -172.181676) (xy 295.0486 -172.133041) (xy 295.082686 -172.088898) (xy 295.122835 -172.050189)
			(xy 295.168193 -172.017738) (xy 295.217793 -171.992237) (xy 295.270577 -171.97423) (xy 295.32542 -171.9641)
			(xy 295.381154 -171.962063) (xy 295.436591 -171.968163) (xy 295.490548 -171.982269) (xy 295.541877 -172.004081)
			(xy 295.589483 -172.033135) (xy 295.632351 -172.06881) (xy 295.669568 -172.110347) (xy 295.700341 -172.15686)
			(xy 295.706662 -172.170344) (xy 296.916092 -172.170344) (xy 296.920163 -172.114722) (xy 296.932289 -172.060285)
			(xy 296.952212 -172.008194) (xy 296.979508 -171.959559) (xy 297.013594 -171.915416) (xy 297.053743 -171.876707)
			(xy 297.099101 -171.844256) (xy 297.148701 -171.818755) (xy 297.201485 -171.800748) (xy 297.256328 -171.790618)
			(xy 297.312062 -171.788581) (xy 297.367499 -171.794681) (xy 297.421456 -171.808787) (xy 297.472785 -171.830599)
			(xy 297.520391 -171.859653) (xy 297.563259 -171.895328) (xy 297.600476 -171.936865) (xy 297.631249 -171.983378)
			(xy 297.654921 -172.033875) (xy 297.670989 -172.087282) (xy 297.679109 -172.142458) (xy 297.679618 -172.170344)
			(xy 297.679109 -172.19823) (xy 297.670989 -172.253406) (xy 297.654921 -172.306813) (xy 297.631249 -172.35731)
			(xy 297.600476 -172.403823) (xy 297.563259 -172.44536) (xy 297.520391 -172.481035) (xy 297.472785 -172.510089)
			(xy 297.421456 -172.531901) (xy 297.367499 -172.546007) (xy 297.312062 -172.552107) (xy 297.256328 -172.55007)
			(xy 297.201485 -172.53994) (xy 297.148701 -172.521933) (xy 297.099101 -172.496432) (xy 297.053743 -172.463981)
			(xy 297.013594 -172.425272) (xy 296.979508 -172.381129) (xy 296.952212 -172.332494) (xy 296.932289 -172.280403)
			(xy 296.920163 -172.225966) (xy 296.916092 -172.170344) (xy 295.706662 -172.170344) (xy 295.724013 -172.207357)
			(xy 295.740081 -172.260764) (xy 295.748201 -172.31594) (xy 295.74871 -172.343826) (xy 295.748201 -172.371712)
			(xy 295.740081 -172.426888) (xy 295.724013 -172.480295) (xy 295.700341 -172.530792) (xy 295.669568 -172.577305)
			(xy 295.632351 -172.618842) (xy 295.589483 -172.654517) (xy 295.541877 -172.683571) (xy 295.490548 -172.705383)
			(xy 295.436591 -172.719489) (xy 295.381154 -172.725589) (xy 295.32542 -172.723552) (xy 295.270577 -172.713422)
			(xy 295.217793 -172.695415) (xy 295.168193 -172.669914) (xy 295.122835 -172.637463) (xy 295.082686 -172.598754)
			(xy 295.0486 -172.554611) (xy 295.021304 -172.505976) (xy 295.001381 -172.453885) (xy 294.989255 -172.399448)
			(xy 294.985184 -172.343826) (xy 294.811186 -172.343826) (xy 294.810941 -172.357234) (xy 294.802821 -172.41241)
			(xy 294.786753 -172.465817) (xy 294.763081 -172.516314) (xy 294.732308 -172.562827) (xy 294.695091 -172.604364)
			(xy 294.652223 -172.640039) (xy 294.604617 -172.669093) (xy 294.553288 -172.690905) (xy 294.499331 -172.705011)
			(xy 294.443894 -172.711111) (xy 294.38816 -172.709074) (xy 294.333317 -172.698944) (xy 294.280533 -172.680937)
			(xy 294.230933 -172.655436) (xy 294.185575 -172.622985) (xy 294.145426 -172.584276) (xy 294.11134 -172.540133)
			(xy 294.084044 -172.491498) (xy 294.064121 -172.439407) (xy 294.051995 -172.38497) (xy 294.047924 -172.329348)
			(xy 292.910579 -172.329348) (xy 292.908228 -172.37456) (xy 292.84549 -173.578774) (xy 292.778942 -174.859188)
			(xy 292.692187 -176.525682) (xy 296.609006 -176.525682) (xy 296.613077 -176.47006) (xy 296.625203 -176.415623)
			(xy 296.645126 -176.363532) (xy 296.672422 -176.314897) (xy 296.706508 -176.270754) (xy 296.746657 -176.232045)
			(xy 296.792015 -176.199594) (xy 296.841615 -176.174093) (xy 296.894399 -176.156086) (xy 296.949242 -176.145956)
			(xy 297.004976 -176.143919) (xy 297.060413 -176.150019) (xy 297.11437 -176.164125) (xy 297.165699 -176.185937)
			(xy 297.213305 -176.214991) (xy 297.256173 -176.250666) (xy 297.29339 -176.292203) (xy 297.324163 -176.338716)
			(xy 297.347835 -176.389213) (xy 297.363903 -176.44262) (xy 297.372023 -176.497796) (xy 297.372532 -176.525682)
			(xy 297.372023 -176.553568) (xy 297.363903 -176.608744) (xy 297.347835 -176.662151) (xy 297.324163 -176.712648)
			(xy 297.29339 -176.759161) (xy 297.256173 -176.800698) (xy 297.213305 -176.836373) (xy 297.165699 -176.865427)
			(xy 297.11437 -176.887239) (xy 297.060413 -176.901345) (xy 297.004976 -176.907445) (xy 296.949242 -176.905408)
			(xy 296.894399 -176.895278) (xy 296.841615 -176.877271) (xy 296.792015 -176.85177) (xy 296.746657 -176.819319)
			(xy 296.706508 -176.78061) (xy 296.672422 -176.736467) (xy 296.645126 -176.687832) (xy 296.625203 -176.635741)
			(xy 296.613077 -176.581304) (xy 296.609006 -176.525682) (xy 292.692187 -176.525682) (xy 292.631161 -177.697949)
			(xy 293.026092 -177.697949) (xy 293.026092 -177.643451) (xy 293.033848 -177.589506) (xy 293.049202 -177.537215)
			(xy 293.071841 -177.48764) (xy 293.101305 -177.441793) (xy 293.136993 -177.400604) (xy 293.17818 -177.364914)
			(xy 293.224026 -177.335449) (xy 293.2736 -177.312807) (xy 293.325891 -177.297451) (xy 293.379835 -177.289693)
			(xy 293.407084 -177.289206) (xy 293.434454 -177.28968) (xy 293.488633 -177.297496) (xy 293.541136 -177.312983)
			(xy 293.590883 -177.335823) (xy 293.63685 -177.365546) (xy 293.657782 -177.383186) (xy 293.658036 -177.38344)
			(xy 293.665133 -177.389011) (xy 293.682042 -177.395266) (xy 293.691056 -177.395632) (xy 293.758112 -177.395632)
			(xy 293.767129 -177.395274) (xy 293.784045 -177.389026) (xy 293.791132 -177.38344) (xy 293.791132 -177.383186)
			(xy 293.791386 -177.383186) (xy 293.812319 -177.365545) (xy 293.858287 -177.335821) (xy 293.908033 -177.312975)
			(xy 293.960535 -177.297479) (xy 294.014713 -177.28965) (xy 294.069455 -177.28965) (xy 294.123633 -177.297479)
			(xy 294.176135 -177.312975) (xy 294.225881 -177.335821) (xy 294.271849 -177.365545) (xy 294.292782 -177.383186)
			(xy 294.293036 -177.38344) (xy 294.300133 -177.389011) (xy 294.317042 -177.395266) (xy 294.326056 -177.395632)
			(xy 294.393112 -177.395632) (xy 294.402129 -177.395274) (xy 294.419045 -177.389026) (xy 294.426132 -177.38344)
			(xy 294.426132 -177.383186) (xy 294.426386 -177.383186) (xy 294.447319 -177.365545) (xy 294.493287 -177.335821)
			(xy 294.543033 -177.312975) (xy 294.595535 -177.297479) (xy 294.649713 -177.28965) (xy 294.704455 -177.28965)
			(xy 294.758633 -177.297479) (xy 294.811135 -177.312975) (xy 294.860881 -177.335821) (xy 294.906849 -177.365545)
			(xy 294.927782 -177.383186) (xy 294.928036 -177.38344) (xy 294.935133 -177.389011) (xy 294.952042 -177.395266)
			(xy 294.961056 -177.395632) (xy 295.028112 -177.395632) (xy 295.037129 -177.395274) (xy 295.054045 -177.389026)
			(xy 295.061132 -177.38344) (xy 295.061132 -177.383186) (xy 295.061386 -177.383186) (xy 295.082311 -177.365538)
			(xy 295.128286 -177.335828) (xy 295.178035 -177.312994) (xy 295.230537 -177.297505) (xy 295.284714 -177.289679)
			(xy 295.312084 -177.289206) (xy 295.339339 -177.28964) (xy 295.393293 -177.297395) (xy 295.445595 -177.31275)
			(xy 295.495179 -177.335393) (xy 295.541036 -177.364862) (xy 295.582232 -177.400557) (xy 295.617929 -177.441751)
			(xy 295.647399 -177.487607) (xy 295.670044 -177.53719) (xy 295.685401 -177.589491) (xy 295.693159 -177.643445)
			(xy 295.693159 -177.697955) (xy 295.685401 -177.751909) (xy 295.670044 -177.80421) (xy 295.647399 -177.853793)
			(xy 295.617929 -177.899649) (xy 295.582232 -177.940843) (xy 295.541036 -177.976538) (xy 295.495179 -178.006007)
			(xy 295.445595 -178.02865) (xy 295.393293 -178.044005) (xy 295.339339 -178.05176) (xy 295.312084 -178.052222)
			(xy 295.284713 -178.051784) (xy 295.230531 -178.043963) (xy 295.178027 -178.028468) (xy 295.128281 -178.005619)
			(xy 295.082316 -177.975887) (xy 295.061386 -177.958242) (xy 295.061132 -177.957988) (xy 295.054041 -177.952407)
			(xy 295.037128 -177.946157) (xy 295.028112 -177.945796) (xy 294.961056 -177.945796) (xy 294.952042 -177.946181)
			(xy 294.935125 -177.952409) (xy 294.928036 -177.957988) (xy 294.927782 -177.958242) (xy 294.906849 -177.975883)
			(xy 294.860881 -178.005607) (xy 294.811135 -178.028453) (xy 294.758633 -178.043949) (xy 294.704455 -178.051778)
			(xy 294.649713 -178.051778) (xy 294.595535 -178.043949) (xy 294.543033 -178.028453) (xy 294.493287 -178.005607)
			(xy 294.447319 -177.975883) (xy 294.426386 -177.958242) (xy 294.426132 -177.957988) (xy 294.419041 -177.952407)
			(xy 294.402128 -177.946157) (xy 294.393112 -177.945796) (xy 294.326056 -177.945796) (xy 294.317042 -177.946181)
			(xy 294.300125 -177.952409) (xy 294.293036 -177.957988) (xy 294.293036 -177.958242) (xy 294.292782 -177.958242)
			(xy 294.271849 -177.975883) (xy 294.225881 -178.005607) (xy 294.176135 -178.028453) (xy 294.123633 -178.043949)
			(xy 294.069455 -178.051778) (xy 294.014713 -178.051778) (xy 293.960535 -178.043949) (xy 293.908033 -178.028453)
			(xy 293.858287 -178.005607) (xy 293.812319 -177.975883) (xy 293.791386 -177.958242) (xy 293.791132 -177.957988)
			(xy 293.784041 -177.952407) (xy 293.767128 -177.946157) (xy 293.758112 -177.945796) (xy 293.691056 -177.945796)
			(xy 293.682042 -177.946181) (xy 293.665125 -177.952409) (xy 293.658036 -177.957988) (xy 293.658036 -177.958242)
			(xy 293.657782 -177.958242) (xy 293.636836 -177.975863) (xy 293.590866 -178.005576) (xy 293.541122 -178.028415)
			(xy 293.488625 -178.043911) (xy 293.434452 -178.051745) (xy 293.407084 -178.052222) (xy 293.379835 -178.051707)
			(xy 293.325891 -178.043949) (xy 293.2736 -178.028593) (xy 293.224026 -178.005951) (xy 293.17818 -177.976486)
			(xy 293.136993 -177.940796) (xy 293.101305 -177.899607) (xy 293.071841 -177.85376) (xy 293.049202 -177.804185)
			(xy 293.033848 -177.751894) (xy 293.026092 -177.697949) (xy 292.631161 -177.697949) (xy 292.449363 -181.190138)
			(xy 295.216578 -181.190138) (xy 295.220649 -181.134516) (xy 295.232775 -181.080079) (xy 295.252698 -181.027988)
			(xy 295.279994 -180.979353) (xy 295.31408 -180.93521) (xy 295.354229 -180.896501) (xy 295.399587 -180.86405)
			(xy 295.449187 -180.838549) (xy 295.501971 -180.820542) (xy 295.556814 -180.810412) (xy 295.612548 -180.808375)
			(xy 295.667985 -180.814475) (xy 295.721942 -180.828581) (xy 295.773271 -180.850393) (xy 295.820877 -180.879447)
			(xy 295.863745 -180.915122) (xy 295.900962 -180.956659) (xy 295.931735 -181.003172) (xy 295.955407 -181.053669)
			(xy 295.971475 -181.107076) (xy 295.979595 -181.162252) (xy 295.980104 -181.190138) (xy 295.979595 -181.218024)
			(xy 295.971475 -181.2732) (xy 295.955407 -181.326607) (xy 295.931735 -181.377104) (xy 295.900962 -181.423617)
			(xy 295.863745 -181.465154) (xy 295.820877 -181.500829) (xy 295.773271 -181.529883) (xy 295.721942 -181.551695)
			(xy 295.667985 -181.565801) (xy 295.612548 -181.571901) (xy 295.556814 -181.569864) (xy 295.501971 -181.559734)
			(xy 295.449187 -181.541727) (xy 295.399587 -181.516226) (xy 295.354229 -181.483775) (xy 295.31408 -181.445066)
			(xy 295.279994 -181.400923) (xy 295.252698 -181.352288) (xy 295.232775 -181.300197) (xy 295.220649 -181.24576)
			(xy 295.216578 -181.190138) (xy 292.449363 -181.190138) (xy 292.381636 -182.491126) (xy 295.811192 -182.491126)
			(xy 295.815263 -182.435504) (xy 295.827389 -182.381067) (xy 295.847312 -182.328976) (xy 295.874608 -182.280341)
			(xy 295.908694 -182.236198) (xy 295.948843 -182.197489) (xy 295.994201 -182.165038) (xy 296.043801 -182.139537)
			(xy 296.096585 -182.12153) (xy 296.151428 -182.1114) (xy 296.207162 -182.109363) (xy 296.262599 -182.115463)
			(xy 296.316556 -182.129569) (xy 296.367885 -182.151381) (xy 296.415491 -182.180435) (xy 296.458359 -182.21611)
			(xy 296.495576 -182.257647) (xy 296.526349 -182.30416) (xy 296.550021 -182.354657) (xy 296.566089 -182.408064)
			(xy 296.574209 -182.46324) (xy 296.574718 -182.491126) (xy 296.574209 -182.519012) (xy 296.566089 -182.574188)
			(xy 296.550021 -182.627595) (xy 296.526349 -182.678092) (xy 296.495576 -182.724605) (xy 296.458359 -182.766142)
			(xy 296.415491 -182.801817) (xy 296.367885 -182.830871) (xy 296.316556 -182.852683) (xy 296.262599 -182.866789)
			(xy 296.207162 -182.872889) (xy 296.151428 -182.870852) (xy 296.096585 -182.860722) (xy 296.043801 -182.842715)
			(xy 295.994201 -182.817214) (xy 295.948843 -182.784763) (xy 295.908694 -182.746054) (xy 295.874608 -182.701911)
			(xy 295.847312 -182.653276) (xy 295.827389 -182.601185) (xy 295.815263 -182.546748) (xy 295.811192 -182.491126)
			(xy 292.381636 -182.491126) (xy 292.366192 -182.787798) (xy 292.36543 -182.80253) (xy 292.36289 -182.85333)
			(xy 292.344602 -183.200548) (xy 292.288468 -184.284366) (xy 292.261544 -184.80278) (xy 292.264338 -184.811416)
			(xy 292.270434 -184.831482) (xy 292.274498 -184.837578) (xy 292.293802 -184.87009) (xy 292.295072 -184.872884)
			(xy 292.298882 -184.878726) (xy 292.304216 -184.885076) (xy 292.305232 -184.885838) (xy 292.319964 -184.897268)
			(xy 292.324847 -184.900333) (xy 292.335615 -184.904441) (xy 292.3413 -184.905396) (xy 292.352984 -184.90692)
			(xy 292.365176 -184.902602) (xy 292.371018 -184.90057) (xy 292.38194 -184.893458) (xy 292.392354 -184.884314)
			(xy 292.396164 -184.879996) (xy 292.399212 -184.874154) (xy 292.411615 -184.851228) (xy 292.441708 -184.808666)
			(xy 292.477313 -184.770596) (xy 292.517769 -184.737727) (xy 292.562322 -184.710671) (xy 292.610143 -184.68993)
			(xy 292.660342 -184.675892) (xy 292.711985 -184.668817) (xy 292.738048 -184.668414) (xy 292.765295 -184.668903)
			(xy 292.819235 -184.676665) (xy 292.871521 -184.692023) (xy 292.921089 -184.714666) (xy 292.966931 -184.744132)
			(xy 293.008113 -184.779821) (xy 293.043797 -184.821008) (xy 293.073257 -184.866853) (xy 293.095893 -184.916424)
			(xy 293.111245 -184.968712) (xy 293.119 -185.022653) (xy 293.119 -185.077147) (xy 293.111245 -185.131088)
			(xy 293.095893 -185.183376) (xy 293.073257 -185.232947) (xy 293.043797 -185.278792) (xy 293.008113 -185.319979)
			(xy 292.966931 -185.355668) (xy 292.921089 -185.385134) (xy 292.871521 -185.407777) (xy 292.819235 -185.423135)
			(xy 292.765295 -185.430897) (xy 292.738048 -185.43143) (xy 292.708362 -185.430861) (xy 292.649709 -185.421656)
			(xy 292.593189 -185.403477) (xy 292.540167 -185.376761) (xy 292.491924 -185.342155) (xy 292.449624 -185.300494)
			(xy 292.43147 -185.276998) (xy 292.429184 -185.27395) (xy 292.42385 -185.268616) (xy 292.421818 -185.267092)
			(xy 292.421056 -185.26633) (xy 292.418262 -185.26379) (xy 292.411479 -185.259038) (xy 292.395803 -185.253726)
			(xy 292.387528 -185.253376) (xy 292.31844 -185.253376) (xy 292.312573 -185.253528) (xy 292.301153 -185.256227)
			(xy 292.295834 -185.25871) (xy 292.295326 -185.258964) (xy 292.277292 -185.268108) (xy 292.273739 -185.269991)
			(xy 292.26723 -185.274712) (xy 292.264338 -185.277506) (xy 292.25875 -185.283094) (xy 292.256464 -185.286142)
			(xy 292.253162 -185.290206) (xy 292.252654 -185.290714) (xy 292.247066 -185.297572) (xy 292.240716 -185.304684)
			(xy 292.23716 -185.31459) (xy 292.234366 -185.32221) (xy 292.228016 -185.444638) (xy 292.206172 -185.864246)
			(xy 292.178293 -186.399678) (xy 297.289218 -186.399678) (xy 297.293289 -186.344056) (xy 297.305415 -186.289619)
			(xy 297.325338 -186.237528) (xy 297.352634 -186.188893) (xy 297.38672 -186.14475) (xy 297.426869 -186.106041)
			(xy 297.472227 -186.07359) (xy 297.521827 -186.048089) (xy 297.574611 -186.030082) (xy 297.629454 -186.019952)
			(xy 297.685188 -186.017915) (xy 297.740625 -186.024015) (xy 297.794582 -186.038121) (xy 297.845911 -186.059933)
			(xy 297.893517 -186.088987) (xy 297.936385 -186.124662) (xy 297.973602 -186.166199) (xy 298.004375 -186.212712)
			(xy 298.028047 -186.263209) (xy 298.044115 -186.316616) (xy 298.052235 -186.371792) (xy 298.052744 -186.399678)
			(xy 298.052235 -186.427564) (xy 298.044115 -186.48274) (xy 298.028047 -186.536147) (xy 298.004375 -186.586644)
			(xy 297.973602 -186.633157) (xy 297.936385 -186.674694) (xy 297.893517 -186.710369) (xy 297.845911 -186.739423)
			(xy 297.794582 -186.761235) (xy 297.740625 -186.775341) (xy 297.685188 -186.781441) (xy 297.629454 -186.779404)
			(xy 297.574611 -186.769274) (xy 297.521827 -186.751267) (xy 297.472227 -186.725766) (xy 297.426869 -186.693315)
			(xy 297.38672 -186.654606) (xy 297.352634 -186.610463) (xy 297.325338 -186.561828) (xy 297.305415 -186.509737)
			(xy 297.293289 -186.4553) (xy 297.289218 -186.399678) (xy 292.178293 -186.399678) (xy 292.021768 -189.405768)
			(xy 292.021768 -189.407546) (xy 292.021006 -189.420246) (xy 292.020244 -189.434978) (xy 292.020244 -189.43955)
			(xy 292.020456 -189.445781) (xy 292.02354 -189.457856) (xy 292.02634 -189.463426) (xy 292.029388 -189.46876)
			(xy 292.037516 -189.47765) (xy 292.043358 -189.48146) (xy 292.065968 -189.496624) (xy 292.107055 -189.532341)
			(xy 292.142651 -189.573533) (xy 292.172033 -189.619365) (xy 292.194605 -189.668906) (xy 292.209909 -189.721151)
			(xy 292.217636 -189.775041) (xy 292.21811 -189.802262) (xy 292.21684 -189.832742) (xy 292.215316 -189.846966)
			(xy 292.2118 -189.873023) (xy 292.19853 -189.923899) (xy 292.178398 -189.972471) (xy 292.151785 -190.017817)
			(xy 292.119196 -190.059078) (xy 292.081249 -190.095472) (xy 292.038663 -190.126309) (xy 292.015672 -190.139066)
			(xy 292.008814 -190.142622) (xy 291.995606 -190.15583) (xy 291.989256 -190.163704) (xy 291.985707 -190.16941)
			(xy 291.981464 -190.182156) (xy 291.980874 -190.18885) (xy 291.980874 -190.189104) (xy 291.900356 -191.737234)
			(xy 291.7825 -194.003422) (xy 291.77262 -194.196208) (xy 292.349172 -194.196208) (xy 292.353243 -194.140586)
			(xy 292.365369 -194.086149) (xy 292.385292 -194.034058) (xy 292.412588 -193.985423) (xy 292.446674 -193.94128)
			(xy 292.486823 -193.902571) (xy 292.532181 -193.87012) (xy 292.581781 -193.844619) (xy 292.634565 -193.826612)
			(xy 292.689408 -193.816482) (xy 292.745142 -193.814445) (xy 292.800579 -193.820545) (xy 292.854536 -193.834651)
			(xy 292.905865 -193.856463) (xy 292.953471 -193.885517) (xy 292.996339 -193.921192) (xy 293.033556 -193.962729)
			(xy 293.064329 -194.009242) (xy 293.088001 -194.059739) (xy 293.104069 -194.113146) (xy 293.112189 -194.168322)
			(xy 293.112698 -194.196208) (xy 293.112189 -194.224094) (xy 293.104069 -194.27927) (xy 293.090238 -194.32524)
			(xy 297.568618 -194.32524) (xy 297.572689 -194.269618) (xy 297.584815 -194.215181) (xy 297.604738 -194.16309)
			(xy 297.632034 -194.114455) (xy 297.66612 -194.070312) (xy 297.706269 -194.031603) (xy 297.751627 -193.999152)
			(xy 297.801227 -193.973651) (xy 297.854011 -193.955644) (xy 297.908854 -193.945514) (xy 297.964588 -193.943477)
			(xy 298.020025 -193.949577) (xy 298.073982 -193.963683) (xy 298.125311 -193.985495) (xy 298.172917 -194.014549)
			(xy 298.215785 -194.050224) (xy 298.253002 -194.091761) (xy 298.283775 -194.138274) (xy 298.307447 -194.188771)
			(xy 298.323515 -194.242178) (xy 298.331635 -194.297354) (xy 298.332144 -194.32524) (xy 298.331635 -194.353126)
			(xy 298.323515 -194.408302) (xy 298.307447 -194.461709) (xy 298.283775 -194.512206) (xy 298.253002 -194.558719)
			(xy 298.215785 -194.600256) (xy 298.172917 -194.635931) (xy 298.125311 -194.664985) (xy 298.073982 -194.686797)
			(xy 298.020025 -194.700903) (xy 297.964588 -194.707003) (xy 297.908854 -194.704966) (xy 297.854011 -194.694836)
			(xy 297.801227 -194.676829) (xy 297.751627 -194.651328) (xy 297.706269 -194.618877) (xy 297.66612 -194.580168)
			(xy 297.632034 -194.536025) (xy 297.604738 -194.48739) (xy 297.584815 -194.435299) (xy 297.572689 -194.380862)
			(xy 297.568618 -194.32524) (xy 293.090238 -194.32524) (xy 293.088001 -194.332677) (xy 293.064329 -194.383174)
			(xy 293.033556 -194.429687) (xy 292.996339 -194.471224) (xy 292.953471 -194.506899) (xy 292.905865 -194.535953)
			(xy 292.854536 -194.557765) (xy 292.800579 -194.571871) (xy 292.745142 -194.577971) (xy 292.689408 -194.575934)
			(xy 292.634565 -194.565804) (xy 292.581781 -194.547797) (xy 292.532181 -194.522296) (xy 292.486823 -194.489845)
			(xy 292.446674 -194.451136) (xy 292.412588 -194.406993) (xy 292.385292 -194.358358) (xy 292.365369 -194.306267)
			(xy 292.353243 -194.25183) (xy 292.349172 -194.196208) (xy 291.77262 -194.196208) (xy 291.772086 -194.206622)
			(xy 291.765228 -194.347592) (xy 291.766752 -194.360038) (xy 291.769038 -194.367912) (xy 291.77361 -194.37477)
			(xy 291.788913 -194.398466) (xy 291.81312 -194.449414) (xy 291.829555 -194.503373) (xy 291.837858 -194.559165)
			(xy 291.83838 -194.587368) (xy 291.83838 -194.588384) (xy 291.837912 -194.61486) (xy 291.830554 -194.667298)
			(xy 291.816004 -194.718213) (xy 291.794544 -194.766621) (xy 291.766587 -194.811592) (xy 291.749988 -194.832224)
			(xy 291.749734 -194.832478) (xy 291.744146 -194.839336) (xy 291.741606 -194.845432) (xy 291.73805 -194.857878)
			(xy 291.735256 -194.912742) (xy 291.725858 -195.09486) (xy 291.68725 -195.835016) (xy 291.648388 -196.581268)
			(xy 291.422543 -200.928224) (xy 292.89959 -200.928224) (xy 292.903661 -200.872602) (xy 292.915787 -200.818165)
			(xy 292.93571 -200.766074) (xy 292.963006 -200.717439) (xy 292.997092 -200.673296) (xy 293.037241 -200.634587)
			(xy 293.082599 -200.602136) (xy 293.132199 -200.576635) (xy 293.184983 -200.558628) (xy 293.239826 -200.548498)
			(xy 293.29556 -200.546461) (xy 293.350997 -200.552561) (xy 293.404954 -200.566667) (xy 293.456283 -200.588479)
			(xy 293.503889 -200.617533) (xy 293.546757 -200.653208) (xy 293.583974 -200.694745) (xy 293.614747 -200.741258)
			(xy 293.638419 -200.791755) (xy 293.654487 -200.845162) (xy 293.662607 -200.900338) (xy 293.663116 -200.928224)
			(xy 293.662607 -200.95611) (xy 293.654487 -201.011286) (xy 293.638419 -201.064693) (xy 293.636785 -201.068178)
			(xy 295.508932 -201.068178) (xy 295.513003 -201.012556) (xy 295.525129 -200.958119) (xy 295.545052 -200.906028)
			(xy 295.572348 -200.857393) (xy 295.606434 -200.81325) (xy 295.646583 -200.774541) (xy 295.691941 -200.74209)
			(xy 295.741541 -200.716589) (xy 295.794325 -200.698582) (xy 295.849168 -200.688452) (xy 295.904902 -200.686415)
			(xy 295.960339 -200.692515) (xy 296.014296 -200.706621) (xy 296.065625 -200.728433) (xy 296.113231 -200.757487)
			(xy 296.156099 -200.793162) (xy 296.193316 -200.834699) (xy 296.224089 -200.881212) (xy 296.247761 -200.931709)
			(xy 296.263829 -200.985116) (xy 296.271949 -201.040292) (xy 296.272458 -201.068178) (xy 296.271949 -201.096064)
			(xy 296.263829 -201.15124) (xy 296.263754 -201.15149) (xy 296.72102 -201.15149) (xy 296.725091 -201.095868)
			(xy 296.737217 -201.041431) (xy 296.75714 -200.98934) (xy 296.784436 -200.940705) (xy 296.818522 -200.896562)
			(xy 296.858671 -200.857853) (xy 296.904029 -200.825402) (xy 296.953629 -200.799901) (xy 297.006413 -200.781894)
			(xy 297.061256 -200.771764) (xy 297.11699 -200.769727) (xy 297.172427 -200.775827) (xy 297.226384 -200.789933)
			(xy 297.277713 -200.811745) (xy 297.325319 -200.840799) (xy 297.368187 -200.876474) (xy 297.405404 -200.918011)
			(xy 297.436177 -200.964524) (xy 297.459849 -201.015021) (xy 297.475917 -201.068428) (xy 297.484037 -201.123604)
			(xy 297.484546 -201.15149) (xy 297.484037 -201.179376) (xy 297.475917 -201.234552) (xy 297.459849 -201.287959)
			(xy 297.436177 -201.338456) (xy 297.405404 -201.384969) (xy 297.368187 -201.426506) (xy 297.325319 -201.462181)
			(xy 297.277713 -201.491235) (xy 297.226384 -201.513047) (xy 297.172427 -201.527153) (xy 297.11699 -201.533253)
			(xy 297.061256 -201.531216) (xy 297.006413 -201.521086) (xy 296.953629 -201.503079) (xy 296.904029 -201.477578)
			(xy 296.858671 -201.445127) (xy 296.818522 -201.406418) (xy 296.784436 -201.362275) (xy 296.75714 -201.31364)
			(xy 296.737217 -201.261549) (xy 296.725091 -201.207112) (xy 296.72102 -201.15149) (xy 296.263754 -201.15149)
			(xy 296.247761 -201.204647) (xy 296.224089 -201.255144) (xy 296.193316 -201.301657) (xy 296.156099 -201.343194)
			(xy 296.113231 -201.378869) (xy 296.065625 -201.407923) (xy 296.014296 -201.429735) (xy 295.960339 -201.443841)
			(xy 295.904902 -201.449941) (xy 295.849168 -201.447904) (xy 295.794325 -201.437774) (xy 295.741541 -201.419767)
			(xy 295.691941 -201.394266) (xy 295.646583 -201.361815) (xy 295.606434 -201.323106) (xy 295.572348 -201.278963)
			(xy 295.545052 -201.230328) (xy 295.525129 -201.178237) (xy 295.513003 -201.1238) (xy 295.508932 -201.068178)
			(xy 293.636785 -201.068178) (xy 293.614747 -201.11519) (xy 293.583974 -201.161703) (xy 293.546757 -201.20324)
			(xy 293.503889 -201.238915) (xy 293.456283 -201.267969) (xy 293.404954 -201.289781) (xy 293.350997 -201.303887)
			(xy 293.29556 -201.309987) (xy 293.239826 -201.30795) (xy 293.184983 -201.29782) (xy 293.132199 -201.279813)
			(xy 293.082599 -201.254312) (xy 293.037241 -201.221861) (xy 292.997092 -201.183152) (xy 292.963006 -201.139009)
			(xy 292.93571 -201.090374) (xy 292.915787 -201.038283) (xy 292.903661 -200.983846) (xy 292.89959 -200.928224)
			(xy 291.422543 -200.928224) (xy 291.391848 -201.519028) (xy 291.391691 -201.522737) (xy 291.392325 -201.530133)
			(xy 291.393118 -201.53376) (xy 291.397182 -201.55027) (xy 291.399214 -201.554334) (xy 291.407596 -201.570844)
			(xy 291.407596 -201.571098) (xy 291.408866 -201.574146) (xy 291.414708 -201.587608) (xy 291.415216 -201.588116)
			(xy 291.420409 -201.601282) (xy 291.429055 -201.628234) (xy 291.432488 -201.641964) (xy 291.432488 -201.642472)
			(xy 291.433504 -201.64679) (xy 291.433504 -201.647552) (xy 291.434012 -201.650346) (xy 291.439092 -201.677778)
			(xy 291.439092 -201.678286) (xy 291.440605 -201.68985) (xy 291.442386 -201.713108) (xy 291.442648 -201.724768)
			(xy 291.442648 -201.733658) (xy 291.441124 -201.765408) (xy 291.438617 -201.789104) (xy 291.428466 -201.835661)
			(xy 291.412608 -201.880596) (xy 291.402262 -201.90206) (xy 291.394896 -201.91603) (xy 291.39007 -201.924666)
			(xy 291.38372 -201.935334) (xy 291.379656 -201.94143) (xy 291.376862 -201.945494) (xy 291.373052 -201.951336)
			(xy 291.370512 -201.958702) (xy 291.367718 -201.972418) (xy 291.363654 -202.050396) (xy 291.338 -202.540616)
			(xy 291.324538 -202.802998) (xy 291.320474 -202.878944) (xy 291.281612 -203.62799) (xy 291.273738 -203.778612)
			(xy 291.273738 -203.79309) (xy 291.279072 -203.803758) (xy 291.282882 -203.811632) (xy 291.292788 -203.821538)
			(xy 291.295328 -203.82357) (xy 291.315896 -203.840131) (xy 291.352715 -203.877984) (xy 291.383965 -203.920551)
			(xy 291.392218 -203.935838) (xy 292.984172 -203.935838) (xy 292.988243 -203.880216) (xy 293.000369 -203.825779)
			(xy 293.020292 -203.773688) (xy 293.047588 -203.725053) (xy 293.081674 -203.68091) (xy 293.121823 -203.642201)
			(xy 293.167181 -203.60975) (xy 293.216781 -203.584249) (xy 293.269565 -203.566242) (xy 293.324408 -203.556112)
			(xy 293.380142 -203.554075) (xy 293.435579 -203.560175) (xy 293.489536 -203.574281) (xy 293.540865 -203.596093)
			(xy 293.588471 -203.625147) (xy 293.631339 -203.660822) (xy 293.668556 -203.702359) (xy 293.699329 -203.748872)
			(xy 293.712199 -203.776326) (xy 295.45991 -203.776326) (xy 295.463981 -203.720704) (xy 295.476107 -203.666267)
			(xy 295.49603 -203.614176) (xy 295.523326 -203.565541) (xy 295.557412 -203.521398) (xy 295.597561 -203.482689)
			(xy 295.642919 -203.450238) (xy 295.692519 -203.424737) (xy 295.745303 -203.40673) (xy 295.800146 -203.3966)
			(xy 295.85588 -203.394563) (xy 295.911317 -203.400663) (xy 295.965274 -203.414769) (xy 296.016603 -203.436581)
			(xy 296.064209 -203.465635) (xy 296.107077 -203.50131) (xy 296.144294 -203.542847) (xy 296.175067 -203.58936)
			(xy 296.198739 -203.639857) (xy 296.214807 -203.693264) (xy 296.222927 -203.74844) (xy 296.223436 -203.776326)
			(xy 296.222927 -203.804212) (xy 296.214807 -203.859388) (xy 296.198739 -203.912795) (xy 296.175067 -203.963292)
			(xy 296.144294 -204.009805) (xy 296.107077 -204.051342) (xy 296.064209 -204.087017) (xy 296.016603 -204.116071)
			(xy 295.965274 -204.137883) (xy 295.911317 -204.151989) (xy 295.85588 -204.158089) (xy 295.800146 -204.156052)
			(xy 295.745303 -204.145922) (xy 295.692519 -204.127915) (xy 295.642919 -204.102414) (xy 295.597561 -204.069963)
			(xy 295.557412 -204.031254) (xy 295.523326 -203.987111) (xy 295.49603 -203.938476) (xy 295.476107 -203.886385)
			(xy 295.463981 -203.831948) (xy 295.45991 -203.776326) (xy 293.712199 -203.776326) (xy 293.723001 -203.799369)
			(xy 293.739069 -203.852776) (xy 293.747189 -203.907952) (xy 293.747698 -203.935838) (xy 293.747189 -203.963724)
			(xy 293.739069 -204.0189) (xy 293.723001 -204.072307) (xy 293.699329 -204.122804) (xy 293.668556 -204.169317)
			(xy 293.631339 -204.210854) (xy 293.588471 -204.246529) (xy 293.540865 -204.275583) (xy 293.489536 -204.297395)
			(xy 293.435579 -204.311501) (xy 293.380142 -204.317601) (xy 293.324408 -204.315564) (xy 293.269565 -204.305434)
			(xy 293.216781 -204.287427) (xy 293.167181 -204.261926) (xy 293.121823 -204.229475) (xy 293.081674 -204.190766)
			(xy 293.047588 -204.146623) (xy 293.020292 -204.097988) (xy 293.000369 -204.045897) (xy 292.988243 -203.99146)
			(xy 292.984172 -203.935838) (xy 291.392218 -203.935838) (xy 291.40905 -203.967018) (xy 291.42749 -204.0165)
			(xy 291.438933 -204.068051) (xy 291.443162 -204.120688) (xy 291.440094 -204.173405) (xy 291.42979 -204.225196)
			(xy 291.421566 -204.25029) (xy 291.417502 -204.26172) (xy 291.406264 -204.289407) (xy 291.376442 -204.341182)
			(xy 291.338923 -204.387683) (xy 291.294623 -204.427777) (xy 291.269928 -204.4446) (xy 291.264594 -204.448156)
			(xy 291.255958 -204.457554) (xy 291.252148 -204.464666) (xy 291.24275 -204.481176) (xy 291.239873 -204.486408)
			(xy 291.236416 -204.497834) (xy 291.235892 -204.503782) (xy 291.130006 -206.538068) (xy 292.603172 -206.538068)
			(xy 292.607243 -206.482446) (xy 292.619369 -206.428009) (xy 292.639292 -206.375918) (xy 292.666588 -206.327283)
			(xy 292.700674 -206.28314) (xy 292.740823 -206.244431) (xy 292.786181 -206.21198) (xy 292.835781 -206.186479)
			(xy 292.888565 -206.168472) (xy 292.943408 -206.158342) (xy 292.999142 -206.156305) (xy 293.054579 -206.162405)
			(xy 293.108536 -206.176511) (xy 293.159865 -206.198323) (xy 293.207471 -206.227377) (xy 293.250339 -206.263052)
			(xy 293.287556 -206.304589) (xy 293.318329 -206.351102) (xy 293.342001 -206.401599) (xy 293.358069 -206.455006)
			(xy 293.366189 -206.510182) (xy 293.366698 -206.538068) (xy 293.366189 -206.565954) (xy 293.358069 -206.62113)
			(xy 293.342001 -206.674537) (xy 293.318329 -206.725034) (xy 293.287556 -206.771547) (xy 293.250339 -206.813084)
			(xy 293.207471 -206.848759) (xy 293.159865 -206.877813) (xy 293.108536 -206.899625) (xy 293.054579 -206.913731)
			(xy 292.999142 -206.919831) (xy 292.943408 -206.917794) (xy 292.888565 -206.907664) (xy 292.835781 -206.889657)
			(xy 292.786181 -206.864156) (xy 292.740823 -206.831705) (xy 292.700674 -206.792996) (xy 292.666588 -206.748853)
			(xy 292.639292 -206.700218) (xy 292.619369 -206.648127) (xy 292.607243 -206.59369) (xy 292.603172 -206.538068)
			(xy 291.130006 -206.538068) (xy 290.719827 -214.418418) (xy 294.647872 -214.418418) (xy 294.651943 -214.362796)
			(xy 294.664069 -214.308359) (xy 294.683992 -214.256268) (xy 294.711288 -214.207633) (xy 294.745374 -214.16349)
			(xy 294.785523 -214.124781) (xy 294.830881 -214.09233) (xy 294.880481 -214.066829) (xy 294.933265 -214.048822)
			(xy 294.988108 -214.038692) (xy 295.043842 -214.036655) (xy 295.099279 -214.042755) (xy 295.153236 -214.056861)
			(xy 295.204565 -214.078673) (xy 295.252171 -214.107727) (xy 295.295039 -214.143402) (xy 295.332256 -214.184939)
			(xy 295.363029 -214.231452) (xy 295.386701 -214.281949) (xy 295.402769 -214.335356) (xy 295.410889 -214.390532)
			(xy 295.411398 -214.418418) (xy 295.410889 -214.446304) (xy 295.402769 -214.50148) (xy 295.386701 -214.554887)
			(xy 295.363029 -214.605384) (xy 295.332256 -214.651897) (xy 295.295039 -214.693434) (xy 295.252171 -214.729109)
			(xy 295.204565 -214.758163) (xy 295.153236 -214.779975) (xy 295.099279 -214.794081) (xy 295.043842 -214.800181)
			(xy 294.988108 -214.798144) (xy 294.933265 -214.788014) (xy 294.880481 -214.770007) (xy 294.830881 -214.744506)
			(xy 294.785523 -214.712055) (xy 294.745374 -214.673346) (xy 294.711288 -214.629203) (xy 294.683992 -214.580568)
			(xy 294.664069 -214.528477) (xy 294.651943 -214.47404) (xy 294.647872 -214.418418) (xy 290.719827 -214.418418)
			(xy 290.66147 -215.539574) (xy 292.538148 -215.539574) (xy 292.542219 -215.483952) (xy 292.554345 -215.429515)
			(xy 292.574268 -215.377424) (xy 292.601564 -215.328789) (xy 292.63565 -215.284646) (xy 292.675799 -215.245937)
			(xy 292.721157 -215.213486) (xy 292.770757 -215.187985) (xy 292.823541 -215.169978) (xy 292.878384 -215.159848)
			(xy 292.934118 -215.157811) (xy 292.989555 -215.163911) (xy 293.043512 -215.178017) (xy 293.094841 -215.199829)
			(xy 293.142447 -215.228883) (xy 293.185315 -215.264558) (xy 293.222532 -215.306095) (xy 293.253305 -215.352608)
			(xy 293.276977 -215.403105) (xy 293.293045 -215.456512) (xy 293.301165 -215.511688) (xy 293.301674 -215.539574)
			(xy 293.301165 -215.56746) (xy 293.293045 -215.622636) (xy 293.276977 -215.676043) (xy 293.253305 -215.72654)
			(xy 293.222532 -215.773053) (xy 293.185315 -215.81459) (xy 293.142447 -215.850265) (xy 293.094841 -215.879319)
			(xy 293.043512 -215.901131) (xy 292.989555 -215.915237) (xy 292.934118 -215.921337) (xy 292.878384 -215.9193)
			(xy 292.823541 -215.90917) (xy 292.770757 -215.891163) (xy 292.721157 -215.865662) (xy 292.675799 -215.833211)
			(xy 292.63565 -215.794502) (xy 292.601564 -215.750359) (xy 292.574268 -215.701724) (xy 292.554345 -215.649633)
			(xy 292.542219 -215.595196) (xy 292.538148 -215.539574) (xy 290.66147 -215.539574) (xy 290.138358 -225.589592)
			(xy 290.044886 -227.387404) (xy 290.044886 -227.388674) (xy 290.045191 -227.40204) (xy 290.051944 -227.427901)
			(xy 290.065177 -227.451124) (xy 290.083984 -227.470115) (xy 290.107076 -227.483575) (xy 290.132869 -227.49058)
			(xy 290.146232 -227.491036) (xy 293.537894 -227.491036) (xy 293.54018 -227.491036) (xy 293.551703 -227.489983)
			(xy 293.572031 -227.478976) (xy 293.585486 -227.46018) (xy 293.587932 -227.448872) (xy 293.952422 -225.355658)
			(xy 294.163496 -224.144078) (xy 294.382952 -222.884746) (xy 294.677338 -221.193868) (xy 294.67877 -221.182451)
			(xy 294.672431 -221.160355) (xy 294.665146 -221.15145) (xy 294.665146 -221.151196) (xy 294.659312 -221.145155)
			(xy 294.644649 -221.136984) (xy 294.636444 -221.135194) (xy 294.635428 -221.13494) (xy 294.62603 -221.134432)
			(xy 294.609774 -221.134432) (xy 294.582593 -221.133842) (xy 294.52881 -221.12591) (xy 294.476696 -221.110424)
			(xy 294.427309 -221.087696) (xy 294.381648 -221.058189) (xy 294.340638 -221.022498) (xy 294.30511 -220.981348)
			(xy 294.275782 -220.935571) (xy 294.253249 -220.886095) (xy 294.237968 -220.833921) (xy 294.230247 -220.780107)
			(xy 294.22979 -220.752924) (xy 294.230272 -220.725695) (xy 294.238013 -220.671789) (xy 294.253341 -220.619532)
			(xy 294.275943 -220.569985) (xy 294.305362 -220.524156) (xy 294.340998 -220.482976) (xy 294.382128 -220.447282)
			(xy 294.427916 -220.4178) (xy 294.477431 -220.395128) (xy 294.529666 -220.379727) (xy 294.583561 -220.371911)
			(xy 294.61079 -220.371416) (xy 294.616124 -220.371416) (xy 294.632126 -220.371924) (xy 294.632634 -220.371924)
			(xy 294.636444 -220.372178) (xy 294.671496 -220.376242) (xy 294.673528 -220.376496) (xy 294.674036 -220.376496)
			(xy 294.70858 -220.384116) (xy 294.709596 -220.384116) (xy 294.713406 -220.384878) (xy 294.719926 -220.385529)
			(xy 294.732916 -220.383853) (xy 294.73906 -220.381576) (xy 294.747696 -220.377004) (xy 294.809926 -220.336618)
			(xy 294.818036 -220.330827) (xy 294.829399 -220.314482) (xy 294.832024 -220.304868) (xy 295.498774 -216.478104)
			(xy 295.49852 -216.47785) (xy 295.49725 -216.477342) (xy 295.474898 -216.4715) (xy 295.453308 -216.465912)
			(xy 295.42639 -216.458434) (xy 295.37493 -216.436683) (xy 295.327193 -216.40766) (xy 295.284199 -216.371986)
			(xy 295.246868 -216.330422) (xy 295.215997 -216.283859) (xy 295.192247 -216.233291) (xy 295.176127 -216.1798)
			(xy 295.167979 -216.12453) (xy 295.167558 -216.096596) (xy 295.168044 -216.069344) (xy 295.175801 -216.015395)
			(xy 295.191156 -215.963099) (xy 295.213797 -215.91352) (xy 295.243263 -215.867668) (xy 295.278954 -215.826475)
			(xy 295.320143 -215.790781) (xy 295.365993 -215.761311) (xy 295.415571 -215.738666) (xy 295.467866 -215.723307)
			(xy 295.521814 -215.715546) (xy 295.549066 -215.715088) (xy 295.583864 -215.716612) (xy 295.628822 -215.720676)
			(xy 295.629584 -215.720676) (xy 295.6306 -215.720422) (xy 297.218354 -206.602584) (xy 297.649646 -204.1271)
			(xy 297.650296 -204.122546) (xy 297.650161 -204.113348) (xy 297.649392 -204.108812) (xy 297.647868 -204.100684)
			(xy 297.643296 -204.09281) (xy 297.630975 -204.070866) (xy 297.611578 -204.024427) (xy 297.598461 -203.97584)
			(xy 297.591853 -203.925949) (xy 297.59148 -203.900786) (xy 297.59197 -203.873107) (xy 297.599968 -203.818331)
			(xy 297.615809 -203.765289) (xy 297.639159 -203.715098) (xy 297.669526 -203.668813) (xy 297.706271 -203.627411)
			(xy 297.727116 -203.609194) (xy 297.728132 -203.608178) (xy 297.740578 -203.586588) (xy 297.742733 -203.582654)
			(xy 297.745797 -203.574223) (xy 297.746674 -203.569824) (xy 298.3992 -199.822816) (xy 298.461176 -199.467216)
			(xy 298.45889 -199.45731) (xy 298.454603 -199.437196) (xy 298.449898 -199.396338) (xy 298.449492 -199.375776)
			(xy 298.449492 -199.367902) (xy 298.450762 -199.342756) (xy 298.453806 -199.311864) (xy 298.468635 -199.251589)
			(xy 298.493028 -199.194511) (xy 298.509182 -199.168004) (xy 298.51477 -199.159368) (xy 298.553378 -198.937372)
			(xy 298.738036 -197.876414) (xy 298.738264 -197.872189) (xy 298.7375 -197.863764) (xy 298.736512 -197.85965)
			(xy 298.736004 -197.858126) (xy 298.728633 -197.831555) (xy 298.720728 -197.776984) (xy 298.720256 -197.749414)
			(xy 298.720256 -197.748906) (xy 298.72178 -197.713092) (xy 298.722796 -197.704202) (xy 298.722796 -197.703948)
			(xy 298.726345 -197.678096) (xy 298.739598 -197.627623) (xy 298.749212 -197.603364) (xy 298.756357 -197.586612)
			(xy 298.773405 -197.554425) (xy 298.783248 -197.539102) (xy 298.783248 -197.538848) (xy 298.791376 -197.52691)
			(xy 298.79671 -197.517766) (xy 298.803568 -197.502018) (xy 298.803568 -197.50151) (xy 298.853098 -197.216776)
			(xy 298.913804 -196.868034) (xy 298.958 -196.614796) (xy 298.993052 -196.413374) (xy 298.994178 -196.405474)
			(xy 298.991976 -196.389677) (xy 298.988734 -196.382386) (xy 298.985178 -196.375274) (xy 298.97451 -196.364098)
			(xy 298.967144 -196.360034) (xy 298.942569 -196.3462) (xy 298.897421 -196.312409) (xy 298.877228 -196.292724)
			(xy 298.866749 -196.2821) (xy 298.847296 -196.259468) (xy 298.838366 -196.247512) (xy 298.834048 -196.24167)
			(xy 298.812458 -196.224906) (xy 298.8056 -196.219826) (xy 298.797472 -196.217032) (xy 298.793637 -196.215874)
			(xy 298.785728 -196.214603) (xy 298.781724 -196.214492) (xy 298.705524 -196.214492) (xy 298.69257 -196.21627)
			(xy 298.684818 -196.218629) (xy 298.671227 -196.227436) (xy 298.6659 -196.233542) (xy 298.662344 -196.238114)
			(xy 298.660566 -196.240654) (xy 298.645205 -196.261978) (xy 298.609569 -196.300605) (xy 298.568971 -196.333978)
			(xy 298.524179 -196.361468) (xy 298.47604 -196.382555) (xy 298.425464 -196.396839) (xy 298.373407 -196.404051)
			(xy 298.34713 -196.404484) (xy 298.319876 -196.404023) (xy 298.265923 -196.396269) (xy 298.213623 -196.380915)
			(xy 298.164041 -196.358274) (xy 298.118186 -196.328807) (xy 298.076992 -196.293113) (xy 298.041297 -196.251919)
			(xy 298.011829 -196.206064) (xy 297.989187 -196.156482) (xy 297.973832 -196.104182) (xy 297.966078 -196.05023)
			(xy 297.965622 -196.022976) (xy 297.966096 -195.995909) (xy 297.973751 -195.942318) (xy 297.988903 -195.890346)
			(xy 298.011248 -195.841038) (xy 298.040337 -195.795383) (xy 298.075588 -195.754298) (xy 298.116291 -195.718607)
			(xy 298.16163 -195.689027) (xy 298.210694 -195.666152) (xy 298.2625 -195.650441) (xy 298.316005 -195.64221)
			(xy 298.343066 -195.641468) (xy 298.348908 -195.641468) (xy 298.378791 -195.642196) (xy 298.437787 -195.651802)
			(xy 298.494567 -195.670482) (xy 298.547743 -195.697779) (xy 298.596018 -195.733026) (xy 298.638213 -195.775363)
			(xy 298.656248 -195.799202) (xy 298.659804 -195.804282) (xy 298.664884 -195.8086) (xy 298.66971 -195.812918)
			(xy 298.696126 -195.826126) (xy 298.701452 -195.828587) (xy 298.712868 -195.831282) (xy 298.718732 -195.83146)
			(xy 298.78274 -195.83146) (xy 298.794678 -195.828412) (xy 298.800266 -195.825618) (xy 298.817284 -195.816728)
			(xy 298.82068 -195.814856) (xy 298.82693 -195.810267) (xy 298.82973 -195.807584) (xy 298.837096 -195.800218)
			(xy 298.839382 -195.79717) (xy 298.857587 -195.773314) (xy 298.900232 -195.731095) (xy 298.948961 -195.696074)
			(xy 299.002573 -195.669114) (xy 299.059744 -195.65088) (xy 299.089318 -195.645786) (xy 299.09135 -195.645532)
			(xy 299.091858 -195.645532) (xy 299.099592 -195.644064) (xy 299.113688 -195.637077) (xy 299.119544 -195.631816)
			(xy 299.125132 -195.626228) (xy 299.132752 -195.612004) (xy 303.416716 -171.012612) (xy 306.197508 -155.044648)
			(xy 306.196238 -155.04287) (xy 306.178966 -155.025598) (xy 306.159326 -155.005311) (xy 306.125634 -154.960001)
			(xy 306.098981 -154.910225) (xy 306.079949 -154.857066) (xy 306.068952 -154.801684) (xy 306.06623 -154.745286)
			(xy 306.071842 -154.689102) (xy 306.085666 -154.634358) (xy 306.107401 -154.582245) (xy 306.136573 -154.533902)
			(xy 306.172546 -154.490381) (xy 306.19319 -154.471116) (xy 306.214378 -154.452597) (xy 306.261177 -154.421348)
			(xy 306.286408 -154.408886) (xy 306.302156 -154.40152) (xy 306.31003 -154.396694) (xy 306.310538 -154.396186)
			(xy 306.313332 -154.380184) (xy 306.341018 -154.220926) (xy 306.341272 -154.220672) (xy 306.341526 -154.21864)
			(xy 306.34178 -154.21737) (xy 306.981352 -149.24532) (xy 307.542184 -144.885664) (xy 307.620924 -144.274032)
			(xy 307.621432 -144.267936) (xy 307.63337 -143.00962) (xy 307.637688 -142.56004) (xy 307.642006 -142.099792)
			(xy 307.698394 -136.127744) (xy 307.819298 -123.317762) (xy 307.87975 -116.901976) (xy 307.880156 -116.874731)
			(xy 307.883587 -116.820344) (xy 307.886608 -116.793264) (xy 307.889008 -116.774179) (xy 307.895104 -116.736195)
			(xy 307.8988 -116.717318) (xy 310.39181 -104.259888) (xy 310.391048 -104.247442) (xy 310.38927 -104.241346)
			(xy 310.388254 -104.238044) (xy 310.379613 -104.209479) (xy 310.370306 -104.150534) (xy 310.369712 -104.120696)
			(xy 310.369712 -104.120188) (xy 310.370212 -104.092951) (xy 310.377989 -104.039034) (xy 310.393354 -103.986772)
			(xy 310.415996 -103.937226) (xy 310.445454 -103.891403) (xy 310.46293 -103.870506) (xy 310.468264 -103.86441)
			(xy 310.47309 -103.85425) (xy 310.473852 -103.85044) (xy 310.474106 -103.849932) (xy 310.474614 -103.846376)
			(xy 310.476392 -103.836978) (xy 310.550052 -103.466138) (xy 310.551175 -103.457049) (xy 310.547646 -103.439091)
			(xy 310.543194 -103.431086) (xy 310.53659 -103.422196) (xy 310.529732 -103.415338) (xy 310.52643 -103.413052)
			(xy 310.502626 -103.39492) (xy 310.460431 -103.352496) (xy 310.425368 -103.30401) (xy 310.398297 -103.250649)
			(xy 310.379878 -103.193719) (xy 310.370562 -103.134614) (xy 310.369966 -103.104696) (xy 310.370461 -103.076554)
			(xy 310.378714 -103.020879) (xy 310.395054 -102.96702) (xy 310.419127 -102.916146) (xy 310.450412 -102.869358)
			(xy 310.488229 -102.827673) (xy 310.531758 -102.791994) (xy 310.580056 -102.763095) (xy 310.632074 -102.741603)
			(xy 310.659272 -102.734364) (xy 310.66486 -102.733094) (xy 310.666638 -102.732586) (xy 310.673242 -102.731316)
			(xy 310.685942 -102.724458) (xy 310.691784 -102.718616) (xy 310.69682 -102.713197) (xy 310.7038 -102.700161)
			(xy 310.7055 -102.692962) (xy 310.707532 -102.682548) (xy 310.707532 -102.682294) (xy 310.753506 -102.452678)
			(xy 310.778144 -102.329234) (xy 310.930798 -101.565964) (xy 310.932259 -101.556376) (xy 310.928719 -101.537322)
			(xy 310.92394 -101.52888) (xy 310.920892 -101.524054) (xy 310.888634 -101.491034) (xy 310.888126 -101.490526)
			(xy 310.85917 -101.460554) (xy 310.851757 -101.45388) (xy 310.833321 -101.446315) (xy 310.823356 -101.445822)
			(xy 310.815228 -101.445822) (xy 310.811164 -101.44633) (xy 310.796342 -101.448559) (xy 310.766462 -101.450974)
			(xy 310.751474 -101.451156) (xy 310.724223 -101.450668) (xy 310.670275 -101.442909) (xy 310.617981 -101.427552)
			(xy 310.568404 -101.40491) (xy 310.522553 -101.375444) (xy 310.481362 -101.339753) (xy 310.445669 -101.298564)
			(xy 310.4162 -101.252715) (xy 310.393555 -101.20314) (xy 310.378195 -101.150846) (xy 310.370433 -101.096899)
			(xy 310.369966 -101.069648) (xy 310.370467 -101.041911) (xy 310.378506 -100.987023) (xy 310.394408 -100.933876)
			(xy 310.417836 -100.883592) (xy 310.448298 -100.83723) (xy 310.485151 -100.795767) (xy 310.527619 -100.760076)
			(xy 310.574807 -100.73091) (xy 310.625721 -100.708883) (xy 310.679287 -100.69446) (xy 310.70677 -100.69068)
			(xy 310.728106 -100.68814) (xy 310.733186 -100.687886) (xy 310.751474 -100.687886) (xy 310.77897 -100.688403)
			(xy 310.833381 -100.696374) (xy 310.886083 -100.712083) (xy 310.91124 -100.723192) (xy 310.921883 -100.728151)
			(xy 310.942599 -100.739208) (xy 310.952642 -100.74529) (xy 310.954674 -100.74656) (xy 310.9595 -100.7491)
			(xy 310.969792 -100.753565) (xy 310.992194 -100.754101) (xy 311.00268 -100.750116) (xy 311.068466 -100.72116)
			(xy 311.073038 -100.719382) (xy 311.082944 -100.716334) (xy 311.090564 -100.709984) (xy 311.09415 -100.706831)
			(xy 311.100163 -100.699415) (xy 311.102502 -100.695252) (xy 311.103518 -100.69322) (xy 311.10809 -100.681282)
			(xy 311.108598 -100.678234) (xy 311.110376 -100.668582) (xy 311.110376 -100.668328) (xy 311.174638 -100.348542)
			(xy 311.601866 -98.213164) (xy 312.022236 -96.094296) (xy 312.297318 -94.707456) (xy 312.381138 -94.285562)
			(xy 312.375804 -94.274132) (xy 312.369708 -94.266512) (xy 312.33999 -94.236032) (xy 312.310018 -94.205552)
			(xy 312.302607 -94.19887) (xy 312.284172 -94.191289) (xy 312.274204 -94.19082) (xy 312.269378 -94.19082)
			(xy 312.264806 -94.191582) (xy 312.248058 -94.19441) (xy 312.214226 -94.197458) (xy 312.197242 -94.197678)
			(xy 312.196988 -94.197678) (xy 312.168974 -94.197187) (xy 312.113546 -94.189012) (xy 312.059904 -94.172837)
			(xy 312.009195 -94.14901) (xy 311.962505 -94.11804) (xy 311.920833 -94.080589) (xy 311.88507 -94.03746)
			(xy 311.87009 -94.013782) (xy 311.869836 -94.013274) (xy 311.866534 -94.00794) (xy 311.853326 -93.994732)
			(xy 311.850278 -93.992446) (xy 311.84723 -93.989906) (xy 311.843166 -93.986604) (xy 311.83707 -93.983048)
			(xy 311.823354 -93.975428) (xy 311.819176 -93.973611) (xy 311.810361 -93.971309) (xy 311.805828 -93.970856)
			(xy 311.771792 -93.97111) (xy 311.72785 -93.971618) (xy 311.718483 -93.972465) (xy 311.701277 -93.980019)
			(xy 311.694322 -93.98635) (xy 311.686956 -93.993716) (xy 311.679082 -94.00413) (xy 311.677304 -94.007432)
			(xy 311.662816 -94.032876) (xy 311.627304 -94.079426) (xy 311.585105 -94.120011) (xy 311.537207 -94.153682)
			(xy 311.484731 -94.179649) (xy 311.428908 -94.197304) (xy 311.371044 -94.206234) (xy 311.34177 -94.206822)
			(xy 311.314247 -94.206339) (xy 311.259772 -94.198432) (xy 311.206997 -94.182787) (xy 311.157014 -94.159727)
			(xy 311.11086 -94.12973) (xy 311.06949 -94.093418) (xy 311.033761 -94.051543) (xy 311.018682 -94.028514)
			(xy 311.015634 -94.023688) (xy 311.006236 -94.01429) (xy 310.99927 -94.007973) (xy 310.982072 -94.000407)
			(xy 310.972708 -93.999558) (xy 310.932576 -93.99778) (xy 310.891936 -93.996002) (xy 310.891682 -93.996002)
			(xy 310.883374 -93.996) (xy 310.86744 -94.00067) (xy 310.86044 -94.005146) (xy 310.855614 -94.008702)
			(xy 310.849264 -94.015052) (xy 310.848756 -94.015814) (xy 310.848502 -94.016068) (xy 310.847486 -94.017338)
			(xy 310.846216 -94.019116) (xy 310.828026 -94.042323) (xy 310.785714 -94.083387) (xy 310.737603 -94.117473)
			(xy 310.684832 -94.143775) (xy 310.628651 -94.161669) (xy 310.570389 -94.170731) (xy 310.540908 -94.171262)
			(xy 310.540654 -94.171262) (xy 310.513408 -94.170773) (xy 310.459472 -94.163012) (xy 310.407189 -94.147655)
			(xy 310.357624 -94.125014) (xy 310.311785 -94.09555) (xy 310.270605 -94.059862) (xy 310.234923 -94.018678)
			(xy 310.205464 -93.972836) (xy 310.182829 -93.923268) (xy 310.167478 -93.870983) (xy 310.159724 -93.817046)
			(xy 310.159724 -93.762554) (xy 310.167478 -93.708617) (xy 310.182829 -93.656332) (xy 310.205464 -93.606764)
			(xy 310.234923 -93.560922) (xy 310.270605 -93.519738) (xy 310.311785 -93.48405) (xy 310.357624 -93.454586)
			(xy 310.407189 -93.431945) (xy 310.459472 -93.416588) (xy 310.513408 -93.408827) (xy 310.540654 -93.408246)
			(xy 310.568176 -93.40873) (xy 310.62265 -93.41664) (xy 310.675424 -93.432287) (xy 310.725406 -93.455347)
			(xy 310.771559 -93.485344) (xy 310.812929 -93.521655) (xy 310.848658 -93.563528) (xy 310.863742 -93.586554)
			(xy 310.86679 -93.59138) (xy 310.876188 -93.600778) (xy 310.883153 -93.607095) (xy 310.900352 -93.614657)
			(xy 310.909716 -93.61551) (xy 310.949848 -93.617288) (xy 310.99125 -93.619066) (xy 310.993028 -93.619066)
			(xy 311.000209 -93.618817) (xy 311.014001 -93.614815) (xy 311.020206 -93.611192) (xy 311.025032 -93.608144)
			(xy 311.03316 -93.600016) (xy 311.033668 -93.599254) (xy 311.033922 -93.599) (xy 311.0357 -93.596714)
			(xy 311.044826 -93.58481) (xy 311.064662 -93.562306) (xy 311.075324 -93.551756) (xy 311.096608 -93.531916)
			(xy 311.144058 -93.498243) (xy 311.169812 -93.4847) (xy 311.191047 -93.474377) (xy 311.235499 -93.458459)
			(xy 311.258458 -93.45295) (xy 311.259982 -93.452696) (xy 311.279032 -93.448378) (xy 311.29097 -93.447108)
			(xy 311.293002 -93.446854) (xy 311.294018 -93.446854) (xy 311.304686 -93.445584) (xy 311.30494 -93.445584)
			(xy 311.307226 -93.44533) (xy 311.34177 -93.443806) (xy 311.369786 -93.444293) (xy 311.425218 -93.452463)
			(xy 311.478865 -93.468633) (xy 311.529579 -93.492457) (xy 311.576275 -93.523424) (xy 311.617954 -93.560873)
			(xy 311.653723 -93.604001) (xy 311.668668 -93.627702) (xy 311.668922 -93.62821) (xy 311.672224 -93.633544)
			(xy 311.685432 -93.646752) (xy 311.68848 -93.649038) (xy 311.691528 -93.651578) (xy 311.695592 -93.65488)
			(xy 311.701688 -93.658436) (xy 311.715404 -93.666056) (xy 311.719583 -93.667869) (xy 311.728398 -93.670161)
			(xy 311.73293 -93.670628) (xy 311.766966 -93.670374) (xy 311.811162 -93.669866) (xy 311.820109 -93.669062)
			(xy 311.836628 -93.662031) (xy 311.84342 -93.65615) (xy 311.851802 -93.647768) (xy 311.854088 -93.64472)
			(xy 311.859676 -93.637354) (xy 311.861708 -93.633798) (xy 311.862216 -93.632782) (xy 311.876744 -93.607487)
			(xy 311.912279 -93.561229) (xy 311.954431 -93.520909) (xy 312.002222 -93.487464) (xy 312.054541 -93.461671)
			(xy 312.110172 -93.44413) (xy 312.167823 -93.435247) (xy 312.196988 -93.434662) (xy 312.197242 -93.434662)
			(xy 312.224573 -93.435129) (xy 312.278674 -93.442933) (xy 312.331105 -93.458391) (xy 312.380788 -93.481183)
			(xy 312.403998 -93.495622) (xy 312.404506 -93.495876) (xy 312.409078 -93.498416) (xy 312.415174 -93.500956)
			(xy 312.415682 -93.50121) (xy 312.416444 -93.501464) (xy 312.427112 -93.50375) (xy 312.429906 -93.504004)
			(xy 312.435221 -93.50413) (xy 312.445719 -93.502465) (xy 312.450734 -93.500702) (xy 312.493152 -93.482414)
			(xy 312.533284 -93.465142) (xy 312.535062 -93.46438) (xy 312.545476 -93.455998) (xy 312.74893 -92.4306)
			(xy 312.983626 -91.247976) (xy 313.204352 -90.136472) (xy 313.201019 -90.131268) (xy 313.192289 -90.122525)
			(xy 313.18708 -90.1192) (xy 313.177936 -90.113866) (xy 313.177428 -90.113358) (xy 313.104784 -90.069924)
			(xy 313.095442 -90.065062) (xy 313.074546 -90.062629) (xy 313.054436 -90.068806) (xy 313.04611 -90.075258)
			(xy 313.043062 -90.077798) (xy 313.022588 -90.093832) (xy 312.978118 -90.120788) (xy 312.930394 -90.141445)
			(xy 312.880305 -90.155419) (xy 312.82878 -90.162449) (xy 312.802778 -90.162888) (xy 312.801508 -90.162888)
			(xy 312.779664 -90.16238) (xy 312.775092 -90.162126) (xy 312.746594 -90.15954) (xy 312.690782 -90.146915)
			(xy 312.63748 -90.1261) (xy 312.587882 -90.097563) (xy 312.543099 -90.061943) (xy 312.504134 -90.020037)
			(xy 312.471861 -89.972785) (xy 312.447002 -89.921245) (xy 312.430114 -89.866572) (xy 312.421576 -89.809991)
			(xy 312.421016 -89.78138) (xy 312.421481 -89.754129) (xy 312.42924 -89.700181) (xy 312.444598 -89.647887)
			(xy 312.467242 -89.598311) (xy 312.496711 -89.552462) (xy 312.532405 -89.511274) (xy 312.573597 -89.475585)
			(xy 312.61945 -89.446121) (xy 312.669028 -89.423483) (xy 312.721324 -89.408131) (xy 312.775273 -89.400378)
			(xy 312.802524 -89.399872) (xy 312.831707 -89.400421) (xy 312.889395 -89.409297) (xy 312.945059 -89.426853)
			(xy 312.9974 -89.452681) (xy 313.045197 -89.486178) (xy 313.087337 -89.526562) (xy 313.122836 -89.572892)
			(xy 313.137296 -89.598246) (xy 313.14136 -89.605612) (xy 313.146672 -89.614292) (xy 313.162659 -89.626853)
			(xy 313.182279 -89.632185) (xy 313.192414 -89.631266) (xy 313.205368 -89.629488) (xy 313.205622 -89.629488)
			(xy 313.21883 -89.62771) (xy 313.236864 -89.62517) (xy 313.248802 -89.62136) (xy 313.254218 -89.618696)
			(xy 313.263712 -89.611247) (xy 313.267598 -89.606628) (xy 313.269884 -89.60358) (xy 313.2709 -89.602056)
			(xy 313.27344 -89.597484) (xy 313.28995 -89.57183) (xy 313.295969 -89.563337) (xy 313.308803 -89.546945)
			(xy 313.315604 -89.539064) (xy 313.316874 -89.53754) (xy 313.317382 -89.537032) (xy 313.321192 -89.531952)
			(xy 313.326018 -89.522046) (xy 313.510676 -88.59139) (xy 313.50839 -88.585802) (xy 313.502294 -88.574626)
			(xy 313.494739 -88.559957) (xy 313.481895 -88.529561) (xy 313.47664 -88.51392) (xy 313.47664 -88.513412)
			(xy 313.47283 -88.501474) (xy 313.471814 -88.497918) (xy 313.470544 -88.492838) (xy 313.464708 -88.469136)
			(xy 313.458462 -88.420725) (xy 313.458098 -88.396318) (xy 313.458098 -88.391238) (xy 313.46013 -88.355424)
			(xy 313.462162 -88.338357) (xy 313.468906 -88.304651) (xy 313.473592 -88.288114) (xy 313.477148 -88.276938)
			(xy 313.477656 -88.274906) (xy 313.47791 -88.274144) (xy 313.483498 -88.257888) (xy 313.48553 -88.252808)
			(xy 313.49061 -88.241632) (xy 313.491118 -88.240616) (xy 313.506104 -88.21039) (xy 313.511544 -88.20083)
			(xy 313.523363 -88.182278) (xy 313.529726 -88.173306) (xy 313.529726 -88.172798) (xy 313.538362 -88.161622)
			(xy 313.551369 -88.145338) (xy 313.580386 -88.115419) (xy 313.596274 -88.101932) (xy 313.603132 -88.096344)
			(xy 313.603386 -88.09609) (xy 313.60745 -88.089232) (xy 313.609658 -88.085438) (xy 313.612853 -88.077262)
			(xy 313.6138 -88.072976) (xy 313.804808 -87.110062) (xy 315.641736 -77.84973) (xy 315.643348 -77.839292)
			(xy 315.638896 -77.818671) (xy 315.626472 -77.801621) (xy 315.617606 -77.795882) (xy 315.605855 -77.789513)
			(xy 315.580063 -77.782534) (xy 315.553344 -77.78248) (xy 315.527524 -77.789356) (xy 315.50437 -77.802691)
			(xy 315.49467 -77.811884) (xy 314.60948 -78.697074) (xy 314.585566 -78.720234) (xy 314.532767 -78.760781)
			(xy 314.475131 -78.794096) (xy 314.413642 -78.819609) (xy 314.349351 -78.836884) (xy 314.283355 -78.845628)
			(xy 314.25007 -78.846172) (xy 313.249056 -78.846172) (xy 313.239091 -78.846653) (xy 313.220659 -78.854232)
			(xy 313.213242 -78.860904) (xy 312.53303 -79.541116) (xy 312.529982 -79.544164) (xy 312.528966 -79.54518)
			(xy 312.528204 -79.545942) (xy 312.527442 -79.546704) (xy 312.52668 -79.547466) (xy 312.526172 -79.547974)
			(xy 312.514234 -79.55915) (xy 312.506868 -79.565754) (xy 312.492644 -79.595472) (xy 312.48985 -79.604108)
			(xy 312.489088 -79.609188) (xy 312.486548 -79.675736) (xy 312.486548 -79.677768) (xy 312.486789 -79.684951)
			(xy 312.490778 -79.698752) (xy 312.494422 -79.704946) (xy 312.49747 -79.709772) (xy 312.507122 -79.719424)
			(xy 312.514234 -79.72679) (xy 312.517282 -79.730346) (xy 312.517536 -79.7306) (xy 312.533132 -79.74911)
			(xy 312.560006 -79.789367) (xy 312.57113 -79.810864) (xy 312.571892 -79.812134) (xy 312.579258 -79.826866)
			(xy 312.581544 -79.832454) (xy 312.584846 -79.841852) (xy 312.585354 -79.842868) (xy 312.596276 -79.874364)
			(xy 312.596276 -79.874618) (xy 312.598054 -79.880968) (xy 312.604213 -79.905015) (xy 312.610962 -79.954195)
			(xy 312.611516 -79.979012) (xy 312.611516 -79.987648) (xy 312.610655 -80.014638) (xy 312.602263 -80.067982)
			(xy 312.586431 -80.119609) (xy 312.563478 -80.168487) (xy 312.53386 -80.21364) (xy 312.498171 -80.254164)
			(xy 312.457123 -80.28925) (xy 312.411537 -80.318197) (xy 312.362325 -80.340426) (xy 312.31047 -80.355492)
			(xy 312.257008 -80.363094) (xy 312.230008 -80.363568) (xy 312.202882 -80.363092) (xy 312.149176 -80.355408)
			(xy 312.0971 -80.340195) (xy 312.047704 -80.31776) (xy 312.001984 -80.288553) (xy 311.960861 -80.253165)
			(xy 311.925166 -80.21231) (xy 311.895617 -80.16681) (xy 311.872812 -80.117583) (xy 311.857208 -80.065623)
			(xy 311.849122 -80.011976) (xy 311.8485 -79.984854) (xy 311.8485 -79.981552) (xy 311.848909 -79.95661)
			(xy 311.855417 -79.907153) (xy 311.868315 -79.858966) (xy 311.877456 -79.835756) (xy 311.879234 -79.831438)
			(xy 311.881266 -79.82204) (xy 311.883552 -79.812134) (xy 311.881774 -79.80172) (xy 311.879996 -79.790544)
			(xy 311.854596 -79.753206) (xy 311.827418 -79.71282) (xy 311.819938 -79.702841) (xy 311.797962 -79.691112)
			(xy 311.785508 -79.690468) (xy 311.262014 -79.690468) (xy 311.253731 -79.690783) (xy 311.23804 -79.696088)
			(xy 311.23128 -79.700882) (xy 311.228994 -79.702914) (xy 311.227216 -79.704692) (xy 311.223406 -79.707994)
			(xy 310.395242 -80.536158) (xy 312.596911 -80.536158) (xy 312.596911 -80.481642) (xy 312.60467 -80.427682)
			(xy 312.62003 -80.375375) (xy 312.642678 -80.325786) (xy 312.672153 -80.279926) (xy 312.707854 -80.238728)
			(xy 312.749056 -80.20303) (xy 312.79492 -80.173559) (xy 312.84451 -80.150916) (xy 312.896819 -80.135562)
			(xy 312.95078 -80.127808) (xy 312.978038 -80.127348) (xy 313.007945 -80.127911) (xy 313.067022 -80.137263)
			(xy 313.123918 -80.155715) (xy 313.177239 -80.182817) (xy 313.22568 -80.217905) (xy 313.247278 -80.2386)
			(xy 313.247532 -80.238854) (xy 313.255016 -80.24551) (xy 313.273591 -80.25295) (xy 313.2836 -80.253332)
			(xy 313.356244 -80.252824) (xy 313.366174 -80.252292) (xy 313.384476 -80.244562) (xy 313.391804 -80.237838)
			(xy 313.392312 -80.23733) (xy 313.410339 -80.219421) (xy 313.450281 -80.188011) (xy 313.494039 -80.16218)
			(xy 313.540838 -80.142387) (xy 313.589851 -80.12898) (xy 313.64021 -80.122198) (xy 313.665616 -80.12176)
			(xy 313.692864 -80.122311) (xy 313.746806 -80.130069) (xy 313.799094 -80.145424) (xy 313.848665 -80.168064)
			(xy 313.894509 -80.197529) (xy 313.935694 -80.233217) (xy 313.971381 -80.274403) (xy 314.000843 -80.320249)
			(xy 314.023481 -80.369821) (xy 314.038834 -80.42211) (xy 314.04659 -80.476052) (xy 314.04659 -80.530548)
			(xy 314.038834 -80.58449) (xy 314.036281 -80.593184) (xy 314.144404 -80.593184) (xy 314.148475 -80.537562)
			(xy 314.160601 -80.483125) (xy 314.180524 -80.431034) (xy 314.20782 -80.382399) (xy 314.241906 -80.338256)
			(xy 314.282055 -80.299547) (xy 314.327413 -80.267096) (xy 314.377013 -80.241595) (xy 314.429797 -80.223588)
			(xy 314.48464 -80.213458) (xy 314.540374 -80.211421) (xy 314.595811 -80.217521) (xy 314.649768 -80.231627)
			(xy 314.701097 -80.253439) (xy 314.748703 -80.282493) (xy 314.791571 -80.318168) (xy 314.828788 -80.359705)
			(xy 314.859561 -80.406218) (xy 314.883233 -80.456715) (xy 314.899301 -80.510122) (xy 314.907421 -80.565298)
			(xy 314.90793 -80.593184) (xy 314.907421 -80.62107) (xy 314.899301 -80.676246) (xy 314.883233 -80.729653)
			(xy 314.859561 -80.78015) (xy 314.828788 -80.826663) (xy 314.791571 -80.8682) (xy 314.748703 -80.903875)
			(xy 314.701097 -80.932929) (xy 314.649768 -80.954741) (xy 314.595811 -80.968847) (xy 314.540374 -80.974947)
			(xy 314.48464 -80.97291) (xy 314.429797 -80.96278) (xy 314.377013 -80.944773) (xy 314.327413 -80.919272)
			(xy 314.282055 -80.886821) (xy 314.241906 -80.848112) (xy 314.20782 -80.803969) (xy 314.180524 -80.755334)
			(xy 314.160601 -80.703243) (xy 314.148475 -80.648806) (xy 314.144404 -80.593184) (xy 314.036281 -80.593184)
			(xy 314.023481 -80.636779) (xy 314.000843 -80.686351) (xy 313.971381 -80.732197) (xy 313.935694 -80.773383)
			(xy 313.894509 -80.809071) (xy 313.848665 -80.838536) (xy 313.799094 -80.861176) (xy 313.746806 -80.876531)
			(xy 313.692864 -80.884289) (xy 313.665616 -80.884776) (xy 313.635711 -80.884172) (xy 313.576635 -80.874829)
			(xy 313.51974 -80.856386) (xy 313.466418 -80.829293) (xy 313.417975 -80.794215) (xy 313.396376 -80.773524)
			(xy 313.396122 -80.77327) (xy 313.388617 -80.766642) (xy 313.370058 -80.759185) (xy 313.360054 -80.758792)
			(xy 313.28741 -80.7593) (xy 313.277483 -80.759853) (xy 313.25918 -80.767568) (xy 313.25185 -80.774286)
			(xy 313.251342 -80.774794) (xy 313.233341 -80.79273) (xy 313.193393 -80.824136) (xy 313.149629 -80.849963)
			(xy 313.102825 -80.869752) (xy 313.053808 -80.883153) (xy 313.003446 -80.889929) (xy 312.978038 -80.890364)
			(xy 312.95078 -80.889992) (xy 312.896819 -80.882238) (xy 312.84451 -80.866884) (xy 312.79492 -80.844241)
			(xy 312.749056 -80.81477) (xy 312.707854 -80.779072) (xy 312.672153 -80.737874) (xy 312.642678 -80.692014)
			(xy 312.62003 -80.642425) (xy 312.60467 -80.590118) (xy 312.596911 -80.536158) (xy 310.395242 -80.536158)
			(xy 308.517036 -82.414364) (xy 309.681624 -82.414364) (xy 309.685695 -82.358742) (xy 309.697821 -82.304305)
			(xy 309.717744 -82.252214) (xy 309.74504 -82.203579) (xy 309.779126 -82.159436) (xy 309.819275 -82.120727)
			(xy 309.864633 -82.088276) (xy 309.914233 -82.062775) (xy 309.967017 -82.044768) (xy 310.02186 -82.034638)
			(xy 310.077594 -82.032601) (xy 310.133031 -82.038701) (xy 310.186988 -82.052807) (xy 310.238317 -82.074619)
			(xy 310.285923 -82.103673) (xy 310.328791 -82.139348) (xy 310.366008 -82.180885) (xy 310.396781 -82.227398)
			(xy 310.420453 -82.277895) (xy 310.436521 -82.331302) (xy 310.444641 -82.386478) (xy 310.44515 -82.414364)
			(xy 310.444909 -82.427572) (xy 311.132726 -82.427572) (xy 311.136797 -82.37195) (xy 311.148923 -82.317513)
			(xy 311.168846 -82.265422) (xy 311.196142 -82.216787) (xy 311.230228 -82.172644) (xy 311.270377 -82.133935)
			(xy 311.315735 -82.101484) (xy 311.365335 -82.075983) (xy 311.418119 -82.057976) (xy 311.472962 -82.047846)
			(xy 311.528696 -82.045809) (xy 311.584133 -82.051909) (xy 311.63809 -82.066015) (xy 311.689419 -82.087827)
			(xy 311.737025 -82.116881) (xy 311.779893 -82.152556) (xy 311.81711 -82.194093) (xy 311.847883 -82.240606)
			(xy 311.871555 -82.291103) (xy 311.887623 -82.34451) (xy 311.895743 -82.399686) (xy 311.896252 -82.427572)
			(xy 311.896104 -82.4357) (xy 312.01817 -82.4357) (xy 312.022241 -82.380078) (xy 312.034367 -82.325641)
			(xy 312.05429 -82.27355) (xy 312.081586 -82.224915) (xy 312.115672 -82.180772) (xy 312.155821 -82.142063)
			(xy 312.201179 -82.109612) (xy 312.250779 -82.084111) (xy 312.303563 -82.066104) (xy 312.358406 -82.055974)
			(xy 312.41414 -82.053937) (xy 312.469577 -82.060037) (xy 312.523534 -82.074143) (xy 312.574863 -82.095955)
			(xy 312.622469 -82.125009) (xy 312.665337 -82.160684) (xy 312.702554 -82.202221) (xy 312.733327 -82.248734)
			(xy 312.756999 -82.299231) (xy 312.773067 -82.352638) (xy 312.781187 -82.407814) (xy 312.781696 -82.4357)
			(xy 312.781187 -82.463586) (xy 312.773067 -82.518762) (xy 312.756999 -82.572169) (xy 312.733327 -82.622666)
			(xy 312.702554 -82.669179) (xy 312.665337 -82.710716) (xy 312.622469 -82.746391) (xy 312.574863 -82.775445)
			(xy 312.523534 -82.797257) (xy 312.469577 -82.811363) (xy 312.41414 -82.817463) (xy 312.358406 -82.815426)
			(xy 312.303563 -82.805296) (xy 312.250779 -82.787289) (xy 312.201179 -82.761788) (xy 312.155821 -82.729337)
			(xy 312.115672 -82.690628) (xy 312.081586 -82.646485) (xy 312.05429 -82.59785) (xy 312.034367 -82.545759)
			(xy 312.022241 -82.491322) (xy 312.01817 -82.4357) (xy 311.896104 -82.4357) (xy 311.895743 -82.455458)
			(xy 311.887623 -82.510634) (xy 311.871555 -82.564041) (xy 311.847883 -82.614538) (xy 311.81711 -82.661051)
			(xy 311.779893 -82.702588) (xy 311.737025 -82.738263) (xy 311.689419 -82.767317) (xy 311.63809 -82.789129)
			(xy 311.584133 -82.803235) (xy 311.528696 -82.809335) (xy 311.472962 -82.807298) (xy 311.418119 -82.797168)
			(xy 311.365335 -82.779161) (xy 311.315735 -82.75366) (xy 311.270377 -82.721209) (xy 311.230228 -82.6825)
			(xy 311.196142 -82.638357) (xy 311.168846 -82.589722) (xy 311.148923 -82.537631) (xy 311.136797 -82.483194)
			(xy 311.132726 -82.427572) (xy 310.444909 -82.427572) (xy 310.444641 -82.44225) (xy 310.436521 -82.497426)
			(xy 310.420453 -82.550833) (xy 310.396781 -82.60133) (xy 310.366008 -82.647843) (xy 310.328791 -82.68938)
			(xy 310.285923 -82.725055) (xy 310.238317 -82.754109) (xy 310.186988 -82.775921) (xy 310.133031 -82.790027)
			(xy 310.077594 -82.796127) (xy 310.02186 -82.79409) (xy 309.967017 -82.78396) (xy 309.914233 -82.765953)
			(xy 309.864633 -82.740452) (xy 309.819275 -82.708001) (xy 309.779126 -82.669292) (xy 309.74504 -82.625149)
			(xy 309.717744 -82.576514) (xy 309.697821 -82.524423) (xy 309.685695 -82.469986) (xy 309.681624 -82.414364)
			(xy 308.517036 -82.414364) (xy 307.284628 -83.646772) (xy 307.281101 -83.650499) (xy 307.275461 -83.659069)
			(xy 307.273452 -83.66379) (xy 307.269896 -83.672426) (xy 307.269896 -84.092288) (xy 308.425086 -84.092288)
			(xy 308.429157 -84.036666) (xy 308.441283 -83.982229) (xy 308.461206 -83.930138) (xy 308.488502 -83.881503)
			(xy 308.522588 -83.83736) (xy 308.562737 -83.798651) (xy 308.608095 -83.7662) (xy 308.657695 -83.740699)
			(xy 308.710479 -83.722692) (xy 308.765322 -83.712562) (xy 308.821056 -83.710525) (xy 308.876493 -83.716625)
			(xy 308.93045 -83.730731) (xy 308.981779 -83.752543) (xy 309.029385 -83.781597) (xy 309.072253 -83.817272)
			(xy 309.10947 -83.858809) (xy 309.140243 -83.905322) (xy 309.163915 -83.955819) (xy 309.179983 -84.009226)
			(xy 309.188103 -84.064402) (xy 309.188612 -84.092288) (xy 309.188103 -84.120174) (xy 309.179983 -84.17535)
			(xy 309.163915 -84.228757) (xy 309.140243 -84.279254) (xy 309.10947 -84.325767) (xy 309.072253 -84.367304)
			(xy 309.029385 -84.402979) (xy 308.981779 -84.432033) (xy 308.93045 -84.453845) (xy 308.876493 -84.467951)
			(xy 308.821056 -84.474051) (xy 308.765322 -84.472014) (xy 308.710479 -84.461884) (xy 308.657695 -84.443877)
			(xy 308.608095 -84.418376) (xy 308.562737 -84.385925) (xy 308.522588 -84.347216) (xy 308.488502 -84.303073)
			(xy 308.461206 -84.254438) (xy 308.441283 -84.202347) (xy 308.429157 -84.14791) (xy 308.425086 -84.092288)
			(xy 307.269896 -84.092288) (xy 307.269896 -84.476336) (xy 311.895234 -84.476336) (xy 311.899305 -84.420714)
			(xy 311.911431 -84.366277) (xy 311.931354 -84.314186) (xy 311.95865 -84.265551) (xy 311.992736 -84.221408)
			(xy 312.032885 -84.182699) (xy 312.078243 -84.150248) (xy 312.127843 -84.124747) (xy 312.180627 -84.10674)
			(xy 312.23547 -84.09661) (xy 312.291204 -84.094573) (xy 312.346641 -84.100673) (xy 312.400598 -84.114779)
			(xy 312.451927 -84.136591) (xy 312.499533 -84.165645) (xy 312.542401 -84.20132) (xy 312.579618 -84.242857)
			(xy 312.610391 -84.28937) (xy 312.634063 -84.339867) (xy 312.650131 -84.393274) (xy 312.658251 -84.44845)
			(xy 312.65876 -84.476336) (xy 312.658251 -84.504222) (xy 312.650131 -84.559398) (xy 312.634063 -84.612805)
			(xy 312.610391 -84.663302) (xy 312.579618 -84.709815) (xy 312.542401 -84.751352) (xy 312.499533 -84.787027)
			(xy 312.451927 -84.816081) (xy 312.400598 -84.837893) (xy 312.346641 -84.851999) (xy 312.291204 -84.858099)
			(xy 312.23547 -84.856062) (xy 312.180627 -84.845932) (xy 312.127843 -84.827925) (xy 312.078243 -84.802424)
			(xy 312.032885 -84.769973) (xy 311.992736 -84.731264) (xy 311.95865 -84.687121) (xy 311.931354 -84.638486)
			(xy 311.911431 -84.586395) (xy 311.899305 -84.531958) (xy 311.895234 -84.476336) (xy 307.269896 -84.476336)
			(xy 307.269896 -86.247986) (xy 307.43855 -86.247986) (xy 307.442621 -86.192364) (xy 307.454747 -86.137927)
			(xy 307.47467 -86.085836) (xy 307.501966 -86.037201) (xy 307.536052 -85.993058) (xy 307.576201 -85.954349)
			(xy 307.621559 -85.921898) (xy 307.671159 -85.896397) (xy 307.723943 -85.87839) (xy 307.778786 -85.86826)
			(xy 307.83452 -85.866223) (xy 307.889957 -85.872323) (xy 307.943914 -85.886429) (xy 307.995243 -85.908241)
			(xy 308.042849 -85.937295) (xy 308.085717 -85.97297) (xy 308.122934 -86.014507) (xy 308.153707 -86.06102)
			(xy 308.177379 -86.111517) (xy 308.193447 -86.164924) (xy 308.201567 -86.2201) (xy 308.202076 -86.247986)
			(xy 308.201567 -86.275872) (xy 308.193447 -86.331048) (xy 308.177379 -86.384455) (xy 308.153707 -86.434952)
			(xy 308.122934 -86.481465) (xy 308.085717 -86.523002) (xy 308.042849 -86.558677) (xy 307.995243 -86.587731)
			(xy 307.943914 -86.609543) (xy 307.889957 -86.623649) (xy 307.83452 -86.629749) (xy 307.778786 -86.627712)
			(xy 307.723943 -86.617582) (xy 307.671159 -86.599575) (xy 307.621559 -86.574074) (xy 307.576201 -86.541623)
			(xy 307.536052 -86.502914) (xy 307.501966 -86.458771) (xy 307.47467 -86.410136) (xy 307.454747 -86.358045)
			(xy 307.442621 -86.303608) (xy 307.43855 -86.247986) (xy 307.269896 -86.247986) (xy 307.269896 -88.375998)
			(xy 312.02325 -88.375998) (xy 312.027321 -88.320376) (xy 312.039447 -88.265939) (xy 312.05937 -88.213848)
			(xy 312.086666 -88.165213) (xy 312.120752 -88.12107) (xy 312.160901 -88.082361) (xy 312.206259 -88.04991)
			(xy 312.255859 -88.024409) (xy 312.308643 -88.006402) (xy 312.363486 -87.996272) (xy 312.41922 -87.994235)
			(xy 312.474657 -88.000335) (xy 312.528614 -88.014441) (xy 312.579943 -88.036253) (xy 312.627549 -88.065307)
			(xy 312.670417 -88.100982) (xy 312.707634 -88.142519) (xy 312.738407 -88.189032) (xy 312.762079 -88.239529)
			(xy 312.778147 -88.292936) (xy 312.786267 -88.348112) (xy 312.786776 -88.375998) (xy 312.786267 -88.403884)
			(xy 312.778147 -88.45906) (xy 312.762079 -88.512467) (xy 312.738407 -88.562964) (xy 312.707634 -88.609477)
			(xy 312.670417 -88.651014) (xy 312.627549 -88.686689) (xy 312.579943 -88.715743) (xy 312.528614 -88.737555)
			(xy 312.474657 -88.751661) (xy 312.41922 -88.757761) (xy 312.363486 -88.755724) (xy 312.308643 -88.745594)
			(xy 312.255859 -88.727587) (xy 312.206259 -88.702086) (xy 312.160901 -88.669635) (xy 312.120752 -88.630926)
			(xy 312.086666 -88.586783) (xy 312.05937 -88.538148) (xy 312.039447 -88.486057) (xy 312.027321 -88.43162)
			(xy 312.02325 -88.375998) (xy 307.269896 -88.375998) (xy 307.269896 -92.76588) (xy 307.270658 -92.774008)
			(xy 307.270658 -92.774516) (xy 307.272255 -92.782037) (xy 307.279224 -92.795732) (xy 307.284374 -92.80144)
			(xy 308.443884 -93.96095) (xy 308.78094 -93.96095) (xy 308.785011 -93.905328) (xy 308.797137 -93.850891)
			(xy 308.81706 -93.7988) (xy 308.844356 -93.750165) (xy 308.878442 -93.706022) (xy 308.918591 -93.667313)
			(xy 308.963949 -93.634862) (xy 309.013549 -93.609361) (xy 309.066333 -93.591354) (xy 309.121176 -93.581224)
			(xy 309.17691 -93.579187) (xy 309.232347 -93.585287) (xy 309.286304 -93.599393) (xy 309.337633 -93.621205)
			(xy 309.385239 -93.650259) (xy 309.428107 -93.685934) (xy 309.465324 -93.727471) (xy 309.496097 -93.773984)
			(xy 309.519769 -93.824481) (xy 309.535837 -93.877888) (xy 309.543957 -93.933064) (xy 309.544466 -93.96095)
			(xy 309.543957 -93.988836) (xy 309.535837 -94.044012) (xy 309.519769 -94.097419) (xy 309.496097 -94.147916)
			(xy 309.465324 -94.194429) (xy 309.428107 -94.235966) (xy 309.385239 -94.271641) (xy 309.337633 -94.300695)
			(xy 309.286304 -94.322507) (xy 309.232347 -94.336613) (xy 309.17691 -94.342713) (xy 309.121176 -94.340676)
			(xy 309.066333 -94.330546) (xy 309.013549 -94.312539) (xy 308.963949 -94.287038) (xy 308.918591 -94.254587)
			(xy 308.878442 -94.215878) (xy 308.844356 -94.171735) (xy 308.81706 -94.1231) (xy 308.797137 -94.071009)
			(xy 308.785011 -94.016572) (xy 308.78094 -93.96095) (xy 308.443884 -93.96095) (xy 309.404004 -94.92107)
			(xy 309.409685 -94.926259) (xy 309.423392 -94.933232) (xy 309.430928 -94.934786) (xy 309.431436 -94.934786)
			(xy 309.439564 -94.935548) (xy 310.206136 -94.935548) (xy 310.239424 -94.936084) (xy 310.305425 -94.944807)
			(xy 310.369723 -94.962073) (xy 310.431216 -94.987586) (xy 310.488852 -95.020909) (xy 310.541644 -95.061472)
			(xy 310.565546 -95.084646) (xy 310.644794 -95.163894) (xy 311.110884 -95.630238) (xy 311.134046 -95.654139)
			(xy 311.17456 -95.706946) (xy 311.207832 -95.76459) (xy 311.233293 -95.826085) (xy 311.250506 -95.890379)
			(xy 311.259177 -95.956369) (xy 311.259728 -95.989648) (xy 311.259728 -97.005648) (xy 311.259227 -97.037593)
			(xy 311.251219 -97.100979) (xy 311.23533 -97.162862) (xy 311.211811 -97.222266) (xy 311.181031 -97.278253)
			(xy 311.143478 -97.329942) (xy 311.099742 -97.376516) (xy 311.050514 -97.417241) (xy 310.996569 -97.451475)
			(xy 310.93876 -97.478678) (xy 310.877997 -97.498421) (xy 310.815238 -97.510393) (xy 310.751474 -97.514405)
			(xy 310.68771 -97.510393) (xy 310.624951 -97.498421) (xy 310.564188 -97.478678) (xy 310.506379 -97.451475)
			(xy 310.452434 -97.417241) (xy 310.403206 -97.376516) (xy 310.35947 -97.329942) (xy 310.321917 -97.278253)
			(xy 310.291137 -97.222266) (xy 310.267618 -97.162862) (xy 310.251729 -97.100979) (xy 310.243721 -97.037593)
			(xy 310.24322 -97.005648) (xy 310.24322 -96.221296) (xy 310.242712 -96.214946) (xy 310.241672 -96.20821)
			(xy 310.236524 -96.195593) (xy 310.232552 -96.190054) (xy 310.228996 -96.186498) (xy 310.22671 -96.183958)
			(xy 310.010048 -95.967296) (xy 310.006316 -95.963776) (xy 309.99774 -95.958152) (xy 309.99303 -95.95612)
			(xy 309.984394 -95.952564) (xy 309.207662 -95.952564) (xy 309.174375 -95.952027) (xy 309.108375 -95.943302)
			(xy 309.044079 -95.926034) (xy 308.982589 -95.900518) (xy 308.924957 -95.867191) (xy 308.872171 -95.826623)
			(xy 308.848252 -95.803466) (xy 306.401978 -93.357192) (xy 306.37882 -93.333278) (xy 306.338279 -93.280478)
			(xy 306.30497 -93.222841) (xy 306.279465 -93.161351) (xy 306.262198 -93.09706) (xy 306.253466 -93.031066)
			(xy 306.25288 -92.997782) (xy 306.25288 -83.450684) (xy 306.253416 -83.417396) (xy 306.262137 -83.351394)
			(xy 306.279401 -83.287095) (xy 306.304913 -83.225601) (xy 306.338237 -83.167965) (xy 306.3788 -83.115173)
			(xy 306.401978 -83.091274) (xy 310.670702 -78.82255) (xy 310.694617 -78.799393) (xy 310.747417 -78.758853)
			(xy 310.805055 -78.725546) (xy 310.866544 -78.700041) (xy 310.930834 -78.682775) (xy 310.996828 -78.674042)
			(xy 311.030112 -78.673452) (xy 311.941464 -78.673452) (xy 311.951338 -78.672985) (xy 311.96963 -78.665536)
			(xy 311.977024 -78.658974) (xy 312.657744 -77.978254) (xy 312.681658 -77.955094) (xy 312.734457 -77.914548)
			(xy 312.792093 -77.881234) (xy 312.853582 -77.855722) (xy 312.917874 -77.838448) (xy 312.983869 -77.829707)
			(xy 313.017154 -77.829156) (xy 314.018168 -77.829156) (xy 314.026296 -77.828394) (xy 314.026804 -77.828394)
			(xy 314.034324 -77.826796) (xy 314.048017 -77.819825) (xy 314.053728 -77.814678) (xy 314.757816 -77.11059)
			(xy 314.76061 -77.10678) (xy 314.760864 -77.106272) (xy 314.762388 -77.10424) (xy 314.762896 -77.103732)
			(xy 314.765944 -77.100176) (xy 314.766452 -77.099668) (xy 314.76696 -77.098652) (xy 314.770008 -77.093064)
			(xy 314.771786 -77.086714) (xy 314.771786 -77.085952) (xy 314.779526 -77.056137) (xy 314.801254 -76.998497)
			(xy 314.829783 -76.943901) (xy 314.864696 -76.89315) (xy 314.905481 -76.846987) (xy 314.951542 -76.806085)
			(xy 315.002205 -76.771045) (xy 315.056729 -76.742379) (xy 315.114314 -76.720506) (xy 315.17412 -76.705747)
			(xy 315.23527 -76.698317) (xy 315.26607 -76.69784) (xy 315.29707 -76.698306) (xy 315.358608 -76.705855)
			(xy 315.418771 -76.720832) (xy 315.476666 -76.743014) (xy 315.531434 -76.772073) (xy 315.582261 -76.807577)
			(xy 315.628393 -76.848999) (xy 315.669145 -76.895723) (xy 315.686948 -76.921106) (xy 315.688726 -76.923646)
			(xy 315.692994 -76.928868) (xy 315.703674 -76.937096) (xy 315.709808 -76.939902) (xy 315.716412 -76.942442)
			(xy 315.723778 -76.943204) (xy 315.729874 -76.943458) (xy 315.739272 -76.942442) (xy 315.761116 -76.93787)
			(xy 315.761624 -76.93787) (xy 315.792358 -76.93152) (xy 315.801066 -76.929395) (xy 315.816314 -76.919991)
			(xy 315.827376 -76.905901) (xy 315.830458 -76.897484) (xy 315.831474 -76.893928) (xy 317.175642 -70.118986)
			(xy 318.570864 -63.08598) (xy 318.571118 -63.083948) (xy 318.572352 -63.072368) (xy 318.565454 -63.050151)
			(xy 318.55791 -63.041276) (xy 318.548004 -63.033148) (xy 318.53886 -63.027306) (xy 318.523112 -63.017146)
			(xy 318.516 -63.01359) (xy 318.508033 -63.011023) (xy 318.491311 -63.010634) (xy 318.483234 -63.012828)
			(xy 318.480694 -63.01359) (xy 318.465454 -63.019178) (xy 318.46012 -63.02248) (xy 318.436378 -63.037859)
			(xy 318.38532 -63.062208) (xy 318.331233 -63.078773) (xy 318.275296 -63.087193) (xy 318.247014 -63.087758)
			(xy 318.232536 -63.087504) (xy 318.21882 -63.086488) (xy 318.190365 -63.083871) (xy 318.134647 -63.0712)
			(xy 318.081441 -63.050361) (xy 318.031938 -63.02182) (xy 317.987245 -62.986216) (xy 317.948361 -62.944346)
			(xy 317.916156 -62.897145) (xy 317.89135 -62.845668) (xy 317.874499 -62.791069) (xy 317.865978 -62.734567)
			(xy 317.865506 -62.705996) (xy 317.86597 -62.679148) (xy 317.87351 -62.625985) (xy 317.888426 -62.574403)
			(xy 317.910425 -62.52542) (xy 317.939071 -62.480005) (xy 317.973799 -62.439052) (xy 318.013925 -62.40337)
			(xy 318.058655 -62.373664) (xy 318.107107 -62.350521) (xy 318.158324 -62.334396) (xy 318.211295 -62.325609)
			(xy 318.238124 -62.324488) (xy 318.247776 -62.324488) (xy 318.268848 -62.324794) (xy 318.310729 -62.3295)
			(xy 318.331342 -62.333886) (xy 318.33185 -62.333886) (xy 318.33947 -62.335664) (xy 318.342772 -62.336426)
			(xy 318.347852 -62.336934) (xy 318.34836 -62.336934) (xy 318.357189 -62.337439) (xy 318.374332 -62.333149)
			(xy 318.381888 -62.328552) (xy 318.388492 -62.323218) (xy 318.449706 -62.252098) (xy 318.457036 -62.242706)
			(xy 318.462889 -62.219643) (xy 318.460882 -62.207902) (xy 318.458342 -62.198504) (xy 318.458342 -62.19825)
			(xy 318.457326 -62.196218) (xy 318.448394 -62.173271) (xy 318.435839 -62.125656) (xy 318.429515 -62.076821)
			(xy 318.429132 -62.0522) (xy 318.429132 -62.051438) (xy 318.430402 -62.021212) (xy 318.43091 -62.017148)
			(xy 318.43091 -62.016132) (xy 318.434012 -61.988118) (xy 318.447411 -61.933372) (xy 318.468721 -61.881194)
			(xy 318.497477 -61.83272) (xy 318.533054 -61.789006) (xy 318.574676 -61.751003) (xy 318.621438 -61.719539)
			(xy 318.67232 -61.695299) (xy 318.726216 -61.678811) (xy 318.781952 -61.670434) (xy 318.810132 -61.66993)
			(xy 318.810386 -61.66993) (xy 318.821875 -61.669344) (xy 318.842521 -61.659251) (xy 318.856703 -61.641168)
			(xy 318.859662 -61.630052) (xy 318.873124 -61.56198) (xy 319.01257 -60.859416) (xy 319.013586 -60.850272)
			(xy 319.016126 -60.680346) (xy 319.015872 -60.677806) (xy 319.014668 -60.666733) (xy 319.013396 -60.644494)
			(xy 319.013332 -60.633356) (xy 319.013332 -60.626752) (xy 319.014602 -60.601352) (xy 319.014856 -60.59932)
			(xy 319.014856 -60.597796) (xy 319.01511 -60.595256) (xy 319.01638 -60.584334) (xy 319.01638 -60.583826)
			(xy 319.017904 -60.57392) (xy 319.019428 -60.480956) (xy 319.048384 -58.623962) (xy 319.046098 -58.614056)
			(xy 319.043558 -58.608468) (xy 319.032634 -58.583445) (xy 319.017243 -58.53106) (xy 319.009467 -58.477018)
			(xy 319.009014 -58.449718) (xy 319.009014 -58.414412) (xy 319.009083 -58.410404) (xy 319.01036 -58.402491)
			(xy 319.011554 -58.398664) (xy 319.013332 -58.393076) (xy 319.014094 -58.388758) (xy 319.019159 -58.360753)
			(xy 319.036506 -58.306552) (xy 319.048638 -58.280808) (xy 319.048638 -58.280554) (xy 319.050776 -58.276053)
			(xy 319.053466 -58.266461) (xy 319.053972 -58.261504) (xy 319.189608 -49.568608) (xy 319.189354 -49.564798)
			(xy 319.1891 -49.56302) (xy 317.86195 -39.7383) (xy 317.858169 -39.708655) (xy 317.853721 -39.649052)
			(xy 317.85306 -39.619174) (xy 317.852806 -39.605712) (xy 317.852298 -39.569898) (xy 317.851536 -39.523162)
			(xy 317.851028 -39.516558) (xy 317.765684 -38.931342) (xy 317.760871 -38.895852) (xy 317.755784 -38.824407)
			(xy 317.755524 -38.788594) (xy 317.755524 -38.498526) (xy 317.754508 -38.487858) (xy 317.753746 -38.485572)
			(xy 317.743076 -38.44497) (xy 317.727785 -38.362418) (xy 317.719487 -38.278873) (xy 317.71844 -38.236906)
			(xy 317.711074 -37.741352) (xy 317.711074 -37.741098) (xy 317.71082 -37.726874) (xy 317.71082 -37.726366)
			(xy 317.711226 -37.687828) (xy 317.717254 -37.610986) (xy 317.729202 -37.53484) (xy 317.737744 -37.497258)
			(xy 317.753238 -37.439346) (xy 317.755524 -37.431472) (xy 317.755524 -37.425122) (xy 317.754762 -37.41674)
			(xy 317.754508 -37.41547) (xy 317.75273 -37.407342) (xy 317.750444 -37.4015) (xy 317.734219 -37.363724)
			(xy 317.707359 -37.286014) (xy 317.687044 -37.206342) (xy 317.673413 -37.125258) (xy 317.666561 -37.043323)
			(xy 317.666116 -37.002212) (xy 317.666116 -36.995862) (xy 317.664846 -36.988496) (xy 317.663385 -36.981157)
			(xy 317.656801 -36.967728) (xy 317.651892 -36.96208) (xy 317.60541 -36.912296) (xy 317.59652 -36.908232)
			(xy 317.571374 -36.896294) (xy 317.567056 -36.89604) (xy 317.56223 -36.895532) (xy 317.534101 -36.892517)
			(xy 317.479108 -36.879244) (xy 317.426678 -36.857996) (xy 317.377961 -36.829239) (xy 317.334023 -36.793603)
			(xy 317.29583 -36.751871) (xy 317.264217 -36.704956) (xy 317.239879 -36.653887) (xy 317.223348 -36.599784)
			(xy 317.214988 -36.543834) (xy 317.214504 -36.515548) (xy 317.215016 -36.48698) (xy 317.223542 -36.430484)
			(xy 317.240395 -36.375891) (xy 317.2652 -36.324421) (xy 317.297401 -36.277223) (xy 317.336279 -36.235355)
			(xy 317.380965 -36.19975) (xy 317.430459 -36.171206) (xy 317.483656 -36.150359) (xy 317.539366 -36.137677)
			(xy 317.567818 -36.135056) (xy 317.576708 -36.134294) (xy 317.593472 -36.126928) (xy 317.600838 -36.123626)
			(xy 317.605043 -36.121652) (xy 317.612712 -36.116413) (xy 317.616078 -36.113212) (xy 317.621666 -36.107624)
			(xy 317.627725 -36.100964) (xy 317.635138 -36.084568) (xy 317.636144 -36.07562) (xy 317.63589 -36.050982)
			(xy 317.631572 -36.045902) (xy 317.622682 -36.03752) (xy 317.613538 -36.028884) (xy 317.603886 -36.022534)
			(xy 317.590424 -36.016692) (xy 317.580518 -36.016692) (xy 317.578232 -36.016692) (xy 317.577978 -36.016692)
			(xy 317.550728 -36.016204) (xy 317.496784 -36.008445) (xy 317.444493 -35.993088) (xy 317.394919 -35.970445)
			(xy 317.349073 -35.940978) (xy 317.307887 -35.905286) (xy 317.272199 -35.864097) (xy 317.242736 -35.818247)
			(xy 317.220099 -35.768672) (xy 317.204747 -35.716379) (xy 317.196993 -35.662434) (xy 317.19647 -35.635184)
			(xy 317.19647 -35.633152) (xy 317.19662 -35.615074) (xy 317.199929 -35.579072) (xy 317.203074 -35.56127)
			(xy 317.203836 -35.557714) (xy 317.204598 -35.542728) (xy 317.205106 -35.533076) (xy 317.205106 -35.530536)
			(xy 317.204315 -35.520483) (xy 317.195925 -35.502163) (xy 317.18885 -35.494976) (xy 317.166244 -35.489388)
			(xy 317.127861 -35.479306) (xy 317.052696 -35.453828) (xy 316.979796 -35.422452) (xy 316.909623 -35.385374)
			(xy 316.875922 -35.36442) (xy 316.874906 -35.364674) (xy 316.868048 -35.365944) (xy 316.853683 -35.368366)
			(xy 316.824695 -35.371288) (xy 316.810136 -35.371786) (xy 316.799214 -35.371786) (xy 316.772033 -35.371199)
			(xy 316.718247 -35.363271) (xy 316.666132 -35.347787) (xy 316.616743 -35.325061) (xy 316.57108 -35.295554)
			(xy 316.530069 -35.259863) (xy 316.49454 -35.218712) (xy 316.465214 -35.172933) (xy 316.442684 -35.123454)
			(xy 316.427406 -35.071278) (xy 316.419691 -35.017461) (xy 316.41923 -34.990278) (xy 316.41923 -34.989008)
			(xy 316.419706 -34.964279) (xy 316.426265 -34.915254) (xy 316.439105 -34.867489) (xy 316.448186 -34.844482)
			(xy 316.449964 -34.840164) (xy 316.456568 -34.824162) (xy 316.457838 -34.818574) (xy 316.453266 -34.802826)
			(xy 316.440769 -34.758474) (xy 316.423058 -34.668039) (xy 316.413775 -34.576355) (xy 316.41288 -34.530284)
			(xy 316.41288 -34.519108) (xy 316.413456 -34.477575) (xy 316.420657 -34.394817) (xy 316.434712 -34.312944)
			(xy 316.455523 -34.232522) (xy 316.482945 -34.154108) (xy 316.499494 -34.11601) (xy 316.502542 -34.106358)
			(xy 316.506098 -34.091118) (xy 316.506098 -34.090102) (xy 316.502542 -34.074862) (xy 316.499494 -34.06521)
			(xy 316.482814 -34.026807) (xy 316.455204 -33.947757) (xy 316.434325 -33.866669) (xy 316.420322 -33.784115)
			(xy 316.413296 -33.700677) (xy 316.41288 -33.65881) (xy 316.41288 -33.658302) (xy 316.41309 -33.629662)
			(xy 316.416393 -33.572476) (xy 316.419484 -33.544002) (xy 316.424202 -33.506546) (xy 316.438566 -33.432425)
			(xy 316.448186 -33.39592) (xy 316.455806 -33.369758) (xy 316.458092 -33.362392) (xy 316.457584 -33.360106)
			(xy 316.455552 -33.354772) (xy 316.444087 -33.329267) (xy 316.427912 -33.27574) (xy 316.419725 -33.220425)
			(xy 316.41923 -33.192466) (xy 316.41923 -33.19145) (xy 316.41923 -33.19018) (xy 316.419695 -33.162929)
			(xy 316.427454 -33.108982) (xy 316.442812 -33.056689) (xy 316.465457 -33.007114) (xy 316.494926 -32.961266)
			(xy 316.53062 -32.920079) (xy 316.571812 -32.884391) (xy 316.617665 -32.854929) (xy 316.667243 -32.832292)
			(xy 316.719539 -32.816942) (xy 316.773487 -32.809191) (xy 316.800738 -32.808672) (xy 316.800992 -32.808672)
			(xy 316.815463 -32.808786) (xy 316.844324 -32.810947) (xy 316.85865 -32.81299) (xy 316.867469 -32.813981)
			(xy 316.884876 -32.8106) (xy 316.892686 -32.806386) (xy 316.931726 -32.783272) (xy 317.01323 -32.743399)
			(xy 317.098016 -32.711089) (xy 317.185385 -32.68661) (xy 317.274616 -32.670163) (xy 317.364971 -32.661885)
			(xy 317.410338 -32.661352) (xy 317.410592 -32.661352) (xy 317.455931 -32.661882) (xy 317.546232 -32.670143)
			(xy 317.635411 -32.68656) (xy 317.722734 -32.710998) (xy 317.80748 -32.743257) (xy 317.888951 -32.78307)
			(xy 317.92799 -32.806132) (xy 317.935714 -32.810401) (xy 317.952996 -32.813918) (xy 317.961772 -32.81299)
			(xy 317.976478 -32.810909) (xy 318.006102 -32.808746) (xy 318.020954 -32.808672) (xy 318.021716 -32.808672)
			(xy 318.052175 -32.809409) (xy 318.112281 -32.819359) (xy 318.14135 -32.828484) (xy 318.152018 -32.83204)
			(xy 318.163702 -32.831024) (xy 318.170649 -32.83011) (xy 318.183673 -32.82496) (xy 318.189356 -32.820864)
			(xy 318.211962 -32.804608) (xy 318.255904 -32.773112) (xy 318.259279 -32.770386) (xy 318.265154 -32.764003)
			(xy 318.267588 -32.760412) (xy 318.267842 -32.760158) (xy 318.267334 -32.741108) (xy 318.267334 -32.737806)
			(xy 318.26708 -32.722566) (xy 318.26708 -32.708596) (xy 318.268053 -32.66811) (xy 318.275754 -32.587486)
			(xy 318.289974 -32.507752) (xy 318.310621 -32.429437) (xy 318.337557 -32.353056) (xy 318.353694 -32.315912)
			(xy 318.356742 -32.30626) (xy 318.360298 -32.29102) (xy 318.360298 -32.290004) (xy 318.356742 -32.274764)
			(xy 318.353694 -32.265112) (xy 318.337556 -32.22797) (xy 318.31064 -32.151583) (xy 318.290003 -32.073266)
			(xy 318.275781 -31.993535) (xy 318.268067 -31.912913) (xy 318.26708 -31.872428) (xy 318.26708 -31.858458)
			(xy 318.267334 -31.843218) (xy 318.267334 -31.840424) (xy 318.267842 -31.821628) (xy 318.265368 -31.817674)
			(xy 318.259228 -31.810652) (xy 318.25565 -31.807658) (xy 318.210438 -31.774638) (xy 318.20993 -31.774638)
			(xy 318.190626 -31.760668) (xy 318.185164 -31.757158) (xy 318.172945 -31.752779) (xy 318.166496 -31.752032)
			(xy 318.165988 -31.752032) (xy 318.161924 -31.751778) (xy 318.142366 -31.751778) (xy 318.134746 -31.754064)
			(xy 318.107137 -31.762245) (xy 318.05025 -31.771172) (xy 318.021462 -31.771844) (xy 318.01943 -31.771844)
			(xy 318.003155 -31.771665) (xy 317.970724 -31.768872) (xy 317.95466 -31.766256) (xy 317.944754 -31.764478)
			(xy 317.904769 -31.789199) (xy 317.820994 -31.831866) (xy 317.733576 -31.866463) (xy 317.643293 -31.892684)
			(xy 317.550942 -31.910296) (xy 317.457345 -31.919143) (xy 317.410338 -31.919672) (xy 317.364928 -31.919166)
			(xy 317.274482 -31.91093) (xy 317.18516 -31.894504) (xy 317.097702 -31.870024) (xy 317.012831 -31.837693)
			(xy 316.931252 -31.797779) (xy 316.892178 -31.774638) (xy 316.891924 -31.774638) (xy 316.885976 -31.771279)
			(xy 316.872841 -31.76755) (xy 316.866016 -31.767272) (xy 316.859666 -31.767272) (xy 316.85611 -31.76778)
			(xy 316.855094 -31.768034) (xy 316.853062 -31.768288) (xy 316.852808 -31.768288) (xy 316.849506 -31.768796)
			(xy 316.836806 -31.77032) (xy 316.836552 -31.77032) (xy 316.806834 -31.771844) (xy 316.800738 -31.771844)
			(xy 316.773482 -31.771384) (xy 316.719525 -31.763631) (xy 316.667221 -31.748279) (xy 316.617634 -31.725639)
			(xy 316.571773 -31.696173) (xy 316.530573 -31.66048) (xy 316.494872 -31.619286) (xy 316.465396 -31.573431)
			(xy 316.442747 -31.523849) (xy 316.427384 -31.471547) (xy 316.419622 -31.417592) (xy 316.41923 -31.390336)
			(xy 316.41923 -31.389066) (xy 316.419702 -31.364336) (xy 316.426254 -31.315309) (xy 316.439088 -31.26754)
			(xy 316.448186 -31.24454) (xy 316.449964 -31.240222) (xy 316.456568 -31.22422) (xy 316.457838 -31.218632)
			(xy 316.453266 -31.202884) (xy 316.440536 -31.157586) (xy 316.422651 -31.065204) (xy 316.41354 -30.971547)
			(xy 316.41288 -30.9245) (xy 316.41288 -30.91561) (xy 316.41348 -30.878397) (xy 316.419539 -30.804211)
			(xy 316.431117 -30.730684) (xy 316.439296 -30.694376) (xy 316.450662 -30.648428) (xy 316.480938 -30.558741)
			(xy 316.499748 -30.515306) (xy 316.501526 -30.511242) (xy 316.506098 -30.491176) (xy 316.506098 -30.49016)
			(xy 316.501526 -30.470094) (xy 316.499748 -30.46603) (xy 316.48302 -30.42756) (xy 316.45533 -30.348367)
			(xy 316.434391 -30.267127) (xy 316.420354 -30.184415) (xy 316.413315 -30.100815) (xy 316.41288 -30.058868)
			(xy 316.413336 -30.015527) (xy 316.420841 -29.929172) (xy 316.427866 -29.886402) (xy 316.432029 -29.863662)
			(xy 316.442193 -29.818559) (xy 316.448186 -29.796232) (xy 316.448186 -29.795724) (xy 316.455298 -29.772102)
			(xy 316.455298 -29.771594) (xy 316.458092 -29.76245) (xy 316.457584 -29.760672) (xy 316.456314 -29.755084)
			(xy 316.444609 -29.729287) (xy 316.428089 -29.675101) (xy 316.419749 -29.61907) (xy 316.41923 -29.590746)
			(xy 316.41923 -29.590238) (xy 316.419691 -29.562984) (xy 316.427444 -29.509031) (xy 316.442797 -29.456731)
			(xy 316.465438 -29.407149) (xy 316.494905 -29.361293) (xy 316.530599 -29.320099) (xy 316.571793 -29.284405)
			(xy 316.617649 -29.254938) (xy 316.667231 -29.232297) (xy 316.719531 -29.216944) (xy 316.773484 -29.209191)
			(xy 316.800738 -29.20873) (xy 316.800992 -29.20873) (xy 316.819785 -29.208965) (xy 316.85719 -29.212657)
			(xy 316.875668 -29.216096) (xy 316.875922 -29.216096) (xy 316.876684 -29.21635) (xy 316.916607 -29.191711)
			(xy 317.00024 -29.149188) (xy 317.087495 -29.114707) (xy 317.177603 -29.08857) (xy 317.269767 -29.071009)
			(xy 317.363173 -29.06218) (xy 317.410084 -29.061664) (xy 317.410592 -29.061664) (xy 317.457475 -29.062204)
			(xy 317.550826 -29.071009) (xy 317.642939 -29.088533) (xy 317.733002 -29.11462) (xy 317.820221 -29.149042)
			(xy 317.903826 -29.191494) (xy 317.943738 -29.216096) (xy 317.943992 -29.216096) (xy 317.9445 -29.215842)
			(xy 317.950088 -29.214826) (xy 317.967336 -29.211897) (xy 318.00219 -29.208844) (xy 318.019684 -29.20873)
			(xy 318.020192 -29.20873) (xy 318.049831 -29.20929) (xy 318.108391 -29.218478) (xy 318.136778 -29.227018)
			(xy 318.141858 -29.228796) (xy 318.145668 -29.230066) (xy 318.152216 -29.231448) (xy 318.165592 -29.231186)
			(xy 318.172084 -29.229558) (xy 318.183006 -29.225748) (xy 318.255396 -29.172916) (xy 318.259006 -29.170121)
			(xy 318.265267 -29.163478) (xy 318.267842 -29.159708) (xy 318.267334 -29.13761) (xy 318.267334 -29.137356)
			(xy 318.26708 -29.122624) (xy 318.26708 -29.108654) (xy 318.268051 -29.068167) (xy 318.275747 -28.987542)
			(xy 318.289963 -28.907807) (xy 318.310606 -28.829489) (xy 318.337538 -28.753106) (xy 318.353694 -28.71597)
			(xy 318.356742 -28.706318) (xy 318.360298 -28.691078) (xy 318.360298 -28.690062) (xy 318.355726 -28.669996)
			(xy 318.353948 -28.665932) (xy 318.33722 -28.627462) (xy 318.309529 -28.548269) (xy 318.288591 -28.467029)
			(xy 318.274553 -28.384317) (xy 318.267515 -28.300717) (xy 318.26708 -28.25877) (xy 318.267536 -28.215429)
			(xy 318.275041 -28.129074) (xy 318.282066 -28.086304) (xy 318.286224 -28.0635) (xy 318.296387 -28.01827)
			(xy 318.302386 -27.99588) (xy 318.310006 -27.969718) (xy 318.312292 -27.962352) (xy 318.311784 -27.960066)
			(xy 318.309244 -27.953462) (xy 318.308482 -27.951938) (xy 318.297372 -27.926654) (xy 318.28173 -27.873689)
			(xy 318.273878 -27.819024) (xy 318.27343 -27.79141) (xy 318.27343 -27.79014) (xy 318.273891 -27.762886)
			(xy 318.281643 -27.708933) (xy 318.296996 -27.656633) (xy 318.319637 -27.60705) (xy 318.349104 -27.561194)
			(xy 318.384799 -27.52) (xy 318.425993 -27.484306) (xy 318.471848 -27.454838) (xy 318.521431 -27.432197)
			(xy 318.573731 -27.416844) (xy 318.627684 -27.409091) (xy 318.654938 -27.408632) (xy 318.671663 -27.408812)
			(xy 318.704985 -27.411737) (xy 318.721486 -27.414474) (xy 318.731138 -27.415998) (xy 318.782954 -27.385264)
			(xy 318.783462 -27.385264) (xy 318.795908 -27.378152) (xy 318.799718 -27.368754) (xy 318.81953 -27.295348)
			(xy 318.819276 -27.281632) (xy 318.817498 -27.275028) (xy 318.81318 -27.259534) (xy 318.810132 -27.2542)
			(xy 318.798438 -27.232663) (xy 318.780022 -27.187249) (xy 318.767563 -27.139852) (xy 318.761266 -27.091251)
			(xy 318.760856 -27.066748) (xy 318.760856 -27.057604) (xy 318.76111 -27.05354) (xy 318.76111 -27.052778)
			(xy 318.763396 -27.022552) (xy 318.766501 -26.998918) (xy 318.777849 -26.952621) (xy 318.794896 -26.908105)
			(xy 318.805814 -26.886916) (xy 318.818644 -26.8638) (xy 318.849716 -26.821025) (xy 318.886397 -26.782951)
			(xy 318.906906 -26.766266) (xy 318.908938 -26.764742) (xy 318.91605 -26.757884) (xy 318.929004 -26.742136)
			(xy 318.931544 -26.736802) (xy 318.934084 -26.725118) (xy 318.93002 -26.647394) (xy 318.929512 -26.634948)
			(xy 318.911224 -26.603452) (xy 318.906652 -26.59888) (xy 318.895476 -26.58745) (xy 318.889126 -26.583132)
			(xy 318.867229 -26.567857) (xy 318.827523 -26.532168) (xy 318.793177 -26.491295) (xy 318.76486 -26.446035)
			(xy 318.743124 -26.397272) (xy 318.728394 -26.345956) (xy 318.720957 -26.293088) (xy 318.72047 -26.266394)
			(xy 318.720956 -26.239143) (xy 318.728712 -26.185195) (xy 318.744067 -26.1329) (xy 318.766709 -26.083323)
			(xy 318.796175 -26.037473) (xy 318.831866 -25.996282) (xy 318.873057 -25.960591) (xy 318.918907 -25.931125)
			(xy 318.968484 -25.908483) (xy 319.020779 -25.893128) (xy 319.074727 -25.885372) (xy 319.129229 -25.885372)
			(xy 319.183177 -25.893128) (xy 319.235472 -25.908483) (xy 319.285049 -25.931125) (xy 319.330899 -25.960591)
			(xy 319.37209 -25.996282) (xy 319.407781 -26.037473) (xy 319.437247 -26.083323) (xy 319.459889 -26.1329)
			(xy 319.475244 -26.185195) (xy 319.483 -26.239143) (xy 319.483486 -26.266394) (xy 319.482934 -26.295552)
			(xy 319.474062 -26.353188) (xy 319.456523 -26.408804) (xy 319.430727 -26.461104) (xy 319.397273 -26.508869)
			(xy 319.356942 -26.550988) (xy 319.334134 -26.569162) (xy 319.33134 -26.571194) (xy 319.324736 -26.577798)
			(xy 319.320164 -26.58364) (xy 319.316091 -26.589981) (xy 319.311439 -26.604309) (xy 319.31102 -26.611834)
			(xy 319.31483 -26.69667) (xy 319.319656 -26.706068) (xy 319.320672 -26.708354) (xy 319.329562 -26.72334)
			(xy 319.333118 -26.729182) (xy 319.348866 -26.745438) (xy 319.355216 -26.749756) (xy 319.377074 -26.764969)
			(xy 319.416721 -26.800524) (xy 319.451033 -26.841251) (xy 319.479343 -26.886358) (xy 319.501098 -26.934966)
			(xy 319.515876 -26.98613) (xy 319.523388 -27.038852) (xy 319.523872 -27.065478) (xy 319.523872 -27.07005)
			(xy 319.523077 -27.09985) (xy 319.513379 -27.158665) (xy 319.504568 -27.187144) (xy 319.503044 -27.191716)
			(xy 319.501774 -27.201876) (xy 319.501523 -27.206164) (xy 319.502295 -27.214717) (xy 319.503298 -27.218894)
			(xy 319.503298 -27.219402) (xy 319.505838 -27.226768) (xy 319.534032 -27.283156) (xy 319.536277 -27.287441)
			(xy 319.542157 -27.29512) (xy 319.545716 -27.298396) (xy 319.551812 -27.303476) (xy 319.55994 -27.30627)
			(xy 319.563496 -27.307286) (xy 319.56375 -27.307286) (xy 319.603462 -27.320245) (xy 319.658595 -27.342846)
			(xy 326.723248 -27.342846) (xy 326.723248 -26.479246) (xy 326.723738 -26.449262) (xy 326.731566 -26.389806)
			(xy 326.747087 -26.331881) (xy 326.770036 -26.276477) (xy 326.80002 -26.224543) (xy 326.836526 -26.176967)
			(xy 326.878931 -26.134562) (xy 326.926507 -26.098056) (xy 326.978441 -26.068072) (xy 327.033845 -26.045123)
			(xy 327.09177 -26.029602) (xy 327.151226 -26.021774) (xy 327.211194 -26.021774) (xy 327.27065 -26.029602)
			(xy 327.328575 -26.045123) (xy 327.383979 -26.068072) (xy 327.435913 -26.098056) (xy 327.483489 -26.134562)
			(xy 327.525894 -26.176967) (xy 327.5624 -26.224543) (xy 327.592384 -26.276477) (xy 327.615333 -26.331881)
			(xy 327.623104 -26.360882) (xy 329.289408 -26.360882) (xy 329.293479 -26.30526) (xy 329.305605 -26.250823)
			(xy 329.325528 -26.198732) (xy 329.352824 -26.150097) (xy 329.38691 -26.105954) (xy 329.427059 -26.067245)
			(xy 329.472417 -26.034794) (xy 329.522017 -26.009293) (xy 329.574801 -25.991286) (xy 329.629644 -25.981156)
			(xy 329.685378 -25.979119) (xy 329.740815 -25.985219) (xy 329.794772 -25.999325) (xy 329.846101 -26.021137)
			(xy 329.893707 -26.050191) (xy 329.936575 -26.085866) (xy 329.973792 -26.127403) (xy 330.004565 -26.173916)
			(xy 330.028237 -26.224413) (xy 330.044305 -26.27782) (xy 330.050473 -26.319734) (xy 335.041746 -26.319734)
			(xy 335.045817 -26.264112) (xy 335.057943 -26.209675) (xy 335.077866 -26.157584) (xy 335.105162 -26.108949)
			(xy 335.139248 -26.064806) (xy 335.179397 -26.026097) (xy 335.224755 -25.993646) (xy 335.274355 -25.968145)
			(xy 335.327139 -25.950138) (xy 335.381982 -25.940008) (xy 335.437716 -25.937971) (xy 335.493153 -25.944071)
			(xy 335.54711 -25.958177) (xy 335.598439 -25.979989) (xy 335.646045 -26.009043) (xy 335.67571 -26.03373)
			(xy 353.567998 -26.03373) (xy 353.572069 -25.978108) (xy 353.584195 -25.923671) (xy 353.604118 -25.87158)
			(xy 353.631414 -25.822945) (xy 353.6655 -25.778802) (xy 353.705649 -25.740093) (xy 353.751007 -25.707642)
			(xy 353.800607 -25.682141) (xy 353.853391 -25.664134) (xy 353.908234 -25.654004) (xy 353.963968 -25.651967)
			(xy 354.019405 -25.658067) (xy 354.073362 -25.672173) (xy 354.124691 -25.693985) (xy 354.172297 -25.723039)
			(xy 354.215165 -25.758714) (xy 354.252382 -25.800251) (xy 354.283155 -25.846764) (xy 354.306827 -25.897261)
			(xy 354.322895 -25.950668) (xy 354.331015 -26.005844) (xy 354.331524 -26.03373) (xy 354.331015 -26.061616)
			(xy 354.322895 -26.116792) (xy 354.306827 -26.170199) (xy 354.283155 -26.220696) (xy 354.252382 -26.267209)
			(xy 354.215165 -26.308746) (xy 354.172297 -26.344421) (xy 354.124691 -26.373475) (xy 354.073362 -26.395287)
			(xy 354.019405 -26.409393) (xy 353.963968 -26.415493) (xy 353.908234 -26.413456) (xy 353.853391 -26.403326)
			(xy 353.800607 -26.385319) (xy 353.751007 -26.359818) (xy 353.705649 -26.327367) (xy 353.6655 -26.288658)
			(xy 353.631414 -26.244515) (xy 353.604118 -26.19588) (xy 353.584195 -26.143789) (xy 353.572069 -26.089352)
			(xy 353.567998 -26.03373) (xy 335.67571 -26.03373) (xy 335.688913 -26.044718) (xy 335.72613 -26.086255)
			(xy 335.756903 -26.132768) (xy 335.780575 -26.183265) (xy 335.796643 -26.236672) (xy 335.804763 -26.291848)
			(xy 335.805272 -26.319734) (xy 335.804763 -26.34762) (xy 335.796643 -26.402796) (xy 335.780575 -26.456203)
			(xy 335.756903 -26.5067) (xy 335.72613 -26.553213) (xy 335.688913 -26.59475) (xy 335.646045 -26.630425)
			(xy 335.598439 -26.659479) (xy 335.54711 -26.681291) (xy 335.493153 -26.695397) (xy 335.437716 -26.701497)
			(xy 335.381982 -26.69946) (xy 335.327139 -26.68933) (xy 335.274355 -26.671323) (xy 335.224755 -26.645822)
			(xy 335.179397 -26.613371) (xy 335.139248 -26.574662) (xy 335.105162 -26.530519) (xy 335.077866 -26.481884)
			(xy 335.057943 -26.429793) (xy 335.045817 -26.375356) (xy 335.041746 -26.319734) (xy 330.050473 -26.319734)
			(xy 330.052425 -26.332996) (xy 330.052934 -26.360882) (xy 330.052425 -26.388768) (xy 330.044305 -26.443944)
			(xy 330.028237 -26.497351) (xy 330.004565 -26.547848) (xy 329.973792 -26.594361) (xy 329.936575 -26.635898)
			(xy 329.893707 -26.671573) (xy 329.846101 -26.700627) (xy 329.794772 -26.722439) (xy 329.740815 -26.736545)
			(xy 329.685378 -26.742645) (xy 329.629644 -26.740608) (xy 329.574801 -26.730478) (xy 329.522017 -26.712471)
			(xy 329.472417 -26.68697) (xy 329.427059 -26.654519) (xy 329.38691 -26.61581) (xy 329.352824 -26.571667)
			(xy 329.325528 -26.523032) (xy 329.305605 -26.470941) (xy 329.293479 -26.416504) (xy 329.289408 -26.360882)
			(xy 327.623104 -26.360882) (xy 327.630854 -26.389806) (xy 327.638682 -26.449262) (xy 327.639172 -26.479246)
			(xy 327.639172 -26.971244) (xy 331.050898 -26.971244) (xy 331.054969 -26.915622) (xy 331.067095 -26.861185)
			(xy 331.087018 -26.809094) (xy 331.114314 -26.760459) (xy 331.1484 -26.716316) (xy 331.188549 -26.677607)
			(xy 331.233907 -26.645156) (xy 331.283507 -26.619655) (xy 331.336291 -26.601648) (xy 331.391134 -26.591518)
			(xy 331.446868 -26.589481) (xy 331.502305 -26.595581) (xy 331.556262 -26.609687) (xy 331.607591 -26.631499)
			(xy 331.655197 -26.660553) (xy 331.698065 -26.696228) (xy 331.735282 -26.737765) (xy 331.766055 -26.784278)
			(xy 331.789727 -26.834775) (xy 331.805795 -26.888182) (xy 331.813915 -26.943358) (xy 331.814424 -26.971244)
			(xy 331.813915 -26.99913) (xy 331.805795 -27.054306) (xy 331.789727 -27.107713) (xy 331.766055 -27.15821)
			(xy 331.735282 -27.204723) (xy 331.698065 -27.24626) (xy 331.655197 -27.281935) (xy 331.607591 -27.310989)
			(xy 331.556262 -27.332801) (xy 331.502305 -27.346907) (xy 331.446868 -27.353007) (xy 331.391134 -27.35097)
			(xy 331.336291 -27.34084) (xy 331.283507 -27.322833) (xy 331.233907 -27.297332) (xy 331.188549 -27.264881)
			(xy 331.1484 -27.226172) (xy 331.114314 -27.182029) (xy 331.087018 -27.133394) (xy 331.067095 -27.081303)
			(xy 331.054969 -27.026866) (xy 331.050898 -26.971244) (xy 327.639172 -26.971244) (xy 327.639172 -27.342846)
			(xy 327.638682 -27.37283) (xy 327.630854 -27.432286) (xy 327.615333 -27.490211) (xy 327.592384 -27.545615)
			(xy 327.5624 -27.597549) (xy 327.525894 -27.645125) (xy 327.483489 -27.68753) (xy 327.435913 -27.724036)
			(xy 327.383979 -27.75402) (xy 327.328575 -27.776969) (xy 327.27065 -27.79249) (xy 327.211194 -27.800318)
			(xy 327.151226 -27.800318) (xy 327.09177 -27.79249) (xy 327.033845 -27.776969) (xy 326.978441 -27.75402)
			(xy 326.926507 -27.724036) (xy 326.878931 -27.68753) (xy 326.836526 -27.645125) (xy 326.80002 -27.597549)
			(xy 326.770036 -27.545615) (xy 326.747087 -27.490211) (xy 326.731566 -27.432286) (xy 326.723738 -27.37283)
			(xy 326.723248 -27.342846) (xy 319.658595 -27.342846) (xy 319.680759 -27.351932) (xy 319.755132 -27.38998)
			(xy 319.790826 -27.41168) (xy 319.798954 -27.41168) (xy 319.802764 -27.411172) (xy 319.803018 -27.411172)
			(xy 319.81521 -27.409902) (xy 319.816734 -27.409902) (xy 319.82029 -27.409394) (xy 319.848738 -27.408378)
			(xy 319.868042 -27.408886) (xy 319.877694 -27.409648) (xy 319.906746 -27.412391) (xy 319.963586 -27.425587)
			(xy 320.01775 -27.447294) (xy 320.067973 -27.477003) (xy 320.11308 -27.51402) (xy 320.132964 -27.535378)
			(xy 320.133218 -27.535632) (xy 320.140762 -27.543142) (xy 320.160182 -27.551799) (xy 320.17081 -27.552396)
			(xy 320.210942 -27.552396) (xy 320.254461 -27.552855) (xy 320.341168 -27.560437) (xy 320.426883 -27.575549)
			(xy 320.510955 -27.598076) (xy 320.592743 -27.627845) (xy 320.671625 -27.664631) (xy 320.747 -27.708154)
			(xy 320.818294 -27.758081) (xy 320.884964 -27.814033) (xy 320.916046 -27.844496) (xy 322.185792 -29.114242)
			(xy 329.047348 -29.114242) (xy 329.047348 -28.250642) (xy 329.047838 -28.220674) (xy 329.055661 -28.161252)
			(xy 329.071174 -28.103359) (xy 329.09411 -28.047986) (xy 329.124077 -27.99608) (xy 329.160564 -27.94853)
			(xy 329.202944 -27.90615) (xy 329.250494 -27.869663) (xy 329.3024 -27.839696) (xy 329.357773 -27.81676)
			(xy 329.415666 -27.801247) (xy 329.475088 -27.793424) (xy 329.535024 -27.793424) (xy 329.594446 -27.801247)
			(xy 329.652339 -27.81676) (xy 329.707712 -27.839696) (xy 329.759618 -27.869663) (xy 329.807168 -27.90615)
			(xy 329.849548 -27.94853) (xy 329.886035 -27.99608) (xy 329.916002 -28.047986) (xy 329.938938 -28.103359)
			(xy 329.954451 -28.161252) (xy 329.962274 -28.220674) (xy 329.962764 -28.250642) (xy 329.962764 -28.469082)
			(xy 333.95234 -28.469082) (xy 333.956411 -28.41346) (xy 333.968537 -28.359023) (xy 333.98846 -28.306932)
			(xy 334.015756 -28.258297) (xy 334.049842 -28.214154) (xy 334.089991 -28.175445) (xy 334.135349 -28.142994)
			(xy 334.184949 -28.117493) (xy 334.237733 -28.099486) (xy 334.292576 -28.089356) (xy 334.34831 -28.087319)
			(xy 334.403747 -28.093419) (xy 334.457704 -28.107525) (xy 334.509033 -28.129337) (xy 334.525089 -28.139136)
			(xy 350.698052 -28.139136) (xy 350.702123 -28.083514) (xy 350.714249 -28.029077) (xy 350.734172 -27.976986)
			(xy 350.761468 -27.928351) (xy 350.795554 -27.884208) (xy 350.835703 -27.845499) (xy 350.881061 -27.813048)
			(xy 350.930661 -27.787547) (xy 350.983445 -27.76954) (xy 351.038288 -27.75941) (xy 351.094022 -27.757373)
			(xy 351.149459 -27.763473) (xy 351.203416 -27.777579) (xy 351.254745 -27.799391) (xy 351.302351 -27.828445)
			(xy 351.345219 -27.86412) (xy 351.382436 -27.905657) (xy 351.413209 -27.95217) (xy 351.436881 -28.002667)
			(xy 351.452949 -28.056074) (xy 351.461069 -28.11125) (xy 351.461578 -28.139136) (xy 351.968052 -28.139136)
			(xy 351.972123 -28.083514) (xy 351.984249 -28.029077) (xy 352.004172 -27.976986) (xy 352.031468 -27.928351)
			(xy 352.065554 -27.884208) (xy 352.105703 -27.845499) (xy 352.151061 -27.813048) (xy 352.200661 -27.787547)
			(xy 352.253445 -27.76954) (xy 352.308288 -27.75941) (xy 352.364022 -27.757373) (xy 352.419459 -27.763473)
			(xy 352.473416 -27.777579) (xy 352.524745 -27.799391) (xy 352.572351 -27.828445) (xy 352.615219 -27.86412)
			(xy 352.652436 -27.905657) (xy 352.683209 -27.95217) (xy 352.706881 -28.002667) (xy 352.722949 -28.056074)
			(xy 352.731069 -28.11125) (xy 352.731578 -28.139136) (xy 352.731069 -28.167022) (xy 352.722949 -28.222198)
			(xy 352.706881 -28.275605) (xy 352.683209 -28.326102) (xy 352.652436 -28.372615) (xy 352.615219 -28.414152)
			(xy 352.572351 -28.449827) (xy 352.524745 -28.478881) (xy 352.473416 -28.500693) (xy 352.419459 -28.514799)
			(xy 352.364022 -28.520899) (xy 352.308288 -28.518862) (xy 352.253445 -28.508732) (xy 352.200661 -28.490725)
			(xy 352.151061 -28.465224) (xy 352.105703 -28.432773) (xy 352.065554 -28.394064) (xy 352.031468 -28.349921)
			(xy 352.004172 -28.301286) (xy 351.984249 -28.249195) (xy 351.972123 -28.194758) (xy 351.968052 -28.139136)
			(xy 351.461578 -28.139136) (xy 351.461069 -28.167022) (xy 351.452949 -28.222198) (xy 351.436881 -28.275605)
			(xy 351.413209 -28.326102) (xy 351.382436 -28.372615) (xy 351.345219 -28.414152) (xy 351.302351 -28.449827)
			(xy 351.254745 -28.478881) (xy 351.203416 -28.500693) (xy 351.149459 -28.514799) (xy 351.094022 -28.520899)
			(xy 351.038288 -28.518862) (xy 350.983445 -28.508732) (xy 350.930661 -28.490725) (xy 350.881061 -28.465224)
			(xy 350.835703 -28.432773) (xy 350.795554 -28.394064) (xy 350.761468 -28.349921) (xy 350.734172 -28.301286)
			(xy 350.714249 -28.249195) (xy 350.702123 -28.194758) (xy 350.698052 -28.139136) (xy 334.525089 -28.139136)
			(xy 334.556639 -28.158391) (xy 334.599507 -28.194066) (xy 334.636724 -28.235603) (xy 334.667497 -28.282116)
			(xy 334.691169 -28.332613) (xy 334.707237 -28.38602) (xy 334.715357 -28.441196) (xy 334.715866 -28.469082)
			(xy 334.715357 -28.496968) (xy 334.707237 -28.552144) (xy 334.691169 -28.605551) (xy 334.667497 -28.656048)
			(xy 334.636724 -28.702561) (xy 334.599507 -28.744098) (xy 334.556639 -28.779773) (xy 334.509033 -28.808827)
			(xy 334.457704 -28.830639) (xy 334.403747 -28.844745) (xy 334.34831 -28.850845) (xy 334.292576 -28.848808)
			(xy 334.237733 -28.838678) (xy 334.184949 -28.820671) (xy 334.135349 -28.79517) (xy 334.089991 -28.762719)
			(xy 334.049842 -28.72401) (xy 334.015756 -28.679867) (xy 333.98846 -28.631232) (xy 333.968537 -28.579141)
			(xy 333.956411 -28.524704) (xy 333.95234 -28.469082) (xy 329.962764 -28.469082) (xy 329.962764 -29.114242)
			(xy 329.962274 -29.14421) (xy 329.954451 -29.203632) (xy 329.938938 -29.261525) (xy 329.916002 -29.316898)
			(xy 329.886035 -29.368804) (xy 329.849548 -29.416354) (xy 329.807168 -29.458734) (xy 329.759618 -29.495221)
			(xy 329.707712 -29.525188) (xy 329.652339 -29.548124) (xy 329.594446 -29.563637) (xy 329.535024 -29.57146)
			(xy 329.475088 -29.57146) (xy 329.415666 -29.563637) (xy 329.357773 -29.548124) (xy 329.3024 -29.525188)
			(xy 329.250494 -29.495221) (xy 329.202944 -29.458734) (xy 329.160564 -29.416354) (xy 329.124077 -29.368804)
			(xy 329.09411 -29.316898) (xy 329.071174 -29.261525) (xy 329.055661 -29.203632) (xy 329.047838 -29.14421)
			(xy 329.047348 -29.114242) (xy 322.185792 -29.114242) (xy 323.456808 -30.385258) (xy 323.4905 -30.419751)
			(xy 323.551782 -30.494201) (xy 323.605591 -30.57422) (xy 323.651426 -30.659058) (xy 323.670676 -30.703266)
			(xy 323.762457 -30.92069) (xy 331.689456 -30.92069) (xy 331.689456 -30.05709) (xy 331.689946 -30.027122)
			(xy 331.697769 -29.9677) (xy 331.713282 -29.909807) (xy 331.736218 -29.854434) (xy 331.766185 -29.802528)
			(xy 331.802672 -29.754978) (xy 331.845052 -29.712598) (xy 331.892602 -29.676111) (xy 331.944508 -29.646144)
			(xy 331.999881 -29.623208) (xy 332.057774 -29.607695) (xy 332.117196 -29.599872) (xy 332.177132 -29.599872)
			(xy 332.236554 -29.607695) (xy 332.294447 -29.623208) (xy 332.34982 -29.646144) (xy 332.401726 -29.676111)
			(xy 332.449276 -29.712598) (xy 332.491656 -29.754978) (xy 332.528143 -29.802528) (xy 332.55811 -29.854434)
			(xy 332.581046 -29.909807) (xy 332.596559 -29.9677) (xy 332.604382 -30.027122) (xy 332.604872 -30.05709)
			(xy 332.604872 -30.376876) (xy 349.18904 -30.376876) (xy 349.189598 -30.34796) (xy 349.198317 -30.29079)
			(xy 349.215566 -30.235592) (xy 349.24095 -30.18363) (xy 349.273887 -30.136095) (xy 349.313623 -30.094077)
			(xy 349.336106 -30.075886) (xy 349.344911 -30.068276) (xy 349.355095 -30.047378) (xy 349.355664 -30.035754)
			(xy 349.355664 -29.955998) (xy 349.355124 -29.944366) (xy 349.344937 -29.923456) (xy 349.336106 -29.915866)
			(xy 349.313607 -29.897693) (xy 349.273873 -29.855669) (xy 349.240936 -29.808131) (xy 349.21555 -29.756166)
			(xy 349.198297 -29.700965) (xy 349.189572 -29.643793) (xy 349.18904 -29.614876) (xy 349.189526 -29.587625)
			(xy 349.197282 -29.533677) (xy 349.212637 -29.481382) (xy 349.235279 -29.431805) (xy 349.264745 -29.385955)
			(xy 349.300436 -29.344764) (xy 349.341627 -29.309073) (xy 349.387477 -29.279607) (xy 349.437054 -29.256965)
			(xy 349.489349 -29.24161) (xy 349.543297 -29.233854) (xy 349.597799 -29.233854) (xy 349.651747 -29.24161)
			(xy 349.704042 -29.256965) (xy 349.753619 -29.279607) (xy 349.799469 -29.309073) (xy 349.84066 -29.344764)
			(xy 349.876351 -29.385955) (xy 349.905817 -29.431805) (xy 349.928459 -29.481382) (xy 349.943814 -29.533677)
			(xy 349.95157 -29.587625) (xy 349.952056 -29.614876) (xy 349.951537 -29.643793) (xy 349.942811 -29.700965)
			(xy 349.925554 -29.756165) (xy 349.900162 -29.808127) (xy 349.867218 -29.85566) (xy 349.827476 -29.897677)
			(xy 349.80499 -29.915866) (xy 349.796207 -29.923496) (xy 349.78601 -29.944379) (xy 349.785432 -29.955998)
			(xy 349.785432 -30.035754) (xy 349.785943 -30.04739) (xy 349.796151 -30.068299) (xy 349.80499 -30.075886)
			(xy 349.827465 -30.094087) (xy 349.867201 -30.136105) (xy 349.900141 -30.183637) (xy 349.925531 -30.235597)
			(xy 349.942789 -30.290792) (xy 349.95152 -30.347961) (xy 349.952056 -30.376876) (xy 352.229166 -30.376876)
			(xy 352.229714 -30.34796) (xy 352.238433 -30.290789) (xy 352.255684 -30.23559) (xy 352.28107 -30.183627)
			(xy 352.314009 -30.136093) (xy 352.353748 -30.094076) (xy 352.376232 -30.075886) (xy 352.385041 -30.068281)
			(xy 352.395222 -30.047378) (xy 352.39579 -30.035754) (xy 352.39579 -29.955998) (xy 352.395241 -29.944367)
			(xy 352.38506 -29.923457) (xy 352.376232 -29.915866) (xy 352.353739 -29.897686) (xy 352.314003 -29.855665)
			(xy 352.281064 -29.808128) (xy 352.255677 -29.756164) (xy 352.238423 -29.700964) (xy 352.229698 -29.643793)
			(xy 352.229166 -29.614876) (xy 352.229652 -29.587625) (xy 352.237408 -29.533677) (xy 352.252763 -29.481382)
			(xy 352.275405 -29.431805) (xy 352.304871 -29.385955) (xy 352.340562 -29.344764) (xy 352.381753 -29.309073)
			(xy 352.427603 -29.279607) (xy 352.47718 -29.256965) (xy 352.529475 -29.24161) (xy 352.583423 -29.233854)
			(xy 352.637925 -29.233854) (xy 352.691873 -29.24161) (xy 352.744168 -29.256965) (xy 352.793745 -29.279607)
			(xy 352.839595 -29.309073) (xy 352.880786 -29.344764) (xy 352.916477 -29.385955) (xy 352.945943 -29.431805)
			(xy 352.968585 -29.481382) (xy 352.98394 -29.533677) (xy 352.991696 -29.587625) (xy 352.992182 -29.614876)
			(xy 352.991653 -29.643793) (xy 352.982927 -29.700964) (xy 352.965672 -29.756163) (xy 352.940282 -29.808124)
			(xy 352.90734 -29.855659) (xy 352.867601 -29.897676) (xy 352.845116 -29.915866) (xy 352.83632 -29.923483)
			(xy 352.826134 -29.944377) (xy 352.825558 -29.955998) (xy 352.825558 -30.035754) (xy 352.82606 -30.047391)
			(xy 352.836273 -30.068302) (xy 352.845116 -30.075886) (xy 352.867596 -30.094081) (xy 352.907331 -30.1361)
			(xy 352.94027 -30.183635) (xy 352.965659 -30.235595) (xy 352.982916 -30.290792) (xy 352.991646 -30.34796)
			(xy 352.992182 -30.376876) (xy 352.991696 -30.404127) (xy 352.98394 -30.458075) (xy 352.968585 -30.51037)
			(xy 352.945943 -30.559947) (xy 352.916477 -30.605797) (xy 352.880786 -30.646988) (xy 352.839595 -30.682679)
			(xy 352.793745 -30.712145) (xy 352.744168 -30.734787) (xy 352.691873 -30.750142) (xy 352.637925 -30.757898)
			(xy 352.583423 -30.757898) (xy 352.529475 -30.750142) (xy 352.47718 -30.734787) (xy 352.427603 -30.712145)
			(xy 352.381753 -30.682679) (xy 352.340562 -30.646988) (xy 352.304871 -30.605797) (xy 352.275405 -30.559947)
			(xy 352.252763 -30.51037) (xy 352.237408 -30.458075) (xy 352.229652 -30.404127) (xy 352.229166 -30.376876)
			(xy 349.952056 -30.376876) (xy 349.95157 -30.404127) (xy 349.943814 -30.458075) (xy 349.928459 -30.51037)
			(xy 349.905817 -30.559947) (xy 349.876351 -30.605797) (xy 349.84066 -30.646988) (xy 349.799469 -30.682679)
			(xy 349.753619 -30.712145) (xy 349.704042 -30.734787) (xy 349.651747 -30.750142) (xy 349.597799 -30.757898)
			(xy 349.543297 -30.757898) (xy 349.489349 -30.750142) (xy 349.437054 -30.734787) (xy 349.387477 -30.712145)
			(xy 349.341627 -30.682679) (xy 349.300436 -30.646988) (xy 349.264745 -30.605797) (xy 349.235279 -30.559947)
			(xy 349.212637 -30.51037) (xy 349.197282 -30.458075) (xy 349.189526 -30.404127) (xy 349.18904 -30.376876)
			(xy 332.604872 -30.376876) (xy 332.604872 -30.92069) (xy 332.604382 -30.950658) (xy 332.596559 -31.01008)
			(xy 332.581046 -31.067973) (xy 332.55811 -31.123346) (xy 332.528143 -31.175252) (xy 332.491656 -31.222802)
			(xy 332.449276 -31.265182) (xy 332.401726 -31.301669) (xy 332.34982 -31.331636) (xy 332.294447 -31.354572)
			(xy 332.236554 -31.370085) (xy 332.177132 -31.377908) (xy 332.117196 -31.377908) (xy 332.057774 -31.370085)
			(xy 331.999881 -31.354572) (xy 331.944508 -31.331636) (xy 331.892602 -31.301669) (xy 331.845052 -31.265182)
			(xy 331.802672 -31.222802) (xy 331.766185 -31.175252) (xy 331.736218 -31.123346) (xy 331.713282 -31.067973)
			(xy 331.697769 -31.01008) (xy 331.689946 -30.950658) (xy 331.689456 -30.92069) (xy 323.762457 -30.92069)
			(xy 323.79666 -31.001716) (xy 323.7992 -31.005526) (xy 323.824911 -31.045428) (xy 323.869436 -31.129267)
			(xy 323.8881 -31.172912) (xy 324.526754 -32.714184) (xy 329.047348 -32.714184) (xy 329.047348 -31.850584)
			(xy 329.047838 -31.820616) (xy 329.055661 -31.761194) (xy 329.071174 -31.703301) (xy 329.09411 -31.647928)
			(xy 329.124077 -31.596022) (xy 329.160564 -31.548472) (xy 329.202944 -31.506092) (xy 329.250494 -31.469605)
			(xy 329.3024 -31.439638) (xy 329.357773 -31.416702) (xy 329.415666 -31.401189) (xy 329.475088 -31.393366)
			(xy 329.535024 -31.393366) (xy 329.594446 -31.401189) (xy 329.652339 -31.416702) (xy 329.707712 -31.439638)
			(xy 329.759618 -31.469605) (xy 329.807168 -31.506092) (xy 329.849548 -31.548472) (xy 329.864442 -31.567882)
			(xy 349.298766 -31.567882) (xy 349.302837 -31.51226) (xy 349.314963 -31.457823) (xy 349.334886 -31.405732)
			(xy 349.362182 -31.357097) (xy 349.396268 -31.312954) (xy 349.436417 -31.274245) (xy 349.481775 -31.241794)
			(xy 349.531375 -31.216293) (xy 349.584159 -31.198286) (xy 349.639002 -31.188156) (xy 349.694736 -31.186119)
			(xy 349.750173 -31.192219) (xy 349.80413 -31.206325) (xy 349.855459 -31.228137) (xy 349.903065 -31.257191)
			(xy 349.945933 -31.292866) (xy 349.98315 -31.334403) (xy 350.013923 -31.380916) (xy 350.037595 -31.431413)
			(xy 350.053663 -31.48482) (xy 350.061783 -31.539996) (xy 350.062292 -31.567882) (xy 350.061783 -31.595768)
			(xy 350.053663 -31.650944) (xy 350.037595 -31.704351) (xy 350.030603 -31.719266) (xy 350.58553 -31.719266)
			(xy 350.589601 -31.663644) (xy 350.601727 -31.609207) (xy 350.62165 -31.557116) (xy 350.648946 -31.508481)
			(xy 350.683032 -31.464338) (xy 350.723181 -31.425629) (xy 350.768539 -31.393178) (xy 350.818139 -31.367677)
			(xy 350.870923 -31.34967) (xy 350.925766 -31.33954) (xy 350.9815 -31.337503) (xy 351.036937 -31.343603)
			(xy 351.090894 -31.357709) (xy 351.142223 -31.379521) (xy 351.189829 -31.408575) (xy 351.232697 -31.44425)
			(xy 351.269914 -31.485787) (xy 351.300687 -31.5323) (xy 351.324359 -31.582797) (xy 351.340427 -31.636204)
			(xy 351.344577 -31.664402) (xy 351.861118 -31.664402) (xy 351.865189 -31.60878) (xy 351.877315 -31.554343)
			(xy 351.897238 -31.502252) (xy 351.924534 -31.453617) (xy 351.95862 -31.409474) (xy 351.998769 -31.370765)
			(xy 352.044127 -31.338314) (xy 352.093727 -31.312813) (xy 352.146511 -31.294806) (xy 352.201354 -31.284676)
			(xy 352.257088 -31.282639) (xy 352.312525 -31.288739) (xy 352.366482 -31.302845) (xy 352.417811 -31.324657)
			(xy 352.465417 -31.353711) (xy 352.508285 -31.389386) (xy 352.545502 -31.430923) (xy 352.576275 -31.477436)
			(xy 352.599947 -31.527933) (xy 352.616015 -31.58134) (xy 352.624135 -31.636516) (xy 352.624644 -31.664402)
			(xy 352.624135 -31.692288) (xy 352.616015 -31.747464) (xy 352.607075 -31.777178) (xy 353.126292 -31.777178)
			(xy 353.130363 -31.721556) (xy 353.142489 -31.667119) (xy 353.162412 -31.615028) (xy 353.189708 -31.566393)
			(xy 353.223794 -31.52225) (xy 353.263943 -31.483541) (xy 353.309301 -31.45109) (xy 353.358901 -31.425589)
			(xy 353.411685 -31.407582) (xy 353.466528 -31.397452) (xy 353.522262 -31.395415) (xy 353.577699 -31.401515)
			(xy 353.631656 -31.415621) (xy 353.682985 -31.437433) (xy 353.730591 -31.466487) (xy 353.773459 -31.502162)
			(xy 353.810676 -31.543699) (xy 353.841449 -31.590212) (xy 353.865121 -31.640709) (xy 353.881189 -31.694116)
			(xy 353.889309 -31.749292) (xy 353.889818 -31.777178) (xy 353.889309 -31.805064) (xy 353.881189 -31.86024)
			(xy 353.865121 -31.913647) (xy 353.841449 -31.964144) (xy 353.810676 -32.010657) (xy 353.773459 -32.052194)
			(xy 353.730591 -32.087869) (xy 353.682985 -32.116923) (xy 353.631656 -32.138735) (xy 353.577699 -32.152841)
			(xy 353.522262 -32.158941) (xy 353.466528 -32.156904) (xy 353.411685 -32.146774) (xy 353.358901 -32.128767)
			(xy 353.309301 -32.103266) (xy 353.263943 -32.070815) (xy 353.223794 -32.032106) (xy 353.189708 -31.987963)
			(xy 353.162412 -31.939328) (xy 353.142489 -31.887237) (xy 353.130363 -31.8328) (xy 353.126292 -31.777178)
			(xy 352.607075 -31.777178) (xy 352.599947 -31.800871) (xy 352.576275 -31.851368) (xy 352.545502 -31.897881)
			(xy 352.508285 -31.939418) (xy 352.465417 -31.975093) (xy 352.417811 -32.004147) (xy 352.366482 -32.025959)
			(xy 352.312525 -32.040065) (xy 352.257088 -32.046165) (xy 352.201354 -32.044128) (xy 352.146511 -32.033998)
			(xy 352.093727 -32.015991) (xy 352.044127 -31.99049) (xy 351.998769 -31.958039) (xy 351.95862 -31.91933)
			(xy 351.924534 -31.875187) (xy 351.897238 -31.826552) (xy 351.877315 -31.774461) (xy 351.865189 -31.720024)
			(xy 351.861118 -31.664402) (xy 351.344577 -31.664402) (xy 351.348547 -31.69138) (xy 351.349056 -31.719266)
			(xy 351.348547 -31.747152) (xy 351.340427 -31.802328) (xy 351.324359 -31.855735) (xy 351.300687 -31.906232)
			(xy 351.269914 -31.952745) (xy 351.232697 -31.994282) (xy 351.189829 -32.029957) (xy 351.142223 -32.059011)
			(xy 351.090894 -32.080823) (xy 351.036937 -32.094929) (xy 350.9815 -32.101029) (xy 350.925766 -32.098992)
			(xy 350.870923 -32.088862) (xy 350.818139 -32.070855) (xy 350.768539 -32.045354) (xy 350.723181 -32.012903)
			(xy 350.683032 -31.974194) (xy 350.648946 -31.930051) (xy 350.62165 -31.881416) (xy 350.601727 -31.829325)
			(xy 350.589601 -31.774888) (xy 350.58553 -31.719266) (xy 350.030603 -31.719266) (xy 350.013923 -31.754848)
			(xy 349.98315 -31.801361) (xy 349.945933 -31.842898) (xy 349.903065 -31.878573) (xy 349.855459 -31.907627)
			(xy 349.80413 -31.929439) (xy 349.750173 -31.943545) (xy 349.694736 -31.949645) (xy 349.639002 -31.947608)
			(xy 349.584159 -31.937478) (xy 349.531375 -31.919471) (xy 349.481775 -31.89397) (xy 349.436417 -31.861519)
			(xy 349.396268 -31.82281) (xy 349.362182 -31.778667) (xy 349.334886 -31.730032) (xy 349.314963 -31.677941)
			(xy 349.302837 -31.623504) (xy 349.298766 -31.567882) (xy 329.864442 -31.567882) (xy 329.886035 -31.596022)
			(xy 329.916002 -31.647928) (xy 329.938938 -31.703301) (xy 329.954451 -31.761194) (xy 329.962274 -31.820616)
			(xy 329.962764 -31.850584) (xy 329.962764 -32.714184) (xy 329.962274 -32.744152) (xy 329.954451 -32.803574)
			(xy 329.938938 -32.861467) (xy 329.916002 -32.91684) (xy 329.886035 -32.968746) (xy 329.849548 -33.016296)
			(xy 329.807168 -33.058676) (xy 329.759618 -33.095163) (xy 329.707712 -33.12513) (xy 329.652339 -33.148066)
			(xy 329.594446 -33.163579) (xy 329.535024 -33.171402) (xy 329.475088 -33.171402) (xy 329.415666 -33.163579)
			(xy 329.357773 -33.148066) (xy 329.3024 -33.12513) (xy 329.250494 -33.095163) (xy 329.202944 -33.058676)
			(xy 329.160564 -33.016296) (xy 329.124077 -32.968746) (xy 329.09411 -32.91684) (xy 329.071174 -32.861467)
			(xy 329.055661 -32.803574) (xy 329.047838 -32.744152) (xy 329.047348 -32.714184) (xy 324.526754 -32.714184)
			(xy 324.563486 -32.80283) (xy 324.566026 -32.807402) (xy 324.57009 -32.812228) (xy 324.571868 -32.81426)
			(xy 324.573392 -32.816546) (xy 324.574154 -32.817562) (xy 324.584568 -32.827976) (xy 324.59168 -32.833818)
			(xy 324.601586 -32.840422) (xy 324.605904 -32.842454) (xy 324.63102 -32.854347) (xy 324.677812 -32.884323)
			(xy 324.719763 -32.920768) (xy 324.755985 -32.96291) (xy 324.785713 -33.00986) (xy 324.808318 -33.060625)
			(xy 324.823322 -33.114131) (xy 324.830409 -33.169248) (xy 324.83044 -33.197038) (xy 324.830186 -33.202118)
			(xy 324.830186 -33.202372) (xy 324.829932 -33.208214) (xy 324.828464 -33.231495) (xy 324.820568 -33.277471)
			(xy 324.814184 -33.299908) (xy 324.814184 -33.300416) (xy 324.81266 -33.305242) (xy 324.81266 -33.30575)
			(xy 324.804278 -33.32861) (xy 324.800722 -33.3375) (xy 324.798436 -33.347406) (xy 324.797076 -33.355156)
			(xy 324.798639 -33.370803) (xy 324.801484 -33.37814) (xy 324.869556 -33.542478) (xy 325.021702 -33.909254)
			(xy 325.021702 -33.909762) (xy 325.279128 -34.520886) (xy 331.689456 -34.520886) (xy 331.689456 -33.657286)
			(xy 331.689946 -33.627318) (xy 331.697769 -33.567896) (xy 331.713282 -33.510003) (xy 331.736218 -33.45463)
			(xy 331.766185 -33.402724) (xy 331.802672 -33.355174) (xy 331.845052 -33.312794) (xy 331.892602 -33.276307)
			(xy 331.944508 -33.24634) (xy 331.999881 -33.223404) (xy 332.057774 -33.207891) (xy 332.117196 -33.200068)
			(xy 332.177132 -33.200068) (xy 332.236554 -33.207891) (xy 332.294447 -33.223404) (xy 332.34982 -33.24634)
			(xy 332.401726 -33.276307) (xy 332.449276 -33.312794) (xy 332.491656 -33.355174) (xy 332.528143 -33.402724)
			(xy 332.55811 -33.45463) (xy 332.581046 -33.510003) (xy 332.596559 -33.567896) (xy 332.604382 -33.627318)
			(xy 332.604872 -33.657286) (xy 332.604872 -34.520886) (xy 332.604382 -34.550854) (xy 332.596559 -34.610276)
			(xy 332.581046 -34.668169) (xy 332.55811 -34.723542) (xy 332.528143 -34.775448) (xy 332.491656 -34.822998)
			(xy 332.449276 -34.865378) (xy 332.401726 -34.901865) (xy 332.34982 -34.931832) (xy 332.294447 -34.954768)
			(xy 332.236554 -34.970281) (xy 332.177132 -34.978104) (xy 332.117196 -34.978104) (xy 332.057774 -34.970281)
			(xy 331.999881 -34.954768) (xy 331.944508 -34.931832) (xy 331.892602 -34.901865) (xy 331.845052 -34.865378)
			(xy 331.802672 -34.822998) (xy 331.766185 -34.775448) (xy 331.736218 -34.723542) (xy 331.713282 -34.668169)
			(xy 331.697769 -34.610276) (xy 331.689946 -34.550854) (xy 331.689456 -34.520886) (xy 325.279128 -34.520886)
			(xy 325.592511 -35.264852) (xy 352.202494 -35.264852) (xy 352.206565 -35.20923) (xy 352.218691 -35.154793)
			(xy 352.238614 -35.102702) (xy 352.26591 -35.054067) (xy 352.299996 -35.009924) (xy 352.340145 -34.971215)
			(xy 352.385503 -34.938764) (xy 352.435103 -34.913263) (xy 352.487887 -34.895256) (xy 352.54273 -34.885126)
			(xy 352.598464 -34.883089) (xy 352.653901 -34.889189) (xy 352.707858 -34.903295) (xy 352.759187 -34.925107)
			(xy 352.806793 -34.954161) (xy 352.849661 -34.989836) (xy 352.886878 -35.031373) (xy 352.917651 -35.077886)
			(xy 352.941323 -35.128383) (xy 352.957391 -35.18179) (xy 352.965511 -35.236966) (xy 352.96602 -35.264852)
			(xy 352.965511 -35.292738) (xy 352.957391 -35.347914) (xy 352.941323 -35.401321) (xy 352.917651 -35.451818)
			(xy 352.886878 -35.498331) (xy 352.849661 -35.539868) (xy 352.806793 -35.575543) (xy 352.759187 -35.604597)
			(xy 352.707858 -35.626409) (xy 352.653901 -35.640515) (xy 352.598464 -35.646615) (xy 352.54273 -35.644578)
			(xy 352.487887 -35.634448) (xy 352.435103 -35.616441) (xy 352.385503 -35.59094) (xy 352.340145 -35.558489)
			(xy 352.299996 -35.51978) (xy 352.26591 -35.475637) (xy 352.238614 -35.427002) (xy 352.218691 -35.374911)
			(xy 352.206565 -35.320474) (xy 352.202494 -35.264852) (xy 325.592511 -35.264852) (xy 325.850258 -35.876738)
			(xy 341.01735 -35.876738) (xy 341.021421 -35.821116) (xy 341.033547 -35.766679) (xy 341.05347 -35.714588)
			(xy 341.080766 -35.665953) (xy 341.114852 -35.62181) (xy 341.155001 -35.583101) (xy 341.200359 -35.55065)
			(xy 341.249959 -35.525149) (xy 341.302743 -35.507142) (xy 341.357586 -35.497012) (xy 341.41332 -35.494975)
			(xy 341.468757 -35.501075) (xy 341.522714 -35.515181) (xy 341.574043 -35.536993) (xy 341.621649 -35.566047)
			(xy 341.664517 -35.601722) (xy 341.701734 -35.643259) (xy 341.732507 -35.689772) (xy 341.756179 -35.740269)
			(xy 341.772247 -35.793676) (xy 341.780367 -35.848852) (xy 341.780876 -35.876738) (xy 345.08897 -35.876738)
			(xy 345.093041 -35.821116) (xy 345.105167 -35.766679) (xy 345.12509 -35.714588) (xy 345.152386 -35.665953)
			(xy 345.186472 -35.62181) (xy 345.226621 -35.583101) (xy 345.271979 -35.55065) (xy 345.321579 -35.525149)
			(xy 345.374363 -35.507142) (xy 345.429206 -35.497012) (xy 345.48494 -35.494975) (xy 345.540377 -35.501075)
			(xy 345.594334 -35.515181) (xy 345.645663 -35.536993) (xy 345.693269 -35.566047) (xy 345.736137 -35.601722)
			(xy 345.773354 -35.643259) (xy 345.804127 -35.689772) (xy 345.827799 -35.740269) (xy 345.843867 -35.793676)
			(xy 345.851987 -35.848852) (xy 345.852496 -35.876738) (xy 345.851987 -35.904624) (xy 345.843867 -35.9598)
			(xy 345.827799 -36.013207) (xy 345.804127 -36.063704) (xy 345.773354 -36.110217) (xy 345.736137 -36.151754)
			(xy 345.693269 -36.187429) (xy 345.645663 -36.216483) (xy 345.594334 -36.238295) (xy 345.540377 -36.252401)
			(xy 345.48494 -36.258501) (xy 345.429206 -36.256464) (xy 345.374363 -36.246334) (xy 345.321579 -36.228327)
			(xy 345.271979 -36.202826) (xy 345.226621 -36.170375) (xy 345.186472 -36.131666) (xy 345.152386 -36.087523)
			(xy 345.12509 -36.038888) (xy 345.105167 -35.986797) (xy 345.093041 -35.93236) (xy 345.08897 -35.876738)
			(xy 341.780876 -35.876738) (xy 341.780367 -35.904624) (xy 341.772247 -35.9598) (xy 341.756179 -36.013207)
			(xy 341.732507 -36.063704) (xy 341.701734 -36.110217) (xy 341.664517 -36.151754) (xy 341.621649 -36.187429)
			(xy 341.574043 -36.216483) (xy 341.522714 -36.238295) (xy 341.468757 -36.252401) (xy 341.41332 -36.258501)
			(xy 341.357586 -36.256464) (xy 341.302743 -36.246334) (xy 341.249959 -36.228327) (xy 341.200359 -36.202826)
			(xy 341.155001 -36.170375) (xy 341.114852 -36.131666) (xy 341.080766 -36.087523) (xy 341.05347 -36.038888)
			(xy 341.033547 -35.986797) (xy 341.021421 -35.93236) (xy 341.01735 -35.876738) (xy 325.850258 -35.876738)
			(xy 326.116992 -36.50996) (xy 342.913968 -36.50996) (xy 342.918039 -36.454338) (xy 342.930165 -36.399901)
			(xy 342.950088 -36.34781) (xy 342.977384 -36.299175) (xy 343.01147 -36.255032) (xy 343.051619 -36.216323)
			(xy 343.096977 -36.183872) (xy 343.146577 -36.158371) (xy 343.199361 -36.140364) (xy 343.254204 -36.130234)
			(xy 343.309938 -36.128197) (xy 343.365375 -36.134297) (xy 343.419332 -36.148403) (xy 343.470661 -36.170215)
			(xy 343.518267 -36.199269) (xy 343.561135 -36.234944) (xy 343.598352 -36.276481) (xy 343.629125 -36.322994)
			(xy 343.652797 -36.373491) (xy 343.668865 -36.426898) (xy 343.67279 -36.453572) (xy 346.228668 -36.453572)
			(xy 346.232739 -36.39795) (xy 346.244865 -36.343513) (xy 346.264788 -36.291422) (xy 346.292084 -36.242787)
			(xy 346.32617 -36.198644) (xy 346.366319 -36.159935) (xy 346.411677 -36.127484) (xy 346.461277 -36.101983)
			(xy 346.514061 -36.083976) (xy 346.568904 -36.073846) (xy 346.624638 -36.071809) (xy 346.680075 -36.077909)
			(xy 346.734032 -36.092015) (xy 346.785361 -36.113827) (xy 346.832967 -36.142881) (xy 346.875835 -36.178556)
			(xy 346.913052 -36.220093) (xy 346.943825 -36.266606) (xy 346.953361 -36.286948) (xy 353.500434 -36.286948)
			(xy 353.504505 -36.231326) (xy 353.516631 -36.176889) (xy 353.536554 -36.124798) (xy 353.56385 -36.076163)
			(xy 353.597936 -36.03202) (xy 353.638085 -35.993311) (xy 353.683443 -35.96086) (xy 353.733043 -35.935359)
			(xy 353.785827 -35.917352) (xy 353.84067 -35.907222) (xy 353.896404 -35.905185) (xy 353.951841 -35.911285)
			(xy 354.005798 -35.925391) (xy 354.057127 -35.947203) (xy 354.104733 -35.976257) (xy 354.147601 -36.011932)
			(xy 354.184818 -36.053469) (xy 354.215591 -36.099982) (xy 354.239263 -36.150479) (xy 354.255331 -36.203886)
			(xy 354.263451 -36.259062) (xy 354.26396 -36.286948) (xy 354.263451 -36.314834) (xy 354.255331 -36.37001)
			(xy 354.239263 -36.423417) (xy 354.215591 -36.473914) (xy 354.184818 -36.520427) (xy 354.147601 -36.561964)
			(xy 354.104733 -36.597639) (xy 354.057127 -36.626693) (xy 354.005798 -36.648505) (xy 353.951841 -36.662611)
			(xy 353.896404 -36.668711) (xy 353.84067 -36.666674) (xy 353.785827 -36.656544) (xy 353.733043 -36.638537)
			(xy 353.683443 -36.613036) (xy 353.638085 -36.580585) (xy 353.597936 -36.541876) (xy 353.56385 -36.497733)
			(xy 353.536554 -36.449098) (xy 353.516631 -36.397007) (xy 353.504505 -36.34257) (xy 353.500434 -36.286948)
			(xy 346.953361 -36.286948) (xy 346.967497 -36.317103) (xy 346.983565 -36.37051) (xy 346.991685 -36.425686)
			(xy 346.992194 -36.453572) (xy 346.991685 -36.481458) (xy 346.983565 -36.536634) (xy 346.967497 -36.590041)
			(xy 346.943825 -36.640538) (xy 346.913052 -36.687051) (xy 346.875835 -36.728588) (xy 346.832967 -36.764263)
			(xy 346.785361 -36.793317) (xy 346.734032 -36.815129) (xy 346.680075 -36.829235) (xy 346.624638 -36.835335)
			(xy 346.568904 -36.833298) (xy 346.514061 -36.823168) (xy 346.461277 -36.805161) (xy 346.411677 -36.77966)
			(xy 346.366319 -36.747209) (xy 346.32617 -36.7085) (xy 346.292084 -36.664357) (xy 346.264788 -36.615722)
			(xy 346.244865 -36.563631) (xy 346.232739 -36.509194) (xy 346.228668 -36.453572) (xy 343.67279 -36.453572)
			(xy 343.676985 -36.482074) (xy 343.677494 -36.50996) (xy 343.676985 -36.537846) (xy 343.668865 -36.593022)
			(xy 343.652797 -36.646429) (xy 343.629125 -36.696926) (xy 343.598352 -36.743439) (xy 343.561135 -36.784976)
			(xy 343.518267 -36.820651) (xy 343.470661 -36.849705) (xy 343.419332 -36.871517) (xy 343.365375 -36.885623)
			(xy 343.309938 -36.891723) (xy 343.254204 -36.889686) (xy 343.199361 -36.879556) (xy 343.146577 -36.861549)
			(xy 343.096977 -36.836048) (xy 343.051619 -36.803597) (xy 343.01147 -36.764888) (xy 342.977384 -36.720745)
			(xy 342.950088 -36.67211) (xy 342.930165 -36.620019) (xy 342.918039 -36.565582) (xy 342.913968 -36.50996)
			(xy 326.116992 -36.50996) (xy 326.363076 -37.09416) (xy 326.382609 -37.142217) (xy 326.412768 -37.24148)
			(xy 326.423274 -37.29228) (xy 326.458581 -37.47516) (xy 340.059262 -37.47516) (xy 340.063333 -37.419538)
			(xy 340.075459 -37.365101) (xy 340.095382 -37.31301) (xy 340.122678 -37.264375) (xy 340.156764 -37.220232)
			(xy 340.196913 -37.181523) (xy 340.242271 -37.149072) (xy 340.291871 -37.123571) (xy 340.344655 -37.105564)
			(xy 340.399498 -37.095434) (xy 340.455232 -37.093397) (xy 340.510669 -37.099497) (xy 340.564626 -37.113603)
			(xy 340.615955 -37.135415) (xy 340.663561 -37.164469) (xy 340.706429 -37.200144) (xy 340.743646 -37.241681)
			(xy 340.774419 -37.288194) (xy 340.798091 -37.338691) (xy 340.814159 -37.392098) (xy 340.822279 -37.447274)
			(xy 340.822788 -37.47516) (xy 340.822279 -37.503046) (xy 340.814159 -37.558222) (xy 340.798091 -37.611629)
			(xy 340.774419 -37.662126) (xy 340.774266 -37.662358) (xy 342.248488 -37.662358) (xy 342.252559 -37.606736)
			(xy 342.264685 -37.552299) (xy 342.284608 -37.500208) (xy 342.311904 -37.451573) (xy 342.34599 -37.40743)
			(xy 342.386139 -37.368721) (xy 342.431497 -37.33627) (xy 342.481097 -37.310769) (xy 342.533881 -37.292762)
			(xy 342.588724 -37.282632) (xy 342.644458 -37.280595) (xy 342.699895 -37.286695) (xy 342.753852 -37.300801)
			(xy 342.805181 -37.322613) (xy 342.852787 -37.351667) (xy 342.895655 -37.387342) (xy 342.932872 -37.428879)
			(xy 342.963645 -37.475392) (xy 342.987317 -37.525889) (xy 343.003385 -37.579296) (xy 343.011505 -37.634472)
			(xy 343.012014 -37.662358) (xy 343.011505 -37.690244) (xy 343.003385 -37.74542) (xy 342.994751 -37.774118)
			(xy 353.764848 -37.774118) (xy 353.768919 -37.718496) (xy 353.781045 -37.664059) (xy 353.800968 -37.611968)
			(xy 353.828264 -37.563333) (xy 353.86235 -37.51919) (xy 353.902499 -37.480481) (xy 353.947857 -37.44803)
			(xy 353.997457 -37.422529) (xy 354.050241 -37.404522) (xy 354.105084 -37.394392) (xy 354.160818 -37.392355)
			(xy 354.216255 -37.398455) (xy 354.270212 -37.412561) (xy 354.321541 -37.434373) (xy 354.369147 -37.463427)
			(xy 354.412015 -37.499102) (xy 354.449232 -37.540639) (xy 354.480005 -37.587152) (xy 354.503677 -37.637649)
			(xy 354.519745 -37.691056) (xy 354.527865 -37.746232) (xy 354.528374 -37.774118) (xy 354.527865 -37.802004)
			(xy 354.519745 -37.85718) (xy 354.503677 -37.910587) (xy 354.480005 -37.961084) (xy 354.449232 -38.007597)
			(xy 354.412015 -38.049134) (xy 354.369147 -38.084809) (xy 354.321541 -38.113863) (xy 354.270212 -38.135675)
			(xy 354.216255 -38.149781) (xy 354.160818 -38.155881) (xy 354.105084 -38.153844) (xy 354.050241 -38.143714)
			(xy 353.997457 -38.125707) (xy 353.947857 -38.100206) (xy 353.902499 -38.067755) (xy 353.86235 -38.029046)
			(xy 353.828264 -37.984903) (xy 353.800968 -37.936268) (xy 353.781045 -37.884177) (xy 353.768919 -37.82974)
			(xy 353.764848 -37.774118) (xy 342.994751 -37.774118) (xy 342.987317 -37.798827) (xy 342.963645 -37.849324)
			(xy 342.932872 -37.895837) (xy 342.895655 -37.937374) (xy 342.852787 -37.973049) (xy 342.805181 -38.002103)
			(xy 342.753852 -38.023915) (xy 342.699895 -38.038021) (xy 342.644458 -38.044121) (xy 342.588724 -38.042084)
			(xy 342.533881 -38.031954) (xy 342.481097 -38.013947) (xy 342.431497 -37.988446) (xy 342.386139 -37.955995)
			(xy 342.34599 -37.917286) (xy 342.311904 -37.873143) (xy 342.284608 -37.824508) (xy 342.264685 -37.772417)
			(xy 342.252559 -37.71798) (xy 342.248488 -37.662358) (xy 340.774266 -37.662358) (xy 340.743646 -37.708639)
			(xy 340.706429 -37.750176) (xy 340.663561 -37.785851) (xy 340.615955 -37.814905) (xy 340.564626 -37.836717)
			(xy 340.510669 -37.850823) (xy 340.455232 -37.856923) (xy 340.399498 -37.854886) (xy 340.344655 -37.844756)
			(xy 340.291871 -37.826749) (xy 340.242271 -37.801248) (xy 340.196913 -37.768797) (xy 340.156764 -37.730088)
			(xy 340.122678 -37.685945) (xy 340.095382 -37.63731) (xy 340.075459 -37.585219) (xy 340.063333 -37.530782)
			(xy 340.059262 -37.47516) (xy 326.458581 -37.47516) (xy 326.53351 -37.863272) (xy 326.541949 -37.91006)
			(xy 326.550982 -38.004709) (xy 326.551544 -38.052248) (xy 326.551419 -38.079798) (xy 326.548494 -38.134821)
			(xy 326.545702 -38.16223) (xy 326.545448 -38.1635) (xy 326.481805 -38.729948) (xy 346.00112 -38.729948)
			(xy 346.00112 -38.675452) (xy 346.008875 -38.621512) (xy 346.024228 -38.569224) (xy 346.046866 -38.519653)
			(xy 346.076327 -38.473809) (xy 346.112013 -38.432623) (xy 346.153197 -38.396936) (xy 346.199041 -38.367472)
			(xy 346.248611 -38.344833) (xy 346.300898 -38.329478) (xy 346.354838 -38.321721) (xy 346.382086 -38.321234)
			(xy 346.410391 -38.321719) (xy 346.46638 -38.33007) (xy 346.52052 -38.346605) (xy 346.571621 -38.37096)
			(xy 346.618561 -38.402602) (xy 346.660308 -38.440835) (xy 346.695945 -38.484818) (xy 346.710762 -38.50894)
			(xy 346.718313 -38.521007) (xy 346.738941 -38.540611) (xy 346.764183 -38.553753) (xy 346.792074 -38.559408)
			(xy 346.820441 -38.557138) (xy 346.847077 -38.547118) (xy 346.869907 -38.530129) (xy 346.87891 -38.5191)
			(xy 346.897096 -38.496223) (xy 346.939259 -38.455759) (xy 346.987095 -38.422192) (xy 347.039487 -38.396305)
			(xy 347.095211 -38.378703) (xy 347.152967 -38.369797) (xy 347.182186 -38.36924) (xy 347.209443 -38.369606)
			(xy 347.263402 -38.377362) (xy 347.315708 -38.392719) (xy 347.365297 -38.415364) (xy 347.411157 -38.444835)
			(xy 347.452357 -38.480533) (xy 347.488057 -38.521731) (xy 347.51753 -38.567591) (xy 347.540176 -38.617178)
			(xy 347.555535 -38.669484) (xy 347.563293 -38.723443) (xy 347.563293 -38.777957) (xy 347.555535 -38.831916)
			(xy 347.540176 -38.884222) (xy 347.51753 -38.933809) (xy 347.488057 -38.979669) (xy 347.452357 -39.020867)
			(xy 347.411157 -39.056565) (xy 347.365297 -39.086036) (xy 347.315708 -39.108681) (xy 347.263402 -39.124038)
			(xy 347.209443 -39.131794) (xy 347.182186 -39.132256) (xy 347.153883 -39.131719) (xy 347.097896 -39.123379)
			(xy 347.043757 -39.106853) (xy 346.992656 -39.082506) (xy 346.945715 -39.050872) (xy 346.903966 -39.012647)
			(xy 346.868327 -38.968669) (xy 346.85351 -38.94455) (xy 346.845866 -38.932548) (xy 346.825256 -38.91295)
			(xy 346.800034 -38.899808) (xy 346.772163 -38.894145) (xy 346.743812 -38.896403) (xy 346.717189 -38.906404)
			(xy 346.694364 -38.923372) (xy 346.685362 -38.93439) (xy 346.66719 -38.957278) (xy 346.625024 -38.997742)
			(xy 346.577186 -39.031308) (xy 346.524791 -39.057193) (xy 346.469064 -39.074793) (xy 346.411306 -39.083695)
			(xy 346.382086 -39.08425) (xy 346.354838 -39.083679) (xy 346.300898 -39.075922) (xy 346.248611 -39.060567)
			(xy 346.199041 -39.037928) (xy 346.153197 -39.008464) (xy 346.112013 -38.972777) (xy 346.076327 -38.931591)
			(xy 346.046866 -38.885747) (xy 346.024228 -38.836176) (xy 346.008875 -38.783888) (xy 346.00112 -38.729948)
			(xy 326.481805 -38.729948) (xy 326.481694 -38.730936) (xy 326.451722 -38.997636) (xy 326.451468 -39.003224)
			(xy 326.451468 -39.269924) (xy 326.45122 -39.300485) (xy 326.447407 -39.361489) (xy 326.443848 -39.391844)
			(xy 326.43953 -39.422832) (xy 326.435466 -39.446454) (xy 326.431148 -39.468298) (xy 326.36079 -39.812722)
			(xy 326.360028 -39.81704) (xy 326.355456 -39.85641) (xy 326.342541 -39.97198) (xy 348.195898 -39.97198)
			(xy 348.199969 -39.916358) (xy 348.212095 -39.861921) (xy 348.232018 -39.80983) (xy 348.259314 -39.761195)
			(xy 348.2934 -39.717052) (xy 348.333549 -39.678343) (xy 348.378907 -39.645892) (xy 348.428507 -39.620391)
			(xy 348.481291 -39.602384) (xy 348.536134 -39.592254) (xy 348.591868 -39.590217) (xy 348.647305 -39.596317)
			(xy 348.701262 -39.610423) (xy 348.752591 -39.632235) (xy 348.800197 -39.661289) (xy 348.843065 -39.696964)
			(xy 348.880282 -39.738501) (xy 348.911055 -39.785014) (xy 348.934727 -39.835511) (xy 348.950795 -39.888918)
			(xy 348.958915 -39.944094) (xy 348.959424 -39.97198) (xy 348.958915 -39.999866) (xy 348.950795 -40.055042)
			(xy 348.934727 -40.108449) (xy 348.911055 -40.158946) (xy 348.880282 -40.205459) (xy 348.843065 -40.246996)
			(xy 348.800197 -40.282671) (xy 348.752591 -40.311725) (xy 348.701262 -40.333537) (xy 348.647305 -40.347643)
			(xy 348.591868 -40.353743) (xy 348.536134 -40.351706) (xy 348.481291 -40.341576) (xy 348.428507 -40.323569)
			(xy 348.378907 -40.298068) (xy 348.333549 -40.265617) (xy 348.2934 -40.226908) (xy 348.259314 -40.182765)
			(xy 348.232018 -40.13413) (xy 348.212095 -40.082039) (xy 348.199969 -40.027602) (xy 348.195898 -39.97198)
			(xy 326.342541 -39.97198) (xy 326.330818 -40.076882) (xy 326.32804 -40.100332) (xy 326.320542 -40.14696)
			(xy 326.315832 -40.1701) (xy 326.310498 -40.195754) (xy 326.259698 -40.438832) (xy 326.187562 -40.783764)
			(xy 326.186058 -40.792617) (xy 326.188672 -40.810371) (xy 326.197289 -40.826112) (xy 326.203818 -40.832278)
			(xy 326.240902 -40.86479) (xy 326.245474 -40.868854) (xy 326.251034 -40.873447) (xy 326.264056 -40.879629)
			(xy 326.271128 -40.881046) (xy 326.295472 -40.87111) (xy 326.346155 -40.857109) (xy 326.398254 -40.850007)
			(xy 326.424544 -40.84955) (xy 326.424798 -40.84955) (xy 326.451868 -40.850006) (xy 326.505492 -40.857459)
			(xy 326.557579 -40.872223) (xy 326.607138 -40.894018) (xy 326.653224 -40.922427) (xy 326.694961 -40.95691)
			(xy 326.713596 -40.97655) (xy 326.719438 -40.976804) (xy 326.790558 -40.976804) (xy 326.7964 -40.97655)
			(xy 326.815036 -40.956912) (xy 326.856776 -40.922434) (xy 326.902864 -40.894027) (xy 326.952422 -40.872231)
			(xy 327.004507 -40.857461) (xy 327.058129 -40.849998) (xy 327.085198 -40.84955) (xy 327.113197 -40.850026)
			(xy 327.168625 -40.857995) (xy 327.222354 -40.873771) (xy 327.273292 -40.897033) (xy 327.3204 -40.927308)
			(xy 327.36272 -40.963978) (xy 327.399391 -41.006298) (xy 327.429666 -41.053407) (xy 327.452928 -41.104344)
			(xy 327.468705 -41.158073) (xy 327.476674 -41.213501) (xy 327.476674 -41.269499) (xy 327.468705 -41.324927)
			(xy 327.452928 -41.378656) (xy 327.429666 -41.429593) (xy 327.399391 -41.476702) (xy 327.36272 -41.519022)
			(xy 327.3204 -41.555692) (xy 327.273292 -41.585967) (xy 327.222354 -41.609229) (xy 327.168625 -41.625005)
			(xy 327.113197 -41.632974) (xy 327.085198 -41.633394) (xy 327.058129 -41.632937) (xy 327.004506 -41.625483)
			(xy 326.952421 -41.610717) (xy 326.902864 -41.58892) (xy 326.856781 -41.560508) (xy 326.815048 -41.526021)
			(xy 326.7964 -41.506394) (xy 326.790558 -41.50614) (xy 326.719438 -41.50614) (xy 326.713596 -41.506394)
			(xy 326.694961 -41.526035) (xy 326.653222 -41.560517) (xy 326.607136 -41.588928) (xy 326.557578 -41.610726)
			(xy 326.505491 -41.625497) (xy 326.451868 -41.632961) (xy 326.424798 -41.633394) (xy 326.398597 -41.632957)
			(xy 326.346662 -41.625977) (xy 326.296119 -41.612142) (xy 326.24787 -41.591697) (xy 326.202774 -41.565008)
			(xy 326.161635 -41.53255) (xy 326.143112 -41.514014) (xy 326.13727 -41.512998) (xy 326.133046 -41.512323)
			(xy 326.124494 -41.512197) (xy 326.120252 -41.512744) (xy 326.108568 -41.51503) (xy 326.076564 -41.525444)
			(xy 326.05853 -41.531286) (xy 326.03059 -41.54043) (xy 326.028812 -41.541192) (xy 325.991982 -41.717722)
			(xy 325.921878 -42.052494) (xy 325.659608 -43.305222) (xy 328.50709 -43.305222) (xy 328.507571 -43.277852)
			(xy 328.515386 -43.223674) (xy 328.530872 -43.171171) (xy 328.55371 -43.121424) (xy 328.583431 -43.075456)
			(xy 328.60107 -43.054524) (xy 328.601324 -43.05427) (xy 328.60689 -43.04717) (xy 328.613148 -43.030263)
			(xy 328.613516 -43.02125) (xy 328.613516 -42.954194) (xy 328.613158 -42.945177) (xy 328.606911 -42.928261)
			(xy 328.601324 -42.921174) (xy 328.60107 -42.921174) (xy 328.60107 -42.92092) (xy 328.583422 -42.899995)
			(xy 328.553713 -42.85402) (xy 328.530879 -42.80427) (xy 328.51539 -42.751768) (xy 328.507563 -42.697592)
			(xy 328.50709 -42.670222) (xy 328.50763 -42.641484) (xy 328.516249 -42.584657) (xy 328.533295 -42.529767)
			(xy 328.558383 -42.478055) (xy 328.590945 -42.430691) (xy 328.610214 -42.409364) (xy 328.616818 -42.402506)
			(xy 328.62393 -42.384472) (xy 328.62393 -42.295572) (xy 328.616818 -42.277538) (xy 328.610214 -42.27068)
			(xy 328.590965 -42.249334) (xy 328.5584 -42.201975) (xy 328.533308 -42.150266) (xy 328.516257 -42.095378)
			(xy 328.507633 -42.038554) (xy 328.50763 -41.981078) (xy 328.51625 -41.924253) (xy 328.533296 -41.869364)
			(xy 328.558384 -41.817653) (xy 328.590945 -41.770291) (xy 328.610214 -41.748964) (xy 328.616818 -41.742106)
			(xy 328.62393 -41.724072) (xy 328.62393 -41.635172) (xy 328.616818 -41.617138) (xy 328.610214 -41.61028)
			(xy 328.59095 -41.588947) (xy 328.558383 -41.541587) (xy 328.53329 -41.489876) (xy 328.516238 -41.434987)
			(xy 328.507613 -41.378161) (xy 328.50709 -41.349422) (xy 328.507576 -41.322171) (xy 328.515332 -41.268223)
			(xy 328.530687 -41.215928) (xy 328.553329 -41.166351) (xy 328.582795 -41.120501) (xy 328.618486 -41.07931)
			(xy 328.659677 -41.043619) (xy 328.705527 -41.014153) (xy 328.755104 -40.991511) (xy 328.807399 -40.976156)
			(xy 328.861347 -40.9684) (xy 328.915849 -40.9684) (xy 328.93897 -40.971724) (xy 348.894144 -40.971724)
			(xy 348.898215 -40.916102) (xy 348.910341 -40.861665) (xy 348.930264 -40.809574) (xy 348.95756 -40.760939)
			(xy 348.991646 -40.716796) (xy 349.031795 -40.678087) (xy 349.077153 -40.645636) (xy 349.126753 -40.620135)
			(xy 349.179537 -40.602128) (xy 349.23438 -40.591998) (xy 349.290114 -40.589961) (xy 349.345551 -40.596061)
			(xy 349.399508 -40.610167) (xy 349.450837 -40.631979) (xy 349.498443 -40.661033) (xy 349.541311 -40.696708)
			(xy 349.578528 -40.738245) (xy 349.609301 -40.784758) (xy 349.632973 -40.835255) (xy 349.649041 -40.888662)
			(xy 349.657161 -40.943838) (xy 349.65767 -40.971724) (xy 349.657161 -40.99961) (xy 349.649041 -41.054786)
			(xy 349.632973 -41.108193) (xy 349.609301 -41.15869) (xy 349.578528 -41.205203) (xy 349.541311 -41.24674)
			(xy 349.498443 -41.282415) (xy 349.450837 -41.311469) (xy 349.399508 -41.333281) (xy 349.345551 -41.347387)
			(xy 349.290114 -41.353487) (xy 349.23438 -41.35145) (xy 349.179537 -41.34132) (xy 349.126753 -41.323313)
			(xy 349.077153 -41.297812) (xy 349.031795 -41.265361) (xy 348.991646 -41.226652) (xy 348.95756 -41.182509)
			(xy 348.930264 -41.133874) (xy 348.910341 -41.081783) (xy 348.898215 -41.027346) (xy 348.894144 -40.971724)
			(xy 328.93897 -40.971724) (xy 328.969797 -40.976156) (xy 329.022092 -40.991511) (xy 329.071669 -41.014153)
			(xy 329.117519 -41.043619) (xy 329.15871 -41.07931) (xy 329.194401 -41.120501) (xy 329.223867 -41.166351)
			(xy 329.246509 -41.215928) (xy 329.261864 -41.268223) (xy 329.26962 -41.322171) (xy 329.270106 -41.349422)
			(xy 329.269594 -41.378161) (xy 329.260968 -41.434989) (xy 329.243915 -41.48988) (xy 329.218821 -41.541591)
			(xy 329.186254 -41.588954) (xy 329.166982 -41.61028) (xy 329.160378 -41.617138) (xy 329.153266 -41.635172)
			(xy 329.153266 -41.724072) (xy 329.160378 -41.742106) (xy 329.166982 -41.748964) (xy 329.186274 -41.770272)
			(xy 329.218838 -41.817638) (xy 329.243928 -41.869353) (xy 329.260976 -41.924246) (xy 329.269597 -41.981076)
			(xy 329.269594 -42.038556) (xy 329.260969 -42.095385) (xy 329.243917 -42.150277) (xy 329.218822 -42.20199)
			(xy 329.186254 -42.249353) (xy 329.166982 -42.27068) (xy 329.160378 -42.277538) (xy 329.153266 -42.295572)
			(xy 329.153266 -42.384472) (xy 329.160378 -42.402506) (xy 329.166982 -42.409364) (xy 329.186266 -42.430679)
			(xy 329.21883 -42.478045) (xy 329.24392 -42.529759) (xy 329.260967 -42.584653) (xy 329.269587 -42.641482)
			(xy 329.270106 -42.670222) (xy 329.269651 -42.697593) (xy 329.261831 -42.751772) (xy 329.246339 -42.804275)
			(xy 329.225784 -42.849038) (xy 331.091792 -42.849038) (xy 331.095863 -42.793416) (xy 331.107989 -42.738979)
			(xy 331.127912 -42.686888) (xy 331.155208 -42.638253) (xy 331.189294 -42.59411) (xy 331.229443 -42.555401)
			(xy 331.274801 -42.52295) (xy 331.324401 -42.497449) (xy 331.377185 -42.479442) (xy 331.432028 -42.469312)
			(xy 331.487762 -42.467275) (xy 331.543199 -42.473375) (xy 331.597156 -42.487481) (xy 331.648485 -42.509293)
			(xy 331.696091 -42.538347) (xy 331.738959 -42.574022) (xy 331.776176 -42.615559) (xy 331.806949 -42.662072)
			(xy 331.830621 -42.712569) (xy 331.846689 -42.765976) (xy 331.854809 -42.821152) (xy 331.85517 -42.84091)
			(xy 337.132928 -42.84091) (xy 337.136999 -42.785288) (xy 337.149125 -42.730851) (xy 337.169048 -42.67876)
			(xy 337.196344 -42.630125) (xy 337.23043 -42.585982) (xy 337.270579 -42.547273) (xy 337.315937 -42.514822)
			(xy 337.365537 -42.489321) (xy 337.418321 -42.471314) (xy 337.473164 -42.461184) (xy 337.528898 -42.459147)
			(xy 337.584335 -42.465247) (xy 337.638292 -42.479353) (xy 337.689621 -42.501165) (xy 337.737227 -42.530219)
			(xy 337.780095 -42.565894) (xy 337.817312 -42.607431) (xy 337.848085 -42.653944) (xy 337.871757 -42.704441)
			(xy 337.887825 -42.757848) (xy 337.895945 -42.813024) (xy 337.896454 -42.84091) (xy 337.895945 -42.868796)
			(xy 337.887825 -42.923972) (xy 337.871757 -42.977379) (xy 337.848085 -43.027876) (xy 337.817312 -43.074389)
			(xy 337.780095 -43.115926) (xy 337.737227 -43.151601) (xy 337.689621 -43.180655) (xy 337.638292 -43.202467)
			(xy 337.584335 -43.216573) (xy 337.528898 -43.222673) (xy 337.473164 -43.220636) (xy 337.418321 -43.210506)
			(xy 337.365537 -43.192499) (xy 337.315937 -43.166998) (xy 337.270579 -43.134547) (xy 337.23043 -43.095838)
			(xy 337.196344 -43.051695) (xy 337.169048 -43.00306) (xy 337.149125 -42.950969) (xy 337.136999 -42.896532)
			(xy 337.132928 -42.84091) (xy 331.85517 -42.84091) (xy 331.855318 -42.849038) (xy 331.854809 -42.876924)
			(xy 331.846689 -42.9321) (xy 331.830621 -42.985507) (xy 331.806949 -43.036004) (xy 331.776176 -43.082517)
			(xy 331.738959 -43.124054) (xy 331.696091 -43.159729) (xy 331.648485 -43.188783) (xy 331.597156 -43.210595)
			(xy 331.543199 -43.224701) (xy 331.487762 -43.230801) (xy 331.432028 -43.228764) (xy 331.377185 -43.218634)
			(xy 331.324401 -43.200627) (xy 331.274801 -43.175126) (xy 331.229443 -43.142675) (xy 331.189294 -43.103966)
			(xy 331.155208 -43.059823) (xy 331.127912 -43.011188) (xy 331.107989 -42.959097) (xy 331.095863 -42.90466)
			(xy 331.091792 -42.849038) (xy 329.225784 -42.849038) (xy 329.223495 -42.854022) (xy 329.193768 -42.899988)
			(xy 329.176126 -42.92092) (xy 329.175872 -42.921174) (xy 329.170287 -42.928262) (xy 329.16404 -42.945178)
			(xy 329.16368 -42.954194) (xy 329.16368 -43.02125) (xy 329.164065 -43.030264) (xy 329.170294 -43.047181)
			(xy 329.175872 -43.05427) (xy 329.176126 -43.05427) (xy 329.176126 -43.054524) (xy 329.193747 -43.075471)
			(xy 329.223461 -43.12144) (xy 329.2463 -43.171184) (xy 329.261795 -43.223681) (xy 329.269629 -43.277854)
			(xy 329.270106 -43.305222) (xy 329.26962 -43.332473) (xy 329.261864 -43.386421) (xy 329.246509 -43.438716)
			(xy 329.223867 -43.488293) (xy 329.194401 -43.534143) (xy 329.15871 -43.575334) (xy 329.117519 -43.611025)
			(xy 329.071669 -43.640491) (xy 329.022092 -43.663133) (xy 328.969797 -43.678488) (xy 328.915849 -43.686244)
			(xy 328.861347 -43.686244) (xy 328.807399 -43.678488) (xy 328.755104 -43.663133) (xy 328.705527 -43.640491)
			(xy 328.659677 -43.611025) (xy 328.618486 -43.575334) (xy 328.582795 -43.534143) (xy 328.553329 -43.488293)
			(xy 328.530687 -43.438716) (xy 328.515332 -43.386421) (xy 328.507576 -43.332473) (xy 328.50709 -43.305222)
			(xy 325.659608 -43.305222) (xy 325.569366 -43.73626) (xy 330.41285 -43.73626) (xy 330.416921 -43.680638)
			(xy 330.429047 -43.626201) (xy 330.44897 -43.57411) (xy 330.476266 -43.525475) (xy 330.510352 -43.481332)
			(xy 330.550501 -43.442623) (xy 330.595859 -43.410172) (xy 330.645459 -43.384671) (xy 330.698243 -43.366664)
			(xy 330.753086 -43.356534) (xy 330.80882 -43.354497) (xy 330.864257 -43.360597) (xy 330.918214 -43.374703)
			(xy 330.969543 -43.396515) (xy 331.017149 -43.425569) (xy 331.060017 -43.461244) (xy 331.097234 -43.502781)
			(xy 331.128007 -43.549294) (xy 331.136233 -43.566842) (xy 333.53324 -43.566842) (xy 333.537311 -43.51122)
			(xy 333.549437 -43.456783) (xy 333.56936 -43.404692) (xy 333.596656 -43.356057) (xy 333.630742 -43.311914)
			(xy 333.670891 -43.273205) (xy 333.716249 -43.240754) (xy 333.765849 -43.215253) (xy 333.818633 -43.197246)
			(xy 333.873476 -43.187116) (xy 333.92921 -43.185079) (xy 333.984647 -43.191179) (xy 334.038604 -43.205285)
			(xy 334.089933 -43.227097) (xy 334.137539 -43.256151) (xy 334.180407 -43.291826) (xy 334.217624 -43.333363)
			(xy 334.248397 -43.379876) (xy 334.272069 -43.430373) (xy 334.288137 -43.48378) (xy 334.296257 -43.538956)
			(xy 334.296766 -43.566842) (xy 334.296257 -43.594728) (xy 334.288137 -43.649904) (xy 334.272069 -43.703311)
			(xy 334.248397 -43.753808) (xy 334.217624 -43.800321) (xy 334.180407 -43.841858) (xy 334.16232 -43.85691)
			(xy 334.919572 -43.85691) (xy 334.923643 -43.801288) (xy 334.935769 -43.746851) (xy 334.955692 -43.69476)
			(xy 334.982988 -43.646125) (xy 335.017074 -43.601982) (xy 335.057223 -43.563273) (xy 335.102581 -43.530822)
			(xy 335.152181 -43.505321) (xy 335.204965 -43.487314) (xy 335.259808 -43.477184) (xy 335.315542 -43.475147)
			(xy 335.370979 -43.481247) (xy 335.424936 -43.495353) (xy 335.476265 -43.517165) (xy 335.523871 -43.546219)
			(xy 335.566739 -43.581894) (xy 335.603956 -43.623431) (xy 335.634729 -43.669944) (xy 335.658401 -43.720441)
			(xy 335.674469 -43.773848) (xy 335.682589 -43.829024) (xy 335.683098 -43.85691) (xy 335.682589 -43.884796)
			(xy 335.674469 -43.939972) (xy 335.658401 -43.993379) (xy 335.634729 -44.043876) (xy 335.603956 -44.090389)
			(xy 335.566739 -44.131926) (xy 335.523871 -44.167601) (xy 335.476265 -44.196655) (xy 335.424936 -44.218467)
			(xy 335.370979 -44.232573) (xy 335.315542 -44.238673) (xy 335.259808 -44.236636) (xy 335.204965 -44.226506)
			(xy 335.152181 -44.208499) (xy 335.102581 -44.182998) (xy 335.057223 -44.150547) (xy 335.017074 -44.111838)
			(xy 334.982988 -44.067695) (xy 334.955692 -44.01906) (xy 334.935769 -43.966969) (xy 334.923643 -43.912532)
			(xy 334.919572 -43.85691) (xy 334.16232 -43.85691) (xy 334.137539 -43.877533) (xy 334.089933 -43.906587)
			(xy 334.038604 -43.928399) (xy 333.984647 -43.942505) (xy 333.92921 -43.948605) (xy 333.873476 -43.946568)
			(xy 333.818633 -43.936438) (xy 333.765849 -43.918431) (xy 333.716249 -43.89293) (xy 333.670891 -43.860479)
			(xy 333.630742 -43.82177) (xy 333.596656 -43.777627) (xy 333.56936 -43.728992) (xy 333.549437 -43.676901)
			(xy 333.537311 -43.622464) (xy 333.53324 -43.566842) (xy 331.136233 -43.566842) (xy 331.151679 -43.599791)
			(xy 331.167747 -43.653198) (xy 331.175867 -43.708374) (xy 331.176376 -43.73626) (xy 331.175867 -43.764146)
			(xy 331.167747 -43.819322) (xy 331.151679 -43.872729) (xy 331.128007 -43.923226) (xy 331.097234 -43.969739)
			(xy 331.060017 -44.011276) (xy 331.017149 -44.046951) (xy 330.969543 -44.076005) (xy 330.918214 -44.097817)
			(xy 330.864257 -44.111923) (xy 330.80882 -44.118023) (xy 330.753086 -44.115986) (xy 330.698243 -44.105856)
			(xy 330.645459 -44.087849) (xy 330.595859 -44.062348) (xy 330.550501 -44.029897) (xy 330.510352 -43.991188)
			(xy 330.476266 -43.947045) (xy 330.44897 -43.89841) (xy 330.429047 -43.846319) (xy 330.416921 -43.791882)
			(xy 330.41285 -43.73626) (xy 325.569366 -43.73626) (xy 325.280826 -45.114464) (xy 330.265276 -45.114464)
			(xy 330.269347 -45.058842) (xy 330.281473 -45.004405) (xy 330.301396 -44.952314) (xy 330.328692 -44.903679)
			(xy 330.362778 -44.859536) (xy 330.402927 -44.820827) (xy 330.448285 -44.788376) (xy 330.497885 -44.762875)
			(xy 330.550669 -44.744868) (xy 330.605512 -44.734738) (xy 330.661246 -44.732701) (xy 330.716683 -44.738801)
			(xy 330.77064 -44.752907) (xy 330.821969 -44.774719) (xy 330.869575 -44.803773) (xy 330.912443 -44.839448)
			(xy 330.942425 -44.87291) (xy 337.132928 -44.87291) (xy 337.136999 -44.817288) (xy 337.149125 -44.762851)
			(xy 337.169048 -44.71076) (xy 337.196344 -44.662125) (xy 337.23043 -44.617982) (xy 337.270579 -44.579273)
			(xy 337.315937 -44.546822) (xy 337.365537 -44.521321) (xy 337.418321 -44.503314) (xy 337.473164 -44.493184)
			(xy 337.528898 -44.491147) (xy 337.584335 -44.497247) (xy 337.638292 -44.511353) (xy 337.689621 -44.533165)
			(xy 337.737227 -44.562219) (xy 337.780095 -44.597894) (xy 337.817312 -44.639431) (xy 337.848085 -44.685944)
			(xy 337.871757 -44.736441) (xy 337.887825 -44.789848) (xy 337.895945 -44.845024) (xy 337.896454 -44.87291)
			(xy 337.895945 -44.900796) (xy 337.887825 -44.955972) (xy 337.871757 -45.009379) (xy 337.848085 -45.059876)
			(xy 337.817312 -45.106389) (xy 337.780095 -45.147926) (xy 337.737227 -45.183601) (xy 337.689621 -45.212655)
			(xy 337.638292 -45.234467) (xy 337.584335 -45.248573) (xy 337.528898 -45.254673) (xy 337.473164 -45.252636)
			(xy 337.418321 -45.242506) (xy 337.365537 -45.224499) (xy 337.315937 -45.198998) (xy 337.270579 -45.166547)
			(xy 337.23043 -45.127838) (xy 337.196344 -45.083695) (xy 337.169048 -45.03506) (xy 337.149125 -44.982969)
			(xy 337.136999 -44.928532) (xy 337.132928 -44.87291) (xy 330.942425 -44.87291) (xy 330.94966 -44.880985)
			(xy 330.980433 -44.927498) (xy 331.004105 -44.977995) (xy 331.020173 -45.031402) (xy 331.028293 -45.086578)
			(xy 331.028802 -45.114464) (xy 331.028293 -45.14235) (xy 331.020173 -45.197526) (xy 331.004105 -45.250933)
			(xy 330.980433 -45.30143) (xy 330.94966 -45.347943) (xy 330.944018 -45.35424) (xy 334.90357 -45.35424)
			(xy 334.907641 -45.298618) (xy 334.919767 -45.244181) (xy 334.93969 -45.19209) (xy 334.966986 -45.143455)
			(xy 335.001072 -45.099312) (xy 335.041221 -45.060603) (xy 335.086579 -45.028152) (xy 335.136179 -45.002651)
			(xy 335.188963 -44.984644) (xy 335.243806 -44.974514) (xy 335.29954 -44.972477) (xy 335.354977 -44.978577)
			(xy 335.408934 -44.992683) (xy 335.460263 -45.014495) (xy 335.507869 -45.043549) (xy 335.550737 -45.079224)
			(xy 335.587954 -45.120761) (xy 335.618727 -45.167274) (xy 335.642399 -45.217771) (xy 335.658467 -45.271178)
			(xy 335.666587 -45.326354) (xy 335.667096 -45.35424) (xy 335.666587 -45.382126) (xy 335.658467 -45.437302)
			(xy 335.642399 -45.490709) (xy 335.618727 -45.541206) (xy 335.587954 -45.587719) (xy 335.550737 -45.629256)
			(xy 335.507869 -45.664931) (xy 335.460263 -45.693985) (xy 335.408934 -45.715797) (xy 335.354977 -45.729903)
			(xy 335.29954 -45.736003) (xy 335.243806 -45.733966) (xy 335.188963 -45.723836) (xy 335.136179 -45.705829)
			(xy 335.086579 -45.680328) (xy 335.041221 -45.647877) (xy 335.001072 -45.609168) (xy 334.966986 -45.565025)
			(xy 334.93969 -45.51639) (xy 334.919767 -45.464299) (xy 334.907641 -45.409862) (xy 334.90357 -45.35424)
			(xy 330.944018 -45.35424) (xy 330.912443 -45.38948) (xy 330.869575 -45.425155) (xy 330.821969 -45.454209)
			(xy 330.77064 -45.476021) (xy 330.716683 -45.490127) (xy 330.661246 -45.496227) (xy 330.605512 -45.49419)
			(xy 330.550669 -45.48406) (xy 330.497885 -45.466053) (xy 330.448285 -45.440552) (xy 330.402927 -45.408101)
			(xy 330.362778 -45.369392) (xy 330.328692 -45.325249) (xy 330.301396 -45.276614) (xy 330.281473 -45.224523)
			(xy 330.269347 -45.170086) (xy 330.265276 -45.114464) (xy 325.280826 -45.114464) (xy 325.078221 -46.082204)
			(xy 328.252328 -46.082204) (xy 328.252759 -46.05495) (xy 328.260517 -46.000996) (xy 328.275874 -45.948695)
			(xy 328.298519 -45.899113) (xy 328.327989 -45.853258) (xy 328.363687 -45.812064) (xy 328.404883 -45.77637)
			(xy 328.450741 -45.746903) (xy 328.500325 -45.724263) (xy 328.552627 -45.70891) (xy 328.606582 -45.701157)
			(xy 328.633836 -45.700696) (xy 328.66074 -45.701131) (xy 328.714011 -45.708708) (xy 328.76569 -45.723692)
			(xy 328.814751 -45.745786) (xy 328.860224 -45.774553) (xy 328.901204 -45.809422) (xy 328.936881 -45.849701)
			(xy 328.952098 -45.871892) (xy 328.95921 -45.882814) (xy 328.98207 -45.894752) (xy 329.094338 -45.89272)
			(xy 329.11669 -45.879766) (xy 329.123548 -45.86859) (xy 329.13845 -45.844976) (xy 329.174133 -45.802024)
			(xy 329.215694 -45.764732) (xy 329.262247 -45.733896) (xy 329.312798 -45.710175) (xy 329.366266 -45.694075)
			(xy 329.42151 -45.68594) (xy 329.44943 -45.685456) (xy 329.476424 -45.6859) (xy 329.529873 -45.69351)
			(xy 329.581716 -45.708574) (xy 329.630921 -45.730792) (xy 329.676504 -45.75972) (xy 329.697334 -45.776896)
			(xy 329.705462 -45.784008) (xy 329.726036 -45.790104) (xy 329.81138 -45.779182) (xy 329.821925 -45.777408)
			(xy 329.840208 -45.766353) (xy 329.846686 -45.757846) (xy 329.862055 -45.736627) (xy 329.897639 -45.698174)
			(xy 329.938153 -45.664954) (xy 329.982834 -45.637594) (xy 330.03084 -45.616609) (xy 330.081266 -45.602393)
			(xy 330.133164 -45.595215) (xy 330.15936 -45.594778) (xy 330.186614 -45.595267) (xy 330.240567 -45.603019)
			(xy 330.292868 -45.618371) (xy 330.342451 -45.64101) (xy 330.388308 -45.670476) (xy 330.429503 -45.706168)
			(xy 330.4652 -45.74736) (xy 330.494671 -45.793214) (xy 330.517315 -45.842795) (xy 330.532673 -45.895094)
			(xy 330.540431 -45.949046) (xy 330.540431 -46.003554) (xy 330.532673 -46.057506) (xy 330.517315 -46.109805)
			(xy 330.494671 -46.159386) (xy 330.4652 -46.20524) (xy 330.429503 -46.246432) (xy 330.388308 -46.282124)
			(xy 330.342451 -46.31159) (xy 330.292868 -46.334229) (xy 330.240567 -46.349581) (xy 330.186614 -46.357333)
			(xy 330.15936 -46.357794) (xy 330.132366 -46.357344) (xy 330.078918 -46.349734) (xy 330.027075 -46.33467)
			(xy 329.977871 -46.312454) (xy 329.932287 -46.283528) (xy 329.911456 -46.266354) (xy 329.903328 -46.259242)
			(xy 329.882754 -46.253146) (xy 329.79741 -46.264068) (xy 329.786869 -46.265855) (xy 329.768586 -46.276902)
			(xy 329.762104 -46.285404) (xy 329.744487 -46.309701) (xy 329.702894 -46.352963) (xy 329.6793 -46.37151)
			(xy 329.671426 -46.377352) (xy 329.661012 -46.394878) (xy 329.647804 -46.485302) (xy 329.65263 -46.504606)
			(xy 329.658472 -46.51248) (xy 329.658472 -46.512734) (xy 329.675975 -46.537478) (xy 329.703777 -46.591331)
			(xy 329.722714 -46.648903) (xy 329.729917 -46.693836) (xy 334.87614 -46.693836) (xy 334.876626 -46.666585)
			(xy 334.884382 -46.612637) (xy 334.899737 -46.560342) (xy 334.922379 -46.510765) (xy 334.951845 -46.464915)
			(xy 334.987536 -46.423724) (xy 335.028727 -46.388033) (xy 335.074577 -46.358567) (xy 335.124154 -46.335925)
			(xy 335.176449 -46.32057) (xy 335.230397 -46.312814) (xy 335.284899 -46.312814) (xy 335.338847 -46.32057)
			(xy 335.391142 -46.335925) (xy 335.440719 -46.358567) (xy 335.486569 -46.388033) (xy 335.52776 -46.423724)
			(xy 335.563451 -46.464915) (xy 335.592917 -46.510765) (xy 335.615559 -46.560342) (xy 335.630914 -46.612637)
			(xy 335.63867 -46.666585) (xy 335.639156 -46.693836) (xy 335.638689 -46.720264) (xy 335.631379 -46.772612)
			(xy 335.616904 -46.823447) (xy 335.595542 -46.871793) (xy 335.582006 -46.894496) (xy 335.581752 -46.89475)
			(xy 335.576415 -46.904768) (xy 335.574158 -46.927318) (xy 335.577434 -46.938184) (xy 335.603596 -47.01286)
			(xy 335.60796 -47.023386) (xy 335.624062 -47.03947) (xy 335.634584 -47.043848) (xy 335.634838 -47.043848)
			(xy 335.659345 -47.052922) (xy 335.705798 -47.076864) (xy 335.74855 -47.106919) (xy 335.786802 -47.142525)
			(xy 335.819839 -47.183018) (xy 335.847043 -47.227638) (xy 335.867905 -47.275553) (xy 335.882035 -47.325866)
			(xy 335.889169 -47.377636) (xy 335.8896 -47.403766) (xy 335.889114 -47.431017) (xy 335.887591 -47.441612)
			(xy 337.16163 -47.441612) (xy 337.165701 -47.38599) (xy 337.177827 -47.331553) (xy 337.19775 -47.279462)
			(xy 337.225046 -47.230827) (xy 337.259132 -47.186684) (xy 337.299281 -47.147975) (xy 337.344639 -47.115524)
			(xy 337.394239 -47.090023) (xy 337.447023 -47.072016) (xy 337.501866 -47.061886) (xy 337.5576 -47.059849)
			(xy 337.613037 -47.065949) (xy 337.666994 -47.080055) (xy 337.718323 -47.101867) (xy 337.765929 -47.130921)
			(xy 337.808797 -47.166596) (xy 337.846014 -47.208133) (xy 337.876787 -47.254646) (xy 337.900459 -47.305143)
			(xy 337.916527 -47.35855) (xy 337.924647 -47.413726) (xy 337.925156 -47.441612) (xy 337.924647 -47.469498)
			(xy 337.916527 -47.524674) (xy 337.900459 -47.578081) (xy 337.876787 -47.628578) (xy 337.846014 -47.675091)
			(xy 337.808797 -47.716628) (xy 337.765929 -47.752303) (xy 337.718323 -47.781357) (xy 337.666994 -47.803169)
			(xy 337.613037 -47.817275) (xy 337.5576 -47.823375) (xy 337.501866 -47.821338) (xy 337.447023 -47.811208)
			(xy 337.394239 -47.793201) (xy 337.344639 -47.7677) (xy 337.299281 -47.735249) (xy 337.259132 -47.69654)
			(xy 337.225046 -47.652397) (xy 337.19775 -47.603762) (xy 337.177827 -47.551671) (xy 337.165701 -47.497234)
			(xy 337.16163 -47.441612) (xy 335.887591 -47.441612) (xy 335.881358 -47.484965) (xy 335.866003 -47.53726)
			(xy 335.843361 -47.586837) (xy 335.813895 -47.632687) (xy 335.778204 -47.673878) (xy 335.737013 -47.709569)
			(xy 335.691163 -47.739035) (xy 335.641586 -47.761677) (xy 335.589291 -47.777032) (xy 335.535343 -47.784788)
			(xy 335.480841 -47.784788) (xy 335.426893 -47.777032) (xy 335.374598 -47.761677) (xy 335.325021 -47.739035)
			(xy 335.279171 -47.709569) (xy 335.23798 -47.673878) (xy 335.202289 -47.632687) (xy 335.172823 -47.586837)
			(xy 335.150181 -47.53726) (xy 335.134826 -47.484965) (xy 335.12707 -47.431017) (xy 335.126584 -47.403766)
			(xy 335.12706 -47.377339) (xy 335.134369 -47.324991) (xy 335.148841 -47.274157) (xy 335.1702 -47.225809)
			(xy 335.183734 -47.203106) (xy 335.183988 -47.202852) (xy 335.189323 -47.192834) (xy 335.19158 -47.170284)
			(xy 335.188306 -47.159418) (xy 335.162144 -47.084742) (xy 335.157761 -47.074226) (xy 335.141672 -47.058138)
			(xy 335.131156 -47.053754) (xy 335.130902 -47.053754) (xy 335.106383 -47.044712) (xy 335.059932 -47.020764)
			(xy 335.017181 -46.990703) (xy 334.978931 -46.955091) (xy 334.945896 -46.914595) (xy 334.918694 -46.869971)
			(xy 334.897834 -46.822054) (xy 334.883705 -46.771739) (xy 334.876571 -46.719967) (xy 334.87614 -46.693836)
			(xy 329.729917 -46.693836) (xy 329.732307 -46.708745) (xy 329.732894 -46.739048) (xy 329.732467 -46.766301)
			(xy 329.724703 -46.820252) (xy 329.709341 -46.872548) (xy 329.686694 -46.922127) (xy 329.657221 -46.967977)
			(xy 329.621524 -47.009167) (xy 329.580328 -47.044858) (xy 329.534472 -47.074323) (xy 329.48489 -47.096963)
			(xy 329.432591 -47.112317) (xy 329.378639 -47.120071) (xy 329.351386 -47.120556) (xy 329.325352 -47.12011)
			(xy 329.27377 -47.113021) (xy 329.223628 -47.098992) (xy 329.175857 -47.078281) (xy 329.131342 -47.051272)
			(xy 329.110848 -47.035212) (xy 329.103084 -47.029482) (xy 329.084679 -47.023734) (xy 329.075034 -47.024036)
			(xy 328.995278 -47.030386) (xy 328.977498 -47.039022) (xy 328.971148 -47.046388) (xy 328.952966 -47.066033)
			(xy 328.912059 -47.100555) (xy 328.86673 -47.129024) (xy 328.817869 -47.150882) (xy 328.766433 -47.1657)
			(xy 328.713432 -47.173187) (xy 328.686668 -47.173642) (xy 328.659418 -47.173152) (xy 328.605472 -47.165392)
			(xy 328.553179 -47.150035) (xy 328.503604 -47.127392) (xy 328.457755 -47.097926) (xy 328.416566 -47.062235)
			(xy 328.380875 -47.021046) (xy 328.351409 -46.975198) (xy 328.328766 -46.925623) (xy 328.313408 -46.87333)
			(xy 328.305648 -46.819384) (xy 328.30516 -46.792134) (xy 328.305695 -46.76336) (xy 328.314345 -46.706467)
			(xy 328.33144 -46.651517) (xy 328.35659 -46.599757) (xy 328.389228 -46.55236) (xy 328.408538 -46.531022)
			(xy 328.415904 -46.523148) (xy 328.423016 -46.503336) (xy 328.41565 -46.40707) (xy 328.405744 -46.388274)
			(xy 328.397362 -46.38167) (xy 328.375186 -46.363435) (xy 328.335974 -46.321503) (xy 328.303486 -46.27417)
			(xy 328.278455 -46.222504) (xy 328.261448 -46.167671) (xy 328.252846 -46.110909) (xy 328.252328 -46.082204)
			(xy 325.078221 -46.082204) (xy 324.94347 -46.72584) (xy 324.747636 -47.68088) (xy 324.619318 -48.30699)
			(xy 334.75371 -48.30699) (xy 334.757781 -48.251368) (xy 334.769907 -48.196931) (xy 334.78983 -48.14484)
			(xy 334.817126 -48.096205) (xy 334.851212 -48.052062) (xy 334.891361 -48.013353) (xy 334.936719 -47.980902)
			(xy 334.986319 -47.955401) (xy 335.039103 -47.937394) (xy 335.093946 -47.927264) (xy 335.14968 -47.925227)
			(xy 335.205117 -47.931327) (xy 335.259074 -47.945433) (xy 335.310403 -47.967245) (xy 335.358009 -47.996299)
			(xy 335.400877 -48.031974) (xy 335.438094 -48.073511) (xy 335.468867 -48.120024) (xy 335.492539 -48.170521)
			(xy 335.508607 -48.223928) (xy 335.516727 -48.279104) (xy 335.517236 -48.30699) (xy 335.516727 -48.334876)
			(xy 335.508607 -48.390052) (xy 335.492539 -48.443459) (xy 335.468867 -48.493956) (xy 335.438094 -48.540469)
			(xy 335.400877 -48.582006) (xy 335.358009 -48.617681) (xy 335.310403 -48.646735) (xy 335.259074 -48.668547)
			(xy 335.205117 -48.682653) (xy 335.14968 -48.688753) (xy 335.093946 -48.686716) (xy 335.039103 -48.676586)
			(xy 334.986319 -48.658579) (xy 334.936719 -48.633078) (xy 334.891361 -48.600627) (xy 334.851212 -48.561918)
			(xy 334.817126 -48.517775) (xy 334.78983 -48.46914) (xy 334.769907 -48.417049) (xy 334.757781 -48.362612)
			(xy 334.75371 -48.30699) (xy 324.619318 -48.30699) (xy 324.527907 -48.753014) (xy 331.368144 -48.753014)
			(xy 331.372215 -48.697392) (xy 331.384341 -48.642955) (xy 331.404264 -48.590864) (xy 331.43156 -48.542229)
			(xy 331.465646 -48.498086) (xy 331.505795 -48.459377) (xy 331.551153 -48.426926) (xy 331.600753 -48.401425)
			(xy 331.653537 -48.383418) (xy 331.70838 -48.373288) (xy 331.764114 -48.371251) (xy 331.819551 -48.377351)
			(xy 331.873508 -48.391457) (xy 331.924837 -48.413269) (xy 331.972443 -48.442323) (xy 332.015311 -48.477998)
			(xy 332.052528 -48.519535) (xy 332.083301 -48.566048) (xy 332.106973 -48.616545) (xy 332.123041 -48.669952)
			(xy 332.131161 -48.725128) (xy 332.13167 -48.753014) (xy 332.131161 -48.7809) (xy 332.123041 -48.836076)
			(xy 332.120597 -48.8442) (xy 332.387192 -48.8442) (xy 332.391263 -48.788578) (xy 332.403389 -48.734141)
			(xy 332.423312 -48.68205) (xy 332.450608 -48.633415) (xy 332.484694 -48.589272) (xy 332.524843 -48.550563)
			(xy 332.570201 -48.518112) (xy 332.619801 -48.492611) (xy 332.672585 -48.474604) (xy 332.727428 -48.464474)
			(xy 332.783162 -48.462437) (xy 332.838599 -48.468537) (xy 332.892556 -48.482643) (xy 332.943885 -48.504455)
			(xy 332.991491 -48.533509) (xy 333.034359 -48.569184) (xy 333.071576 -48.610721) (xy 333.102349 -48.657234)
			(xy 333.126021 -48.707731) (xy 333.142089 -48.761138) (xy 333.150209 -48.816314) (xy 333.150718 -48.8442)
			(xy 333.150209 -48.872086) (xy 333.147211 -48.89246) (xy 333.41386 -48.89246) (xy 333.417931 -48.836838)
			(xy 333.430057 -48.782401) (xy 333.44998 -48.73031) (xy 333.477276 -48.681675) (xy 333.511362 -48.637532)
			(xy 333.551511 -48.598823) (xy 333.596869 -48.566372) (xy 333.646469 -48.540871) (xy 333.699253 -48.522864)
			(xy 333.754096 -48.512734) (xy 333.80983 -48.510697) (xy 333.865267 -48.516797) (xy 333.919224 -48.530903)
			(xy 333.970553 -48.552715) (xy 334.018159 -48.581769) (xy 334.061027 -48.617444) (xy 334.098244 -48.658981)
			(xy 334.129017 -48.705494) (xy 334.152689 -48.755991) (xy 334.168757 -48.809398) (xy 334.176877 -48.864574)
			(xy 334.177386 -48.89246) (xy 334.176877 -48.920346) (xy 334.174439 -48.93691) (xy 337.132928 -48.93691)
			(xy 337.136999 -48.881288) (xy 337.149125 -48.826851) (xy 337.169048 -48.77476) (xy 337.196344 -48.726125)
			(xy 337.23043 -48.681982) (xy 337.270579 -48.643273) (xy 337.315937 -48.610822) (xy 337.365537 -48.585321)
			(xy 337.418321 -48.567314) (xy 337.473164 -48.557184) (xy 337.528898 -48.555147) (xy 337.584335 -48.561247)
			(xy 337.638292 -48.575353) (xy 337.689621 -48.597165) (xy 337.737227 -48.626219) (xy 337.780095 -48.661894)
			(xy 337.817312 -48.703431) (xy 337.848085 -48.749944) (xy 337.871757 -48.800441) (xy 337.887825 -48.853848)
			(xy 337.895945 -48.909024) (xy 337.896454 -48.93691) (xy 337.895945 -48.964796) (xy 337.887825 -49.019972)
			(xy 337.871757 -49.073379) (xy 337.848085 -49.123876) (xy 337.817312 -49.170389) (xy 337.780095 -49.211926)
			(xy 337.737227 -49.247601) (xy 337.689621 -49.276655) (xy 337.638292 -49.298467) (xy 337.584335 -49.312573)
			(xy 337.528898 -49.318673) (xy 337.473164 -49.316636) (xy 337.418321 -49.306506) (xy 337.365537 -49.288499)
			(xy 337.315937 -49.262998) (xy 337.270579 -49.230547) (xy 337.23043 -49.191838) (xy 337.196344 -49.147695)
			(xy 337.169048 -49.09906) (xy 337.149125 -49.046969) (xy 337.136999 -48.992532) (xy 337.132928 -48.93691)
			(xy 334.174439 -48.93691) (xy 334.168757 -48.975522) (xy 334.152689 -49.028929) (xy 334.129017 -49.079426)
			(xy 334.098244 -49.125939) (xy 334.061027 -49.167476) (xy 334.018159 -49.203151) (xy 333.970553 -49.232205)
			(xy 333.919224 -49.254017) (xy 333.865267 -49.268123) (xy 333.80983 -49.274223) (xy 333.754096 -49.272186)
			(xy 333.699253 -49.262056) (xy 333.646469 -49.244049) (xy 333.596869 -49.218548) (xy 333.551511 -49.186097)
			(xy 333.511362 -49.147388) (xy 333.477276 -49.103245) (xy 333.44998 -49.05461) (xy 333.430057 -49.002519)
			(xy 333.417931 -48.948082) (xy 333.41386 -48.89246) (xy 333.147211 -48.89246) (xy 333.142089 -48.927262)
			(xy 333.126021 -48.980669) (xy 333.102349 -49.031166) (xy 333.071576 -49.077679) (xy 333.034359 -49.119216)
			(xy 332.991491 -49.154891) (xy 332.943885 -49.183945) (xy 332.892556 -49.205757) (xy 332.838599 -49.219863)
			(xy 332.783162 -49.225963) (xy 332.727428 -49.223926) (xy 332.672585 -49.213796) (xy 332.619801 -49.195789)
			(xy 332.570201 -49.170288) (xy 332.524843 -49.137837) (xy 332.484694 -49.099128) (xy 332.450608 -49.054985)
			(xy 332.423312 -49.00635) (xy 332.403389 -48.954259) (xy 332.391263 -48.899822) (xy 332.387192 -48.8442)
			(xy 332.120597 -48.8442) (xy 332.106973 -48.889483) (xy 332.083301 -48.93998) (xy 332.052528 -48.986493)
			(xy 332.015311 -49.02803) (xy 331.972443 -49.063705) (xy 331.924837 -49.092759) (xy 331.873508 -49.114571)
			(xy 331.819551 -49.128677) (xy 331.764114 -49.134777) (xy 331.70838 -49.13274) (xy 331.653537 -49.12261)
			(xy 331.600753 -49.104603) (xy 331.551153 -49.079102) (xy 331.505795 -49.046651) (xy 331.465646 -49.007942)
			(xy 331.43156 -48.963799) (xy 331.404264 -48.915164) (xy 331.384341 -48.863073) (xy 331.372215 -48.808636)
			(xy 331.368144 -48.753014) (xy 324.527907 -48.753014) (xy 324.38975 -49.42713) (xy 324.388988 -49.435258)
			(xy 324.388988 -49.95291) (xy 337.132928 -49.95291) (xy 337.136999 -49.897288) (xy 337.149125 -49.842851)
			(xy 337.169048 -49.79076) (xy 337.196344 -49.742125) (xy 337.23043 -49.697982) (xy 337.270579 -49.659273)
			(xy 337.315937 -49.626822) (xy 337.365537 -49.601321) (xy 337.418321 -49.583314) (xy 337.473164 -49.573184)
			(xy 337.528898 -49.571147) (xy 337.584335 -49.577247) (xy 337.638292 -49.591353) (xy 337.689621 -49.613165)
			(xy 337.737227 -49.642219) (xy 337.780095 -49.677894) (xy 337.817312 -49.719431) (xy 337.848085 -49.765944)
			(xy 337.871757 -49.816441) (xy 337.887825 -49.869848) (xy 337.895945 -49.925024) (xy 337.896454 -49.95291)
			(xy 337.895945 -49.980796) (xy 337.887825 -50.035972) (xy 337.871757 -50.089379) (xy 337.848085 -50.139876)
			(xy 337.817312 -50.186389) (xy 337.780095 -50.227926) (xy 337.737227 -50.263601) (xy 337.689621 -50.292655)
			(xy 337.638292 -50.314467) (xy 337.584335 -50.328573) (xy 337.528898 -50.334673) (xy 337.473164 -50.332636)
			(xy 337.418321 -50.322506) (xy 337.365537 -50.304499) (xy 337.315937 -50.278998) (xy 337.270579 -50.246547)
			(xy 337.23043 -50.207838) (xy 337.196344 -50.163695) (xy 337.169048 -50.11506) (xy 337.149125 -50.062969)
			(xy 337.136999 -50.008532) (xy 337.132928 -49.95291) (xy 324.388988 -49.95291) (xy 324.388988 -51.019456)
			(xy 334.94929 -51.019456) (xy 334.953361 -50.963834) (xy 334.965487 -50.909397) (xy 334.98541 -50.857306)
			(xy 335.012706 -50.808671) (xy 335.046792 -50.764528) (xy 335.086941 -50.725819) (xy 335.132299 -50.693368)
			(xy 335.181899 -50.667867) (xy 335.234683 -50.64986) (xy 335.289526 -50.63973) (xy 335.34526 -50.637693)
			(xy 335.400697 -50.643793) (xy 335.454654 -50.657899) (xy 335.505983 -50.679711) (xy 335.553589 -50.708765)
			(xy 335.596457 -50.74444) (xy 335.633674 -50.785977) (xy 335.664447 -50.83249) (xy 335.688119 -50.882987)
			(xy 335.704187 -50.936394) (xy 335.712307 -50.99157) (xy 335.712816 -51.019456) (xy 335.712307 -51.047342)
			(xy 335.704187 -51.102518) (xy 335.688119 -51.155925) (xy 335.664447 -51.206422) (xy 335.633674 -51.252935)
			(xy 335.596457 -51.294472) (xy 335.553589 -51.330147) (xy 335.505983 -51.359201) (xy 335.454654 -51.381013)
			(xy 335.400697 -51.395119) (xy 335.34526 -51.401219) (xy 335.289526 -51.399182) (xy 335.234683 -51.389052)
			(xy 335.181899 -51.371045) (xy 335.132299 -51.345544) (xy 335.086941 -51.313093) (xy 335.046792 -51.274384)
			(xy 335.012706 -51.230241) (xy 334.98541 -51.181606) (xy 334.965487 -51.129515) (xy 334.953361 -51.075078)
			(xy 334.94929 -51.019456) (xy 324.388988 -51.019456) (xy 324.388988 -52.035456) (xy 337.141056 -52.035456)
			(xy 337.145127 -51.979834) (xy 337.157253 -51.925397) (xy 337.177176 -51.873306) (xy 337.204472 -51.824671)
			(xy 337.238558 -51.780528) (xy 337.278707 -51.741819) (xy 337.324065 -51.709368) (xy 337.373665 -51.683867)
			(xy 337.426449 -51.66586) (xy 337.481292 -51.65573) (xy 337.537026 -51.653693) (xy 337.592463 -51.659793)
			(xy 337.64642 -51.673899) (xy 337.697749 -51.695711) (xy 337.745355 -51.724765) (xy 337.788223 -51.76044)
			(xy 337.82544 -51.801977) (xy 337.856213 -51.84849) (xy 337.879885 -51.898987) (xy 337.895953 -51.952394)
			(xy 337.904073 -52.00757) (xy 337.904582 -52.035456) (xy 337.904073 -52.063342) (xy 337.895953 -52.118518)
			(xy 337.879885 -52.171925) (xy 337.856213 -52.222422) (xy 337.82544 -52.268935) (xy 337.788223 -52.310472)
			(xy 337.745355 -52.346147) (xy 337.697749 -52.375201) (xy 337.64642 -52.397013) (xy 337.592463 -52.411119)
			(xy 337.537026 -52.417219) (xy 337.481292 -52.415182) (xy 337.426449 -52.405052) (xy 337.373665 -52.387045)
			(xy 337.324065 -52.361544) (xy 337.278707 -52.329093) (xy 337.238558 -52.290384) (xy 337.204472 -52.246241)
			(xy 337.177176 -52.197606) (xy 337.157253 -52.145515) (xy 337.145127 -52.091078) (xy 337.141056 -52.035456)
			(xy 324.388988 -52.035456) (xy 324.388988 -52.54752) (xy 324.389032 -52.551391) (xy 324.390174 -52.559048)
			(xy 324.391274 -52.56276) (xy 324.400164 -52.58816) (xy 324.405244 -52.594764) (xy 324.418278 -52.612325)
			(xy 324.440682 -52.649885) (xy 324.449948 -52.669694) (xy 324.460353 -52.693887) (xy 324.475148 -52.744429)
			(xy 324.48283 -52.796529) (xy 324.483476 -52.822856) (xy 324.483476 -52.826666) (xy 324.483063 -52.851921)
			(xy 324.47639 -52.901988) (xy 324.463171 -52.950737) (xy 324.443635 -52.997315) (xy 324.418124 -53.040909)
			(xy 324.402958 -53.061108) (xy 324.399402 -53.065426) (xy 324.394322 -53.075586) (xy 324.391865 -53.080913)
			(xy 324.389181 -53.092329) (xy 324.388988 -53.098192) (xy 324.388988 -53.18252) (xy 324.389032 -53.186391)
			(xy 324.390174 -53.194048) (xy 324.391274 -53.19776) (xy 324.400164 -53.22316) (xy 324.405244 -53.229764)
			(xy 324.42002 -53.249805) (xy 324.44481 -53.292989) (xy 324.463776 -53.339029) (xy 324.476596 -53.387143)
			(xy 324.483054 -53.436515) (xy 324.483476 -53.461412) (xy 324.483476 -53.465984) (xy 324.482493 -53.49701)
			(xy 324.471724 -53.558141) (xy 324.451228 -53.616731) (xy 324.421543 -53.671245) (xy 324.402958 -53.696108)
			(xy 324.402704 -53.696362) (xy 324.399402 -53.70068) (xy 324.391782 -53.71592) (xy 324.388988 -53.72735)
			(xy 324.388988 -53.81752) (xy 324.389032 -53.821391) (xy 324.390174 -53.829048) (xy 324.391274 -53.83276)
			(xy 324.400164 -53.85816) (xy 324.405244 -53.864764) (xy 324.42002 -53.884805) (xy 324.44481 -53.927989)
			(xy 324.463776 -53.974029) (xy 324.476596 -54.022143) (xy 324.483054 -54.071515) (xy 324.483476 -54.096412)
			(xy 324.483476 -54.100984) (xy 324.482493 -54.13201) (xy 324.471724 -54.193141) (xy 324.451228 -54.251731)
			(xy 324.421543 -54.306245) (xy 324.402958 -54.331108) (xy 324.402704 -54.331362) (xy 324.399402 -54.33568)
			(xy 324.391782 -54.35092) (xy 324.388988 -54.36235) (xy 324.388988 -54.45252) (xy 324.389032 -54.456391)
			(xy 324.390174 -54.464048) (xy 324.391274 -54.46776) (xy 324.400164 -54.49316) (xy 324.405244 -54.499764)
			(xy 324.42002 -54.519805) (xy 324.44481 -54.562989) (xy 324.463776 -54.609029) (xy 324.476596 -54.657143)
			(xy 324.483054 -54.706515) (xy 324.483476 -54.731412) (xy 324.483476 -54.735984) (xy 324.482746 -54.762138)
			(xy 324.478415 -54.791102) (xy 326.376284 -54.791102) (xy 326.376731 -54.763731) (xy 326.38455 -54.70955)
			(xy 326.400043 -54.657046) (xy 326.422889 -54.607299) (xy 326.45262 -54.561334) (xy 326.470264 -54.540404)
			(xy 326.470518 -54.54015) (xy 326.476092 -54.533055) (xy 326.482346 -54.516145) (xy 326.48271 -54.50713)
			(xy 326.48271 -54.440074) (xy 326.482363 -54.431056) (xy 326.476108 -54.414139) (xy 326.470518 -54.407054)
			(xy 326.470264 -54.407054) (xy 326.470264 -54.4068) (xy 326.452624 -54.385866) (xy 326.422896 -54.3399)
			(xy 326.400048 -54.290154) (xy 326.38455 -54.237652) (xy 326.376721 -54.183472) (xy 326.37672 -54.128731)
			(xy 326.38455 -54.074551) (xy 326.400047 -54.022049) (xy 326.422895 -53.972303) (xy 326.452622 -53.926336)
			(xy 326.470264 -53.905404) (xy 326.470518 -53.90515) (xy 326.476092 -53.898055) (xy 326.482346 -53.881145)
			(xy 326.48271 -53.87213) (xy 326.48271 -53.805074) (xy 326.482363 -53.796056) (xy 326.476108 -53.779139)
			(xy 326.470518 -53.772054) (xy 326.470264 -53.772054) (xy 326.470264 -53.7718) (xy 326.452624 -53.750866)
			(xy 326.422896 -53.7049) (xy 326.400048 -53.655154) (xy 326.38455 -53.602652) (xy 326.376721 -53.548472)
			(xy 326.37672 -53.493731) (xy 326.38455 -53.439551) (xy 326.400047 -53.387049) (xy 326.422895 -53.337303)
			(xy 326.452622 -53.291336) (xy 326.470264 -53.270404) (xy 326.470518 -53.27015) (xy 326.476092 -53.263055)
			(xy 326.482346 -53.246145) (xy 326.48271 -53.23713) (xy 326.48271 -53.170074) (xy 326.482363 -53.161056)
			(xy 326.476108 -53.144139) (xy 326.470518 -53.137054) (xy 326.470264 -53.137054) (xy 326.470264 -53.1368)
			(xy 326.452606 -53.115883) (xy 326.422898 -53.069906) (xy 326.400066 -53.020154) (xy 326.38458 -52.96765)
			(xy 326.376756 -52.913472) (xy 326.376284 -52.886102) (xy 326.37677 -52.858851) (xy 326.384526 -52.804903)
			(xy 326.399881 -52.752608) (xy 326.422523 -52.703031) (xy 326.451989 -52.657181) (xy 326.48768 -52.61599)
			(xy 326.528871 -52.580299) (xy 326.574721 -52.550833) (xy 326.624298 -52.528191) (xy 326.676593 -52.512836)
			(xy 326.730541 -52.50508) (xy 326.785043 -52.50508) (xy 326.838991 -52.512836) (xy 326.891286 -52.528191)
			(xy 326.930399 -52.546054) (xy 331.879373 -52.546054) (xy 331.879373 -52.491546) (xy 331.887131 -52.437594)
			(xy 331.902489 -52.385294) (xy 331.925134 -52.335713) (xy 331.954605 -52.28986) (xy 331.990302 -52.248668)
			(xy 332.031499 -52.212976) (xy 332.077356 -52.183511) (xy 332.126939 -52.160872) (xy 332.179241 -52.145521)
			(xy 332.233194 -52.13777) (xy 332.260448 -52.13731) (xy 332.287817 -52.137804) (xy 332.341995 -52.145615)
			(xy 332.394498 -52.161097) (xy 332.444245 -52.183933) (xy 332.490213 -52.213651) (xy 332.511146 -52.23129)
			(xy 332.5114 -52.231544) (xy 332.518479 -52.237142) (xy 332.535402 -52.243381) (xy 332.54442 -52.243736)
			(xy 332.611476 -52.243736) (xy 332.620491 -52.24336) (xy 332.637407 -52.237125) (xy 332.644496 -52.231544)
			(xy 332.644496 -52.23129) (xy 332.64475 -52.23129) (xy 332.665683 -52.213649) (xy 332.711651 -52.183925)
			(xy 332.761397 -52.161079) (xy 332.813899 -52.145583) (xy 332.868077 -52.137754) (xy 332.922819 -52.137754)
			(xy 332.976997 -52.145583) (xy 333.029499 -52.161079) (xy 333.079245 -52.183925) (xy 333.125213 -52.213649)
			(xy 333.146146 -52.23129) (xy 333.1464 -52.231544) (xy 333.153479 -52.237142) (xy 333.170402 -52.243381)
			(xy 333.17942 -52.243736) (xy 333.246476 -52.243736) (xy 333.255491 -52.24336) (xy 333.272407 -52.237125)
			(xy 333.279496 -52.231544) (xy 333.279496 -52.23129) (xy 333.27975 -52.23129) (xy 333.300689 -52.213659)
			(xy 333.34666 -52.183947) (xy 333.396406 -52.161109) (xy 333.448905 -52.145616) (xy 333.503079 -52.137785)
			(xy 333.530448 -52.13731) (xy 333.557698 -52.137763) (xy 333.611643 -52.145526) (xy 333.663935 -52.160886)
			(xy 333.713508 -52.18353) (xy 333.759355 -52.212999) (xy 333.800541 -52.248693) (xy 333.836229 -52.289884)
			(xy 333.865693 -52.335734) (xy 333.888331 -52.38531) (xy 333.903685 -52.437604) (xy 333.91144 -52.49155)
			(xy 333.91144 -52.54605) (xy 333.905496 -52.587398) (xy 334.955132 -52.587398) (xy 334.959203 -52.531776)
			(xy 334.971329 -52.477339) (xy 334.991252 -52.425248) (xy 335.018548 -52.376613) (xy 335.052634 -52.33247)
			(xy 335.092783 -52.293761) (xy 335.138141 -52.26131) (xy 335.187741 -52.235809) (xy 335.240525 -52.217802)
			(xy 335.295368 -52.207672) (xy 335.351102 -52.205635) (xy 335.406539 -52.211735) (xy 335.460496 -52.225841)
			(xy 335.511825 -52.247653) (xy 335.559431 -52.276707) (xy 335.602299 -52.312382) (xy 335.639516 -52.353919)
			(xy 335.670289 -52.400432) (xy 335.693961 -52.450929) (xy 335.710029 -52.504336) (xy 335.717625 -52.555948)
			(xy 354.884002 -52.555948) (xy 354.884002 -52.501452) (xy 354.891757 -52.44751) (xy 354.90711 -52.39522)
			(xy 354.929748 -52.345648) (xy 354.95921 -52.299802) (xy 354.994897 -52.258615) (xy 355.036081 -52.222926)
			(xy 355.081925 -52.193461) (xy 355.131496 -52.170819) (xy 355.183784 -52.155463) (xy 355.237726 -52.147704)
			(xy 355.264974 -52.147216) (xy 355.292344 -52.147693) (xy 355.346523 -52.155508) (xy 355.399026 -52.170994)
			(xy 355.448773 -52.193833) (xy 355.49474 -52.223556) (xy 355.515672 -52.241196) (xy 355.515926 -52.24145)
			(xy 355.523025 -52.247018) (xy 355.539932 -52.253275) (xy 355.548946 -52.253642) (xy 355.616002 -52.253642)
			(xy 355.62502 -52.253298) (xy 355.641938 -52.247043) (xy 355.649022 -52.24145) (xy 355.649022 -52.241196)
			(xy 355.649276 -52.241196) (xy 355.670206 -52.223554) (xy 355.716179 -52.193843) (xy 355.765927 -52.171007)
			(xy 355.818429 -52.155517) (xy 355.872605 -52.14769) (xy 355.899974 -52.147216) (xy 355.92723 -52.147629)
			(xy 355.981187 -52.155384) (xy 356.033491 -52.170738) (xy 356.083078 -52.193381) (xy 356.128937 -52.22285)
			(xy 356.170136 -52.258546) (xy 356.205834 -52.299742) (xy 356.235307 -52.345599) (xy 356.257953 -52.395184)
			(xy 356.273311 -52.447488) (xy 356.281069 -52.501444) (xy 356.281069 -52.555956) (xy 356.273311 -52.609912)
			(xy 356.257953 -52.662216) (xy 356.235307 -52.711801) (xy 356.205834 -52.757658) (xy 356.170136 -52.798854)
			(xy 356.128937 -52.83455) (xy 356.083078 -52.864019) (xy 356.033491 -52.886662) (xy 355.981187 -52.902016)
			(xy 355.92723 -52.909771) (xy 355.899974 -52.910232) (xy 355.872602 -52.909798) (xy 355.818421 -52.901975)
			(xy 355.765917 -52.886479) (xy 355.716171 -52.86363) (xy 355.670206 -52.833897) (xy 355.649276 -52.816252)
			(xy 355.649022 -52.815998) (xy 355.641933 -52.810414) (xy 355.625018 -52.804166) (xy 355.616002 -52.803806)
			(xy 355.548946 -52.803806) (xy 355.539931 -52.804184) (xy 355.523014 -52.810417) (xy 355.515926 -52.815998)
			(xy 355.515926 -52.816252) (xy 355.515672 -52.816252) (xy 355.494717 -52.833863) (xy 355.448752 -52.863581)
			(xy 355.39901 -52.886423) (xy 355.346514 -52.90192) (xy 355.292342 -52.909755) (xy 355.264974 -52.910232)
			(xy 355.237726 -52.909696) (xy 355.183784 -52.901937) (xy 355.131496 -52.886581) (xy 355.081925 -52.863939)
			(xy 355.036081 -52.834474) (xy 354.994897 -52.798785) (xy 354.95921 -52.757598) (xy 354.929748 -52.711752)
			(xy 354.90711 -52.66218) (xy 354.891757 -52.60989) (xy 354.884002 -52.555948) (xy 335.717625 -52.555948)
			(xy 335.718149 -52.559512) (xy 335.718658 -52.587398) (xy 335.718149 -52.615284) (xy 335.710029 -52.67046)
			(xy 335.693961 -52.723867) (xy 335.670289 -52.774364) (xy 335.639516 -52.820877) (xy 335.602299 -52.862414)
			(xy 335.559431 -52.898089) (xy 335.511825 -52.927143) (xy 335.460496 -52.948955) (xy 335.406539 -52.963061)
			(xy 335.351102 -52.969161) (xy 335.295368 -52.967124) (xy 335.240525 -52.956994) (xy 335.187741 -52.938987)
			(xy 335.138141 -52.913486) (xy 335.092783 -52.881035) (xy 335.052634 -52.842326) (xy 335.018548 -52.798183)
			(xy 334.991252 -52.749548) (xy 334.971329 -52.697457) (xy 334.959203 -52.64302) (xy 334.955132 -52.587398)
			(xy 333.905496 -52.587398) (xy 333.903685 -52.599996) (xy 333.888331 -52.65229) (xy 333.865693 -52.701866)
			(xy 333.836229 -52.747716) (xy 333.800541 -52.788907) (xy 333.759355 -52.824601) (xy 333.713508 -52.85407)
			(xy 333.663935 -52.876714) (xy 333.611643 -52.892074) (xy 333.557698 -52.899837) (xy 333.530448 -52.900326)
			(xy 333.503078 -52.89985) (xy 333.448899 -52.892037) (xy 333.396395 -52.876552) (xy 333.346648 -52.853712)
			(xy 333.300681 -52.823987) (xy 333.27975 -52.806346) (xy 333.279496 -52.806092) (xy 333.272415 -52.800497)
			(xy 333.255494 -52.794256) (xy 333.246476 -52.7939) (xy 333.17942 -52.7939) (xy 333.170404 -52.794266)
			(xy 333.153487 -52.800507) (xy 333.1464 -52.806092) (xy 333.146146 -52.806346) (xy 333.125213 -52.823987)
			(xy 333.079245 -52.853711) (xy 333.029499 -52.876557) (xy 332.976997 -52.892053) (xy 332.922819 -52.899882)
			(xy 332.868077 -52.899882) (xy 332.813899 -52.892053) (xy 332.761397 -52.876557) (xy 332.711651 -52.853711)
			(xy 332.665683 -52.823987) (xy 332.64475 -52.806346) (xy 332.644496 -52.806092) (xy 332.637415 -52.800497)
			(xy 332.620494 -52.794256) (xy 332.611476 -52.7939) (xy 332.54442 -52.7939) (xy 332.535404 -52.794266)
			(xy 332.518487 -52.800507) (xy 332.5114 -52.806092) (xy 332.5114 -52.806346) (xy 332.511146 -52.806346)
			(xy 332.4902 -52.823969) (xy 332.444232 -52.853685) (xy 332.394488 -52.876525) (xy 332.34199 -52.892019)
			(xy 332.287816 -52.899851) (xy 332.260448 -52.900326) (xy 332.233194 -52.89983) (xy 332.179241 -52.892079)
			(xy 332.126939 -52.876728) (xy 332.077356 -52.854089) (xy 332.031499 -52.824624) (xy 331.990302 -52.788932)
			(xy 331.954605 -52.74774) (xy 331.925134 -52.701887) (xy 331.902489 -52.652306) (xy 331.887131 -52.600006)
			(xy 331.879373 -52.546054) (xy 326.930399 -52.546054) (xy 326.940863 -52.550833) (xy 326.986713 -52.580299)
			(xy 327.027904 -52.61599) (xy 327.063595 -52.657181) (xy 327.093061 -52.703031) (xy 327.115703 -52.752608)
			(xy 327.131058 -52.804903) (xy 327.138814 -52.858851) (xy 327.1393 -52.886102) (xy 327.138835 -52.913472)
			(xy 327.131017 -52.967651) (xy 327.115528 -53.020155) (xy 327.092686 -53.069901) (xy 327.062961 -53.115868)
			(xy 327.04532 -53.1368) (xy 327.045066 -53.137054) (xy 327.039489 -53.144147) (xy 327.033238 -53.161059)
			(xy 327.032874 -53.170074) (xy 327.032874 -53.23713) (xy 327.033222 -53.246148) (xy 327.039476 -53.263064)
			(xy 327.045066 -53.27015) (xy 327.04532 -53.27015) (xy 327.04532 -53.270404) (xy 327.062961 -53.291336)
			(xy 327.092682 -53.337305) (xy 327.115524 -53.387052) (xy 327.131018 -53.439554) (xy 327.138846 -53.493731)
			(xy 327.138845 -53.548472) (xy 327.131018 -53.602649) (xy 327.115523 -53.655151) (xy 327.09268 -53.704897)
			(xy 327.062959 -53.750866) (xy 327.04639 -53.77053) (xy 327.410572 -53.77053) (xy 327.411084 -53.741613)
			(xy 327.419811 -53.68444) (xy 327.437068 -53.62924) (xy 327.462461 -53.577277) (xy 327.495407 -53.529744)
			(xy 327.535151 -53.487729) (xy 327.557638 -53.46954) (xy 327.566423 -53.461912) (xy 327.576617 -53.441027)
			(xy 327.577196 -53.429408) (xy 327.577196 -53.349652) (xy 327.576672 -53.338018) (xy 327.566473 -53.317109)
			(xy 327.557638 -53.30952) (xy 327.535172 -53.291308) (xy 327.495434 -53.249294) (xy 327.462492 -53.201764)
			(xy 327.4371 -53.149806) (xy 327.419841 -53.094612) (xy 327.411108 -53.037445) (xy 327.410572 -53.00853)
			(xy 327.411083 -52.981279) (xy 327.418836 -52.927331) (xy 327.434187 -52.875035) (xy 327.456824 -52.825456)
			(xy 327.486287 -52.779604) (xy 327.521976 -52.738411) (xy 327.563164 -52.702717) (xy 327.609012 -52.673248)
			(xy 327.658588 -52.650604) (xy 327.710882 -52.635246) (xy 327.764829 -52.627487) (xy 327.79208 -52.627022)
			(xy 327.818394 -52.627496) (xy 327.870522 -52.634728) (xy 327.921165 -52.649046) (xy 327.969364 -52.670177)
			(xy 328.014208 -52.697722) (xy 328.054848 -52.731161) (xy 328.073004 -52.750212) (xy 328.08052 -52.757619)
			(xy 328.099804 -52.76614) (xy 328.110342 -52.766722) (xy 328.185018 -52.766722) (xy 328.195563 -52.766155)
			(xy 328.214858 -52.757646) (xy 328.222356 -52.750212) (xy 328.240494 -52.731139) (xy 328.281127 -52.697683)
			(xy 328.325971 -52.670126) (xy 328.374175 -52.64899) (xy 328.424826 -52.634677) (xy 328.476963 -52.627458)
			(xy 328.50328 -52.627022) (xy 328.530534 -52.627474) (xy 328.584487 -52.635229) (xy 328.636787 -52.650584)
			(xy 328.686369 -52.673226) (xy 328.732223 -52.702695) (xy 328.773417 -52.73839) (xy 328.809111 -52.779585)
			(xy 328.838578 -52.82544) (xy 328.861219 -52.875023) (xy 328.876573 -52.927323) (xy 328.884327 -52.981276)
			(xy 328.884788 -53.00853) (xy 328.884305 -53.036196) (xy 328.876301 -53.090947) (xy 328.86048 -53.143969)
			(xy 328.837172 -53.194154) (xy 328.806866 -53.240449) (xy 328.770197 -53.281886) (xy 328.727931 -53.317598)
			(xy 328.704702 -53.332634) (xy 328.695021 -53.339266) (xy 328.682577 -53.35913) (xy 328.680826 -53.370734)
			(xy 328.672952 -53.450744) (xy 328.6723 -53.462383) (xy 328.680394 -53.484221) (xy 328.688446 -53.492654)
			(xy 328.6887 -53.492908) (xy 328.707267 -53.511003) (xy 328.739847 -53.551332) (xy 328.766662 -53.595703)
			(xy 328.787217 -53.643299) (xy 328.801133 -53.693241) (xy 328.808154 -53.744608) (xy 328.808588 -53.77053)
			(xy 328.80815 -53.797783) (xy 328.800389 -53.851733) (xy 328.785029 -53.90403) (xy 328.762383 -53.953609)
			(xy 328.732912 -53.99946) (xy 328.697215 -54.040651) (xy 328.65602 -54.076342) (xy 328.610165 -54.105807)
			(xy 328.560583 -54.128446) (xy 328.508284 -54.1438) (xy 328.454333 -54.151554) (xy 328.42708 -54.152038)
			(xy 328.399709 -54.151599) (xy 328.345528 -54.143777) (xy 328.293024 -54.128282) (xy 328.243277 -54.105434)
			(xy 328.197312 -54.075703) (xy 328.176382 -54.058058) (xy 328.176128 -54.057804) (xy 328.169037 -54.052223)
			(xy 328.152124 -54.045973) (xy 328.143108 -54.045612) (xy 328.076052 -54.045612) (xy 328.067037 -54.045991)
			(xy 328.05012 -54.052223) (xy 328.043032 -54.057804) (xy 328.043032 -54.058058) (xy 328.042778 -54.058058)
			(xy 328.021822 -54.075667) (xy 327.975856 -54.105385) (xy 327.926115 -54.128228) (xy 327.873619 -54.143725)
			(xy 327.819448 -54.151561) (xy 327.79208 -54.152038) (xy 327.76483 -54.151541) (xy 327.710884 -54.143782)
			(xy 327.658591 -54.128426) (xy 327.609016 -54.105785) (xy 327.563167 -54.076319) (xy 327.521978 -54.040629)
			(xy 327.486287 -53.999441) (xy 327.45682 -53.953593) (xy 327.434177 -53.904018) (xy 327.41882 -53.851726)
			(xy 327.41106 -53.79778) (xy 327.410572 -53.77053) (xy 327.04639 -53.77053) (xy 327.04532 -53.7718)
			(xy 327.045066 -53.772054) (xy 327.039489 -53.779147) (xy 327.033238 -53.796059) (xy 327.032874 -53.805074)
			(xy 327.032874 -53.87213) (xy 327.033222 -53.881148) (xy 327.039476 -53.898064) (xy 327.045066 -53.90515)
			(xy 327.04532 -53.90515) (xy 327.04532 -53.905404) (xy 327.062961 -53.926336) (xy 327.092682 -53.972305)
			(xy 327.115524 -54.022052) (xy 327.131018 -54.074554) (xy 327.138846 -54.128731) (xy 327.138845 -54.183472)
			(xy 327.131018 -54.237649) (xy 327.115523 -54.290151) (xy 327.101731 -54.320186) (xy 329.330304 -54.320186)
			(xy 329.330761 -54.292815) (xy 329.338581 -54.238636) (xy 329.354072 -54.186133) (xy 329.376916 -54.136386)
			(xy 329.406642 -54.090419) (xy 329.424284 -54.069488) (xy 329.424538 -54.069234) (xy 329.430121 -54.062145)
			(xy 329.436369 -54.04523) (xy 329.43673 -54.036214) (xy 329.43673 -53.969158) (xy 329.436339 -53.960145)
			(xy 329.430114 -53.943228) (xy 329.424538 -53.936138) (xy 329.424284 -53.936138) (xy 329.424284 -53.935884)
			(xy 329.406668 -53.914933) (xy 329.376954 -53.868965) (xy 329.354113 -53.819222) (xy 329.338617 -53.766726)
			(xy 329.330782 -53.712554) (xy 329.330304 -53.685186) (xy 329.33079 -53.657935) (xy 329.338546 -53.603987)
			(xy 329.353901 -53.551692) (xy 329.376543 -53.502115) (xy 329.406009 -53.456265) (xy 329.4417 -53.415074)
			(xy 329.482891 -53.379383) (xy 329.528741 -53.349917) (xy 329.578318 -53.327275) (xy 329.630613 -53.31192)
			(xy 329.684561 -53.304164) (xy 329.739063 -53.304164) (xy 329.793011 -53.31192) (xy 329.845306 -53.327275)
			(xy 329.894883 -53.349917) (xy 329.940733 -53.379383) (xy 329.981924 -53.415074) (xy 330.017615 -53.456265)
			(xy 330.047081 -53.502115) (xy 330.069723 -53.551692) (xy 330.085078 -53.603987) (xy 330.092834 -53.657935)
			(xy 330.09332 -53.685186) (xy 330.092865 -53.712557) (xy 330.085048 -53.766737) (xy 330.069557 -53.819241)
			(xy 330.046712 -53.868988) (xy 330.016984 -53.914954) (xy 329.99934 -53.935884) (xy 329.999086 -53.936138)
			(xy 329.993518 -53.943237) (xy 329.98726 -53.960144) (xy 329.986894 -53.969158) (xy 329.986894 -54.036214)
			(xy 329.987246 -54.045231) (xy 329.993497 -54.062148) (xy 329.999086 -54.069234) (xy 329.99934 -54.069234)
			(xy 329.99934 -54.069488) (xy 330.016994 -54.090408) (xy 330.046702 -54.136385) (xy 330.069535 -54.186136)
			(xy 330.085022 -54.238639) (xy 330.092848 -54.292816) (xy 330.09332 -54.320186) (xy 330.092834 -54.347437)
			(xy 330.085078 -54.401385) (xy 330.069723 -54.45368) (xy 330.047081 -54.503257) (xy 330.017615 -54.549107)
			(xy 329.981924 -54.590298) (xy 329.940733 -54.625989) (xy 329.894883 -54.655455) (xy 329.845306 -54.678097)
			(xy 329.793011 -54.693452) (xy 329.739063 -54.701208) (xy 329.684561 -54.701208) (xy 329.630613 -54.693452)
			(xy 329.578318 -54.678097) (xy 329.528741 -54.655455) (xy 329.482891 -54.625989) (xy 329.4417 -54.590298)
			(xy 329.406009 -54.549107) (xy 329.376543 -54.503257) (xy 329.353901 -54.45368) (xy 329.338546 -54.401385)
			(xy 329.33079 -54.347437) (xy 329.330304 -54.320186) (xy 327.101731 -54.320186) (xy 327.09268 -54.339897)
			(xy 327.062959 -54.385866) (xy 327.04532 -54.4068) (xy 327.045066 -54.407054) (xy 327.039489 -54.414147)
			(xy 327.033238 -54.431059) (xy 327.032874 -54.440074) (xy 327.032874 -54.50713) (xy 327.033222 -54.516148)
			(xy 327.039476 -54.533064) (xy 327.045066 -54.54015) (xy 327.04532 -54.54015) (xy 327.04532 -54.540404)
			(xy 327.062978 -54.561321) (xy 327.092686 -54.607298) (xy 327.115518 -54.65705) (xy 327.131005 -54.709554)
			(xy 327.138828 -54.763732) (xy 327.138945 -54.770528) (xy 330.270866 -54.770528) (xy 330.271332 -54.743158)
			(xy 330.279148 -54.688978) (xy 330.294636 -54.636474) (xy 330.317478 -54.586727) (xy 330.347204 -54.540761)
			(xy 330.364846 -54.51983) (xy 330.3651 -54.519576) (xy 330.370703 -54.5125) (xy 330.37694 -54.495575)
			(xy 330.377292 -54.486556) (xy 330.377292 -54.4195) (xy 330.376937 -54.410483) (xy 330.370688 -54.393566)
			(xy 330.3651 -54.38648) (xy 330.364846 -54.38648) (xy 330.364846 -54.386226) (xy 330.347213 -54.365289)
			(xy 330.317498 -54.319318) (xy 330.294661 -54.269572) (xy 330.279168 -54.217072) (xy 330.27134 -54.162897)
			(xy 330.270866 -54.135528) (xy 330.271352 -54.108277) (xy 330.279108 -54.054329) (xy 330.294463 -54.002034)
			(xy 330.317105 -53.952457) (xy 330.346571 -53.906607) (xy 330.382262 -53.865416) (xy 330.423453 -53.829725)
			(xy 330.469303 -53.800259) (xy 330.51888 -53.777617) (xy 330.571175 -53.762262) (xy 330.625123 -53.754506)
			(xy 330.679625 -53.754506) (xy 330.733573 -53.762262) (xy 330.785868 -53.777617) (xy 330.835445 -53.800259)
			(xy 330.881295 -53.829725) (xy 330.922486 -53.865416) (xy 330.958177 -53.906607) (xy 330.987643 -53.952457)
			(xy 330.992718 -53.96357) (xy 334.971896 -53.96357) (xy 334.975967 -53.907948) (xy 334.988093 -53.853511)
			(xy 335.008016 -53.80142) (xy 335.035312 -53.752785) (xy 335.069398 -53.708642) (xy 335.109547 -53.669933)
			(xy 335.154905 -53.637482) (xy 335.204505 -53.611981) (xy 335.257289 -53.593974) (xy 335.312132 -53.583844)
			(xy 335.367866 -53.581807) (xy 335.423303 -53.587907) (xy 335.47726 -53.602013) (xy 335.528589 -53.623825)
			(xy 335.576195 -53.652879) (xy 335.619063 -53.688554) (xy 335.65628 -53.730091) (xy 335.687053 -53.776604)
			(xy 335.710725 -53.827101) (xy 335.726793 -53.880508) (xy 335.734913 -53.935684) (xy 335.735422 -53.96357)
			(xy 335.734913 -53.991456) (xy 335.726793 -54.046632) (xy 335.710725 -54.100039) (xy 335.687053 -54.150536)
			(xy 335.65628 -54.197049) (xy 335.619063 -54.238586) (xy 335.576195 -54.274261) (xy 335.528589 -54.303315)
			(xy 335.47726 -54.325127) (xy 335.423303 -54.339233) (xy 335.367866 -54.345333) (xy 335.312132 -54.343296)
			(xy 335.257289 -54.333166) (xy 335.204505 -54.315159) (xy 335.154905 -54.289658) (xy 335.109547 -54.257207)
			(xy 335.069398 -54.218498) (xy 335.035312 -54.174355) (xy 335.008016 -54.12572) (xy 334.988093 -54.073629)
			(xy 334.975967 -54.019192) (xy 334.971896 -53.96357) (xy 330.992718 -53.96357) (xy 331.010285 -54.002034)
			(xy 331.02564 -54.054329) (xy 331.033396 -54.108277) (xy 331.033882 -54.135528) (xy 331.033437 -54.162899)
			(xy 331.025615 -54.217079) (xy 331.010121 -54.269583) (xy 330.987274 -54.319329) (xy 330.957545 -54.365295)
			(xy 330.939902 -54.386226) (xy 330.939648 -54.38648) (xy 330.934057 -54.393564) (xy 330.927814 -54.410483)
			(xy 330.927456 -54.4195) (xy 330.927456 -54.486556) (xy 330.927822 -54.495572) (xy 330.934062 -54.51249)
			(xy 330.939648 -54.519576) (xy 330.939902 -54.519576) (xy 330.939902 -54.51983) (xy 330.957522 -54.540777)
			(xy 330.987237 -54.586746) (xy 331.010076 -54.63649) (xy 331.025572 -54.688987) (xy 331.033405 -54.74316)
			(xy 331.033882 -54.770528) (xy 331.033396 -54.797779) (xy 331.02564 -54.851727) (xy 331.010285 -54.904022)
			(xy 330.987643 -54.953599) (xy 330.958177 -54.999449) (xy 330.922486 -55.04064) (xy 330.881295 -55.076331)
			(xy 330.835445 -55.105797) (xy 330.785868 -55.128439) (xy 330.733573 -55.143794) (xy 330.679625 -55.15155)
			(xy 330.625123 -55.15155) (xy 330.571175 -55.143794) (xy 330.51888 -55.128439) (xy 330.469303 -55.105797)
			(xy 330.423453 -55.076331) (xy 330.382262 -55.04064) (xy 330.346571 -54.999449) (xy 330.317105 -54.953599)
			(xy 330.294463 -54.904022) (xy 330.279108 -54.851727) (xy 330.271352 -54.797779) (xy 330.270866 -54.770528)
			(xy 327.138945 -54.770528) (xy 327.1393 -54.791102) (xy 327.138814 -54.818353) (xy 327.131058 -54.872301)
			(xy 327.115703 -54.924596) (xy 327.093061 -54.974173) (xy 327.063595 -55.020023) (xy 327.027904 -55.061214)
			(xy 326.986713 -55.096905) (xy 326.940863 -55.126371) (xy 326.891286 -55.149013) (xy 326.838991 -55.164368)
			(xy 326.785043 -55.172124) (xy 326.730541 -55.172124) (xy 326.676593 -55.164368) (xy 326.624298 -55.149013)
			(xy 326.574721 -55.126371) (xy 326.528871 -55.096905) (xy 326.48768 -55.061214) (xy 326.451989 -55.020023)
			(xy 326.422523 -54.974173) (xy 326.399881 -54.924596) (xy 326.384526 -54.872301) (xy 326.37677 -54.818353)
			(xy 326.376284 -54.791102) (xy 324.478415 -54.791102) (xy 324.475009 -54.813885) (xy 324.46028 -54.864092)
			(xy 324.449948 -54.88813) (xy 324.446646 -54.895242) (xy 324.44055 -54.907688) (xy 324.439026 -54.910736)
			(xy 324.43164 -54.924266) (xy 324.414981 -54.950205) (xy 324.405752 -54.962552) (xy 324.400164 -54.969664)
			(xy 324.391274 -54.995064) (xy 324.390207 -54.998783) (xy 324.389059 -55.006435) (xy 324.388988 -55.010304)
			(xy 324.388988 -55.722266) (xy 336.03387 -55.722266) (xy 336.037941 -55.666644) (xy 336.050067 -55.612207)
			(xy 336.06999 -55.560116) (xy 336.097286 -55.511481) (xy 336.131372 -55.467338) (xy 336.171521 -55.428629)
			(xy 336.216879 -55.396178) (xy 336.266479 -55.370677) (xy 336.319263 -55.35267) (xy 336.374106 -55.34254)
			(xy 336.42984 -55.340503) (xy 336.485277 -55.346603) (xy 336.539234 -55.360709) (xy 336.590563 -55.382521)
			(xy 336.638169 -55.411575) (xy 336.681037 -55.44725) (xy 336.718254 -55.488787) (xy 336.749027 -55.5353)
			(xy 336.772699 -55.585797) (xy 336.788767 -55.639204) (xy 336.796887 -55.69438) (xy 336.797396 -55.722266)
			(xy 336.796887 -55.750152) (xy 336.788767 -55.805328) (xy 336.772699 -55.858735) (xy 336.749027 -55.909232)
			(xy 336.718254 -55.955745) (xy 336.681037 -55.997282) (xy 336.638169 -56.032957) (xy 336.590563 -56.062011)
			(xy 336.539234 -56.083823) (xy 336.485277 -56.097929) (xy 336.42984 -56.104029) (xy 336.374106 -56.101992)
			(xy 336.319263 -56.091862) (xy 336.266479 -56.073855) (xy 336.216879 -56.048354) (xy 336.171521 -56.015903)
			(xy 336.131372 -55.977194) (xy 336.097286 -55.933051) (xy 336.06999 -55.884416) (xy 336.050067 -55.832325)
			(xy 336.037941 -55.777888) (xy 336.03387 -55.722266) (xy 324.388988 -55.722266) (xy 324.388988 -55.923434)
			(xy 324.389242 -55.927244) (xy 324.389242 -55.93334) (xy 324.389496 -55.949596) (xy 324.389496 -55.950104)
			(xy 324.389496 -55.950866) (xy 324.389242 -55.968138) (xy 324.389242 -55.970678) (xy 324.388988 -55.973472)
			(xy 324.383654 -56.207914) (xy 324.37832 -56.438546) (xy 324.376034 -56.532272) (xy 324.376034 -56.542686)
			(xy 324.385178 -56.566054) (xy 324.386815 -56.569961) (xy 324.391153 -56.577236) (xy 324.393814 -56.580532)
			(xy 324.396862 -56.584088) (xy 324.397624 -56.585104) (xy 324.39864 -56.586374) (xy 324.398894 -56.586628)
			(xy 324.416799 -56.609677) (xy 324.446129 -56.660134) (xy 324.467429 -56.714471) (xy 324.480203 -56.771418)
			(xy 324.482714 -56.800496) (xy 324.483476 -56.82234) (xy 324.483476 -56.82742) (xy 324.482881 -56.855806)
			(xy 324.474325 -56.911932) (xy 324.457554 -56.966173) (xy 324.439865 -57.002934) (xy 331.76337 -57.002934)
			(xy 331.763897 -56.974844) (xy 331.772119 -56.919268) (xy 331.788405 -56.8655) (xy 331.812403 -56.814703)
			(xy 331.843592 -56.767976) (xy 331.881299 -56.72633) (xy 331.924708 -56.690666) (xy 331.948536 -56.675782)
			(xy 331.957426 -56.670448) (xy 331.969618 -56.65343) (xy 331.989938 -56.560212) (xy 331.98562 -56.539638)
			(xy 331.979778 -56.531002) (xy 331.963774 -56.506941) (xy 331.938433 -56.455008) (xy 331.921208 -56.399849)
			(xy 331.912494 -56.342725) (xy 331.91196 -56.313832) (xy 331.912508 -56.286583) (xy 331.920259 -56.232639)
			(xy 331.935609 -56.180348) (xy 331.958244 -56.130773) (xy 331.987704 -56.084924) (xy 332.023389 -56.043734)
			(xy 332.064572 -56.008042) (xy 332.110416 -55.978574) (xy 332.159988 -55.955931) (xy 332.212277 -55.940573)
			(xy 332.266219 -55.932812) (xy 332.293468 -55.932324) (xy 332.320838 -55.932803) (xy 332.375017 -55.940617)
			(xy 332.42752 -55.956103) (xy 332.477267 -55.978942) (xy 332.523234 -56.008664) (xy 332.544166 -56.026304)
			(xy 332.54442 -56.026558) (xy 332.551492 -56.032166) (xy 332.56842 -56.038398) (xy 332.57744 -56.03875)
			(xy 332.644496 -56.03875) (xy 332.653514 -56.038402) (xy 332.670431 -56.032149) (xy 332.677516 -56.026558)
			(xy 332.677516 -56.026304) (xy 332.67777 -56.026304) (xy 332.698703 -56.008663) (xy 332.744671 -55.978939)
			(xy 332.794417 -55.956093) (xy 332.846919 -55.940597) (xy 332.901097 -55.932768) (xy 332.955839 -55.932768)
			(xy 333.010017 -55.940597) (xy 333.062519 -55.956093) (xy 333.112265 -55.978939) (xy 333.158233 -56.008663)
			(xy 333.179166 -56.026304) (xy 333.17942 -56.026558) (xy 333.186492 -56.032166) (xy 333.20342 -56.038398)
			(xy 333.21244 -56.03875) (xy 333.279496 -56.03875) (xy 333.288514 -56.038402) (xy 333.305431 -56.032149)
			(xy 333.312516 -56.026558) (xy 333.312516 -56.026304) (xy 333.31277 -56.026304) (xy 333.333703 -56.008666)
			(xy 333.379676 -55.978954) (xy 333.429423 -55.956118) (xy 333.481923 -55.940626) (xy 333.536099 -55.932798)
			(xy 333.563468 -55.932324) (xy 333.590725 -55.932721) (xy 333.644684 -55.940475) (xy 333.69699 -55.955829)
			(xy 333.746578 -55.978472) (xy 333.792439 -56.007941) (xy 333.833639 -56.043638) (xy 333.869339 -56.084835)
			(xy 333.898813 -56.130694) (xy 333.92146 -56.18028) (xy 333.936819 -56.232585) (xy 333.944577 -56.286543)
			(xy 333.944577 -56.297068) (xy 334.28635 -56.297068) (xy 334.290421 -56.241446) (xy 334.302547 -56.187009)
			(xy 334.32247 -56.134918) (xy 334.349766 -56.086283) (xy 334.383852 -56.04214) (xy 334.424001 -56.003431)
			(xy 334.469359 -55.97098) (xy 334.518959 -55.945479) (xy 334.571743 -55.927472) (xy 334.626586 -55.917342)
			(xy 334.68232 -55.915305) (xy 334.737757 -55.921405) (xy 334.791714 -55.935511) (xy 334.843043 -55.957323)
			(xy 334.890649 -55.986377) (xy 334.933517 -56.022052) (xy 334.970734 -56.063589) (xy 335.001507 -56.110102)
			(xy 335.025179 -56.160599) (xy 335.041247 -56.214006) (xy 335.049367 -56.269182) (xy 335.049876 -56.297068)
			(xy 335.049367 -56.324954) (xy 335.041247 -56.38013) (xy 335.025179 -56.433537) (xy 335.001507 -56.484034)
			(xy 334.970734 -56.530547) (xy 334.933517 -56.572084) (xy 334.890649 -56.607759) (xy 334.843043 -56.636813)
			(xy 334.791714 -56.658625) (xy 334.737757 -56.672731) (xy 334.68232 -56.678831) (xy 334.626586 -56.676794)
			(xy 334.571743 -56.666664) (xy 334.518959 -56.648657) (xy 334.469359 -56.623156) (xy 334.424001 -56.590705)
			(xy 334.383852 -56.551996) (xy 334.349766 -56.507853) (xy 334.32247 -56.459218) (xy 334.302547 -56.407127)
			(xy 334.290421 -56.35269) (xy 334.28635 -56.297068) (xy 333.944577 -56.297068) (xy 333.944577 -56.341057)
			(xy 333.936819 -56.395015) (xy 333.92146 -56.44732) (xy 333.898813 -56.496906) (xy 333.869339 -56.542765)
			(xy 333.833639 -56.583962) (xy 333.792439 -56.619659) (xy 333.746578 -56.649128) (xy 333.69699 -56.671771)
			(xy 333.644684 -56.687125) (xy 333.590725 -56.694879) (xy 333.563468 -56.69534) (xy 333.536096 -56.694907)
			(xy 333.481915 -56.687084) (xy 333.429411 -56.671588) (xy 333.379665 -56.648738) (xy 333.3337 -56.619005)
			(xy 333.31277 -56.60136) (xy 333.312516 -56.601106) (xy 333.305429 -56.595521) (xy 333.288512 -56.589273)
			(xy 333.279496 -56.588914) (xy 333.21244 -56.588914) (xy 333.203425 -56.589287) (xy 333.186508 -56.595523)
			(xy 333.17942 -56.601106) (xy 333.17942 -56.60136) (xy 333.179166 -56.60136) (xy 333.158233 -56.619001)
			(xy 333.112265 -56.648725) (xy 333.062519 -56.671571) (xy 333.010017 -56.687067) (xy 332.955839 -56.694896)
			(xy 332.901097 -56.694896) (xy 332.846919 -56.687067) (xy 332.794417 -56.671571) (xy 332.744671 -56.648725)
			(xy 332.698703 -56.619001) (xy 332.67777 -56.60136) (xy 332.677516 -56.601106) (xy 332.670429 -56.595521)
			(xy 332.653512 -56.589273) (xy 332.644496 -56.588914) (xy 332.57744 -56.588914) (xy 332.568425 -56.589287)
			(xy 332.551508 -56.595523) (xy 332.54442 -56.601106) (xy 332.543912 -56.60136) (xy 332.531181 -56.612308)
			(xy 332.504087 -56.632147) (xy 332.48981 -56.640984) (xy 332.48092 -56.646318) (xy 332.468728 -56.663336)
			(xy 332.448408 -56.756554) (xy 332.452726 -56.777128) (xy 332.458568 -56.785764) (xy 332.474551 -56.809839)
			(xy 332.499899 -56.861766) (xy 332.517129 -56.916921) (xy 332.525849 -56.974042) (xy 332.526386 -57.002934)
			(xy 332.5259 -57.030185) (xy 332.518144 -57.084133) (xy 332.502789 -57.136428) (xy 332.480147 -57.186005)
			(xy 332.450681 -57.231855) (xy 332.41499 -57.273046) (xy 332.373799 -57.308737) (xy 332.327949 -57.338203)
			(xy 332.278372 -57.360845) (xy 332.226077 -57.3762) (xy 332.172129 -57.383956) (xy 332.117627 -57.383956)
			(xy 332.063679 -57.3762) (xy 332.011384 -57.360845) (xy 331.961807 -57.338203) (xy 331.915957 -57.308737)
			(xy 331.874766 -57.273046) (xy 331.839075 -57.231855) (xy 331.809609 -57.186005) (xy 331.786967 -57.136428)
			(xy 331.771612 -57.084133) (xy 331.763856 -57.030185) (xy 331.76337 -57.002934) (xy 324.439865 -57.002934)
			(xy 324.432937 -57.017333) (xy 324.401017 -57.064285) (xy 324.38213 -57.085484) (xy 324.376034 -57.092088)
			(xy 324.363842 -57.12079) (xy 324.362826 -57.126378) (xy 324.36181 -57.135268) (xy 324.361302 -57.15889)
			(xy 324.361048 -57.169304) (xy 324.368414 -57.1881) (xy 324.375526 -57.195466) (xy 324.395642 -57.216937)
			(xy 324.429692 -57.264916) (xy 324.455972 -57.317554) (xy 324.47386 -57.373603) (xy 324.48293 -57.431733)
			(xy 324.483476 -57.46115) (xy 324.483476 -57.46242) (xy 324.483222 -57.478422) (xy 324.482968 -57.48274)
			(xy 324.482968 -57.483248) (xy 324.481144 -57.508247) (xy 324.471748 -57.557482) (xy 324.455971 -57.605058)
			(xy 324.445376 -57.627774) (xy 324.439026 -57.640982) (xy 324.434454 -57.648856) (xy 324.4342 -57.64911)
			(xy 324.430898 -57.654952) (xy 324.417082 -57.677731) (xy 324.38406 -57.719536) (xy 324.365112 -57.738264)
			(xy 324.357492 -57.74563) (xy 324.349364 -57.764426) (xy 324.349364 -57.777634) (xy 324.349451 -57.782045)
			(xy 324.350982 -57.790732) (xy 324.352412 -57.794906) (xy 324.362064 -57.81675) (xy 324.368922 -57.823608)
			(xy 324.390059 -57.845112) (xy 324.425961 -57.893553) (xy 324.453797 -57.947038) (xy 324.472876 -58.004235)
			(xy 324.482723 -58.063721) (xy 324.483476 -58.093864) (xy 324.483476 -58.096404) (xy 324.482968 -58.118248)
			(xy 324.482714 -58.121042) (xy 324.482714 -58.121804) (xy 324.481444 -58.135266) (xy 324.481444 -58.136282)
			(xy 324.480428 -58.14568) (xy 324.480428 -58.145934) (xy 324.480174 -58.147204) (xy 324.47992 -58.149744)
			(xy 324.47992 -58.149998) (xy 324.475405 -58.178128) (xy 324.459111 -58.232717) (xy 324.434864 -58.284269)
			(xy 324.419468 -58.30824) (xy 324.41388 -58.316368) (xy 324.410832 -58.320686) (xy 324.404736 -58.329068)
			(xy 324.400418 -58.334148) (xy 324.395846 -58.341514) (xy 324.39483 -58.343546) (xy 324.392368 -58.348872)
			(xy 324.389675 -58.360288) (xy 324.389496 -58.366152) (xy 324.389496 -58.387234) (xy 324.389353 -58.392673)
			(xy 324.387045 -58.403305) (xy 324.384924 -58.408316) (xy 324.378574 -58.420508) (xy 324.376409 -58.425446)
			(xy 324.373978 -58.435949) (xy 324.373748 -58.441336) (xy 324.373748 -58.444892) (xy 324.374256 -58.450734)
			(xy 324.375526 -58.457338) (xy 324.382384 -58.471816) (xy 324.38721 -58.47715) (xy 324.405282 -58.498237)
			(xy 324.435773 -58.54465) (xy 324.45923 -58.594985) (xy 324.475157 -58.648185) (xy 324.479729 -58.679334)
			(xy 332.19517 -58.679334) (xy 332.195603 -58.653019) (xy 332.202846 -58.600889) (xy 332.217173 -58.550246)
			(xy 332.238312 -58.502048) (xy 332.265863 -58.457205) (xy 332.299307 -58.416566) (xy 332.31836 -58.39841)
			(xy 332.325753 -58.390881) (xy 332.334284 -58.371607) (xy 332.33487 -58.361072) (xy 332.33487 -58.286396)
			(xy 332.334365 -58.275843) (xy 332.325814 -58.256548) (xy 332.31836 -58.249058) (xy 332.299283 -58.230924)
			(xy 332.26583 -58.190289) (xy 332.238274 -58.145444) (xy 332.21714 -58.097239) (xy 332.202827 -58.046588)
			(xy 332.195606 -57.994451) (xy 332.19517 -57.968134) (xy 332.195656 -57.940883) (xy 332.203412 -57.886935)
			(xy 332.218767 -57.83464) (xy 332.241409 -57.785063) (xy 332.270875 -57.739213) (xy 332.306566 -57.698022)
			(xy 332.347757 -57.662331) (xy 332.393607 -57.632865) (xy 332.443184 -57.610223) (xy 332.495479 -57.594868)
			(xy 332.549427 -57.587112) (xy 332.603929 -57.587112) (xy 332.657877 -57.594868) (xy 332.710172 -57.610223)
			(xy 332.759749 -57.632865) (xy 332.805599 -57.662331) (xy 332.84679 -57.698022) (xy 332.882481 -57.739213)
			(xy 332.911947 -57.785063) (xy 332.934589 -57.83464) (xy 332.949944 -57.886935) (xy 332.9577 -57.940883)
			(xy 332.958186 -57.968134) (xy 332.957746 -57.994449) (xy 332.950506 -58.046579) (xy 332.943238 -58.072274)
			(xy 336.193382 -58.072274) (xy 336.197453 -58.016652) (xy 336.209579 -57.962215) (xy 336.229502 -57.910124)
			(xy 336.256798 -57.861489) (xy 336.290884 -57.817346) (xy 336.331033 -57.778637) (xy 336.376391 -57.746186)
			(xy 336.425991 -57.720685) (xy 336.478775 -57.702678) (xy 336.533618 -57.692548) (xy 336.589352 -57.690511)
			(xy 336.644789 -57.696611) (xy 336.698746 -57.710717) (xy 336.750075 -57.732529) (xy 336.797681 -57.761583)
			(xy 336.840549 -57.797258) (xy 336.877766 -57.838795) (xy 336.908539 -57.885308) (xy 336.932211 -57.935805)
			(xy 336.948279 -57.989212) (xy 336.956399 -58.044388) (xy 336.956908 -58.072274) (xy 336.956399 -58.10016)
			(xy 336.948279 -58.155336) (xy 336.932211 -58.208743) (xy 336.908539 -58.25924) (xy 336.877766 -58.305753)
			(xy 336.840549 -58.34729) (xy 336.797681 -58.382965) (xy 336.750075 -58.412019) (xy 336.698746 -58.433831)
			(xy 336.644789 -58.447937) (xy 336.589352 -58.454037) (xy 336.533618 -58.452) (xy 336.478775 -58.44187)
			(xy 336.425991 -58.423863) (xy 336.376391 -58.398362) (xy 336.331033 -58.365911) (xy 336.290884 -58.327202)
			(xy 336.256798 -58.283059) (xy 336.229502 -58.234424) (xy 336.209579 -58.182333) (xy 336.197453 -58.127896)
			(xy 336.193382 -58.072274) (xy 332.943238 -58.072274) (xy 332.936182 -58.097222) (xy 332.915044 -58.145421)
			(xy 332.887493 -58.190264) (xy 332.85405 -58.230902) (xy 332.834996 -58.249058) (xy 332.82761 -58.256593)
			(xy 332.819077 -58.275863) (xy 332.818486 -58.286396) (xy 332.818486 -58.361072) (xy 332.819021 -58.371621)
			(xy 332.827553 -58.390916) (xy 332.834996 -58.39841) (xy 332.854049 -58.416569) (xy 332.887506 -58.457197)
			(xy 332.915066 -58.502037) (xy 332.936205 -58.550237) (xy 332.950522 -58.600884) (xy 332.957747 -58.653018)
			(xy 332.958186 -58.679334) (xy 332.9577 -58.706585) (xy 332.949944 -58.760533) (xy 332.934589 -58.812828)
			(xy 332.911947 -58.862405) (xy 332.882481 -58.908255) (xy 332.84679 -58.949446) (xy 332.805599 -58.985137)
			(xy 332.759749 -59.014603) (xy 332.710172 -59.037245) (xy 332.657877 -59.0526) (xy 332.603929 -59.060356)
			(xy 332.549427 -59.060356) (xy 332.495479 -59.0526) (xy 332.443184 -59.037245) (xy 332.393607 -59.014603)
			(xy 332.347757 -58.985137) (xy 332.306566 -58.949446) (xy 332.270875 -58.908255) (xy 332.241409 -58.862405)
			(xy 332.218767 -58.812828) (xy 332.203412 -58.760533) (xy 332.195656 -58.706585) (xy 332.19517 -58.679334)
			(xy 324.479729 -58.679334) (xy 324.483221 -58.70313) (xy 324.48373 -58.730896) (xy 324.48373 -58.731404)
			(xy 324.48373 -58.737754) (xy 324.482968 -58.75274) (xy 324.481512 -58.77386) (xy 324.47451 -58.815612)
			(xy 324.468998 -58.836052) (xy 324.460147 -58.864954) (xy 324.434603 -58.919735) (xy 324.400747 -58.969807)
			(xy 324.359427 -59.013921) (xy 324.335902 -59.032902) (xy 324.335648 -59.032902) (xy 324.33134 -59.036493)
			(xy 324.324293 -59.045213) (xy 324.321678 -59.050174) (xy 324.319138 -59.055254) (xy 324.316344 -59.065922)
			(xy 324.293976 -60.019254) (xy 332.335561 -60.019254) (xy 332.335561 -59.964746) (xy 332.343319 -59.910793)
			(xy 332.358677 -59.858494) (xy 332.381321 -59.808912) (xy 332.410791 -59.763058) (xy 332.446488 -59.721865)
			(xy 332.487684 -59.686172) (xy 332.53354 -59.656706) (xy 332.583124 -59.634065) (xy 332.635425 -59.618712)
			(xy 332.689378 -59.610959) (xy 332.716632 -59.610498) (xy 332.744003 -59.610946) (xy 332.798183 -59.618768)
			(xy 332.850686 -59.634261) (xy 332.900433 -59.657107) (xy 332.946399 -59.686835) (xy 332.96733 -59.704478)
			(xy 332.967584 -59.704732) (xy 332.974668 -59.710322) (xy 332.991587 -59.716565) (xy 333.000604 -59.716924)
			(xy 333.06766 -59.716924) (xy 333.076674 -59.716543) (xy 333.093591 -59.710311) (xy 333.10068 -59.704732)
			(xy 333.10068 -59.704478) (xy 333.100934 -59.704478) (xy 333.121867 -59.686837) (xy 333.167835 -59.657113)
			(xy 333.217581 -59.634267) (xy 333.270083 -59.618771) (xy 333.324261 -59.610942) (xy 333.379003 -59.610942)
			(xy 333.433181 -59.618771) (xy 333.485683 -59.634267) (xy 333.535429 -59.657113) (xy 333.581397 -59.686837)
			(xy 333.60233 -59.704478) (xy 333.602584 -59.704732) (xy 333.609668 -59.710322) (xy 333.626587 -59.716565)
			(xy 333.635604 -59.716924) (xy 333.70266 -59.716924) (xy 333.711674 -59.716543) (xy 333.728591 -59.710311)
			(xy 333.73568 -59.704732) (xy 333.73568 -59.704478) (xy 333.735934 -59.704478) (xy 333.756877 -59.686853)
			(xy 333.802847 -59.65714) (xy 333.852592 -59.634301) (xy 333.90509 -59.618807) (xy 333.959264 -59.610975)
			(xy 333.986632 -59.610498) (xy 334.013882 -59.610974) (xy 334.067827 -59.618734) (xy 334.120119 -59.634092)
			(xy 334.169693 -59.656736) (xy 334.21554 -59.686203) (xy 334.256727 -59.721895) (xy 334.292416 -59.763086)
			(xy 334.32188 -59.808935) (xy 334.344519 -59.858511) (xy 334.359872 -59.910804) (xy 334.367628 -59.96475)
			(xy 334.367628 -60.01925) (xy 334.359872 -60.073196) (xy 334.344519 -60.125489) (xy 334.32188 -60.175065)
			(xy 334.292416 -60.220914) (xy 334.256727 -60.262105) (xy 334.21554 -60.297797) (xy 334.169693 -60.327264)
			(xy 334.120119 -60.349908) (xy 334.067827 -60.365266) (xy 334.013882 -60.373026) (xy 333.986632 -60.373514)
			(xy 333.959263 -60.373026) (xy 333.905085 -60.365213) (xy 333.852582 -60.349729) (xy 333.802835 -60.326892)
			(xy 333.756867 -60.297173) (xy 333.735934 -60.279534) (xy 333.73568 -60.27928) (xy 333.728605 -60.273677)
			(xy 333.711679 -60.267441) (xy 333.70266 -60.267088) (xy 333.635604 -60.267088) (xy 333.626588 -60.26745)
			(xy 333.609671 -60.273694) (xy 333.602584 -60.27928) (xy 333.60233 -60.279534) (xy 333.581397 -60.297175)
			(xy 333.535429 -60.326899) (xy 333.485683 -60.349745) (xy 333.433181 -60.365241) (xy 333.379003 -60.37307)
			(xy 333.324261 -60.37307) (xy 333.270083 -60.365241) (xy 333.217581 -60.349745) (xy 333.167835 -60.326899)
			(xy 333.121867 -60.297175) (xy 333.100934 -60.279534) (xy 333.10068 -60.27928) (xy 333.093605 -60.273677)
			(xy 333.076679 -60.267441) (xy 333.06766 -60.267088) (xy 333.000604 -60.267088) (xy 332.991588 -60.26745)
			(xy 332.974671 -60.273694) (xy 332.967584 -60.27928) (xy 332.967584 -60.279534) (xy 332.96733 -60.279534)
			(xy 332.946402 -60.297178) (xy 332.900427 -60.326888) (xy 332.850679 -60.349722) (xy 332.798178 -60.365212)
			(xy 332.744001 -60.37304) (xy 332.716632 -60.373514) (xy 332.689378 -60.373041) (xy 332.635425 -60.365288)
			(xy 332.583124 -60.349935) (xy 332.53354 -60.327294) (xy 332.487684 -60.297828) (xy 332.446488 -60.262135)
			(xy 332.410791 -60.220942) (xy 332.381321 -60.175088) (xy 332.358677 -60.125506) (xy 332.343319 -60.073207)
			(xy 332.335561 -60.019254) (xy 324.293976 -60.019254) (xy 324.27545 -60.80887) (xy 324.274007 -60.852552)
			(xy 324.264341 -60.939422) (xy 324.256146 -60.982352) (xy 324.075298 -61.88583) (xy 324.039738 -62.063376)
			(xy 323.809532 -63.213554) (xy 332.320565 -63.213554) (xy 332.320565 -63.159046) (xy 332.328323 -63.105092)
			(xy 332.343681 -63.052792) (xy 332.366327 -63.00321) (xy 332.395798 -62.957356) (xy 332.431496 -62.916163)
			(xy 332.472693 -62.880471) (xy 332.518551 -62.851005) (xy 332.568135 -62.828365) (xy 332.620437 -62.813014)
			(xy 332.674392 -62.805262) (xy 332.701646 -62.804802) (xy 332.729015 -62.805299) (xy 332.783193 -62.813109)
			(xy 332.835696 -62.828591) (xy 332.885443 -62.851426) (xy 332.931411 -62.881144) (xy 332.952344 -62.898782)
			(xy 332.952598 -62.899036) (xy 332.959678 -62.904632) (xy 332.9766 -62.910872) (xy 332.985618 -62.911228)
			(xy 333.052674 -62.911228) (xy 333.061689 -62.910852) (xy 333.078606 -62.904617) (xy 333.085694 -62.899036)
			(xy 333.085694 -62.898782) (xy 333.085948 -62.898782) (xy 333.106881 -62.881141) (xy 333.152849 -62.851417)
			(xy 333.202595 -62.828571) (xy 333.255097 -62.813075) (xy 333.309275 -62.805246) (xy 333.364017 -62.805246)
			(xy 333.418195 -62.813075) (xy 333.470697 -62.828571) (xy 333.520443 -62.851417) (xy 333.566411 -62.881141)
			(xy 333.587344 -62.898782) (xy 333.587598 -62.899036) (xy 333.594678 -62.904632) (xy 333.6116 -62.910872)
			(xy 333.620618 -62.911228) (xy 333.687674 -62.911228) (xy 333.696689 -62.910852) (xy 333.713606 -62.904617)
			(xy 333.720694 -62.899036) (xy 333.720694 -62.898782) (xy 333.720948 -62.898782) (xy 333.741887 -62.881151)
			(xy 333.787858 -62.851439) (xy 333.837604 -62.828601) (xy 333.890103 -62.813108) (xy 333.944277 -62.805278)
			(xy 333.971646 -62.804802) (xy 333.998896 -62.805271) (xy 334.05284 -62.813033) (xy 334.105131 -62.828392)
			(xy 334.154703 -62.851037) (xy 334.200549 -62.880505) (xy 334.241735 -62.916198) (xy 334.277422 -62.957388)
			(xy 334.306885 -63.003237) (xy 334.329524 -63.052813) (xy 334.344877 -63.105105) (xy 334.352632 -63.15905)
			(xy 334.352632 -63.21355) (xy 334.344877 -63.267495) (xy 334.329524 -63.319787) (xy 334.306885 -63.369363)
			(xy 334.277422 -63.415212) (xy 334.241735 -63.456402) (xy 334.200549 -63.492095) (xy 334.154703 -63.521563)
			(xy 334.105131 -63.544208) (xy 334.05284 -63.559567) (xy 333.998896 -63.567329) (xy 333.971646 -63.567818)
			(xy 333.944276 -63.567345) (xy 333.890096 -63.559532) (xy 333.837592 -63.544046) (xy 333.787845 -63.521205)
			(xy 333.741879 -63.49148) (xy 333.720948 -63.473838) (xy 333.720694 -63.473584) (xy 333.713615 -63.467987)
			(xy 333.696692 -63.461747) (xy 333.687674 -63.461392) (xy 333.620618 -63.461392) (xy 333.611602 -63.461759)
			(xy 333.594685 -63.468) (xy 333.587598 -63.473584) (xy 333.587344 -63.473838) (xy 333.566411 -63.491479)
			(xy 333.520443 -63.521203) (xy 333.470697 -63.544049) (xy 333.418195 -63.559545) (xy 333.364017 -63.567374)
			(xy 333.309275 -63.567374) (xy 333.255097 -63.559545) (xy 333.202595 -63.544049) (xy 333.152849 -63.521203)
			(xy 333.106881 -63.491479) (xy 333.085948 -63.473838) (xy 333.085694 -63.473584) (xy 333.078615 -63.467987)
			(xy 333.061692 -63.461747) (xy 333.052674 -63.461392) (xy 332.985618 -63.461392) (xy 332.976602 -63.461759)
			(xy 332.959685 -63.468) (xy 332.952598 -63.473584) (xy 332.952598 -63.473838) (xy 332.952344 -63.473838)
			(xy 332.931411 -63.491476) (xy 332.885438 -63.521187) (xy 332.835691 -63.544023) (xy 332.78319 -63.559514)
			(xy 332.729015 -63.567344) (xy 332.701646 -63.567818) (xy 332.674392 -63.567338) (xy 332.620437 -63.559586)
			(xy 332.568135 -63.544235) (xy 332.518551 -63.521595) (xy 332.472693 -63.492129) (xy 332.431496 -63.456437)
			(xy 332.395798 -63.415244) (xy 332.366327 -63.36939) (xy 332.343681 -63.319808) (xy 332.328323 -63.267508)
			(xy 332.320565 -63.213554) (xy 323.809532 -63.213554) (xy 323.431771 -65.100962) (xy 330.332332 -65.100962)
			(xy 330.336403 -65.04534) (xy 330.348529 -64.990903) (xy 330.368452 -64.938812) (xy 330.395748 -64.890177)
			(xy 330.429834 -64.846034) (xy 330.469983 -64.807325) (xy 330.515341 -64.774874) (xy 330.564941 -64.749373)
			(xy 330.617725 -64.731366) (xy 330.672568 -64.721236) (xy 330.728302 -64.719199) (xy 330.783739 -64.725299)
			(xy 330.837696 -64.739405) (xy 330.889025 -64.761217) (xy 330.936631 -64.790271) (xy 330.979499 -64.825946)
			(xy 331.016716 -64.867483) (xy 331.047489 -64.913996) (xy 331.071161 -64.964493) (xy 331.087229 -65.0179)
			(xy 331.095349 -65.073076) (xy 331.095858 -65.100962) (xy 331.095349 -65.128848) (xy 331.087229 -65.184024)
			(xy 331.071161 -65.237431) (xy 331.047489 -65.287928) (xy 331.016716 -65.334441) (xy 330.979499 -65.375978)
			(xy 330.936631 -65.411653) (xy 330.889025 -65.440707) (xy 330.837696 -65.462519) (xy 330.783739 -65.476625)
			(xy 330.728302 -65.482725) (xy 330.672568 -65.480688) (xy 330.617725 -65.470558) (xy 330.564941 -65.452551)
			(xy 330.515341 -65.42705) (xy 330.469983 -65.394599) (xy 330.429834 -65.35589) (xy 330.395748 -65.311747)
			(xy 330.368452 -65.263112) (xy 330.348529 -65.211021) (xy 330.336403 -65.156584) (xy 330.332332 -65.100962)
			(xy 323.431771 -65.100962) (xy 323.300762 -65.75552) (xy 324.546466 -65.75552) (xy 324.550537 -65.699898)
			(xy 324.562663 -65.645461) (xy 324.582586 -65.59337) (xy 324.609882 -65.544735) (xy 324.643968 -65.500592)
			(xy 324.684117 -65.461883) (xy 324.729475 -65.429432) (xy 324.779075 -65.403931) (xy 324.831859 -65.385924)
			(xy 324.886702 -65.375794) (xy 324.942436 -65.373757) (xy 324.997873 -65.379857) (xy 325.05183 -65.393963)
			(xy 325.103159 -65.415775) (xy 325.150765 -65.444829) (xy 325.193633 -65.480504) (xy 325.23085 -65.522041)
			(xy 325.261623 -65.568554) (xy 325.285295 -65.619051) (xy 325.301363 -65.672458) (xy 325.309483 -65.727634)
			(xy 325.309992 -65.75552) (xy 325.309483 -65.783406) (xy 325.301363 -65.838582) (xy 325.285295 -65.891989)
			(xy 325.261623 -65.942486) (xy 325.23085 -65.988999) (xy 325.193633 -66.030536) (xy 325.150765 -66.066211)
			(xy 325.103159 -66.095265) (xy 325.05183 -66.117077) (xy 324.997873 -66.131183) (xy 324.942436 -66.137283)
			(xy 324.886702 -66.135246) (xy 324.831859 -66.125116) (xy 324.779075 -66.107109) (xy 324.729475 -66.081608)
			(xy 324.684117 -66.049157) (xy 324.643968 -66.010448) (xy 324.609882 -65.966305) (xy 324.582586 -65.91767)
			(xy 324.562663 -65.865579) (xy 324.550537 -65.811142) (xy 324.546466 -65.75552) (xy 323.300762 -65.75552)
			(xy 323.025872 -67.128953) (xy 324.566475 -67.128953) (xy 324.566475 -67.074447) (xy 324.574233 -67.020496)
			(xy 324.58959 -66.968198) (xy 324.612234 -66.918618) (xy 324.641703 -66.872766) (xy 324.677399 -66.831575)
			(xy 324.718593 -66.795883) (xy 324.764448 -66.766417) (xy 324.81403 -66.743778) (xy 324.866329 -66.728426)
			(xy 324.920281 -66.720673) (xy 324.947534 -66.720212) (xy 324.974905 -66.720655) (xy 325.029085 -66.728478)
			(xy 325.081589 -66.743972) (xy 325.131335 -66.766819) (xy 325.177301 -66.796549) (xy 325.198232 -66.814192)
			(xy 325.198486 -66.814446) (xy 325.205568 -66.820038) (xy 325.222489 -66.82628) (xy 325.231506 -66.826638)
			(xy 325.298562 -66.826638) (xy 325.307576 -66.826255) (xy 325.324493 -66.820024) (xy 325.331582 -66.814446)
			(xy 325.331582 -66.814192) (xy 325.331836 -66.814192) (xy 325.35278 -66.796568) (xy 325.39875 -66.766854)
			(xy 325.448494 -66.744016) (xy 325.500992 -66.728521) (xy 325.555166 -66.720688) (xy 325.582534 -66.720212)
			(xy 325.609785 -66.72066) (xy 325.663732 -66.728421) (xy 325.716025 -66.74378) (xy 325.765601 -66.766424)
			(xy 325.811449 -66.795893) (xy 325.852638 -66.831586) (xy 325.888328 -66.872778) (xy 325.917792 -66.918629)
			(xy 325.940432 -66.968207) (xy 325.955786 -67.020501) (xy 325.963542 -67.074449) (xy 325.963542 -67.128951)
			(xy 325.955786 -67.182899) (xy 325.940432 -67.235193) (xy 325.917792 -67.284771) (xy 325.888328 -67.330622)
			(xy 325.852638 -67.371814) (xy 325.811449 -67.407507) (xy 325.765601 -67.436976) (xy 325.716025 -67.45962)
			(xy 325.663732 -67.474979) (xy 325.609785 -67.48274) (xy 325.582534 -67.483228) (xy 325.555164 -67.48276)
			(xy 325.500984 -67.474945) (xy 325.44848 -67.459457) (xy 325.398733 -67.436616) (xy 325.352767 -67.40689)
			(xy 325.331836 -67.389248) (xy 325.331582 -67.388994) (xy 325.324505 -67.383393) (xy 325.307581 -67.377155)
			(xy 325.298562 -67.376802) (xy 325.231506 -67.376802) (xy 325.222489 -67.377161) (xy 325.205572 -67.383407)
			(xy 325.198486 -67.388994) (xy 325.198486 -67.389248) (xy 325.198232 -67.389248) (xy 325.177292 -67.406877)
			(xy 325.131322 -67.436593) (xy 325.081577 -67.459431) (xy 325.029078 -67.474924) (xy 324.974903 -67.482754)
			(xy 324.947534 -67.483228) (xy 324.920281 -67.482727) (xy 324.866329 -67.474974) (xy 324.81403 -67.459622)
			(xy 324.764448 -67.436983) (xy 324.718593 -67.407517) (xy 324.677399 -67.371825) (xy 324.641703 -67.330634)
			(xy 324.612234 -67.284782) (xy 324.58959 -67.235202) (xy 324.574233 -67.182904) (xy 324.566475 -67.128953)
			(xy 323.025872 -67.128953) (xy 322.953999 -67.488054) (xy 328.97902 -67.488054) (xy 328.983091 -67.432432)
			(xy 328.995217 -67.377995) (xy 329.01514 -67.325904) (xy 329.042436 -67.277269) (xy 329.076522 -67.233126)
			(xy 329.116671 -67.194417) (xy 329.162029 -67.161966) (xy 329.211629 -67.136465) (xy 329.264413 -67.118458)
			(xy 329.319256 -67.108328) (xy 329.37499 -67.106291) (xy 329.430427 -67.112391) (xy 329.484384 -67.126497)
			(xy 329.535713 -67.148309) (xy 329.583319 -67.177363) (xy 329.626187 -67.213038) (xy 329.663404 -67.254575)
			(xy 329.694177 -67.301088) (xy 329.717849 -67.351585) (xy 329.733917 -67.404992) (xy 329.742037 -67.460168)
			(xy 329.742546 -67.488054) (xy 329.742037 -67.51594) (xy 329.738852 -67.537584) (xy 330.271118 -67.537584)
			(xy 330.275189 -67.481962) (xy 330.287315 -67.427525) (xy 330.307238 -67.375434) (xy 330.334534 -67.326799)
			(xy 330.36862 -67.282656) (xy 330.408769 -67.243947) (xy 330.454127 -67.211496) (xy 330.503727 -67.185995)
			(xy 330.556511 -67.167988) (xy 330.611354 -67.157858) (xy 330.667088 -67.155821) (xy 330.722525 -67.161921)
			(xy 330.776482 -67.176027) (xy 330.827811 -67.197839) (xy 330.875417 -67.226893) (xy 330.918285 -67.262568)
			(xy 330.955502 -67.304105) (xy 330.986275 -67.350618) (xy 331.009947 -67.401115) (xy 331.026015 -67.454522)
			(xy 331.034135 -67.509698) (xy 331.034644 -67.537584) (xy 331.034135 -67.56547) (xy 331.03009 -67.592956)
			(xy 331.545182 -67.592956) (xy 331.549253 -67.537334) (xy 331.561379 -67.482897) (xy 331.581302 -67.430806)
			(xy 331.608598 -67.382171) (xy 331.642684 -67.338028) (xy 331.682833 -67.299319) (xy 331.728191 -67.266868)
			(xy 331.777791 -67.241367) (xy 331.830575 -67.22336) (xy 331.885418 -67.21323) (xy 331.941152 -67.211193)
			(xy 331.996589 -67.217293) (xy 332.050546 -67.231399) (xy 332.101875 -67.253211) (xy 332.149481 -67.282265)
			(xy 332.192349 -67.31794) (xy 332.229566 -67.359477) (xy 332.260339 -67.40599) (xy 332.284011 -67.456487)
			(xy 332.300079 -67.509894) (xy 332.308196 -67.565051) (xy 334.646493 -67.565051) (xy 334.646493 -67.510549)
			(xy 334.65425 -67.456601) (xy 334.669606 -67.404307) (xy 334.692248 -67.35473) (xy 334.721715 -67.30888)
			(xy 334.757408 -67.267691) (xy 334.798599 -67.232001) (xy 334.844451 -67.202536) (xy 334.894029 -67.179897)
			(xy 334.946325 -67.164545) (xy 335.000273 -67.156792) (xy 335.027524 -67.15633) (xy 335.054895 -67.156775)
			(xy 335.109075 -67.164597) (xy 335.161579 -67.18009) (xy 335.211326 -67.202937) (xy 335.257291 -67.232666)
			(xy 335.278222 -67.25031) (xy 335.278476 -67.250564) (xy 335.28556 -67.256154) (xy 335.302479 -67.262397)
			(xy 335.311496 -67.262756) (xy 335.378552 -67.262756) (xy 335.387568 -67.262386) (xy 335.404485 -67.256148)
			(xy 335.411572 -67.250564) (xy 335.411572 -67.25031) (xy 335.411826 -67.25031) (xy 335.432776 -67.232694)
			(xy 335.478744 -67.202978) (xy 335.528487 -67.180138) (xy 335.580984 -67.164641) (xy 335.635156 -67.156807)
			(xy 335.662524 -67.15633) (xy 335.689777 -67.156742) (xy 335.743727 -67.164502) (xy 335.796024 -67.17986)
			(xy 335.845604 -67.202505) (xy 335.891456 -67.231975) (xy 335.932647 -67.26767) (xy 335.968339 -67.308864)
			(xy 335.997806 -67.354718) (xy 336.020448 -67.404298) (xy 336.035804 -67.456596) (xy 336.04356 -67.510547)
			(xy 336.04356 -67.565053) (xy 336.035804 -67.619004) (xy 336.020448 -67.671302) (xy 335.997806 -67.720882)
			(xy 335.968339 -67.766736) (xy 335.932647 -67.80793) (xy 335.891456 -67.843625) (xy 335.845604 -67.873095)
			(xy 335.796024 -67.89574) (xy 335.743727 -67.911098) (xy 335.689777 -67.918858) (xy 335.662524 -67.919346)
			(xy 335.635154 -67.918879) (xy 335.580974 -67.911063) (xy 335.52847 -67.895575) (xy 335.478724 -67.872733)
			(xy 335.432757 -67.843008) (xy 335.411826 -67.825366) (xy 335.411572 -67.825112) (xy 335.404468 -67.819551)
			(xy 335.387565 -67.813288) (xy 335.378552 -67.81292) (xy 335.311496 -67.81292) (xy 335.302478 -67.813271)
			(xy 335.285561 -67.819522) (xy 335.278476 -67.825112) (xy 335.278476 -67.825366) (xy 335.278222 -67.825366)
			(xy 335.257288 -67.843003) (xy 335.211316 -67.872716) (xy 335.161569 -67.895553) (xy 335.109069 -67.911045)
			(xy 335.054893 -67.918872) (xy 335.027524 -67.919346) (xy 335.000273 -67.918808) (xy 334.946325 -67.911055)
			(xy 334.894029 -67.895703) (xy 334.844451 -67.873064) (xy 334.798599 -67.843599) (xy 334.757408 -67.807909)
			(xy 334.721715 -67.76672) (xy 334.692248 -67.72087) (xy 334.669606 -67.671293) (xy 334.65425 -67.618999)
			(xy 334.646493 -67.565051) (xy 332.308196 -67.565051) (xy 332.308199 -67.56507) (xy 332.308708 -67.592956)
			(xy 332.308199 -67.620842) (xy 332.300079 -67.676018) (xy 332.284011 -67.729425) (xy 332.260339 -67.779922)
			(xy 332.229566 -67.826435) (xy 332.192349 -67.867972) (xy 332.149481 -67.903647) (xy 332.101875 -67.932701)
			(xy 332.050546 -67.954513) (xy 331.996589 -67.968619) (xy 331.941152 -67.974719) (xy 331.885418 -67.972682)
			(xy 331.830575 -67.962552) (xy 331.777791 -67.944545) (xy 331.728191 -67.919044) (xy 331.682833 -67.886593)
			(xy 331.642684 -67.847884) (xy 331.608598 -67.803741) (xy 331.581302 -67.755106) (xy 331.561379 -67.703015)
			(xy 331.549253 -67.648578) (xy 331.545182 -67.592956) (xy 331.03009 -67.592956) (xy 331.026015 -67.620646)
			(xy 331.009947 -67.674053) (xy 330.986275 -67.72455) (xy 330.955502 -67.771063) (xy 330.918285 -67.8126)
			(xy 330.875417 -67.848275) (xy 330.827811 -67.877329) (xy 330.776482 -67.899141) (xy 330.722525 -67.913247)
			(xy 330.667088 -67.919347) (xy 330.611354 -67.91731) (xy 330.556511 -67.90718) (xy 330.503727 -67.889173)
			(xy 330.454127 -67.863672) (xy 330.408769 -67.831221) (xy 330.36862 -67.792512) (xy 330.334534 -67.748369)
			(xy 330.307238 -67.699734) (xy 330.287315 -67.647643) (xy 330.275189 -67.593206) (xy 330.271118 -67.537584)
			(xy 329.738852 -67.537584) (xy 329.733917 -67.571116) (xy 329.717849 -67.624523) (xy 329.694177 -67.67502)
			(xy 329.663404 -67.721533) (xy 329.626187 -67.76307) (xy 329.583319 -67.798745) (xy 329.535713 -67.827799)
			(xy 329.484384 -67.849611) (xy 329.430427 -67.863717) (xy 329.37499 -67.869817) (xy 329.319256 -67.86778)
			(xy 329.264413 -67.85765) (xy 329.211629 -67.839643) (xy 329.162029 -67.814142) (xy 329.116671 -67.781691)
			(xy 329.076522 -67.742982) (xy 329.042436 -67.698839) (xy 329.01514 -67.650204) (xy 328.995217 -67.598113)
			(xy 328.983091 -67.543676) (xy 328.97902 -67.488054) (xy 322.953999 -67.488054) (xy 322.734126 -68.586604)
			(xy 326.825102 -68.586604) (xy 326.82557 -68.559234) (xy 326.833387 -68.505055) (xy 326.848876 -68.452552)
			(xy 326.871717 -68.402805) (xy 326.901441 -68.356838) (xy 326.919082 -68.335906) (xy 326.919336 -68.335652)
			(xy 326.924911 -68.328558) (xy 326.931164 -68.311647) (xy 326.931528 -68.302632) (xy 326.931528 -68.235576)
			(xy 326.931177 -68.226559) (xy 326.924925 -68.209642) (xy 326.919336 -68.202556) (xy 326.919082 -68.202556)
			(xy 326.919082 -68.202302) (xy 326.901428 -68.181382) (xy 326.871719 -68.135406) (xy 326.848886 -68.085655)
			(xy 326.833398 -68.033152) (xy 326.825574 -67.978974) (xy 326.825102 -67.951604) (xy 326.825559 -67.924351)
			(xy 326.833316 -67.870399) (xy 326.848672 -67.818101) (xy 326.871315 -67.76852) (xy 326.900783 -67.722666)
			(xy 326.936477 -67.681473) (xy 326.977671 -67.645779) (xy 327.023525 -67.616312) (xy 327.073106 -67.59367)
			(xy 327.125405 -67.578314) (xy 327.179357 -67.570559) (xy 327.20661 -67.570096) (xy 327.232924 -67.570558)
			(xy 327.285053 -67.577794) (xy 327.335696 -67.592114) (xy 327.383895 -67.613248) (xy 327.428738 -67.640795)
			(xy 327.469377 -67.674234) (xy 327.487534 -67.693286) (xy 327.495043 -67.700703) (xy 327.514333 -67.709219)
			(xy 327.524872 -67.709796) (xy 327.599548 -67.709796) (xy 327.610096 -67.709254) (xy 327.629392 -67.700728)
			(xy 327.636886 -67.693286) (xy 327.655053 -67.674242) (xy 327.69568 -67.640784) (xy 327.740518 -67.613224)
			(xy 327.788717 -67.592084) (xy 327.839362 -67.577764) (xy 327.891495 -67.570536) (xy 327.91781 -67.570096)
			(xy 327.94518 -67.570557) (xy 327.99936 -67.578376) (xy 328.051863 -67.593867) (xy 328.10161 -67.616709)
			(xy 328.147576 -67.646435) (xy 328.168508 -67.664076) (xy 328.168762 -67.66433) (xy 328.175853 -67.66991)
			(xy 328.192766 -67.67616) (xy 328.201782 -67.676522) (xy 328.268838 -67.676522) (xy 328.277856 -67.676179)
			(xy 328.294773 -67.669921) (xy 328.301858 -67.66433) (xy 328.301858 -67.664076) (xy 328.302112 -67.664076)
			(xy 328.323063 -67.646461) (xy 328.369031 -67.616746) (xy 328.418774 -67.593906) (xy 328.47127 -67.578409)
			(xy 328.525442 -67.570574) (xy 328.55281 -67.570096) (xy 328.580062 -67.570569) (xy 328.63401 -67.578326)
			(xy 328.686305 -67.593683) (xy 328.735883 -67.616326) (xy 328.781733 -67.645793) (xy 328.822924 -67.681486)
			(xy 328.858615 -67.722678) (xy 328.888081 -67.768529) (xy 328.910722 -67.818108) (xy 328.926077 -67.870404)
			(xy 328.933832 -67.924352) (xy 328.934318 -67.951604) (xy 328.933874 -67.978975) (xy 328.926054 -68.033156)
			(xy 328.910561 -68.08566) (xy 328.887714 -68.135407) (xy 328.857983 -68.181372) (xy 328.840338 -68.202302)
			(xy 328.840084 -68.202556) (xy 328.834508 -68.20965) (xy 328.828255 -68.226561) (xy 328.827892 -68.235576)
			(xy 328.827892 -68.302632) (xy 328.828236 -68.31165) (xy 328.834493 -68.328567) (xy 328.840084 -68.335652)
			(xy 328.840338 -68.335652) (xy 328.840338 -68.335906) (xy 328.858 -68.35682) (xy 328.887707 -68.402798)
			(xy 328.910538 -68.45255) (xy 328.926024 -68.505055) (xy 328.933847 -68.559234) (xy 328.934318 -68.586604)
			(xy 328.933826 -68.613855) (xy 328.926069 -68.667802) (xy 328.910714 -68.720096) (xy 328.894075 -68.75653)
			(xy 332.370176 -68.75653) (xy 332.370641 -68.72916) (xy 332.378456 -68.67498) (xy 332.393945 -68.622476)
			(xy 332.416787 -68.572729) (xy 332.446513 -68.526763) (xy 332.464156 -68.505832) (xy 332.46441 -68.505578)
			(xy 332.470013 -68.498503) (xy 332.47625 -68.481577) (xy 332.476602 -68.472558) (xy 332.476602 -68.405502)
			(xy 332.476244 -68.396485) (xy 332.469997 -68.379568) (xy 332.46441 -68.372482) (xy 332.464156 -68.372482)
			(xy 332.464156 -68.372228) (xy 332.446509 -68.351302) (xy 332.4168 -68.305327) (xy 332.393966 -68.255578)
			(xy 332.378477 -68.203076) (xy 332.370649 -68.148899) (xy 332.370176 -68.12153) (xy 332.370683 -68.094279)
			(xy 332.378436 -68.04033) (xy 332.393787 -67.988034) (xy 332.416425 -67.938455) (xy 332.445888 -67.892603)
			(xy 332.481577 -67.85141) (xy 332.522766 -67.815716) (xy 332.568615 -67.786247) (xy 332.618191 -67.763603)
			(xy 332.670485 -67.748245) (xy 332.724433 -67.740486) (xy 332.751684 -67.740022) (xy 332.779054 -67.740492)
			(xy 332.833233 -67.748308) (xy 332.885737 -67.763796) (xy 332.935483 -67.786637) (xy 332.98145 -67.816361)
			(xy 333.002382 -67.834002) (xy 333.002636 -67.834256) (xy 333.009732 -67.839829) (xy 333.026642 -67.846082)
			(xy 333.035656 -67.846448) (xy 333.102712 -67.846448) (xy 333.111731 -67.846108) (xy 333.128648 -67.83985)
			(xy 333.135732 -67.834256) (xy 333.135732 -67.834002) (xy 333.135986 -67.834002) (xy 333.156913 -67.816356)
			(xy 333.202887 -67.786645) (xy 333.252636 -67.763811) (xy 333.305138 -67.748321) (xy 333.359314 -67.740495)
			(xy 333.386684 -67.740022) (xy 333.412998 -67.740493) (xy 333.465127 -67.747726) (xy 333.515769 -67.762044)
			(xy 333.563969 -67.783176) (xy 333.608812 -67.810722) (xy 333.649452 -67.84416) (xy 333.667608 -67.863212)
			(xy 333.675123 -67.870621) (xy 333.694408 -67.879141) (xy 333.704946 -67.879722) (xy 333.779622 -67.879722)
			(xy 333.790167 -67.879158) (xy 333.809463 -67.870647) (xy 333.81696 -67.863212) (xy 333.835096 -67.844137)
			(xy 333.875729 -67.810681) (xy 333.920574 -67.783124) (xy 333.968779 -67.761989) (xy 334.01943 -67.747676)
			(xy 334.071567 -67.740457) (xy 334.097884 -67.740022) (xy 334.125138 -67.74047) (xy 334.179091 -67.748226)
			(xy 334.231391 -67.763581) (xy 334.280973 -67.786224) (xy 334.326828 -67.815693) (xy 334.368021 -67.851389)
			(xy 334.403715 -67.892584) (xy 334.433183 -67.938439) (xy 334.455824 -67.988022) (xy 334.471177 -68.040323)
			(xy 334.478931 -68.094276) (xy 334.479392 -68.12153) (xy 334.478945 -68.148901) (xy 334.471123 -68.203081)
			(xy 334.45563 -68.255584) (xy 334.432784 -68.305331) (xy 334.403055 -68.351297) (xy 334.385412 -68.372228)
			(xy 334.385158 -68.372482) (xy 334.379568 -68.379566) (xy 334.373324 -68.396485) (xy 334.372966 -68.405502)
			(xy 334.372966 -68.472558) (xy 334.37335 -68.481572) (xy 334.37958 -68.498489) (xy 334.385158 -68.505578)
			(xy 334.385412 -68.505578) (xy 334.385412 -68.505832) (xy 334.403035 -68.526777) (xy 334.432748 -68.572747)
			(xy 334.455587 -68.622491) (xy 334.471082 -68.674989) (xy 334.478915 -68.729162) (xy 334.479392 -68.75653)
			(xy 334.47895 -68.783783) (xy 334.471189 -68.837733) (xy 334.455829 -68.890029) (xy 334.433183 -68.939608)
			(xy 334.403713 -68.985459) (xy 334.368017 -69.026649) (xy 334.326822 -69.06234) (xy 334.280967 -69.091806)
			(xy 334.231386 -69.114445) (xy 334.179088 -69.129799) (xy 334.125137 -69.137553) (xy 334.097884 -69.138038)
			(xy 334.071569 -69.137601) (xy 334.019438 -69.130363) (xy 333.968794 -69.116039) (xy 333.920595 -69.094901)
			(xy 333.875752 -69.067349) (xy 333.835115 -69.033903) (xy 333.81696 -69.014848) (xy 333.809449 -69.007434)
			(xy 333.790161 -68.998915) (xy 333.779622 -68.998338) (xy 333.704946 -68.998338) (xy 333.694396 -68.998867)
			(xy 333.6751 -69.007401) (xy 333.667608 -69.014848) (xy 333.649451 -69.033902) (xy 333.60882 -69.067357)
			(xy 333.56398 -69.094915) (xy 333.51578 -69.116054) (xy 333.465133 -69.130372) (xy 333.413 -69.137598)
			(xy 333.386684 -69.138038) (xy 333.359313 -69.137596) (xy 333.305132 -69.129775) (xy 333.252628 -69.114281)
			(xy 333.202881 -69.091433) (xy 333.156916 -69.061703) (xy 333.135986 -69.044058) (xy 333.135732 -69.043804)
			(xy 333.12864 -69.038225) (xy 333.111727 -69.031974) (xy 333.102712 -69.031612) (xy 333.035656 -69.031612)
			(xy 333.026642 -69.031993) (xy 333.009724 -69.038224) (xy 333.002636 -69.043804) (xy 333.002636 -69.044058)
			(xy 333.002382 -69.044058) (xy 332.981424 -69.061666) (xy 332.935459 -69.091384) (xy 332.885718 -69.114226)
			(xy 332.833223 -69.129725) (xy 332.779052 -69.13756) (xy 332.751684 -69.138038) (xy 332.724434 -69.137537)
			(xy 332.670488 -69.129779) (xy 332.618195 -69.114424) (xy 332.56862 -69.091783) (xy 332.522771 -69.062318)
			(xy 332.481582 -69.026628) (xy 332.445891 -68.98544) (xy 332.416424 -68.939592) (xy 332.393781 -68.890018)
			(xy 332.378424 -68.837726) (xy 332.370664 -68.78378) (xy 332.370176 -68.75653) (xy 328.894075 -68.75653)
			(xy 328.888073 -68.769672) (xy 328.858607 -68.815522) (xy 328.822917 -68.856712) (xy 328.781727 -68.892404)
			(xy 328.735878 -68.92187) (xy 328.686302 -68.944512) (xy 328.634008 -68.959868) (xy 328.580061 -68.967626)
			(xy 328.55281 -68.968112) (xy 328.52544 -68.967637) (xy 328.471262 -68.959821) (xy 328.418759 -68.944334)
			(xy 328.369012 -68.921494) (xy 328.323044 -68.891772) (xy 328.302112 -68.874132) (xy 328.301858 -68.873878)
			(xy 328.294761 -68.868307) (xy 328.277852 -68.862052) (xy 328.268838 -68.861686) (xy 328.201782 -68.861686)
			(xy 328.192765 -68.862038) (xy 328.175848 -68.868289) (xy 328.168762 -68.873878) (xy 328.168762 -68.874132)
			(xy 328.168508 -68.874132) (xy 328.147588 -68.891786) (xy 328.101611 -68.921494) (xy 328.051861 -68.944327)
			(xy 327.999358 -68.959815) (xy 327.94518 -68.96764) (xy 327.91781 -68.968112) (xy 327.891496 -68.967634)
			(xy 327.839369 -68.960401) (xy 327.788726 -68.946084) (xy 327.740527 -68.924953) (xy 327.695683 -68.897409)
			(xy 327.655043 -68.863972) (xy 327.636886 -68.844922) (xy 327.629369 -68.837515) (xy 327.610086 -68.828993)
			(xy 327.599548 -68.828412) (xy 327.524872 -68.828412) (xy 327.514325 -68.828963) (xy 327.495029 -68.837483)
			(xy 327.487534 -68.844922) (xy 327.469408 -68.864007) (xy 327.428771 -68.89746) (xy 327.383925 -68.925015)
			(xy 327.335718 -68.946148) (xy 327.285066 -68.960459) (xy 327.232928 -68.967677) (xy 327.20661 -68.968112)
			(xy 327.179358 -68.967635) (xy 327.125407 -68.95988) (xy 327.07311 -68.944525) (xy 327.02353 -68.921884)
			(xy 326.977677 -68.892418) (xy 326.936485 -68.856725) (xy 326.900791 -68.815534) (xy 326.871322 -68.769682)
			(xy 326.84868 -68.720103) (xy 326.833323 -68.667806) (xy 326.825566 -68.613856) (xy 326.825102 -68.586604)
			(xy 322.734126 -68.586604) (xy 322.27196 -70.895718) (xy 340.004398 -70.895718) (xy 340.008469 -70.840096)
			(xy 340.020595 -70.785659) (xy 340.040518 -70.733568) (xy 340.067814 -70.684933) (xy 340.1019 -70.64079)
			(xy 340.142049 -70.602081) (xy 340.187407 -70.56963) (xy 340.237007 -70.544129) (xy 340.289791 -70.526122)
			(xy 340.344634 -70.515992) (xy 340.400368 -70.513955) (xy 340.455805 -70.520055) (xy 340.509762 -70.534161)
			(xy 340.561091 -70.555973) (xy 340.608697 -70.585027) (xy 340.651565 -70.620702) (xy 340.688782 -70.662239)
			(xy 340.719555 -70.708752) (xy 340.743227 -70.759249) (xy 340.759295 -70.812656) (xy 340.767415 -70.867832)
			(xy 340.767632 -70.879716) (xy 340.99576 -70.879716) (xy 340.999831 -70.824094) (xy 341.011957 -70.769657)
			(xy 341.03188 -70.717566) (xy 341.059176 -70.668931) (xy 341.093262 -70.624788) (xy 341.133411 -70.586079)
			(xy 341.178769 -70.553628) (xy 341.228369 -70.528127) (xy 341.281153 -70.51012) (xy 341.335996 -70.49999)
			(xy 341.39173 -70.497953) (xy 341.447167 -70.504053) (xy 341.501124 -70.518159) (xy 341.552453 -70.539971)
			(xy 341.600059 -70.569025) (xy 341.642927 -70.6047) (xy 341.680144 -70.646237) (xy 341.710917 -70.69275)
			(xy 341.734589 -70.743247) (xy 341.750657 -70.796654) (xy 341.758777 -70.85183) (xy 341.759286 -70.879716)
			(xy 341.758777 -70.907602) (xy 341.750657 -70.962778) (xy 341.734589 -71.016185) (xy 341.710917 -71.066682)
			(xy 341.680144 -71.113195) (xy 341.642927 -71.154732) (xy 341.600059 -71.190407) (xy 341.552453 -71.219461)
			(xy 341.501124 -71.241273) (xy 341.447167 -71.255379) (xy 341.39173 -71.261479) (xy 341.335996 -71.259442)
			(xy 341.281153 -71.249312) (xy 341.228369 -71.231305) (xy 341.178769 -71.205804) (xy 341.133411 -71.173353)
			(xy 341.093262 -71.134644) (xy 341.059176 -71.090501) (xy 341.03188 -71.041866) (xy 341.011957 -70.989775)
			(xy 340.999831 -70.935338) (xy 340.99576 -70.879716) (xy 340.767632 -70.879716) (xy 340.767924 -70.895718)
			(xy 340.767415 -70.923604) (xy 340.759295 -70.97878) (xy 340.743227 -71.032187) (xy 340.719555 -71.082684)
			(xy 340.688782 -71.129197) (xy 340.651565 -71.170734) (xy 340.608697 -71.206409) (xy 340.561091 -71.235463)
			(xy 340.509762 -71.257275) (xy 340.455805 -71.271381) (xy 340.400368 -71.277481) (xy 340.344634 -71.275444)
			(xy 340.289791 -71.265314) (xy 340.237007 -71.247307) (xy 340.187407 -71.221806) (xy 340.142049 -71.189355)
			(xy 340.1019 -71.150646) (xy 340.067814 -71.106503) (xy 340.040518 -71.057868) (xy 340.020595 -71.005777)
			(xy 340.008469 -70.95134) (xy 340.004398 -70.895718) (xy 322.27196 -70.895718) (xy 322.187824 -71.316088)
			(xy 322.166844 -71.42099) (xy 322.597016 -71.42099) (xy 322.601087 -71.365368) (xy 322.613213 -71.310931)
			(xy 322.633136 -71.25884) (xy 322.660432 -71.210205) (xy 322.694518 -71.166062) (xy 322.734667 -71.127353)
			(xy 322.780025 -71.094902) (xy 322.829625 -71.069401) (xy 322.882409 -71.051394) (xy 322.937252 -71.041264)
			(xy 322.992986 -71.039227) (xy 323.048423 -71.045327) (xy 323.10238 -71.059433) (xy 323.153709 -71.081245)
			(xy 323.201315 -71.110299) (xy 323.244183 -71.145974) (xy 323.2814 -71.187511) (xy 323.312173 -71.234024)
			(xy 323.335845 -71.284521) (xy 323.351913 -71.337928) (xy 323.360033 -71.393104) (xy 323.360542 -71.42099)
			(xy 323.360033 -71.448876) (xy 323.351913 -71.504052) (xy 323.336325 -71.555864) (xy 329.39431 -71.555864)
			(xy 329.398381 -71.500242) (xy 329.410507 -71.445805) (xy 329.43043 -71.393714) (xy 329.457726 -71.345079)
			(xy 329.491812 -71.300936) (xy 329.531961 -71.262227) (xy 329.577319 -71.229776) (xy 329.626919 -71.204275)
			(xy 329.679703 -71.186268) (xy 329.734546 -71.176138) (xy 329.79028 -71.174101) (xy 329.845717 -71.180201)
			(xy 329.899674 -71.194307) (xy 329.951003 -71.216119) (xy 329.998609 -71.245173) (xy 330.041477 -71.280848)
			(xy 330.078694 -71.322385) (xy 330.109467 -71.368898) (xy 330.133139 -71.419395) (xy 330.149207 -71.472802)
			(xy 330.157327 -71.527978) (xy 330.157836 -71.555864) (xy 330.157327 -71.58375) (xy 330.151488 -71.623428)
			(xy 330.903324 -71.623428) (xy 330.907395 -71.567806) (xy 330.919521 -71.513369) (xy 330.939444 -71.461278)
			(xy 330.96674 -71.412643) (xy 331.000826 -71.3685) (xy 331.040975 -71.329791) (xy 331.086333 -71.29734)
			(xy 331.135933 -71.271839) (xy 331.188717 -71.253832) (xy 331.24356 -71.243702) (xy 331.299294 -71.241665)
			(xy 331.354731 -71.247765) (xy 331.408688 -71.261871) (xy 331.460017 -71.283683) (xy 331.507623 -71.312737)
			(xy 331.550491 -71.348412) (xy 331.587708 -71.389949) (xy 331.618481 -71.436462) (xy 331.642153 -71.486959)
			(xy 331.658221 -71.540366) (xy 331.666341 -71.595542) (xy 331.66685 -71.623428) (xy 331.666341 -71.651314)
			(xy 331.658221 -71.70649) (xy 331.642153 -71.759897) (xy 331.618481 -71.810394) (xy 331.587708 -71.856907)
			(xy 331.550491 -71.898444) (xy 331.507623 -71.934119) (xy 331.460017 -71.963173) (xy 331.408688 -71.984985)
			(xy 331.354731 -71.999091) (xy 331.299294 -72.005191) (xy 331.24356 -72.003154) (xy 331.188717 -71.993024)
			(xy 331.135933 -71.975017) (xy 331.086333 -71.949516) (xy 331.040975 -71.917065) (xy 331.000826 -71.878356)
			(xy 330.96674 -71.834213) (xy 330.939444 -71.785578) (xy 330.919521 -71.733487) (xy 330.907395 -71.67905)
			(xy 330.903324 -71.623428) (xy 330.151488 -71.623428) (xy 330.149207 -71.638926) (xy 330.133139 -71.692333)
			(xy 330.109467 -71.74283) (xy 330.078694 -71.789343) (xy 330.041477 -71.83088) (xy 329.998609 -71.866555)
			(xy 329.951003 -71.895609) (xy 329.899674 -71.917421) (xy 329.845717 -71.931527) (xy 329.79028 -71.937627)
			(xy 329.734546 -71.93559) (xy 329.679703 -71.92546) (xy 329.626919 -71.907453) (xy 329.577319 -71.881952)
			(xy 329.531961 -71.849501) (xy 329.491812 -71.810792) (xy 329.457726 -71.766649) (xy 329.43043 -71.718014)
			(xy 329.410507 -71.665923) (xy 329.398381 -71.611486) (xy 329.39431 -71.555864) (xy 323.336325 -71.555864)
			(xy 323.335845 -71.557459) (xy 323.312173 -71.607956) (xy 323.2814 -71.654469) (xy 323.244183 -71.696006)
			(xy 323.201315 -71.731681) (xy 323.153709 -71.760735) (xy 323.10238 -71.782547) (xy 323.048423 -71.796653)
			(xy 322.992986 -71.802753) (xy 322.937252 -71.800716) (xy 322.882409 -71.790586) (xy 322.829625 -71.772579)
			(xy 322.780025 -71.747078) (xy 322.734667 -71.714627) (xy 322.694518 -71.675918) (xy 322.660432 -71.631775)
			(xy 322.633136 -71.58314) (xy 322.613213 -71.531049) (xy 322.601087 -71.476612) (xy 322.597016 -71.42099)
			(xy 322.166844 -71.42099) (xy 321.9323 -72.593708) (xy 321.404742 -75.22972) (xy 321.281298 -75.85202)
			(xy 321.284092 -75.861164) (xy 321.285393 -75.865366) (xy 321.289221 -75.873286) (xy 321.291712 -75.876912)
			(xy 321.296284 -75.882246) (xy 321.313556 -75.899518) (xy 321.322954 -75.903328) (xy 321.348846 -75.914521)
			(xy 321.397293 -75.94341) (xy 321.440965 -75.97911) (xy 321.478912 -76.020845) (xy 321.510308 -76.067706)
			(xy 321.534472 -76.118676) (xy 321.550876 -76.172644) (xy 321.559166 -76.228439) (xy 321.559682 -76.256642)
			(xy 321.55892 -76.28255) (xy 321.558666 -76.288138) (xy 321.558666 -76.290932) (xy 321.559682 -76.29779)
			(xy 321.563238 -76.30795) (xy 321.564973 -76.311614) (xy 321.569436 -76.318381) (xy 321.572128 -76.321412)
			(xy 321.576192 -76.325222) (xy 321.57797 -76.326492) (xy 321.578224 -76.326746) (xy 321.62877 -76.366624)
			(xy 321.631818 -76.36891) (xy 321.632326 -76.369164) (xy 321.647058 -76.38034) (xy 321.652023 -76.383552)
			(xy 321.663063 -76.387785) (xy 321.668902 -76.388722) (xy 321.682872 -76.389992) (xy 321.693794 -76.386436)
			(xy 321.698112 -76.385166) (xy 321.70497 -76.383134) (xy 321.729987 -76.376562) (xy 321.781217 -76.369431)
			(xy 321.807078 -76.36891) (xy 321.81038 -76.36891) (xy 321.837538 -76.369531) (xy 321.891271 -76.377516)
			(xy 321.943327 -76.393042) (xy 321.992655 -76.415795) (xy 322.038256 -76.445315) (xy 322.079209 -76.481006)
			(xy 322.114684 -76.522145) (xy 322.143965 -76.5679) (xy 322.16646 -76.617346) (xy 322.181713 -76.669483)
			(xy 322.189417 -76.723257) (xy 322.189856 -76.750418) (xy 322.189369 -76.77767) (xy 322.181611 -76.831618)
			(xy 322.166255 -76.883913) (xy 322.143613 -76.933491) (xy 322.114147 -76.979343) (xy 322.078456 -77.020535)
			(xy 322.037267 -77.056229) (xy 321.991418 -77.085699) (xy 321.941841 -77.108344) (xy 321.889547 -77.123704)
			(xy 321.8356 -77.131467) (xy 321.808348 -77.131926) (xy 321.781106 -77.131444) (xy 321.727174 -77.1237)
			(xy 321.674893 -77.108362) (xy 321.625325 -77.085742) (xy 321.57948 -77.056301) (xy 321.538289 -77.020638)
			(xy 321.502591 -76.979477) (xy 321.473111 -76.933656) (xy 321.45045 -76.884107) (xy 321.435068 -76.831839)
			(xy 321.427279 -76.777914) (xy 321.42684 -76.750672) (xy 321.42684 -76.745084) (xy 321.427602 -76.727304)
			(xy 321.427602 -76.72578) (xy 321.427856 -76.720192) (xy 321.427438 -76.709635) (xy 321.419179 -76.690212)
			(xy 321.411854 -76.6826) (xy 321.340226 -76.62672) (xy 321.336162 -76.624688) (xy 321.329304 -76.620116)
			(xy 321.306952 -76.61656) (xy 321.306444 -76.616306) (xy 321.305936 -76.616306) (xy 321.294252 -76.620116)
			(xy 321.267267 -76.628207) (xy 321.211666 -76.637266) (xy 321.183508 -76.63815) (xy 321.169284 -76.63815)
			(xy 321.165728 -76.637896) (xy 321.164712 -76.637896) (xy 321.160237 -76.637966) (xy 321.151421 -76.639497)
			(xy 321.147186 -76.640944) (xy 321.138794 -76.644361) (xy 321.124988 -76.656074) (xy 321.120262 -76.663804)
			(xy 321.090544 -76.813156) (xy 321.090798 -76.81595) (xy 321.091306 -76.818998) (xy 321.095624 -76.846938)
			(xy 321.095624 -76.847192) (xy 321.095878 -76.85024) (xy 321.09664 -76.857352) (xy 321.096894 -76.858876)
			(xy 321.096894 -76.859384) (xy 321.098418 -76.886054) (xy 321.098418 -76.887578) (xy 321.098672 -76.891642)
			(xy 321.098672 -76.89342) (xy 321.098149 -76.921767) (xy 321.089762 -76.977837) (xy 321.073191 -77.032054)
			(xy 321.048798 -77.083232) (xy 321.033394 -77.107034) (xy 321.031616 -77.109828) (xy 320.853054 -78.009496)
			(xy 320.854288 -78.014383) (xy 320.858378 -78.023595) (xy 320.861182 -78.027784) (xy 320.903346 -78.087728)
			(xy 320.91249 -78.093316) (xy 320.936874 -78.108302) (xy 320.94678 -78.11008) (xy 320.973244 -78.114884)
			(xy 321.024576 -78.130949) (xy 321.066013 -78.150664) (xy 336.40703 -78.150664) (xy 336.40703 -78.090736)
			(xy 336.414852 -78.031319) (xy 336.430363 -77.973433) (xy 336.453297 -77.918066) (xy 336.483261 -77.866166)
			(xy 336.519743 -77.818621) (xy 336.562119 -77.776245) (xy 336.609664 -77.739762) (xy 336.661564 -77.709797)
			(xy 336.716931 -77.686864) (xy 336.774817 -77.671353) (xy 336.834234 -77.66353) (xy 336.864198 -77.66304)
			(xy 337.727798 -77.66304) (xy 337.75777 -77.663413) (xy 337.817202 -77.671237) (xy 337.875104 -77.686751)
			(xy 337.930486 -77.709691) (xy 337.982399 -77.739663) (xy 338.029957 -77.776155) (xy 338.072344 -77.818542)
			(xy 338.108836 -77.866099) (xy 338.138808 -77.918013) (xy 338.161748 -77.973394) (xy 338.177263 -78.031296)
			(xy 338.185087 -78.090728) (xy 338.185087 -78.150672) (xy 338.177263 -78.210104) (xy 338.161748 -78.268006)
			(xy 338.138808 -78.323387) (xy 338.108836 -78.375301) (xy 338.072344 -78.422858) (xy 338.029957 -78.465245)
			(xy 337.982399 -78.501737) (xy 337.930486 -78.531709) (xy 337.875104 -78.554649) (xy 337.817202 -78.570163)
			(xy 337.75777 -78.577987) (xy 337.727798 -78.578456) (xy 336.864198 -78.578456) (xy 336.834234 -78.57787)
			(xy 336.774817 -78.570047) (xy 336.716931 -78.554536) (xy 336.661564 -78.531603) (xy 336.609664 -78.501638)
			(xy 336.562119 -78.465155) (xy 336.519743 -78.422779) (xy 336.483261 -78.375234) (xy 336.453297 -78.323334)
			(xy 336.430363 -78.267967) (xy 336.414852 -78.210081) (xy 336.40703 -78.150664) (xy 321.066013 -78.150664)
			(xy 321.073144 -78.154057) (xy 321.11799 -78.183753) (xy 321.158225 -78.219447) (xy 321.193052 -78.260435)
			(xy 321.221784 -78.305904) (xy 321.24385 -78.354956) (xy 321.258815 -78.406618) (xy 321.266382 -78.459869)
			(xy 321.26682 -78.486762) (xy 321.26636 -78.514017) (xy 321.258607 -78.567973) (xy 321.243255 -78.620276)
			(xy 321.220614 -78.669862) (xy 321.191148 -78.71572) (xy 321.155454 -78.756919) (xy 321.11426 -78.792618)
			(xy 321.068406 -78.82209) (xy 321.018823 -78.844737) (xy 320.966522 -78.860097) (xy 320.912567 -78.867856)
			(xy 320.885312 -78.86827) (xy 320.885058 -78.86827) (xy 320.860781 -78.867842) (xy 320.812628 -78.861606)
			(xy 320.789046 -78.855824) (xy 320.782188 -78.854046) (xy 320.774822 -78.8543) (xy 320.760598 -78.854554)
			(xy 320.691002 -78.898242) (xy 320.683382 -78.904084) (xy 320.682112 -78.905354) (xy 320.679318 -78.908148)
			(xy 320.676885 -78.912666) (xy 334.407009 -78.912666) (xy 334.407009 -78.852734) (xy 334.414832 -78.793315)
			(xy 334.430343 -78.735425) (xy 334.453278 -78.680055) (xy 334.483244 -78.628153) (xy 334.519729 -78.580606)
			(xy 334.562107 -78.538227) (xy 334.609654 -78.501743) (xy 334.661557 -78.471777) (xy 334.716927 -78.448843)
			(xy 334.774817 -78.433331) (xy 334.834236 -78.425509) (xy 334.864202 -78.42504) (xy 335.727802 -78.42504)
			(xy 335.757773 -78.425434) (xy 335.817201 -78.433258) (xy 335.8751 -78.448773) (xy 335.930479 -78.471711)
			(xy 335.982389 -78.501682) (xy 336.029944 -78.538172) (xy 336.072329 -78.580557) (xy 336.108819 -78.628112)
			(xy 336.13879 -78.680023) (xy 336.161728 -78.735402) (xy 336.177242 -78.793301) (xy 336.185066 -78.852729)
			(xy 336.185066 -78.912664) (xy 338.40703 -78.912664) (xy 338.40703 -78.852736) (xy 338.414852 -78.79332)
			(xy 338.430363 -78.735433) (xy 338.453296 -78.680067) (xy 338.48326 -78.628167) (xy 338.519742 -78.580622)
			(xy 338.562118 -78.538246) (xy 338.609662 -78.501763) (xy 338.661561 -78.471799) (xy 338.716928 -78.448865)
			(xy 338.774814 -78.433353) (xy 338.83423 -78.42553) (xy 338.864194 -78.42504) (xy 339.727794 -78.42504)
			(xy 339.757766 -78.425412) (xy 339.817199 -78.433236) (xy 339.875101 -78.44875) (xy 339.930483 -78.47169)
			(xy 339.982397 -78.501662) (xy 340.029955 -78.538153) (xy 340.072343 -78.580541) (xy 340.108835 -78.628098)
			(xy 340.138808 -78.680011) (xy 340.161748 -78.735393) (xy 340.177263 -78.793296) (xy 340.185087 -78.852728)
			(xy 340.185087 -78.912672) (xy 340.177263 -78.972104) (xy 340.161748 -79.030007) (xy 340.138808 -79.085389)
			(xy 340.108835 -79.137302) (xy 340.072343 -79.184859) (xy 340.029955 -79.227247) (xy 339.982397 -79.263738)
			(xy 339.930483 -79.29371) (xy 339.875101 -79.31665) (xy 339.817199 -79.332164) (xy 339.757766 -79.339988)
			(xy 339.727794 -79.340456) (xy 338.864194 -79.340456) (xy 338.83423 -79.33987) (xy 338.774814 -79.332047)
			(xy 338.716928 -79.316535) (xy 338.661561 -79.293601) (xy 338.609662 -79.263637) (xy 338.562118 -79.227154)
			(xy 338.519742 -79.184778) (xy 338.48326 -79.137233) (xy 338.453296 -79.085333) (xy 338.430363 -79.029967)
			(xy 338.414852 -78.97208) (xy 338.40703 -78.912664) (xy 336.185066 -78.912664) (xy 336.185066 -78.912671)
			(xy 336.177242 -78.972099) (xy 336.161728 -79.029998) (xy 336.13879 -79.085377) (xy 336.108819 -79.137288)
			(xy 336.072329 -79.184843) (xy 336.029944 -79.227228) (xy 335.982389 -79.263718) (xy 335.930479 -79.293689)
			(xy 335.8751 -79.316627) (xy 335.817201 -79.332142) (xy 335.757773 -79.339966) (xy 335.727802 -79.340456)
			(xy 334.864202 -79.340456) (xy 334.834236 -79.339891) (xy 334.774817 -79.332069) (xy 334.716927 -79.316557)
			(xy 334.661557 -79.293623) (xy 334.609654 -79.263657) (xy 334.562107 -79.227173) (xy 334.519729 -79.184794)
			(xy 334.483244 -79.137247) (xy 334.453278 -79.085345) (xy 334.430343 -79.029975) (xy 334.414832 -78.972085)
			(xy 334.407009 -78.912666) (xy 320.676885 -78.912666) (xy 320.675762 -78.914752) (xy 320.674012 -78.918119)
			(xy 320.671458 -78.925262) (xy 320.670682 -78.928976) (xy 320.620136 -79.1845) (xy 320.491866 -79.83093)
			(xy 320.386202 -80.363568) (xy 320.392044 -80.374744) (xy 320.399918 -80.384904) (xy 320.40068 -80.38592)
			(xy 320.419222 -80.409796) (xy 320.434462 -80.429354) (xy 320.438282 -80.433963) (xy 320.447648 -80.441414)
			(xy 320.453004 -80.444086) (xy 320.462148 -80.448404) (xy 320.478912 -80.456024) (xy 320.48831 -80.456786)
			(xy 320.488564 -80.456786) (xy 320.50736 -80.458564) (xy 320.535262 -80.462458) (xy 320.589587 -80.477377)
			(xy 320.615564 -80.488282) (xy 320.617596 -80.489298) (xy 320.645691 -80.502606) (xy 320.69751 -80.536943)
			(xy 320.72072 -80.557624) (xy 320.720974 -80.557878) (xy 320.72199 -80.55864) (xy 320.732105 -80.568307)
			(xy 320.751049 -80.5889) (xy 320.759836 -80.599788) (xy 320.773044 -80.616552) (xy 320.773806 -80.617568)
			(xy 320.78295 -80.631792) (xy 320.792094 -80.647032) (xy 320.79692 -80.655668) (xy 320.799714 -80.661002)
			(xy 320.81313 -80.687991) (xy 320.832226 -80.745155) (xy 320.842107 -80.804608) (xy 320.842894 -80.834738)
			(xy 320.842894 -80.847184) (xy 320.841921 -80.862753) (xy 331.324655 -80.862753) (xy 331.324655 -80.808247)
			(xy 331.332413 -80.754295) (xy 331.347769 -80.701996) (xy 331.370413 -80.652415) (xy 331.399882 -80.606561)
			(xy 331.435577 -80.565368) (xy 331.476771 -80.529675) (xy 331.522625 -80.500207) (xy 331.572207 -80.477565)
			(xy 331.624506 -80.46221) (xy 331.678459 -80.454455) (xy 331.705712 -80.453992) (xy 331.733082 -80.454453)
			(xy 331.787262 -80.462272) (xy 331.839765 -80.477763) (xy 331.889511 -80.500605) (xy 331.935478 -80.530331)
			(xy 331.95641 -80.547972) (xy 331.956664 -80.548226) (xy 331.963755 -80.553807) (xy 331.980668 -80.560056)
			(xy 331.989684 -80.560418) (xy 332.05674 -80.560418) (xy 332.065758 -80.560076) (xy 332.082675 -80.553818)
			(xy 332.08976 -80.548226) (xy 332.08976 -80.547972) (xy 332.090014 -80.547972) (xy 332.110964 -80.530355)
			(xy 332.156932 -80.500641) (xy 332.206675 -80.477801) (xy 332.259172 -80.462305) (xy 332.313344 -80.45447)
			(xy 332.340712 -80.453992) (xy 332.367963 -80.454479) (xy 332.421909 -80.462237) (xy 332.474202 -80.477593)
			(xy 332.523778 -80.500235) (xy 332.569627 -80.529701) (xy 332.610816 -80.565393) (xy 332.646506 -80.606583)
			(xy 332.675971 -80.652432) (xy 332.698612 -80.702009) (xy 332.713966 -80.754303) (xy 332.721722 -80.808249)
			(xy 332.721722 -80.862751) (xy 332.713966 -80.916697) (xy 332.698612 -80.968991) (xy 332.675971 -81.018568)
			(xy 332.646506 -81.064417) (xy 332.610816 -81.105607) (xy 332.569627 -81.141299) (xy 332.523778 -81.170765)
			(xy 332.474202 -81.193407) (xy 332.421909 -81.208763) (xy 332.367963 -81.216521) (xy 332.340712 -81.217008)
			(xy 332.313342 -81.216533) (xy 332.259164 -81.208717) (xy 332.206661 -81.19323) (xy 332.156914 -81.17039)
			(xy 332.110946 -81.140668) (xy 332.090014 -81.123028) (xy 332.08976 -81.122774) (xy 332.082663 -81.117204)
			(xy 332.065754 -81.110948) (xy 332.05674 -81.110582) (xy 331.989684 -81.110582) (xy 331.980667 -81.110935)
			(xy 331.96375 -81.117186) (xy 331.956664 -81.122774) (xy 331.956664 -81.123028) (xy 331.95641 -81.123028)
			(xy 331.935489 -81.14068) (xy 331.889512 -81.170389) (xy 331.839762 -81.193222) (xy 331.787259 -81.20871)
			(xy 331.733082 -81.216535) (xy 331.705712 -81.217008) (xy 331.678459 -81.216545) (xy 331.624506 -81.20879)
			(xy 331.572207 -81.193435) (xy 331.522625 -81.170793) (xy 331.476771 -81.141325) (xy 331.435577 -81.105632)
			(xy 331.399882 -81.064439) (xy 331.370413 -81.018585) (xy 331.347769 -80.969004) (xy 331.332413 -80.916705)
			(xy 331.324655 -80.862753) (xy 320.841921 -80.862753) (xy 320.841116 -80.875632) (xy 320.840354 -80.88249)
			(xy 320.840354 -80.909414) (xy 320.84093 -80.919953) (xy 320.849449 -80.939242) (xy 320.856864 -80.946752)
			(xy 320.872104 -80.95996) (xy 320.919856 -81.001362) (xy 320.921126 -81.002378) (xy 320.927913 -81.007287)
			(xy 320.943744 -81.012732) (xy 320.952114 -81.013046) (xy 320.957702 -81.013046) (xy 320.967608 -81.01203)
			(xy 320.97218 -81.010506) (xy 320.999104 -81.003648) (xy 320.999358 -81.003648) (xy 321.004438 -81.002632)
			(xy 321.033648 -80.99806) (xy 321.04711 -80.996536) (xy 321.05219 -80.996536) (xy 321.078352 -80.99552)
			(xy 321.09109 -80.995597) (xy 321.116512 -80.997247) (xy 321.129152 -80.998822) (xy 321.152485 -81.002273)
			(xy 321.198119 -81.014208) (xy 321.241926 -81.031697) (xy 321.262756 -81.042764) (xy 321.267582 -81.045304)
			(xy 321.915536 -81.045304) (xy 321.94156 -81.04583) (xy 321.992966 -81.053994) (xy 322.042466 -81.070085)
			(xy 322.088846 -81.093708) (xy 322.130969 -81.124283) (xy 322.149724 -81.142332) (xy 322.560696 -81.553304)
			(xy 322.578726 -81.572076) (xy 322.609302 -81.614194) (xy 322.632924 -81.66057) (xy 322.649013 -81.710067)
			(xy 322.657174 -81.761469) (xy 322.657724 -81.787492) (xy 322.657724 -82.296) (xy 328.293982 -82.296)
			(xy 328.298053 -82.240378) (xy 328.310179 -82.185941) (xy 328.330102 -82.13385) (xy 328.357398 -82.085215)
			(xy 328.391484 -82.041072) (xy 328.431633 -82.002363) (xy 328.476991 -81.969912) (xy 328.526591 -81.944411)
			(xy 328.579375 -81.926404) (xy 328.634218 -81.916274) (xy 328.689952 -81.914237) (xy 328.745389 -81.920337)
			(xy 328.799346 -81.934443) (xy 328.850675 -81.956255) (xy 328.860072 -81.96199) (xy 338.037168 -81.96199)
			(xy 338.041239 -81.906368) (xy 338.053365 -81.851931) (xy 338.073288 -81.79984) (xy 338.100584 -81.751205)
			(xy 338.13467 -81.707062) (xy 338.174819 -81.668353) (xy 338.220177 -81.635902) (xy 338.269777 -81.610401)
			(xy 338.322561 -81.592394) (xy 338.377404 -81.582264) (xy 338.433138 -81.580227) (xy 338.488575 -81.586327)
			(xy 338.542532 -81.600433) (xy 338.593861 -81.622245) (xy 338.641467 -81.651299) (xy 338.684335 -81.686974)
			(xy 338.721552 -81.728511) (xy 338.752325 -81.775024) (xy 338.775997 -81.825521) (xy 338.792065 -81.878928)
			(xy 338.798831 -81.924906) (xy 342.007442 -81.924906) (xy 342.011513 -81.869284) (xy 342.023639 -81.814847)
			(xy 342.043562 -81.762756) (xy 342.070858 -81.714121) (xy 342.104944 -81.669978) (xy 342.145093 -81.631269)
			(xy 342.190451 -81.598818) (xy 342.240051 -81.573317) (xy 342.292835 -81.55531) (xy 342.347678 -81.54518)
			(xy 342.403412 -81.543143) (xy 342.458849 -81.549243) (xy 342.512806 -81.563349) (xy 342.564135 -81.585161)
			(xy 342.611741 -81.614215) (xy 342.654609 -81.64989) (xy 342.691826 -81.691427) (xy 342.722599 -81.73794)
			(xy 342.746271 -81.788437) (xy 342.762339 -81.841844) (xy 342.770459 -81.89702) (xy 342.770968 -81.924906)
			(xy 342.770459 -81.952792) (xy 342.762339 -82.007968) (xy 342.746271 -82.061375) (xy 342.722599 -82.111872)
			(xy 342.691826 -82.158385) (xy 342.654609 -82.199922) (xy 342.611741 -82.235597) (xy 342.564135 -82.264651)
			(xy 342.512806 -82.286463) (xy 342.458849 -82.300569) (xy 342.403412 -82.306669) (xy 342.347678 -82.304632)
			(xy 342.292835 -82.294502) (xy 342.240051 -82.276495) (xy 342.190451 -82.250994) (xy 342.145093 -82.218543)
			(xy 342.104944 -82.179834) (xy 342.070858 -82.135691) (xy 342.043562 -82.087056) (xy 342.023639 -82.034965)
			(xy 342.011513 -81.980528) (xy 342.007442 -81.924906) (xy 338.798831 -81.924906) (xy 338.800185 -81.934104)
			(xy 338.800694 -81.96199) (xy 338.800185 -81.989876) (xy 338.792065 -82.045052) (xy 338.775997 -82.098459)
			(xy 338.752325 -82.148956) (xy 338.721552 -82.195469) (xy 338.684335 -82.237006) (xy 338.641467 -82.272681)
			(xy 338.593861 -82.301735) (xy 338.542532 -82.323547) (xy 338.488575 -82.337653) (xy 338.433138 -82.343753)
			(xy 338.377404 -82.341716) (xy 338.322561 -82.331586) (xy 338.269777 -82.313579) (xy 338.220177 -82.288078)
			(xy 338.174819 -82.255627) (xy 338.13467 -82.216918) (xy 338.100584 -82.172775) (xy 338.073288 -82.12414)
			(xy 338.053365 -82.072049) (xy 338.041239 -82.017612) (xy 338.037168 -81.96199) (xy 328.860072 -81.96199)
			(xy 328.898281 -81.985309) (xy 328.941149 -82.020984) (xy 328.978366 -82.062521) (xy 329.009139 -82.109034)
			(xy 329.032811 -82.159531) (xy 329.048879 -82.212938) (xy 329.056999 -82.268114) (xy 329.057508 -82.296)
			(xy 329.056999 -82.323886) (xy 329.048879 -82.379062) (xy 329.032811 -82.432469) (xy 329.009139 -82.482966)
			(xy 328.978366 -82.529479) (xy 328.941149 -82.571016) (xy 328.898281 -82.606691) (xy 328.850675 -82.635745)
			(xy 328.799346 -82.657557) (xy 328.745389 -82.671663) (xy 328.689952 -82.677763) (xy 328.634218 -82.675726)
			(xy 328.579375 -82.665596) (xy 328.526591 -82.647589) (xy 328.476991 -82.622088) (xy 328.431633 -82.589637)
			(xy 328.391484 -82.550928) (xy 328.357398 -82.506785) (xy 328.330102 -82.45815) (xy 328.310179 -82.406059)
			(xy 328.298053 -82.351622) (xy 328.293982 -82.296) (xy 322.657724 -82.296) (xy 322.657724 -82.677508)
			(xy 322.657192 -82.70353) (xy 322.649017 -82.754928) (xy 322.632915 -82.804419) (xy 322.609282 -82.850788)
			(xy 322.578698 -82.892897) (xy 322.560696 -82.911696) (xy 322.492624 -82.979768) (xy 330.579982 -82.979768)
			(xy 330.584053 -82.924146) (xy 330.596179 -82.869709) (xy 330.616102 -82.817618) (xy 330.643398 -82.768983)
			(xy 330.677484 -82.72484) (xy 330.717633 -82.686131) (xy 330.762991 -82.65368) (xy 330.812591 -82.628179)
			(xy 330.865375 -82.610172) (xy 330.920218 -82.600042) (xy 330.975952 -82.598005) (xy 331.031389 -82.604105)
			(xy 331.085346 -82.618211) (xy 331.136675 -82.640023) (xy 331.184281 -82.669077) (xy 331.227149 -82.704752)
			(xy 331.264366 -82.746289) (xy 331.295139 -82.792802) (xy 331.318811 -82.843299) (xy 331.334879 -82.896706)
			(xy 331.342999 -82.951882) (xy 331.343508 -82.979768) (xy 331.343383 -82.986626) (xy 336.313524 -82.986626)
			(xy 336.317595 -82.931004) (xy 336.329721 -82.876567) (xy 336.349644 -82.824476) (xy 336.37694 -82.775841)
			(xy 336.411026 -82.731698) (xy 336.451175 -82.692989) (xy 336.496533 -82.660538) (xy 336.546133 -82.635037)
			(xy 336.598917 -82.61703) (xy 336.65376 -82.6069) (xy 336.709494 -82.604863) (xy 336.764931 -82.610963)
			(xy 336.818888 -82.625069) (xy 336.870217 -82.646881) (xy 336.917823 -82.675935) (xy 336.960691 -82.71161)
			(xy 336.997908 -82.753147) (xy 337.028681 -82.79966) (xy 337.052353 -82.850157) (xy 337.065671 -82.894424)
			(xy 338.088984 -82.894424) (xy 338.093055 -82.838802) (xy 338.105181 -82.784365) (xy 338.125104 -82.732274)
			(xy 338.1524 -82.683639) (xy 338.186486 -82.639496) (xy 338.226635 -82.600787) (xy 338.271993 -82.568336)
			(xy 338.321593 -82.542835) (xy 338.374377 -82.524828) (xy 338.42922 -82.514698) (xy 338.484954 -82.512661)
			(xy 338.540391 -82.518761) (xy 338.594348 -82.532867) (xy 338.645677 -82.554679) (xy 338.693283 -82.583733)
			(xy 338.736151 -82.619408) (xy 338.773368 -82.660945) (xy 338.804141 -82.707458) (xy 338.827813 -82.757955)
			(xy 338.836011 -82.785204) (xy 340.274908 -82.785204) (xy 340.278979 -82.729582) (xy 340.291105 -82.675145)
			(xy 340.311028 -82.623054) (xy 340.338324 -82.574419) (xy 340.37241 -82.530276) (xy 340.412559 -82.491567)
			(xy 340.457917 -82.459116) (xy 340.507517 -82.433615) (xy 340.560301 -82.415608) (xy 340.615144 -82.405478)
			(xy 340.670878 -82.403441) (xy 340.726315 -82.409541) (xy 340.780272 -82.423647) (xy 340.831601 -82.445459)
			(xy 340.879207 -82.474513) (xy 340.922075 -82.510188) (xy 340.959292 -82.551725) (xy 340.990065 -82.598238)
			(xy 341.013737 -82.648735) (xy 341.029805 -82.702142) (xy 341.037925 -82.757318) (xy 341.038434 -82.785204)
			(xy 341.037925 -82.81309) (xy 341.029805 -82.868266) (xy 341.013737 -82.921673) (xy 340.990065 -82.97217)
			(xy 340.959292 -83.018683) (xy 340.922075 -83.06022) (xy 340.879207 -83.095895) (xy 340.831601 -83.124949)
			(xy 340.780272 -83.146761) (xy 340.726315 -83.160867) (xy 340.670878 -83.166967) (xy 340.615144 -83.16493)
			(xy 340.560301 -83.1548) (xy 340.507517 -83.136793) (xy 340.457917 -83.111292) (xy 340.412559 -83.078841)
			(xy 340.37241 -83.040132) (xy 340.338324 -82.995989) (xy 340.311028 -82.947354) (xy 340.291105 -82.895263)
			(xy 340.278979 -82.840826) (xy 340.274908 -82.785204) (xy 338.836011 -82.785204) (xy 338.843881 -82.811362)
			(xy 338.852001 -82.866538) (xy 338.85251 -82.894424) (xy 338.852001 -82.92231) (xy 338.843881 -82.977486)
			(xy 338.827813 -83.030893) (xy 338.804141 -83.08139) (xy 338.773368 -83.127903) (xy 338.736151 -83.16944)
			(xy 338.693283 -83.205115) (xy 338.645677 -83.234169) (xy 338.594348 -83.255981) (xy 338.540391 -83.270087)
			(xy 338.484954 -83.276187) (xy 338.42922 -83.27415) (xy 338.374377 -83.26402) (xy 338.321593 -83.246013)
			(xy 338.271993 -83.220512) (xy 338.226635 -83.188061) (xy 338.186486 -83.149352) (xy 338.1524 -83.105209)
			(xy 338.125104 -83.056574) (xy 338.105181 -83.004483) (xy 338.093055 -82.950046) (xy 338.088984 -82.894424)
			(xy 337.065671 -82.894424) (xy 337.068421 -82.903564) (xy 337.076541 -82.95874) (xy 337.07705 -82.986626)
			(xy 337.076541 -83.014512) (xy 337.068421 -83.069688) (xy 337.052353 -83.123095) (xy 337.028681 -83.173592)
			(xy 336.997908 -83.220105) (xy 336.960691 -83.261642) (xy 336.917823 -83.297317) (xy 336.870217 -83.326371)
			(xy 336.818888 -83.348183) (xy 336.764931 -83.362289) (xy 336.709494 -83.368389) (xy 336.65376 -83.366352)
			(xy 336.598917 -83.356222) (xy 336.546133 -83.338215) (xy 336.496533 -83.312714) (xy 336.451175 -83.280263)
			(xy 336.411026 -83.241554) (xy 336.37694 -83.197411) (xy 336.349644 -83.148776) (xy 336.329721 -83.096685)
			(xy 336.317595 -83.042248) (xy 336.313524 -82.986626) (xy 331.343383 -82.986626) (xy 331.342999 -83.007654)
			(xy 331.334879 -83.06283) (xy 331.318811 -83.116237) (xy 331.295139 -83.166734) (xy 331.264366 -83.213247)
			(xy 331.227149 -83.254784) (xy 331.184281 -83.290459) (xy 331.136675 -83.319513) (xy 331.085346 -83.341325)
			(xy 331.031389 -83.355431) (xy 330.975952 -83.361531) (xy 330.920218 -83.359494) (xy 330.865375 -83.349364)
			(xy 330.812591 -83.331357) (xy 330.762991 -83.305856) (xy 330.717633 -83.273405) (xy 330.677484 -83.234696)
			(xy 330.643398 -83.190553) (xy 330.616102 -83.141918) (xy 330.596179 -83.089827) (xy 330.584053 -83.03539)
			(xy 330.579982 -82.979768) (xy 322.492624 -82.979768) (xy 322.452492 -83.0199) (xy 322.449788 -83.022752)
			(xy 322.445198 -83.029132) (xy 322.443348 -83.0326) (xy 322.440758 -83.038025) (xy 322.437922 -83.049705)
			(xy 322.43776 -83.055714) (xy 322.43776 -83.98637) (xy 327.111612 -83.98637) (xy 327.115683 -83.930748)
			(xy 327.127809 -83.876311) (xy 327.147732 -83.82422) (xy 327.175028 -83.775585) (xy 327.209114 -83.731442)
			(xy 327.249263 -83.692733) (xy 327.294621 -83.660282) (xy 327.344221 -83.634781) (xy 327.397005 -83.616774)
			(xy 327.451848 -83.606644) (xy 327.507582 -83.604607) (xy 327.563019 -83.610707) (xy 327.616976 -83.624813)
			(xy 327.668305 -83.646625) (xy 327.715911 -83.675679) (xy 327.758779 -83.711354) (xy 327.795996 -83.752891)
			(xy 327.826769 -83.799404) (xy 327.850441 -83.849901) (xy 327.866509 -83.903308) (xy 327.874629 -83.958484)
			(xy 327.875138 -83.98637) (xy 327.874629 -84.014256) (xy 327.866509 -84.069432) (xy 327.865135 -84.074)
			(xy 330.579982 -84.074) (xy 330.584053 -84.018378) (xy 330.596179 -83.963941) (xy 330.616102 -83.91185)
			(xy 330.643398 -83.863215) (xy 330.677484 -83.819072) (xy 330.717633 -83.780363) (xy 330.762991 -83.747912)
			(xy 330.812591 -83.722411) (xy 330.865375 -83.704404) (xy 330.920218 -83.694274) (xy 330.975952 -83.692237)
			(xy 331.031389 -83.698337) (xy 331.085346 -83.712443) (xy 331.136675 -83.734255) (xy 331.184281 -83.763309)
			(xy 331.227149 -83.798984) (xy 331.264366 -83.840521) (xy 331.295139 -83.887034) (xy 331.318811 -83.937531)
			(xy 331.334879 -83.990938) (xy 331.342999 -84.046114) (xy 331.343508 -84.074) (xy 331.342999 -84.101886)
			(xy 331.336711 -84.144612) (xy 345.879928 -84.144612) (xy 345.879928 -83.281012) (xy 345.880418 -83.251028)
			(xy 345.888246 -83.191572) (xy 345.903767 -83.133647) (xy 345.926716 -83.078243) (xy 345.9567 -83.026309)
			(xy 345.993206 -82.978733) (xy 346.035611 -82.936328) (xy 346.083187 -82.899822) (xy 346.135121 -82.869838)
			(xy 346.190525 -82.846889) (xy 346.24845 -82.831368) (xy 346.307906 -82.82354) (xy 346.367874 -82.82354)
			(xy 346.42733 -82.831368) (xy 346.485255 -82.846889) (xy 346.540659 -82.869838) (xy 346.592593 -82.899822)
			(xy 346.640169 -82.936328) (xy 346.682574 -82.978733) (xy 346.71908 -83.026309) (xy 346.749064 -83.078243)
			(xy 346.772013 -83.133647) (xy 346.787534 -83.191572) (xy 346.795362 -83.251028) (xy 346.795852 -83.281012)
			(xy 346.795852 -84.144612) (xy 346.795362 -84.174596) (xy 346.787534 -84.234052) (xy 346.772013 -84.291977)
			(xy 346.749064 -84.347381) (xy 346.71908 -84.399315) (xy 346.682574 -84.446891) (xy 346.640169 -84.489296)
			(xy 346.592593 -84.525802) (xy 346.540659 -84.555786) (xy 346.485255 -84.578735) (xy 346.42733 -84.594256)
			(xy 346.367874 -84.602084) (xy 346.307906 -84.602084) (xy 346.24845 -84.594256) (xy 346.190525 -84.578735)
			(xy 346.135121 -84.555786) (xy 346.083187 -84.525802) (xy 346.035611 -84.489296) (xy 345.993206 -84.446891)
			(xy 345.9567 -84.399315) (xy 345.926716 -84.347381) (xy 345.903767 -84.291977) (xy 345.888246 -84.234052)
			(xy 345.880418 -84.174596) (xy 345.879928 -84.144612) (xy 331.336711 -84.144612) (xy 331.334879 -84.157062)
			(xy 331.318811 -84.210469) (xy 331.295139 -84.260966) (xy 331.264366 -84.307479) (xy 331.227149 -84.349016)
			(xy 331.184281 -84.384691) (xy 331.136675 -84.413745) (xy 331.085346 -84.435557) (xy 331.031389 -84.449663)
			(xy 330.975952 -84.455763) (xy 330.920218 -84.453726) (xy 330.865375 -84.443596) (xy 330.812591 -84.425589)
			(xy 330.762991 -84.400088) (xy 330.717633 -84.367637) (xy 330.677484 -84.328928) (xy 330.643398 -84.284785)
			(xy 330.616102 -84.23615) (xy 330.596179 -84.184059) (xy 330.584053 -84.129622) (xy 330.579982 -84.074)
			(xy 327.865135 -84.074) (xy 327.850441 -84.122839) (xy 327.826769 -84.173336) (xy 327.795996 -84.219849)
			(xy 327.758779 -84.261386) (xy 327.715911 -84.297061) (xy 327.668305 -84.326115) (xy 327.616976 -84.347927)
			(xy 327.563019 -84.362033) (xy 327.507582 -84.368133) (xy 327.451848 -84.366096) (xy 327.397005 -84.355966)
			(xy 327.344221 -84.337959) (xy 327.294621 -84.312458) (xy 327.249263 -84.280007) (xy 327.209114 -84.241298)
			(xy 327.175028 -84.197155) (xy 327.147732 -84.14852) (xy 327.127809 -84.096429) (xy 327.115683 -84.041992)
			(xy 327.111612 -83.98637) (xy 322.43776 -83.98637) (xy 322.43776 -85.09) (xy 327.912982 -85.09) (xy 327.917053 -85.034378)
			(xy 327.929179 -84.979941) (xy 327.949102 -84.92785) (xy 327.976398 -84.879215) (xy 328.010484 -84.835072)
			(xy 328.050633 -84.796363) (xy 328.095991 -84.763912) (xy 328.145591 -84.738411) (xy 328.198375 -84.720404)
			(xy 328.253218 -84.710274) (xy 328.308952 -84.708237) (xy 328.364389 -84.714337) (xy 328.418346 -84.728443)
			(xy 328.469675 -84.750255) (xy 328.517281 -84.779309) (xy 328.560149 -84.814984) (xy 328.597366 -84.856521)
			(xy 328.628139 -84.903034) (xy 328.651811 -84.953531) (xy 328.660311 -84.981782) (xy 332.927949 -84.981782)
			(xy 332.935701 -84.927831) (xy 332.951052 -84.875531) (xy 332.97369 -84.825949) (xy 333.003154 -84.780093)
			(xy 333.038843 -84.738897) (xy 333.080033 -84.703199) (xy 333.125883 -84.673726) (xy 333.175461 -84.651079)
			(xy 333.227757 -84.635717) (xy 333.281707 -84.627955) (xy 333.30896 -84.627466) (xy 333.3377 -84.627962)
			(xy 333.394528 -84.636593) (xy 333.449419 -84.65365) (xy 333.50113 -84.678747) (xy 333.548492 -84.711317)
			(xy 333.569818 -84.73059) (xy 333.576632 -84.736397) (xy 333.593069 -84.74345) (xy 333.610925 -84.744471)
			(xy 333.619602 -84.742274) (xy 333.717138 -84.712048) (xy 333.735426 -84.691982) (xy 333.738474 -84.678774)
			(xy 333.745269 -84.650944) (xy 333.766005 -84.597544) (xy 333.79449 -84.547843) (xy 333.830084 -84.502958)
			(xy 333.871987 -84.463897) (xy 333.919257 -84.431538) (xy 333.970833 -84.406608) (xy 334.025555 -84.389667)
			(xy 334.082196 -84.381096) (xy 334.110838 -84.380578) (xy 334.13809 -84.381042) (xy 334.192037 -84.388804)
			(xy 334.244332 -84.404163) (xy 334.293908 -84.426808) (xy 334.339758 -84.456276) (xy 334.380947 -84.49197)
			(xy 334.416638 -84.533162) (xy 334.446104 -84.579013) (xy 334.468745 -84.628591) (xy 334.484101 -84.680886)
			(xy 334.491859 -84.734834) (xy 334.492346 -84.762086) (xy 334.491869 -84.790055) (xy 334.483714 -84.845395)
			(xy 334.467562 -84.898949) (xy 334.44376 -84.94957) (xy 334.412819 -84.996171) (xy 334.375402 -85.037751)
			(xy 334.35417 -85.055964) (xy 334.346042 -85.062822) (xy 334.33639 -85.081872) (xy 334.331818 -85.167216)
			(xy 334.331824 -85.177844) (xy 334.33945 -85.197659) (xy 334.34655 -85.20557) (xy 334.367046 -85.22711)
			(xy 334.401742 -85.275395) (xy 334.428525 -85.328478) (xy 334.440065 -85.36432) (xy 341.504268 -85.36432)
			(xy 341.508339 -85.308698) (xy 341.520465 -85.254261) (xy 341.540388 -85.20217) (xy 341.567684 -85.153535)
			(xy 341.60177 -85.109392) (xy 341.641919 -85.070683) (xy 341.687277 -85.038232) (xy 341.736877 -85.012731)
			(xy 341.789661 -84.994724) (xy 341.844504 -84.984594) (xy 341.900238 -84.982557) (xy 341.955675 -84.988657)
			(xy 342.009632 -85.002763) (xy 342.060961 -85.024575) (xy 342.108567 -85.053629) (xy 342.151435 -85.089304)
			(xy 342.188652 -85.130841) (xy 342.219425 -85.177354) (xy 342.243097 -85.227851) (xy 342.259165 -85.281258)
			(xy 342.267285 -85.336434) (xy 342.267794 -85.36432) (xy 342.267285 -85.392206) (xy 342.259165 -85.447382)
			(xy 342.243097 -85.500789) (xy 342.219425 -85.551286) (xy 342.188652 -85.597799) (xy 342.151435 -85.639336)
			(xy 342.108567 -85.675011) (xy 342.060961 -85.704065) (xy 342.009632 -85.725877) (xy 341.955675 -85.739983)
			(xy 341.900238 -85.746083) (xy 341.844504 -85.744046) (xy 341.789661 -85.733916) (xy 341.736877 -85.715909)
			(xy 341.687277 -85.690408) (xy 341.641919 -85.657957) (xy 341.60177 -85.619248) (xy 341.567684 -85.575105)
			(xy 341.540388 -85.52647) (xy 341.520465 -85.474379) (xy 341.508339 -85.419942) (xy 341.504268 -85.36432)
			(xy 334.440065 -85.36432) (xy 334.446747 -85.385074) (xy 334.455966 -85.443811) (xy 334.456532 -85.47354)
			(xy 334.456046 -85.500791) (xy 334.44829 -85.554739) (xy 334.432935 -85.607034) (xy 334.410293 -85.656611)
			(xy 334.380827 -85.702461) (xy 334.345136 -85.743652) (xy 334.303945 -85.779343) (xy 334.258095 -85.808809)
			(xy 334.208518 -85.831451) (xy 334.156223 -85.846806) (xy 334.102275 -85.854562) (xy 334.047773 -85.854562)
			(xy 333.993825 -85.846806) (xy 333.94153 -85.831451) (xy 333.891953 -85.808809) (xy 333.846103 -85.779343)
			(xy 333.804912 -85.743652) (xy 333.769221 -85.702461) (xy 333.739755 -85.656611) (xy 333.717113 -85.607034)
			(xy 333.701758 -85.554739) (xy 333.694002 -85.500791) (xy 333.693516 -85.47354) (xy 333.694025 -85.445572)
			(xy 333.702175 -85.390235) (xy 333.718322 -85.336681) (xy 333.742118 -85.286061) (xy 333.773053 -85.239459)
			(xy 333.810463 -85.197876) (xy 333.831692 -85.179662) (xy 333.83982 -85.172804) (xy 333.849472 -85.153754)
			(xy 333.854044 -85.06841) (xy 333.854034 -85.057782) (xy 333.846411 -85.037966) (xy 333.839312 -85.030056)
			(xy 333.823735 -85.013812) (xy 333.796102 -84.978287) (xy 333.784194 -84.95919) (xy 333.778783 -84.951164)
			(xy 333.76341 -84.939443) (xy 333.744787 -84.934255) (xy 333.725568 -84.936339) (xy 333.70849 -84.945399)
			(xy 333.695987 -84.960143) (xy 333.68984 -84.978472) (xy 333.68996 -84.988146) (xy 333.690468 -85.008974)
			(xy 333.69005 -85.036227) (xy 333.682297 -85.090178) (xy 333.666944 -85.142477) (xy 333.644305 -85.192059)
			(xy 333.614841 -85.237915) (xy 333.57915 -85.27911) (xy 333.53796 -85.314807) (xy 333.492109 -85.344278)
			(xy 333.442531 -85.366925) (xy 333.390234 -85.382285) (xy 333.336284 -85.390046) (xy 333.281778 -85.39005)
			(xy 333.227826 -85.382298) (xy 333.175527 -85.366946) (xy 333.125945 -85.344308) (xy 333.080089 -85.314844)
			(xy 333.038893 -85.279153) (xy 333.003196 -85.237964) (xy 332.973724 -85.192113) (xy 332.951077 -85.142535)
			(xy 332.935716 -85.090238) (xy 332.927954 -85.036288) (xy 332.927949 -84.981782) (xy 328.660311 -84.981782)
			(xy 328.667879 -85.006938) (xy 328.675999 -85.062114) (xy 328.676508 -85.09) (xy 328.675999 -85.117886)
			(xy 328.667879 -85.173062) (xy 328.651811 -85.226469) (xy 328.628139 -85.276966) (xy 328.597366 -85.323479)
			(xy 328.560149 -85.365016) (xy 328.517281 -85.400691) (xy 328.469675 -85.429745) (xy 328.418346 -85.451557)
			(xy 328.364389 -85.465663) (xy 328.308952 -85.471763) (xy 328.253218 -85.469726) (xy 328.198375 -85.459596)
			(xy 328.145591 -85.441589) (xy 328.095991 -85.416088) (xy 328.050633 -85.383637) (xy 328.010484 -85.344928)
			(xy 327.976398 -85.300785) (xy 327.949102 -85.25215) (xy 327.929179 -85.200059) (xy 327.917053 -85.145622)
			(xy 327.912982 -85.09) (xy 322.43776 -85.09) (xy 322.43776 -85.979) (xy 328.039982 -85.979) (xy 328.044053 -85.923378)
			(xy 328.056179 -85.868941) (xy 328.076102 -85.81685) (xy 328.103398 -85.768215) (xy 328.137484 -85.724072)
			(xy 328.177633 -85.685363) (xy 328.222991 -85.652912) (xy 328.272591 -85.627411) (xy 328.325375 -85.609404)
			(xy 328.380218 -85.599274) (xy 328.435952 -85.597237) (xy 328.491389 -85.603337) (xy 328.545346 -85.617443)
			(xy 328.596675 -85.639255) (xy 328.644281 -85.668309) (xy 328.687149 -85.703984) (xy 328.724366 -85.745521)
			(xy 328.755139 -85.792034) (xy 328.778811 -85.842531) (xy 328.794879 -85.895938) (xy 328.802999 -85.951114)
			(xy 328.803508 -85.979) (xy 328.802999 -86.006886) (xy 328.794879 -86.062062) (xy 328.778811 -86.115469)
			(xy 328.755139 -86.165966) (xy 328.724366 -86.212479) (xy 328.687149 -86.254016) (xy 328.644281 -86.289691)
			(xy 328.596675 -86.318745) (xy 328.545346 -86.340557) (xy 328.491389 -86.354663) (xy 328.435952 -86.360763)
			(xy 328.380218 -86.358726) (xy 328.325375 -86.348596) (xy 328.272591 -86.330589) (xy 328.222991 -86.305088)
			(xy 328.177633 -86.272637) (xy 328.137484 -86.233928) (xy 328.103398 -86.189785) (xy 328.076102 -86.14115)
			(xy 328.056179 -86.089059) (xy 328.044053 -86.034622) (xy 328.039982 -85.979) (xy 322.43776 -85.979)
			(xy 322.43776 -86.66988) (xy 322.437275 -86.695968) (xy 322.429111 -86.747501) (xy 322.412982 -86.797121)
			(xy 322.389284 -86.843605) (xy 322.358602 -86.885806) (xy 322.340478 -86.904576) (xy 321.920659 -87.324184)
			(xy 330.477876 -87.324184) (xy 330.477876 -86.460584) (xy 330.478366 -86.430616) (xy 330.486189 -86.371194)
			(xy 330.501702 -86.313301) (xy 330.524638 -86.257928) (xy 330.554605 -86.206022) (xy 330.591092 -86.158472)
			(xy 330.633472 -86.116092) (xy 330.681022 -86.079605) (xy 330.732928 -86.049638) (xy 330.788301 -86.026702)
			(xy 330.846194 -86.011189) (xy 330.905616 -86.003366) (xy 330.965552 -86.003366) (xy 331.024974 -86.011189)
			(xy 331.082867 -86.026702) (xy 331.13824 -86.049638) (xy 331.190146 -86.079605) (xy 331.237696 -86.116092)
			(xy 331.280076 -86.158472) (xy 331.316563 -86.206022) (xy 331.34653 -86.257928) (xy 331.347357 -86.259924)
			(xy 333.146144 -86.259924) (xy 333.150215 -86.204302) (xy 333.162341 -86.149865) (xy 333.182264 -86.097774)
			(xy 333.20956 -86.049139) (xy 333.243646 -86.004996) (xy 333.283795 -85.966287) (xy 333.329153 -85.933836)
			(xy 333.378753 -85.908335) (xy 333.431537 -85.890328) (xy 333.48638 -85.880198) (xy 333.542114 -85.878161)
			(xy 333.597551 -85.884261) (xy 333.651508 -85.898367) (xy 333.702837 -85.920179) (xy 333.750443 -85.949233)
			(xy 333.793311 -85.984908) (xy 333.830528 -86.026445) (xy 333.861301 -86.072958) (xy 333.884973 -86.123455)
			(xy 333.891337 -86.144608) (xy 346.641928 -86.144608) (xy 346.641928 -85.281008) (xy 346.642418 -85.251024)
			(xy 346.650246 -85.191568) (xy 346.665767 -85.133643) (xy 346.688716 -85.078239) (xy 346.7187 -85.026305)
			(xy 346.755206 -84.978729) (xy 346.797611 -84.936324) (xy 346.845187 -84.899818) (xy 346.897121 -84.869834)
			(xy 346.952525 -84.846885) (xy 347.01045 -84.831364) (xy 347.069906 -84.823536) (xy 347.129874 -84.823536)
			(xy 347.18933 -84.831364) (xy 347.247255 -84.846885) (xy 347.302659 -84.869834) (xy 347.354593 -84.899818)
			(xy 347.402169 -84.936324) (xy 347.444574 -84.978729) (xy 347.48108 -85.026305) (xy 347.511064 -85.078239)
			(xy 347.534013 -85.133643) (xy 347.549534 -85.191568) (xy 347.557362 -85.251024) (xy 347.557852 -85.281008)
			(xy 347.557852 -86.144608) (xy 347.557362 -86.174592) (xy 347.549534 -86.234048) (xy 347.534013 -86.291973)
			(xy 347.511064 -86.347377) (xy 347.48108 -86.399311) (xy 347.444574 -86.446887) (xy 347.402169 -86.489292)
			(xy 347.354593 -86.525798) (xy 347.302659 -86.555782) (xy 347.247255 -86.578731) (xy 347.18933 -86.594252)
			(xy 347.129874 -86.60208) (xy 347.069906 -86.60208) (xy 347.01045 -86.594252) (xy 346.952525 -86.578731)
			(xy 346.897121 -86.555782) (xy 346.845187 -86.525798) (xy 346.797611 -86.489292) (xy 346.755206 -86.446887)
			(xy 346.7187 -86.399311) (xy 346.688716 -86.347377) (xy 346.665767 -86.291973) (xy 346.650246 -86.234048)
			(xy 346.642418 -86.174592) (xy 346.641928 -86.144608) (xy 333.891337 -86.144608) (xy 333.901041 -86.176862)
			(xy 333.909161 -86.232038) (xy 333.90967 -86.259924) (xy 333.909161 -86.28781) (xy 333.901041 -86.342986)
			(xy 333.884973 -86.396393) (xy 333.861301 -86.44689) (xy 333.830528 -86.493403) (xy 333.793311 -86.53494)
			(xy 333.757827 -86.56447) (xy 341.525604 -86.56447) (xy 341.529675 -86.508848) (xy 341.541801 -86.454411)
			(xy 341.561724 -86.40232) (xy 341.58902 -86.353685) (xy 341.623106 -86.309542) (xy 341.663255 -86.270833)
			(xy 341.708613 -86.238382) (xy 341.758213 -86.212881) (xy 341.810997 -86.194874) (xy 341.86584 -86.184744)
			(xy 341.921574 -86.182707) (xy 341.977011 -86.188807) (xy 342.030968 -86.202913) (xy 342.082297 -86.224725)
			(xy 342.129903 -86.253779) (xy 342.172771 -86.289454) (xy 342.209988 -86.330991) (xy 342.240761 -86.377504)
			(xy 342.264433 -86.428001) (xy 342.280501 -86.481408) (xy 342.288621 -86.536584) (xy 342.28913 -86.56447)
			(xy 342.288866 -86.578948) (xy 342.425526 -86.578948) (xy 342.429597 -86.523326) (xy 342.441723 -86.468889)
			(xy 342.461646 -86.416798) (xy 342.488942 -86.368163) (xy 342.523028 -86.32402) (xy 342.563177 -86.285311)
			(xy 342.608535 -86.25286) (xy 342.658135 -86.227359) (xy 342.710919 -86.209352) (xy 342.765762 -86.199222)
			(xy 342.821496 -86.197185) (xy 342.876933 -86.203285) (xy 342.93089 -86.217391) (xy 342.982219 -86.239203)
			(xy 343.029825 -86.268257) (xy 343.072693 -86.303932) (xy 343.10991 -86.345469) (xy 343.140683 -86.391982)
			(xy 343.164355 -86.442479) (xy 343.180423 -86.495886) (xy 343.188543 -86.551062) (xy 343.189052 -86.578948)
			(xy 343.188543 -86.606834) (xy 343.180423 -86.66201) (xy 343.164355 -86.715417) (xy 343.140683 -86.765914)
			(xy 343.10991 -86.812427) (xy 343.072693 -86.853964) (xy 343.029825 -86.889639) (xy 342.982219 -86.918693)
			(xy 342.93089 -86.940505) (xy 342.876933 -86.954611) (xy 342.821496 -86.960711) (xy 342.765762 -86.958674)
			(xy 342.710919 -86.948544) (xy 342.658135 -86.930537) (xy 342.608535 -86.905036) (xy 342.563177 -86.872585)
			(xy 342.523028 -86.833876) (xy 342.488942 -86.789733) (xy 342.461646 -86.741098) (xy 342.441723 -86.689007)
			(xy 342.429597 -86.63457) (xy 342.425526 -86.578948) (xy 342.288866 -86.578948) (xy 342.288621 -86.592356)
			(xy 342.280501 -86.647532) (xy 342.264433 -86.700939) (xy 342.240761 -86.751436) (xy 342.209988 -86.797949)
			(xy 342.172771 -86.839486) (xy 342.129903 -86.875161) (xy 342.082297 -86.904215) (xy 342.030968 -86.926027)
			(xy 341.977011 -86.940133) (xy 341.921574 -86.946233) (xy 341.86584 -86.944196) (xy 341.810997 -86.934066)
			(xy 341.758213 -86.916059) (xy 341.708613 -86.890558) (xy 341.663255 -86.858107) (xy 341.623106 -86.819398)
			(xy 341.58902 -86.775255) (xy 341.561724 -86.72662) (xy 341.541801 -86.674529) (xy 341.529675 -86.620092)
			(xy 341.525604 -86.56447) (xy 333.757827 -86.56447) (xy 333.750443 -86.570615) (xy 333.702837 -86.599669)
			(xy 333.651508 -86.621481) (xy 333.597551 -86.635587) (xy 333.542114 -86.641687) (xy 333.48638 -86.63965)
			(xy 333.431537 -86.62952) (xy 333.378753 -86.611513) (xy 333.329153 -86.586012) (xy 333.283795 -86.553561)
			(xy 333.243646 -86.514852) (xy 333.20956 -86.470709) (xy 333.182264 -86.422074) (xy 333.162341 -86.369983)
			(xy 333.150215 -86.315546) (xy 333.146144 -86.259924) (xy 331.347357 -86.259924) (xy 331.369466 -86.313301)
			(xy 331.384979 -86.371194) (xy 331.392802 -86.430616) (xy 331.393292 -86.460584) (xy 331.393292 -87.324184)
			(xy 331.392802 -87.354152) (xy 331.384979 -87.413574) (xy 331.369466 -87.471467) (xy 331.34653 -87.52684)
			(xy 331.316563 -87.578746) (xy 331.280076 -87.626296) (xy 331.237696 -87.668676) (xy 331.190146 -87.705163)
			(xy 331.13824 -87.73513) (xy 331.082867 -87.758066) (xy 331.024974 -87.773579) (xy 330.965552 -87.781402)
			(xy 330.905616 -87.781402) (xy 330.846194 -87.773579) (xy 330.788301 -87.758066) (xy 330.732928 -87.73513)
			(xy 330.681022 -87.705163) (xy 330.633472 -87.668676) (xy 330.591092 -87.626296) (xy 330.554605 -87.578746)
			(xy 330.524638 -87.52684) (xy 330.501702 -87.471467) (xy 330.486189 -87.413574) (xy 330.478366 -87.354152)
			(xy 330.477876 -87.324184) (xy 321.920659 -87.324184) (xy 321.83578 -87.40902) (xy 321.830751 -87.414442)
			(xy 321.823785 -87.427481) (xy 321.822064 -87.434674) (xy 321.821556 -87.437722) (xy 321.821556 -88.419686)
			(xy 331.72654 -88.419686) (xy 331.726996 -88.38898) (xy 331.734397 -88.328016) (xy 331.749091 -88.268387)
			(xy 331.770862 -88.210964) (xy 331.799394 -88.156583) (xy 331.834271 -88.106035) (xy 331.874985 -88.060059)
			(xy 331.920942 -88.019323) (xy 331.971472 -87.984422) (xy 332.02584 -87.955863) (xy 332.083252 -87.934064)
			(xy 332.142874 -87.919342) (xy 332.203834 -87.911911) (xy 332.23454 -87.911432) (xy 332.235048 -87.911432)
			(xy 332.268328 -87.911968) (xy 332.334319 -87.92064) (xy 332.398613 -87.937855) (xy 332.460109 -87.963318)
			(xy 332.517753 -87.996593) (xy 332.570558 -88.037111) (xy 332.594458 -88.060276) (xy 332.699106 -88.164924)
			(xy 341.518492 -88.164924) (xy 341.522563 -88.109302) (xy 341.534689 -88.054865) (xy 341.554612 -88.002774)
			(xy 341.581908 -87.954139) (xy 341.615994 -87.909996) (xy 341.656143 -87.871287) (xy 341.701501 -87.838836)
			(xy 341.751101 -87.813335) (xy 341.803885 -87.795328) (xy 341.858728 -87.785198) (xy 341.914462 -87.783161)
			(xy 341.969899 -87.789261) (xy 342.023856 -87.803367) (xy 342.075185 -87.825179) (xy 342.122791 -87.854233)
			(xy 342.165659 -87.889908) (xy 342.202876 -87.931445) (xy 342.233649 -87.977958) (xy 342.257321 -88.028455)
			(xy 342.273389 -88.081862) (xy 342.281509 -88.137038) (xy 342.281647 -88.144604) (xy 345.879928 -88.144604)
			(xy 345.879928 -87.281004) (xy 345.880418 -87.25102) (xy 345.888246 -87.191564) (xy 345.903767 -87.133639)
			(xy 345.926716 -87.078235) (xy 345.9567 -87.026301) (xy 345.993206 -86.978725) (xy 346.035611 -86.93632)
			(xy 346.083187 -86.899814) (xy 346.135121 -86.86983) (xy 346.190525 -86.846881) (xy 346.24845 -86.83136)
			(xy 346.307906 -86.823532) (xy 346.367874 -86.823532) (xy 346.42733 -86.83136) (xy 346.485255 -86.846881)
			(xy 346.540659 -86.86983) (xy 346.592593 -86.899814) (xy 346.640169 -86.93632) (xy 346.682574 -86.978725)
			(xy 346.71908 -87.026301) (xy 346.749064 -87.078235) (xy 346.772013 -87.133639) (xy 346.787534 -87.191564)
			(xy 346.795362 -87.25102) (xy 346.795852 -87.281004) (xy 346.795852 -88.144604) (xy 346.795362 -88.174588)
			(xy 346.787534 -88.234044) (xy 346.772013 -88.291969) (xy 346.749064 -88.347373) (xy 346.71908 -88.399307)
			(xy 346.682574 -88.446883) (xy 346.640169 -88.489288) (xy 346.592593 -88.525794) (xy 346.540659 -88.555778)
			(xy 346.485255 -88.578727) (xy 346.42733 -88.594248) (xy 346.367874 -88.602076) (xy 346.307906 -88.602076)
			(xy 346.24845 -88.594248) (xy 346.190525 -88.578727) (xy 346.135121 -88.555778) (xy 346.083187 -88.525794)
			(xy 346.035611 -88.489288) (xy 345.993206 -88.446883) (xy 345.9567 -88.399307) (xy 345.926716 -88.347373)
			(xy 345.903767 -88.291969) (xy 345.888246 -88.234044) (xy 345.880418 -88.174588) (xy 345.879928 -88.144604)
			(xy 342.281647 -88.144604) (xy 342.282018 -88.164924) (xy 342.281509 -88.19281) (xy 342.273389 -88.247986)
			(xy 342.257321 -88.301393) (xy 342.233649 -88.35189) (xy 342.202876 -88.398403) (xy 342.165659 -88.43994)
			(xy 342.122791 -88.475615) (xy 342.075185 -88.504669) (xy 342.023856 -88.526481) (xy 341.969899 -88.540587)
			(xy 341.914462 -88.546687) (xy 341.858728 -88.54465) (xy 341.803885 -88.53452) (xy 341.751101 -88.516513)
			(xy 341.701501 -88.491012) (xy 341.656143 -88.458561) (xy 341.615994 -88.419852) (xy 341.581908 -88.375709)
			(xy 341.554612 -88.327074) (xy 341.534689 -88.274983) (xy 341.522563 -88.220546) (xy 341.518492 -88.164924)
			(xy 332.699106 -88.164924) (xy 333.53502 -89.000838) (xy 333.542415 -89.007685) (xy 333.561018 -89.015399)
			(xy 333.571088 -89.015824) (xy 333.982314 -89.015824) (xy 334.015595 -89.01632) (xy 334.081588 -89.025)
			(xy 334.145883 -89.042223) (xy 334.207378 -89.067694) (xy 334.265021 -89.100976) (xy 334.317825 -89.141501)
			(xy 334.341724 -89.164668) (xy 335.321656 -90.1446) (xy 346.641928 -90.1446) (xy 346.641928 -89.281)
			(xy 346.642418 -89.251016) (xy 346.650246 -89.19156) (xy 346.665767 -89.133635) (xy 346.688716 -89.078231)
			(xy 346.7187 -89.026297) (xy 346.755206 -88.978721) (xy 346.797611 -88.936316) (xy 346.845187 -88.89981)
			(xy 346.897121 -88.869826) (xy 346.952525 -88.846877) (xy 347.01045 -88.831356) (xy 347.069906 -88.823528)
			(xy 347.129874 -88.823528) (xy 347.18933 -88.831356) (xy 347.247255 -88.846877) (xy 347.302659 -88.869826)
			(xy 347.354593 -88.89981) (xy 347.402169 -88.936316) (xy 347.444574 -88.978721) (xy 347.48108 -89.026297)
			(xy 347.511064 -89.078231) (xy 347.534013 -89.133635) (xy 347.549534 -89.19156) (xy 347.557362 -89.251016)
			(xy 347.557852 -89.281) (xy 347.557852 -90.1446) (xy 347.557362 -90.174584) (xy 347.549534 -90.23404)
			(xy 347.534013 -90.291965) (xy 347.511064 -90.347369) (xy 347.48108 -90.399303) (xy 347.444574 -90.446879)
			(xy 347.402169 -90.489284) (xy 347.354593 -90.52579) (xy 347.302659 -90.555774) (xy 347.247255 -90.578723)
			(xy 347.18933 -90.594244) (xy 347.129874 -90.602072) (xy 347.069906 -90.602072) (xy 347.01045 -90.594244)
			(xy 346.952525 -90.578723) (xy 346.897121 -90.555774) (xy 346.845187 -90.52579) (xy 346.797611 -90.489284)
			(xy 346.755206 -90.446879) (xy 346.7187 -90.399303) (xy 346.688716 -90.347369) (xy 346.665767 -90.291965)
			(xy 346.650246 -90.23404) (xy 346.642418 -90.174584) (xy 346.641928 -90.1446) (xy 335.321656 -90.1446)
			(xy 335.62925 -90.452194) (xy 335.636674 -90.459004) (xy 335.655255 -90.466741) (xy 335.665318 -90.46718)
			(xy 336.385154 -90.46718) (xy 336.395221 -90.466736) (xy 336.413819 -90.459029) (xy 336.421222 -90.452194)
			(xy 336.568796 -90.30462) (xy 336.592699 -90.281461) (xy 336.645511 -90.240955) (xy 336.703156 -90.207686)
			(xy 336.76465 -90.182224) (xy 336.82894 -90.165003) (xy 336.894928 -90.156319) (xy 336.928206 -90.155776)
			(xy 336.958924 -90.156186) (xy 337.019912 -90.163592) (xy 337.079563 -90.178296) (xy 337.137006 -90.200082)
			(xy 337.191404 -90.228635) (xy 337.241964 -90.263536) (xy 337.287948 -90.304277) (xy 337.328686 -90.350264)
			(xy 337.363584 -90.400827) (xy 337.392132 -90.455227) (xy 337.413915 -90.512672) (xy 337.428615 -90.572323)
			(xy 337.431268 -90.59418) (xy 337.693762 -90.59418) (xy 337.694248 -90.566929) (xy 337.702004 -90.512981)
			(xy 337.717359 -90.460686) (xy 337.740001 -90.411109) (xy 337.769467 -90.365259) (xy 337.805158 -90.324068)
			(xy 337.846349 -90.288377) (xy 337.892199 -90.258911) (xy 337.941776 -90.236269) (xy 337.994071 -90.220914)
			(xy 338.048019 -90.213158) (xy 338.102521 -90.213158) (xy 338.156469 -90.220914) (xy 338.208764 -90.236269)
			(xy 338.258341 -90.258911) (xy 338.304191 -90.288377) (xy 338.345382 -90.324068) (xy 338.381073 -90.365259)
			(xy 338.410539 -90.411109) (xy 338.433181 -90.460686) (xy 338.448536 -90.512981) (xy 338.456292 -90.566929)
			(xy 338.456778 -90.59418) (xy 338.456178 -90.623438) (xy 338.449355 -90.667586) (xy 339.589616 -90.667586)
			(xy 339.593687 -90.611964) (xy 339.605813 -90.557527) (xy 339.625736 -90.505436) (xy 339.653032 -90.456801)
			(xy 339.687118 -90.412658) (xy 339.727267 -90.373949) (xy 339.772625 -90.341498) (xy 339.822225 -90.315997)
			(xy 339.875009 -90.29799) (xy 339.929852 -90.28786) (xy 339.985586 -90.285823) (xy 340.041023 -90.291923)
			(xy 340.09498 -90.306029) (xy 340.146309 -90.327841) (xy 340.193915 -90.356895) (xy 340.236783 -90.39257)
			(xy 340.274 -90.434107) (xy 340.304773 -90.48062) (xy 340.328445 -90.531117) (xy 340.344513 -90.584524)
			(xy 340.352633 -90.6397) (xy 340.352734 -90.645234) (xy 348.886524 -90.645234) (xy 348.890595 -90.589612)
			(xy 348.902721 -90.535175) (xy 348.922644 -90.483084) (xy 348.94994 -90.434449) (xy 348.984026 -90.390306)
			(xy 349.024175 -90.351597) (xy 349.069533 -90.319146) (xy 349.119133 -90.293645) (xy 349.171917 -90.275638)
			(xy 349.22676 -90.265508) (xy 349.282494 -90.263471) (xy 349.337931 -90.269571) (xy 349.391888 -90.283677)
			(xy 349.443217 -90.305489) (xy 349.490823 -90.334543) (xy 349.533691 -90.370218) (xy 349.570908 -90.411755)
			(xy 349.601681 -90.458268) (xy 349.625353 -90.508765) (xy 349.641421 -90.562172) (xy 349.649541 -90.617348)
			(xy 349.65005 -90.645234) (xy 349.649541 -90.67312) (xy 349.641421 -90.728296) (xy 349.625353 -90.781703)
			(xy 349.601681 -90.8322) (xy 349.570908 -90.878713) (xy 349.533691 -90.92025) (xy 349.490823 -90.955925)
			(xy 349.443217 -90.984979) (xy 349.391888 -91.006791) (xy 349.337931 -91.020897) (xy 349.282494 -91.026997)
			(xy 349.22676 -91.02496) (xy 349.171917 -91.01483) (xy 349.119133 -90.996823) (xy 349.069533 -90.971322)
			(xy 349.024175 -90.938871) (xy 348.984026 -90.900162) (xy 348.94994 -90.856019) (xy 348.922644 -90.807384)
			(xy 348.902721 -90.755293) (xy 348.890595 -90.700856) (xy 348.886524 -90.645234) (xy 340.352734 -90.645234)
			(xy 340.353142 -90.667586) (xy 340.352633 -90.695472) (xy 340.344513 -90.750648) (xy 340.328445 -90.804055)
			(xy 340.304773 -90.854552) (xy 340.274 -90.901065) (xy 340.236783 -90.942602) (xy 340.193915 -90.978277)
			(xy 340.146309 -91.007331) (xy 340.09498 -91.029143) (xy 340.041023 -91.043249) (xy 339.985586 -91.049349)
			(xy 339.929852 -91.047312) (xy 339.875009 -91.037182) (xy 339.822225 -91.019175) (xy 339.772625 -90.993674)
			(xy 339.727267 -90.961223) (xy 339.687118 -90.922514) (xy 339.653032 -90.878371) (xy 339.625736 -90.829736)
			(xy 339.605813 -90.777645) (xy 339.593687 -90.723208) (xy 339.589616 -90.667586) (xy 338.449355 -90.667586)
			(xy 338.44724 -90.681268) (xy 338.429586 -90.737057) (xy 338.403629 -90.789501) (xy 338.369976 -90.837372)
			(xy 338.350098 -90.858848) (xy 338.340017 -90.870248) (xy 338.326402 -90.897443) (xy 338.32139 -90.927441)
			(xy 338.325425 -90.957585) (xy 338.338151 -90.985208) (xy 338.35844 -91.007864) (xy 338.384497 -91.023549)
			(xy 338.39912 -91.027758) (xy 338.426396 -91.034968) (xy 338.478601 -91.056354) (xy 338.527091 -91.085191)
			(xy 338.570807 -91.120852) (xy 338.608798 -91.162559) (xy 338.640236 -91.209404) (xy 338.664437 -91.260366)
			(xy 338.680872 -91.314335) (xy 338.689185 -91.370136) (xy 338.689696 -91.398344) (xy 338.68921 -91.425595)
			(xy 338.681454 -91.479543) (xy 338.666099 -91.531838) (xy 338.643457 -91.581415) (xy 338.613991 -91.627265)
			(xy 338.5783 -91.668456) (xy 338.537109 -91.704147) (xy 338.491259 -91.733613) (xy 338.441682 -91.756255)
			(xy 338.389387 -91.77161) (xy 338.335439 -91.779366) (xy 338.280937 -91.779366) (xy 338.226989 -91.77161)
			(xy 338.174694 -91.756255) (xy 338.125117 -91.733613) (xy 338.079267 -91.704147) (xy 338.038076 -91.668456)
			(xy 338.002385 -91.627265) (xy 337.972919 -91.581415) (xy 337.950277 -91.531838) (xy 337.934922 -91.479543)
			(xy 337.927166 -91.425595) (xy 337.92668 -91.398344) (xy 337.927217 -91.369083) (xy 337.936168 -91.31125)
			(xy 337.953836 -91.255459) (xy 337.979807 -91.203016) (xy 338.013475 -91.155149) (xy 338.03336 -91.133676)
			(xy 338.043385 -91.122233) (xy 338.056991 -91.095049) (xy 338.062001 -91.065067) (xy 338.057971 -91.034937)
			(xy 338.045259 -91.007324) (xy 338.024988 -90.984671) (xy 337.998952 -90.968981) (xy 337.984338 -90.964766)
			(xy 337.957079 -90.957496) (xy 337.904874 -90.936119) (xy 337.856385 -90.907291) (xy 337.812667 -90.871639)
			(xy 337.774674 -90.829939) (xy 337.743233 -90.783101) (xy 337.71903 -90.732145) (xy 337.702591 -90.678182)
			(xy 337.694275 -90.622386) (xy 337.693762 -90.59418) (xy 337.431268 -90.59418) (xy 337.436017 -90.633312)
			(xy 337.43646 -90.66403) (xy 337.435979 -90.697311) (xy 337.427296 -90.763305) (xy 337.410071 -90.827601)
			(xy 337.384597 -90.889096) (xy 337.351312 -90.946739) (xy 337.310785 -90.999542) (xy 337.287616 -91.02344)
			(xy 336.976212 -91.334844) (xy 336.952316 -91.358011) (xy 336.899502 -91.398514) (xy 336.841855 -91.43178)
			(xy 336.78036 -91.457241) (xy 336.716069 -91.47446) (xy 336.650081 -91.483144) (xy 336.616802 -91.483688)
			(xy 335.43367 -91.483688) (xy 335.400389 -91.483199) (xy 335.334396 -91.474517) (xy 335.270101 -91.457292)
			(xy 335.208605 -91.43182) (xy 335.150962 -91.398537) (xy 335.098159 -91.358012) (xy 335.07426 -91.334844)
			(xy 333.786734 -90.047318) (xy 333.779314 -90.040503) (xy 333.76073 -90.032768) (xy 333.750666 -90.032332)
			(xy 333.33944 -90.032332) (xy 333.306161 -90.031785) (xy 333.24017 -90.023113) (xy 333.175877 -90.005899)
			(xy 333.114382 -89.980438) (xy 333.056738 -89.947165) (xy 333.003931 -89.906651) (xy 332.98003 -89.883488)
			(xy 331.875638 -88.779096) (xy 331.852456 -88.7552) (xy 331.811891 -88.702409) (xy 331.778567 -88.644772)
			(xy 331.753055 -88.583277) (xy 331.735792 -88.518978) (xy 331.727074 -88.452974) (xy 331.72654 -88.419686)
			(xy 321.821556 -88.419686) (xy 321.821556 -88.85428) (xy 328.314302 -88.85428) (xy 328.318373 -88.798658)
			(xy 328.330499 -88.744221) (xy 328.350422 -88.69213) (xy 328.377718 -88.643495) (xy 328.411804 -88.599352)
			(xy 328.451953 -88.560643) (xy 328.497311 -88.528192) (xy 328.546911 -88.502691) (xy 328.599695 -88.484684)
			(xy 328.654538 -88.474554) (xy 328.710272 -88.472517) (xy 328.765709 -88.478617) (xy 328.819666 -88.492723)
			(xy 328.870995 -88.514535) (xy 328.918601 -88.543589) (xy 328.961469 -88.579264) (xy 328.998686 -88.620801)
			(xy 329.029459 -88.667314) (xy 329.053131 -88.717811) (xy 329.069199 -88.771218) (xy 329.077319 -88.826394)
			(xy 329.077828 -88.85428) (xy 329.077319 -88.882166) (xy 329.069199 -88.937342) (xy 329.053131 -88.990749)
			(xy 329.029459 -89.041246) (xy 328.998686 -89.087759) (xy 328.961469 -89.129296) (xy 328.918601 -89.164971)
			(xy 328.870995 -89.194025) (xy 328.819666 -89.215837) (xy 328.765709 -89.229943) (xy 328.710272 -89.236043)
			(xy 328.654538 -89.234006) (xy 328.599695 -89.223876) (xy 328.546911 -89.205869) (xy 328.497311 -89.180368)
			(xy 328.451953 -89.147917) (xy 328.411804 -89.109208) (xy 328.377718 -89.065065) (xy 328.350422 -89.01643)
			(xy 328.330499 -88.964339) (xy 328.318373 -88.909902) (xy 328.314302 -88.85428) (xy 321.821556 -88.85428)
			(xy 321.821556 -90.666316) (xy 329.807568 -90.666316) (xy 329.811639 -90.610694) (xy 329.823765 -90.556257)
			(xy 329.843688 -90.504166) (xy 329.870984 -90.455531) (xy 329.90507 -90.411388) (xy 329.945219 -90.372679)
			(xy 329.990577 -90.340228) (xy 330.040177 -90.314727) (xy 330.092961 -90.29672) (xy 330.147804 -90.28659)
			(xy 330.203538 -90.284553) (xy 330.258975 -90.290653) (xy 330.312932 -90.304759) (xy 330.364261 -90.326571)
			(xy 330.411867 -90.355625) (xy 330.454735 -90.3913) (xy 330.491952 -90.432837) (xy 330.522725 -90.47935)
			(xy 330.546397 -90.529847) (xy 330.562465 -90.583254) (xy 330.570585 -90.63843) (xy 330.571094 -90.666316)
			(xy 330.570585 -90.694202) (xy 330.562465 -90.749378) (xy 330.546397 -90.802785) (xy 330.522725 -90.853282)
			(xy 330.491952 -90.899795) (xy 330.454735 -90.941332) (xy 330.411867 -90.977007) (xy 330.364261 -91.006061)
			(xy 330.312932 -91.027873) (xy 330.258975 -91.041979) (xy 330.203538 -91.048079) (xy 330.147804 -91.046042)
			(xy 330.092961 -91.035912) (xy 330.040177 -91.017905) (xy 329.990577 -90.992404) (xy 329.945219 -90.959953)
			(xy 329.90507 -90.921244) (xy 329.870984 -90.877101) (xy 329.843688 -90.828466) (xy 329.823765 -90.776375)
			(xy 329.811639 -90.721938) (xy 329.807568 -90.666316) (xy 321.821556 -90.666316) (xy 321.821556 -91.281758)
			(xy 325.860408 -91.281758) (xy 325.864479 -91.226136) (xy 325.876605 -91.171699) (xy 325.896528 -91.119608)
			(xy 325.923824 -91.070973) (xy 325.95791 -91.02683) (xy 325.998059 -90.988121) (xy 326.043417 -90.95567)
			(xy 326.093017 -90.930169) (xy 326.145801 -90.912162) (xy 326.200644 -90.902032) (xy 326.256378 -90.899995)
			(xy 326.311815 -90.906095) (xy 326.365772 -90.920201) (xy 326.417101 -90.942013) (xy 326.464707 -90.971067)
			(xy 326.507575 -91.006742) (xy 326.544792 -91.048279) (xy 326.575565 -91.094792) (xy 326.599237 -91.145289)
			(xy 326.615305 -91.198696) (xy 326.623425 -91.253872) (xy 326.623934 -91.281758) (xy 326.623425 -91.309644)
			(xy 326.615305 -91.36482) (xy 326.599237 -91.418227) (xy 326.575565 -91.468724) (xy 326.544792 -91.515237)
			(xy 326.507575 -91.556774) (xy 326.464707 -91.592449) (xy 326.417101 -91.621503) (xy 326.365772 -91.643315)
			(xy 326.311815 -91.657421) (xy 326.256378 -91.663521) (xy 326.200644 -91.661484) (xy 326.145801 -91.651354)
			(xy 326.093017 -91.633347) (xy 326.043417 -91.607846) (xy 325.998059 -91.575395) (xy 325.95791 -91.536686)
			(xy 325.923824 -91.492543) (xy 325.896528 -91.443908) (xy 325.876605 -91.391817) (xy 325.864479 -91.33738)
			(xy 325.860408 -91.281758) (xy 321.821556 -91.281758) (xy 321.821556 -91.796955) (xy 348.165847 -91.796955)
			(xy 348.165847 -91.742445) (xy 348.173605 -91.688491) (xy 348.188963 -91.63619) (xy 348.211608 -91.586607)
			(xy 348.241079 -91.540751) (xy 348.276777 -91.499557) (xy 348.317974 -91.463863) (xy 348.363831 -91.434395)
			(xy 348.413416 -91.411753) (xy 348.465718 -91.396399) (xy 348.519673 -91.388645) (xy 348.546928 -91.388184)
			(xy 348.574574 -91.388676) (xy 348.629285 -91.396678) (xy 348.682268 -91.412496) (xy 348.732411 -91.435799)
			(xy 348.778664 -91.466098) (xy 348.820057 -91.502757) (xy 348.838266 -91.523566) (xy 348.845593 -91.531385)
			(xy 348.864916 -91.540599) (xy 348.875604 -91.541346) (xy 348.962726 -91.543886) (xy 348.982792 -91.53525)
			(xy 348.990158 -91.527376) (xy 349.008249 -91.508679) (xy 349.048654 -91.475902) (xy 349.093138 -91.44892)
			(xy 349.140876 -91.428235) (xy 349.190983 -91.41423) (xy 349.242528 -91.407165) (xy 349.268542 -91.406726)
			(xy 349.295794 -91.407147) (xy 349.349742 -91.414909) (xy 349.402036 -91.430269) (xy 349.451612 -91.452914)
			(xy 349.497462 -91.482385) (xy 349.538651 -91.518079) (xy 349.574341 -91.559272) (xy 349.603806 -91.605124)
			(xy 349.626446 -91.654703) (xy 349.6418 -91.706999) (xy 349.649556 -91.760948) (xy 349.649556 -91.815452)
			(xy 349.6418 -91.869401) (xy 349.626446 -91.921697) (xy 349.603806 -91.971276) (xy 349.574341 -92.017128)
			(xy 349.538651 -92.058321) (xy 349.497462 -92.094015) (xy 349.451612 -92.123486) (xy 349.402036 -92.146131)
			(xy 349.349742 -92.161491) (xy 349.295794 -92.169253) (xy 349.268542 -92.169742) (xy 349.240896 -92.169228)
			(xy 349.186185 -92.161234) (xy 349.133202 -92.145422) (xy 349.083058 -92.122123) (xy 349.036805 -92.091827)
			(xy 348.995412 -92.055169) (xy 348.977204 -92.03436) (xy 348.969885 -92.026532) (xy 348.950556 -92.017322)
			(xy 348.939866 -92.01658) (xy 348.852744 -92.01404) (xy 348.832678 -92.022676) (xy 348.825312 -92.03055)
			(xy 348.807192 -92.049218) (xy 348.766793 -92.081997) (xy 348.722315 -92.108981) (xy 348.674582 -92.129672)
			(xy 348.624481 -92.143683) (xy 348.57294 -92.150757) (xy 348.546928 -92.1512) (xy 348.519673 -92.150755)
			(xy 348.465718 -92.143001) (xy 348.413416 -92.127647) (xy 348.363831 -92.105005) (xy 348.317974 -92.075537)
			(xy 348.276777 -92.039843) (xy 348.241079 -91.998649) (xy 348.211608 -91.952793) (xy 348.188963 -91.90321)
			(xy 348.173605 -91.850909) (xy 348.165847 -91.796955) (xy 321.821556 -91.796955) (xy 321.821556 -93.460824)
			(xy 332.40218 -93.460824) (xy 332.402678 -93.433572) (xy 332.410431 -93.379623) (xy 332.425783 -93.327327)
			(xy 332.448422 -93.277747) (xy 332.477887 -93.231895) (xy 332.513577 -93.190702) (xy 332.554766 -93.155008)
			(xy 332.600616 -93.125539) (xy 332.650193 -93.102896) (xy 332.702488 -93.087539) (xy 332.756436 -93.07978)
			(xy 332.783688 -93.079316) (xy 332.810327 -93.0798) (xy 332.863087 -93.087224) (xy 332.9143 -93.101916)
			(xy 332.962971 -93.12359) (xy 333.008154 -93.151825) (xy 333.048969 -93.18607) (xy 333.084623 -93.225661)
			(xy 333.114422 -93.269828) (xy 333.137787 -93.31771) (xy 333.154264 -93.368377) (xy 333.159354 -93.39453)
			(xy 333.161325 -93.4036) (xy 333.17085 -93.419518) (xy 333.185421 -93.430998) (xy 333.194152 -93.434154)
			(xy 333.280004 -93.461332) (xy 333.288994 -93.463708) (xy 333.30754 -93.46258) (xy 333.324472 -93.454931)
			(xy 333.331312 -93.448632) (xy 333.487014 -93.29293) (xy 333.50579 -93.274812) (xy 333.547989 -93.244129)
			(xy 333.594472 -93.22043) (xy 333.64409 -93.204299) (xy 333.695622 -93.196133) (xy 333.72171 -93.195648)
			(xy 344.287348 -93.195648) (xy 344.313435 -93.196139) (xy 344.364968 -93.204301) (xy 344.414586 -93.220431)
			(xy 344.461067 -93.244131) (xy 344.503264 -93.274816) (xy 344.522044 -93.29293) (xy 347.003624 -95.77451)
			(xy 347.021634 -95.793301) (xy 347.052216 -95.835413) (xy 347.075847 -95.881784) (xy 347.091947 -95.931277)
			(xy 347.100121 -95.982676) (xy 347.100652 -96.008698) (xy 347.100652 -106.70286) (xy 347.100155 -106.728885)
			(xy 347.091985 -106.780291) (xy 347.075884 -106.829789) (xy 347.052249 -106.876165) (xy 347.021661 -106.918279)
			(xy 347.003624 -106.937048) (xy 345.999308 -107.941364) (xy 345.995186 -107.945752) (xy 345.988904 -107.95602)
			(xy 345.986862 -107.961684) (xy 345.986862 -107.962192) (xy 345.978413 -107.987735) (xy 345.955341 -108.036338)
			(xy 345.92567 -108.081217) (xy 345.889988 -108.121483) (xy 345.849005 -108.156338) (xy 345.803531 -108.18509)
			(xy 345.75447 -108.20717) (xy 345.702793 -108.222138) (xy 345.649526 -108.229699) (xy 345.622626 -108.230162)
			(xy 345.595372 -108.22972) (xy 345.541418 -108.221966) (xy 345.489117 -108.206611) (xy 345.439533 -108.183968)
			(xy 345.393678 -108.154498) (xy 345.352484 -108.118802) (xy 345.31679 -108.077606) (xy 345.287323 -108.031749)
			(xy 345.264682 -107.982165) (xy 345.24933 -107.929863) (xy 345.241578 -107.875908) (xy 345.241118 -107.848654)
			(xy 345.241564 -107.821743) (xy 345.249147 -107.768457) (xy 345.264143 -107.716765) (xy 345.286252 -107.667694)
			(xy 345.315038 -107.622216) (xy 345.349928 -107.581233) (xy 345.390231 -107.54556) (xy 345.435146 -107.515904)
			(xy 345.483782 -107.492853) (xy 345.509342 -107.484418) (xy 345.509596 -107.484418) (xy 345.515286 -107.482431)
			(xy 345.525563 -107.476141) (xy 345.529916 -107.471972) (xy 346.422218 -106.579924) (xy 346.429042 -106.572512)
			(xy 346.436771 -106.553922) (xy 346.437204 -106.543856) (xy 346.437204 -96.167702) (xy 346.436803 -96.157629)
			(xy 346.429068 -96.13903) (xy 346.422218 -96.131634) (xy 344.16492 -93.87459) (xy 344.157508 -93.867765)
			(xy 344.138918 -93.860037) (xy 344.128852 -93.859604) (xy 336.958686 -93.859604) (xy 336.949579 -93.859995)
			(xy 336.932505 -93.866337) (xy 336.918705 -93.878225) (xy 336.913982 -93.88602) (xy 336.87131 -93.963998)
			(xy 336.867245 -93.97215) (xy 336.864623 -93.990164) (xy 336.868481 -94.007955) (xy 336.873088 -94.015814)
			(xy 336.887344 -94.038953) (xy 336.909848 -94.088421) (xy 336.925107 -94.140582) (xy 336.93281 -94.19438)
			(xy 336.933286 -94.221554) (xy 336.9328 -94.248805) (xy 336.925044 -94.302753) (xy 336.909689 -94.355048)
			(xy 336.887047 -94.404625) (xy 336.857581 -94.450475) (xy 336.82189 -94.491666) (xy 336.780699 -94.527357)
			(xy 336.734849 -94.556823) (xy 336.685272 -94.579465) (xy 336.632977 -94.59482) (xy 336.579029 -94.602576)
			(xy 336.524527 -94.602576) (xy 336.470579 -94.59482) (xy 336.418284 -94.579465) (xy 336.368707 -94.556823)
			(xy 336.322857 -94.527357) (xy 336.281666 -94.491666) (xy 336.245975 -94.450475) (xy 336.216509 -94.404625)
			(xy 336.193867 -94.355048) (xy 336.178512 -94.302753) (xy 336.170756 -94.248805) (xy 336.17027 -94.221554)
			(xy 336.170766 -94.194382) (xy 336.178476 -94.140588) (xy 336.193734 -94.08843) (xy 336.21623 -94.038962)
			(xy 336.230468 -94.015814) (xy 336.235056 -94.007948) (xy 336.238901 -93.990164) (xy 336.236289 -93.972157)
			(xy 336.232246 -93.963998) (xy 336.189574 -93.88602) (xy 336.184862 -93.878204) (xy 336.171091 -93.866254)
			(xy 336.153989 -93.859932) (xy 336.14487 -93.859604) (xy 333.880206 -93.859604) (xy 333.870133 -93.860005)
			(xy 333.851534 -93.86774) (xy 333.844138 -93.87459) (xy 333.442564 -94.276164) (xy 333.438437 -94.280548)
			(xy 333.432159 -94.290819) (xy 333.430118 -94.296484) (xy 333.430118 -94.296992) (xy 333.421708 -94.322549)
			(xy 333.398632 -94.371154) (xy 333.368956 -94.416034) (xy 333.33327 -94.456301) (xy 333.292282 -94.491155)
			(xy 333.246803 -94.519905) (xy 333.197736 -94.541982) (xy 333.146055 -94.556946) (xy 333.092784 -94.564502)
			(xy 333.065882 -94.564962) (xy 333.038627 -94.564562) (xy 332.984671 -94.556801) (xy 332.932369 -94.54144)
			(xy 332.882786 -94.518792) (xy 332.83693 -94.489318) (xy 332.795737 -94.453618) (xy 332.760043 -94.412418)
			(xy 332.730577 -94.366558) (xy 332.707937 -94.316971) (xy 332.692585 -94.264666) (xy 332.684834 -94.210709)
			(xy 332.684374 -94.183454) (xy 332.684374 -94.182946) (xy 332.684866 -94.156293) (xy 332.692332 -94.103511)
			(xy 332.70707 -94.052282) (xy 332.728792 -94.003601) (xy 332.74254 -93.980762) (xy 332.749144 -93.970602)
			(xy 332.75143 -93.946726) (xy 332.71714 -93.85935) (xy 332.712288 -93.848562) (xy 332.694814 -93.832665)
			(xy 332.683612 -93.82887) (xy 332.683358 -93.82887) (xy 332.656812 -93.821071) (xy 332.606092 -93.798974)
			(xy 332.559097 -93.769781) (xy 332.516813 -93.734104) (xy 332.480126 -93.692693) (xy 332.449808 -93.646416)
			(xy 332.426493 -93.596244) (xy 332.410671 -93.54323) (xy 332.402675 -93.488486) (xy 332.40218 -93.460824)
			(xy 321.821556 -93.460824) (xy 321.821556 -93.998542) (xy 321.825366 -94.00286) (xy 321.8307 -94.008194)
			(xy 321.90182 -94.059502) (xy 321.90309 -94.060264) (xy 321.921124 -94.054168) (xy 321.92214 -94.05366)
			(xy 321.954891 -94.042622) (xy 322.022968 -94.030737) (xy 322.057522 -94.030038) (xy 322.057776 -94.030038)
			(xy 322.086263 -94.03052) (xy 322.142658 -94.038626) (xy 322.197326 -94.054675) (xy 322.249153 -94.078342)
			(xy 322.297083 -94.109143) (xy 322.340142 -94.146453) (xy 322.377453 -94.189512) (xy 322.408255 -94.237442)
			(xy 322.413643 -94.24924) (xy 327.636122 -94.24924) (xy 327.640193 -94.193618) (xy 327.652319 -94.139181)
			(xy 327.672242 -94.08709) (xy 327.699538 -94.038455) (xy 327.733624 -93.994312) (xy 327.773773 -93.955603)
			(xy 327.819131 -93.923152) (xy 327.868731 -93.897651) (xy 327.921515 -93.879644) (xy 327.976358 -93.869514)
			(xy 328.032092 -93.867477) (xy 328.087529 -93.873577) (xy 328.141486 -93.887683) (xy 328.192815 -93.909495)
			(xy 328.240421 -93.938549) (xy 328.283289 -93.974224) (xy 328.320506 -94.015761) (xy 328.351279 -94.062274)
			(xy 328.374951 -94.112771) (xy 328.391019 -94.166178) (xy 328.399139 -94.221354) (xy 328.399648 -94.24924)
			(xy 328.399574 -94.253304) (xy 328.652122 -94.253304) (xy 328.656193 -94.197682) (xy 328.668319 -94.143245)
			(xy 328.688242 -94.091154) (xy 328.715538 -94.042519) (xy 328.749624 -93.998376) (xy 328.789773 -93.959667)
			(xy 328.835131 -93.927216) (xy 328.884731 -93.901715) (xy 328.937515 -93.883708) (xy 328.992358 -93.873578)
			(xy 329.048092 -93.871541) (xy 329.103529 -93.877641) (xy 329.157486 -93.891747) (xy 329.208815 -93.913559)
			(xy 329.256421 -93.942613) (xy 329.299289 -93.978288) (xy 329.336506 -94.019825) (xy 329.367279 -94.066338)
			(xy 329.390951 -94.116835) (xy 329.407019 -94.170242) (xy 329.415139 -94.225418) (xy 329.415648 -94.253304)
			(xy 329.415139 -94.28119) (xy 329.407019 -94.336366) (xy 329.390951 -94.389773) (xy 329.367279 -94.44027)
			(xy 329.336506 -94.486783) (xy 329.299289 -94.52832) (xy 329.256421 -94.563995) (xy 329.208815 -94.593049)
			(xy 329.157486 -94.614861) (xy 329.103529 -94.628967) (xy 329.048092 -94.635067) (xy 328.992358 -94.63303)
			(xy 328.937515 -94.6229) (xy 328.884731 -94.604893) (xy 328.835131 -94.579392) (xy 328.789773 -94.546941)
			(xy 328.749624 -94.508232) (xy 328.715538 -94.464089) (xy 328.688242 -94.415454) (xy 328.668319 -94.363363)
			(xy 328.656193 -94.308926) (xy 328.652122 -94.253304) (xy 328.399574 -94.253304) (xy 328.399139 -94.277126)
			(xy 328.391019 -94.332302) (xy 328.374951 -94.385709) (xy 328.351279 -94.436206) (xy 328.320506 -94.482719)
			(xy 328.283289 -94.524256) (xy 328.240421 -94.559931) (xy 328.192815 -94.588985) (xy 328.141486 -94.610797)
			(xy 328.087529 -94.624903) (xy 328.032092 -94.631003) (xy 327.976358 -94.628966) (xy 327.921515 -94.618836)
			(xy 327.868731 -94.600829) (xy 327.819131 -94.575328) (xy 327.773773 -94.542877) (xy 327.733624 -94.504168)
			(xy 327.699538 -94.460025) (xy 327.672242 -94.41139) (xy 327.652319 -94.359299) (xy 327.640193 -94.304862)
			(xy 327.636122 -94.24924) (xy 322.413643 -94.24924) (xy 322.431923 -94.289268) (xy 322.447973 -94.343936)
			(xy 322.456079 -94.400331) (xy 322.456556 -94.428818) (xy 322.456556 -94.429072) (xy 322.456064 -94.458324)
			(xy 322.447553 -94.516206) (xy 322.430665 -94.572219) (xy 322.405764 -94.625159) (xy 322.373386 -94.673887)
			(xy 322.334228 -94.717353) (xy 322.31203 -94.736412) (xy 322.305934 -94.741238) (xy 322.288662 -94.768924)
			(xy 322.286884 -94.776544) (xy 322.282058 -94.786704) (xy 322.276978 -94.7928) (xy 322.269425 -94.800715)
			(xy 322.249551 -94.80981) (xy 322.238624 -94.810326) (xy 322.184776 -94.810326) (xy 322.178426 -94.810834)
			(xy 322.16725 -94.812358) (xy 322.140571 -94.819469) (xy 322.08589 -94.827119) (xy 322.058284 -94.827598)
			(xy 322.057776 -94.827598) (xy 322.028201 -94.827066) (xy 321.9697 -94.818336) (xy 321.913132 -94.801057)
			(xy 321.859737 -94.775608) (xy 321.81069 -94.742548) (xy 321.788536 -94.72295) (xy 321.788028 -94.722442)
			(xy 321.78117 -94.716092) (xy 321.77228 -94.71279) (xy 321.767606 -94.711278) (xy 321.757886 -94.709868)
			(xy 321.752976 -94.709996) (xy 321.74434 -94.71025) (xy 321.741546 -94.710504) (xy 321.73418 -94.71787)
			(xy 321.732656 -94.719394) (xy 321.724274 -94.728284) (xy 321.578601 -94.87389) (xy 338.405861 -94.87389)
			(xy 338.405861 -94.81391) (xy 338.413691 -94.754443) (xy 338.429215 -94.696507) (xy 338.45217 -94.641093)
			(xy 338.482161 -94.58915) (xy 338.518676 -94.541565) (xy 338.561089 -94.499155) (xy 338.608676 -94.462643)
			(xy 338.660622 -94.432655) (xy 338.716037 -94.409705) (xy 338.773975 -94.394184) (xy 338.833442 -94.386359)
			(xy 338.863432 -94.385892) (xy 339.727032 -94.385892) (xy 339.757012 -94.386476) (xy 339.816458 -94.394306)
			(xy 339.874374 -94.409828) (xy 339.929769 -94.432777) (xy 339.981694 -94.462759) (xy 339.984135 -94.464632)
			(xy 342.457784 -94.464632) (xy 342.461855 -94.40901) (xy 342.473981 -94.354573) (xy 342.493904 -94.302482)
			(xy 342.5212 -94.253847) (xy 342.555286 -94.209704) (xy 342.595435 -94.170995) (xy 342.640793 -94.138544)
			(xy 342.690393 -94.113043) (xy 342.743177 -94.095036) (xy 342.79802 -94.084906) (xy 342.853754 -94.082869)
			(xy 342.909191 -94.088969) (xy 342.963148 -94.103075) (xy 343.014477 -94.124887) (xy 343.062083 -94.153941)
			(xy 343.104951 -94.189616) (xy 343.142168 -94.231153) (xy 343.172941 -94.277666) (xy 343.196613 -94.328163)
			(xy 343.212681 -94.38157) (xy 343.220801 -94.436746) (xy 343.22131 -94.464632) (xy 343.220801 -94.492518)
			(xy 343.212681 -94.547694) (xy 343.196613 -94.601101) (xy 343.172941 -94.651598) (xy 343.142168 -94.698111)
			(xy 343.104951 -94.739648) (xy 343.062083 -94.775323) (xy 343.014477 -94.804377) (xy 342.963148 -94.826189)
			(xy 342.909191 -94.840295) (xy 342.853754 -94.846395) (xy 342.79802 -94.844358) (xy 342.743177 -94.834228)
			(xy 342.690393 -94.816221) (xy 342.640793 -94.79072) (xy 342.595435 -94.758269) (xy 342.555286 -94.71956)
			(xy 342.5212 -94.675417) (xy 342.493904 -94.626782) (xy 342.473981 -94.574691) (xy 342.461855 -94.520254)
			(xy 342.457784 -94.464632) (xy 339.984135 -94.464632) (xy 340.029262 -94.499262) (xy 340.071659 -94.541662)
			(xy 340.108159 -94.589232) (xy 340.138137 -94.64116) (xy 340.161082 -94.696556) (xy 340.1766 -94.754473)
			(xy 340.184426 -94.81392) (xy 340.184426 -94.87388) (xy 340.1766 -94.933327) (xy 340.161082 -94.991244)
			(xy 340.138137 -95.04664) (xy 340.108159 -95.098568) (xy 340.071659 -95.146138) (xy 340.029262 -95.188538)
			(xy 339.981694 -95.225041) (xy 339.929769 -95.255023) (xy 339.874374 -95.277972) (xy 339.816458 -95.293494)
			(xy 339.757012 -95.301324) (xy 339.727032 -95.301816) (xy 338.863432 -95.301816) (xy 338.833442 -95.301441)
			(xy 338.773975 -95.293616) (xy 338.716037 -95.278095) (xy 338.660622 -95.255145) (xy 338.608676 -95.225157)
			(xy 338.561089 -95.188645) (xy 338.518676 -95.146235) (xy 338.482161 -95.09865) (xy 338.45217 -95.046707)
			(xy 338.429215 -94.991293) (xy 338.413691 -94.933357) (xy 338.405861 -94.87389) (xy 321.578601 -94.87389)
			(xy 321.174872 -95.277432) (xy 321.174229 -95.282518) (xy 321.174736 -95.292756) (xy 321.175888 -95.297752)
			(xy 321.190112 -95.336614) (xy 321.190112 -95.337122) (xy 321.204844 -95.376238) (xy 321.206114 -95.379032)
			(xy 321.209416 -95.384874) (xy 321.213226 -95.389192) (xy 321.21348 -95.389446) (xy 321.215512 -95.39224)
			(xy 321.21729 -95.394272) (xy 321.21856 -95.395542) (xy 321.219322 -95.39605) (xy 321.240912 -95.41256)
			(xy 321.241674 -95.413068) (xy 321.246754 -95.416878) (xy 321.252596 -95.419418) (xy 321.255968 -95.420729)
			(xy 321.262978 -95.422512) (xy 321.266566 -95.422974) (xy 321.26682 -95.422974) (xy 321.294377 -95.426642)
			(xy 321.348102 -95.440929) (xy 321.399186 -95.462859) (xy 321.446547 -95.491969) (xy 321.489183 -95.527643)
			(xy 321.526192 -95.569126) (xy 321.55679 -95.615539) (xy 321.58033 -95.665901) (xy 321.596313 -95.719146)
			(xy 321.604402 -95.774146) (xy 321.604894 -95.801942) (xy 321.604405 -95.829191) (xy 321.601857 -95.8469)
			(xy 323.324726 -95.8469) (xy 323.328797 -95.791278) (xy 323.340923 -95.736841) (xy 323.360846 -95.68475)
			(xy 323.388142 -95.636115) (xy 323.422228 -95.591972) (xy 323.462377 -95.553263) (xy 323.507735 -95.520812)
			(xy 323.557335 -95.495311) (xy 323.610119 -95.477304) (xy 323.664962 -95.467174) (xy 323.720696 -95.465137)
			(xy 323.776133 -95.471237) (xy 323.83009 -95.485343) (xy 323.881419 -95.507155) (xy 323.929025 -95.536209)
			(xy 323.971893 -95.571884) (xy 324.00911 -95.613421) (xy 324.039883 -95.659934) (xy 324.063555 -95.710431)
			(xy 324.079623 -95.763838) (xy 324.085231 -95.801942) (xy 324.915528 -95.801942) (xy 324.919599 -95.74632)
			(xy 324.931725 -95.691883) (xy 324.951648 -95.639792) (xy 324.978944 -95.591157) (xy 325.01303 -95.547014)
			(xy 325.053179 -95.508305) (xy 325.098537 -95.475854) (xy 325.148137 -95.450353) (xy 325.200921 -95.432346)
			(xy 325.255764 -95.422216) (xy 325.311498 -95.420179) (xy 325.366935 -95.426279) (xy 325.420892 -95.440385)
			(xy 325.472221 -95.462197) (xy 325.519827 -95.491251) (xy 325.562695 -95.526926) (xy 325.599912 -95.568463)
			(xy 325.630685 -95.614976) (xy 325.654357 -95.665473) (xy 325.670425 -95.71888) (xy 325.678545 -95.774056)
			(xy 325.679054 -95.801942) (xy 325.921368 -95.801942) (xy 325.925439 -95.74632) (xy 325.937565 -95.691883)
			(xy 325.957488 -95.639792) (xy 325.984784 -95.591157) (xy 326.01887 -95.547014) (xy 326.059019 -95.508305)
			(xy 326.104377 -95.475854) (xy 326.153977 -95.450353) (xy 326.206761 -95.432346) (xy 326.261604 -95.422216)
			(xy 326.317338 -95.420179) (xy 326.372775 -95.426279) (xy 326.426732 -95.440385) (xy 326.478061 -95.462197)
			(xy 326.525667 -95.491251) (xy 326.568535 -95.526926) (xy 326.605752 -95.568463) (xy 326.636525 -95.614976)
			(xy 326.660197 -95.665473) (xy 326.676265 -95.71888) (xy 326.684385 -95.774056) (xy 326.684894 -95.801942)
			(xy 326.684385 -95.829828) (xy 326.67724 -95.878379) (xy 331.320012 -95.878379) (xy 331.327765 -95.824422)
			(xy 331.343118 -95.772116) (xy 331.365759 -95.722529) (xy 331.395226 -95.676668) (xy 331.43092 -95.635467)
			(xy 331.472115 -95.599766) (xy 331.517971 -95.570291) (xy 331.567554 -95.547641) (xy 331.619857 -95.532279)
			(xy 331.673813 -95.524517) (xy 331.728325 -95.524513) (xy 331.782283 -95.532266) (xy 331.834588 -95.54762)
			(xy 331.884176 -95.570261) (xy 331.930036 -95.599729) (xy 331.971236 -95.635424) (xy 332.006937 -95.676619)
			(xy 332.036412 -95.722475) (xy 332.05906 -95.772059) (xy 332.074422 -95.824362) (xy 332.082183 -95.878318)
			(xy 332.082648 -95.905574) (xy 332.082648 -95.906082) (xy 332.082565 -95.916454) (xy 332.081423 -95.937166)
			(xy 332.080362 -95.947484) (xy 332.0793 -95.96203) (xy 332.084505 -95.990715) (xy 332.097592 -96.016765)
			(xy 332.117497 -96.038065) (xy 332.142604 -96.052883) (xy 332.170871 -96.060014) (xy 332.200002 -96.058881)
			(xy 332.213966 -96.054672) (xy 332.243575 -96.045318) (xy 332.304841 -96.035236) (xy 332.335886 -96.034606)
			(xy 332.33614 -96.034606) (xy 332.363387 -96.035121) (xy 332.417327 -96.042882) (xy 332.469613 -96.05824)
			(xy 332.519182 -96.080883) (xy 332.565023 -96.110349) (xy 332.606205 -96.146039) (xy 332.641888 -96.187226)
			(xy 332.671347 -96.233073) (xy 332.693982 -96.282645) (xy 332.709331 -96.334934) (xy 332.717083 -96.388874)
			(xy 332.71708 -96.44337) (xy 332.709322 -96.497309) (xy 332.693966 -96.549596) (xy 332.671326 -96.599166)
			(xy 332.641862 -96.645009) (xy 332.606174 -96.686192) (xy 332.564988 -96.721878) (xy 332.519143 -96.751339)
			(xy 332.469572 -96.773975) (xy 332.417284 -96.789328) (xy 332.363344 -96.797082) (xy 332.308848 -96.797082)
			(xy 332.254908 -96.789326) (xy 332.20262 -96.773973) (xy 332.15305 -96.751335) (xy 332.107206 -96.721873)
			(xy 332.066021 -96.686187) (xy 332.030333 -96.645002) (xy 332.00087 -96.599159) (xy 331.978231 -96.549589)
			(xy 331.962876 -96.497302) (xy 331.955119 -96.443362) (xy 331.954632 -96.416114) (xy 331.954632 -96.415606)
			(xy 331.954714 -96.405234) (xy 331.955857 -96.384522) (xy 331.956918 -96.374204) (xy 331.958018 -96.359659)
			(xy 331.952809 -96.330969) (xy 331.939716 -96.304915) (xy 331.919804 -96.283613) (xy 331.894691 -96.268796)
			(xy 331.866417 -96.261667) (xy 331.83728 -96.262805) (xy 331.823314 -96.267016) (xy 331.793707 -96.276374)
			(xy 331.732439 -96.286453) (xy 331.701394 -96.287082) (xy 331.70114 -96.287082) (xy 331.673884 -96.286688)
			(xy 331.619926 -96.278936) (xy 331.567621 -96.263583) (xy 331.518033 -96.240943) (xy 331.472171 -96.211476)
			(xy 331.430971 -96.175783) (xy 331.395269 -96.134589) (xy 331.365793 -96.088734) (xy 331.343143 -96.03915)
			(xy 331.32778 -95.986848) (xy 331.320017 -95.932891) (xy 331.320012 -95.878379) (xy 326.67724 -95.878379)
			(xy 326.676265 -95.885004) (xy 326.660197 -95.938411) (xy 326.636525 -95.988908) (xy 326.605752 -96.035421)
			(xy 326.568535 -96.076958) (xy 326.525667 -96.112633) (xy 326.478061 -96.141687) (xy 326.426732 -96.163499)
			(xy 326.372775 -96.177605) (xy 326.317338 -96.183705) (xy 326.261604 -96.181668) (xy 326.206761 -96.171538)
			(xy 326.153977 -96.153531) (xy 326.104377 -96.12803) (xy 326.059019 -96.095579) (xy 326.01887 -96.05687)
			(xy 325.984784 -96.012727) (xy 325.957488 -95.964092) (xy 325.937565 -95.912001) (xy 325.925439 -95.857564)
			(xy 325.921368 -95.801942) (xy 325.679054 -95.801942) (xy 325.678545 -95.829828) (xy 325.670425 -95.885004)
			(xy 325.654357 -95.938411) (xy 325.630685 -95.988908) (xy 325.599912 -96.035421) (xy 325.562695 -96.076958)
			(xy 325.519827 -96.112633) (xy 325.472221 -96.141687) (xy 325.420892 -96.163499) (xy 325.366935 -96.177605)
			(xy 325.311498 -96.183705) (xy 325.255764 -96.181668) (xy 325.200921 -96.171538) (xy 325.148137 -96.153531)
			(xy 325.098537 -96.12803) (xy 325.053179 -96.095579) (xy 325.01303 -96.05687) (xy 324.978944 -96.012727)
			(xy 324.951648 -95.964092) (xy 324.931725 -95.912001) (xy 324.919599 -95.857564) (xy 324.915528 -95.801942)
			(xy 324.085231 -95.801942) (xy 324.087743 -95.819014) (xy 324.088252 -95.8469) (xy 324.087743 -95.874786)
			(xy 324.079623 -95.929962) (xy 324.063555 -95.983369) (xy 324.039883 -96.033866) (xy 324.00911 -96.080379)
			(xy 323.971893 -96.121916) (xy 323.929025 -96.157591) (xy 323.881419 -96.186645) (xy 323.83009 -96.208457)
			(xy 323.776133 -96.222563) (xy 323.720696 -96.228663) (xy 323.664962 -96.226626) (xy 323.610119 -96.216496)
			(xy 323.557335 -96.198489) (xy 323.507735 -96.172988) (xy 323.462377 -96.140537) (xy 323.422228 -96.101828)
			(xy 323.388142 -96.057685) (xy 323.360846 -96.00905) (xy 323.340923 -95.956959) (xy 323.328797 -95.902522)
			(xy 323.324726 -95.8469) (xy 321.601857 -95.8469) (xy 321.596643 -95.883133) (xy 321.581285 -95.935422)
			(xy 321.558641 -95.984993) (xy 321.529173 -96.030837) (xy 321.493482 -96.072021) (xy 321.452292 -96.107707)
			(xy 321.406444 -96.137168) (xy 321.35687 -96.159804) (xy 321.304578 -96.175155) (xy 321.250635 -96.182909)
			(xy 321.223386 -96.18345) (xy 321.195611 -96.182949) (xy 321.14065 -96.174891) (xy 321.087437 -96.15895)
			(xy 321.037099 -96.13546) (xy 320.990699 -96.104919) (xy 320.949218 -96.067973) (xy 320.913533 -96.025402)
			(xy 320.884399 -95.978106) (xy 320.862431 -95.927085) (xy 320.848093 -95.873418) (xy 320.844418 -95.845884)
			(xy 320.844418 -95.84563) (xy 320.843656 -95.840042) (xy 320.84137 -95.833184) (xy 320.83883 -95.825818)
			(xy 320.815208 -95.79483) (xy 320.814954 -95.794576) (xy 320.812922 -95.792036) (xy 320.807588 -95.785432)
			(xy 320.800222 -95.781114) (xy 320.796288 -95.778957) (xy 320.787859 -95.775888) (xy 320.783458 -95.775018)
			(xy 320.776346 -95.773748) (xy 320.776092 -95.773748) (xy 320.773806 -95.77324) (xy 320.7639 -95.7707)
			(xy 320.74485 -95.763588) (xy 320.743834 -95.76308) (xy 320.723006 -95.755714) (xy 320.719409 -95.754681)
			(xy 320.712014 -95.753541) (xy 320.708274 -95.753428) (xy 320.706496 -95.753428) (xy 320.681858 -95.770954)
			(xy 320.679572 -95.772732) (xy 320.077435 -96.374966) (xy 326.62698 -96.374966) (xy 326.631051 -96.319344)
			(xy 326.643177 -96.264907) (xy 326.6631 -96.212816) (xy 326.690396 -96.164181) (xy 326.724482 -96.120038)
			(xy 326.764631 -96.081329) (xy 326.809989 -96.048878) (xy 326.859589 -96.023377) (xy 326.912373 -96.00537)
			(xy 326.967216 -95.99524) (xy 327.02295 -95.993203) (xy 327.078387 -95.999303) (xy 327.132344 -96.013409)
			(xy 327.183673 -96.035221) (xy 327.231279 -96.064275) (xy 327.274147 -96.09995) (xy 327.311364 -96.141487)
			(xy 327.342137 -96.188) (xy 327.365809 -96.238497) (xy 327.380808 -96.288352) (xy 328.052174 -96.288352)
			(xy 328.056245 -96.23273) (xy 328.068371 -96.178293) (xy 328.088294 -96.126202) (xy 328.11559 -96.077567)
			(xy 328.149676 -96.033424) (xy 328.189825 -95.994715) (xy 328.235183 -95.962264) (xy 328.284783 -95.936763)
			(xy 328.337567 -95.918756) (xy 328.39241 -95.908626) (xy 328.448144 -95.906589) (xy 328.503581 -95.912689)
			(xy 328.557538 -95.926795) (xy 328.608867 -95.948607) (xy 328.656473 -95.977661) (xy 328.699341 -96.013336)
			(xy 328.736558 -96.054873) (xy 328.767331 -96.101386) (xy 328.791003 -96.151883) (xy 328.807071 -96.20529)
			(xy 328.815191 -96.260466) (xy 328.815422 -96.273112) (xy 329.397866 -96.273112) (xy 329.401937 -96.21749)
			(xy 329.414063 -96.163053) (xy 329.433986 -96.110962) (xy 329.461282 -96.062327) (xy 329.495368 -96.018184)
			(xy 329.535517 -95.979475) (xy 329.580875 -95.947024) (xy 329.630475 -95.921523) (xy 329.683259 -95.903516)
			(xy 329.738102 -95.893386) (xy 329.793836 -95.891349) (xy 329.849273 -95.897449) (xy 329.90323 -95.911555)
			(xy 329.954559 -95.933367) (xy 330.002165 -95.962421) (xy 330.045033 -95.998096) (xy 330.08225 -96.039633)
			(xy 330.113023 -96.086146) (xy 330.136695 -96.136643) (xy 330.152763 -96.19005) (xy 330.160883 -96.245226)
			(xy 330.161392 -96.273112) (xy 330.160883 -96.300998) (xy 330.152763 -96.356174) (xy 330.136695 -96.409581)
			(xy 330.113023 -96.460078) (xy 330.08225 -96.506591) (xy 330.045033 -96.548128) (xy 330.002165 -96.583803)
			(xy 329.954559 -96.612857) (xy 329.90323 -96.634669) (xy 329.849273 -96.648775) (xy 329.793836 -96.654875)
			(xy 329.738102 -96.652838) (xy 329.683259 -96.642708) (xy 329.630475 -96.624701) (xy 329.580875 -96.5992)
			(xy 329.535517 -96.566749) (xy 329.495368 -96.52804) (xy 329.461282 -96.483897) (xy 329.433986 -96.435262)
			(xy 329.414063 -96.383171) (xy 329.401937 -96.328734) (xy 329.397866 -96.273112) (xy 328.815422 -96.273112)
			(xy 328.8157 -96.288352) (xy 328.815191 -96.316238) (xy 328.807071 -96.371414) (xy 328.791003 -96.424821)
			(xy 328.767331 -96.475318) (xy 328.736558 -96.521831) (xy 328.699341 -96.563368) (xy 328.656473 -96.599043)
			(xy 328.608867 -96.628097) (xy 328.557538 -96.649909) (xy 328.503581 -96.664015) (xy 328.448144 -96.670115)
			(xy 328.39241 -96.668078) (xy 328.337567 -96.657948) (xy 328.284783 -96.639941) (xy 328.235183 -96.61444)
			(xy 328.189825 -96.581989) (xy 328.149676 -96.54328) (xy 328.11559 -96.499137) (xy 328.088294 -96.450502)
			(xy 328.068371 -96.398411) (xy 328.056245 -96.343974) (xy 328.052174 -96.288352) (xy 327.380808 -96.288352)
			(xy 327.381877 -96.291904) (xy 327.389997 -96.34708) (xy 327.390506 -96.374966) (xy 327.389997 -96.402852)
			(xy 327.381877 -96.458028) (xy 327.365809 -96.511435) (xy 327.342137 -96.561932) (xy 327.311364 -96.608445)
			(xy 327.274147 -96.649982) (xy 327.231279 -96.685657) (xy 327.183673 -96.714711) (xy 327.132344 -96.736523)
			(xy 327.078387 -96.750629) (xy 327.02295 -96.756729) (xy 326.967216 -96.754692) (xy 326.912373 -96.744562)
			(xy 326.859589 -96.726555) (xy 326.809989 -96.701054) (xy 326.764631 -96.668603) (xy 326.724482 -96.629894)
			(xy 326.690396 -96.585751) (xy 326.6631 -96.537116) (xy 326.643177 -96.485025) (xy 326.631051 -96.430588)
			(xy 326.62698 -96.374966) (xy 320.077435 -96.374966) (xy 319.10782 -97.344738) (xy 319.103157 -97.35148)
			(xy 319.097984 -97.367026) (xy 319.09766 -97.375218) (xy 319.09766 -97.953576) (xy 320.542918 -97.953576)
			(xy 320.546989 -97.897954) (xy 320.559115 -97.843517) (xy 320.579038 -97.791426) (xy 320.606334 -97.742791)
			(xy 320.64042 -97.698648) (xy 320.680569 -97.659939) (xy 320.725927 -97.627488) (xy 320.775527 -97.601987)
			(xy 320.828311 -97.58398) (xy 320.883154 -97.57385) (xy 320.938888 -97.571813) (xy 320.994325 -97.577913)
			(xy 321.048282 -97.592019) (xy 321.099611 -97.613831) (xy 321.147217 -97.642885) (xy 321.190085 -97.67856)
			(xy 321.227302 -97.720097) (xy 321.258075 -97.76661) (xy 321.281747 -97.817107) (xy 321.282991 -97.821242)
			(xy 321.857368 -97.821242) (xy 321.861439 -97.76562) (xy 321.873565 -97.711183) (xy 321.893488 -97.659092)
			(xy 321.920784 -97.610457) (xy 321.95487 -97.566314) (xy 321.995019 -97.527605) (xy 322.040377 -97.495154)
			(xy 322.089977 -97.469653) (xy 322.142761 -97.451646) (xy 322.197604 -97.441516) (xy 322.253338 -97.439479)
			(xy 322.308775 -97.445579) (xy 322.362732 -97.459685) (xy 322.414061 -97.481497) (xy 322.461667 -97.510551)
			(xy 322.504535 -97.546226) (xy 322.541752 -97.587763) (xy 322.572525 -97.634276) (xy 322.596197 -97.684773)
			(xy 322.612265 -97.73818) (xy 322.620385 -97.793356) (xy 322.620894 -97.821242) (xy 322.620397 -97.848448)
			(xy 323.12842 -97.848448) (xy 323.12842 -97.793952) (xy 323.136175 -97.740012) (xy 323.151528 -97.687724)
			(xy 323.174166 -97.638153) (xy 323.203627 -97.592309) (xy 323.239313 -97.551123) (xy 323.280497 -97.515436)
			(xy 323.326341 -97.485972) (xy 323.375911 -97.463333) (xy 323.428198 -97.447978) (xy 323.482138 -97.440221)
			(xy 323.509386 -97.439734) (xy 323.538303 -97.44025) (xy 323.595475 -97.448977) (xy 323.650675 -97.466235)
			(xy 323.702636 -97.491627) (xy 323.75017 -97.524572) (xy 323.792186 -97.564314) (xy 323.810376 -97.5868)
			(xy 323.818003 -97.595586) (xy 323.838889 -97.605781) (xy 323.850508 -97.606358) (xy 323.930264 -97.606358)
			(xy 323.941901 -97.605856) (xy 323.962811 -97.595642) (xy 323.970396 -97.5868) (xy 323.988589 -97.564318)
			(xy 324.030609 -97.524583) (xy 324.078143 -97.491644) (xy 324.130104 -97.466255) (xy 324.185301 -97.448999)
			(xy 324.24247 -97.440269) (xy 324.271386 -97.439734) (xy 324.298643 -97.440112) (xy 324.352601 -97.447868)
			(xy 324.404906 -97.463225) (xy 324.454494 -97.485869) (xy 324.500354 -97.51534) (xy 324.541553 -97.551037)
			(xy 324.577252 -97.592235) (xy 324.606724 -97.638094) (xy 324.62937 -97.687681) (xy 324.644729 -97.739985)
			(xy 324.652487 -97.793943) (xy 324.652487 -97.821242) (xy 324.905368 -97.821242) (xy 324.909439 -97.76562)
			(xy 324.921565 -97.711183) (xy 324.941488 -97.659092) (xy 324.968784 -97.610457) (xy 325.00287 -97.566314)
			(xy 325.043019 -97.527605) (xy 325.088377 -97.495154) (xy 325.137977 -97.469653) (xy 325.190761 -97.451646)
			(xy 325.245604 -97.441516) (xy 325.301338 -97.439479) (xy 325.356775 -97.445579) (xy 325.410732 -97.459685)
			(xy 325.462061 -97.481497) (xy 325.509667 -97.510551) (xy 325.552535 -97.546226) (xy 325.589752 -97.587763)
			(xy 325.620525 -97.634276) (xy 325.644197 -97.684773) (xy 325.660265 -97.73818) (xy 325.668385 -97.793356)
			(xy 325.668894 -97.821242) (xy 325.668385 -97.849128) (xy 325.660265 -97.904304) (xy 325.644197 -97.957711)
			(xy 325.620525 -98.008208) (xy 325.589752 -98.054721) (xy 325.552535 -98.096258) (xy 325.509667 -98.131933)
			(xy 325.462061 -98.160987) (xy 325.410732 -98.182799) (xy 325.356775 -98.196905) (xy 325.301338 -98.203005)
			(xy 325.245604 -98.200968) (xy 325.190761 -98.190838) (xy 325.137977 -98.172831) (xy 325.088377 -98.14733)
			(xy 325.043019 -98.114879) (xy 325.00287 -98.07617) (xy 324.968784 -98.032027) (xy 324.941488 -97.983392)
			(xy 324.921565 -97.931301) (xy 324.909439 -97.876864) (xy 324.905368 -97.821242) (xy 324.652487 -97.821242)
			(xy 324.652487 -97.848457) (xy 324.644729 -97.902415) (xy 324.62937 -97.954719) (xy 324.606724 -98.004306)
			(xy 324.577252 -98.050165) (xy 324.541553 -98.091363) (xy 324.500354 -98.12706) (xy 324.454494 -98.156531)
			(xy 324.404906 -98.179175) (xy 324.352601 -98.194532) (xy 324.298643 -98.202288) (xy 324.271386 -98.20275)
			(xy 324.24247 -98.202189) (xy 324.1853 -98.193471) (xy 324.130102 -98.176223) (xy 324.078139 -98.15084)
			(xy 324.030605 -98.117902) (xy 323.988587 -98.078167) (xy 323.970396 -98.055684) (xy 323.962784 -98.046882)
			(xy 323.941887 -98.036696) (xy 323.930264 -98.036126) (xy 323.850508 -98.036126) (xy 323.838877 -98.036675)
			(xy 323.817967 -98.046856) (xy 323.810376 -98.055684) (xy 323.792194 -98.078176) (xy 323.750173 -98.117911)
			(xy 323.702637 -98.15085) (xy 323.650673 -98.176237) (xy 323.595474 -98.193491) (xy 323.538303 -98.202217)
			(xy 323.509386 -98.20275) (xy 323.482138 -98.202179) (xy 323.428198 -98.194422) (xy 323.375911 -98.179067)
			(xy 323.326341 -98.156428) (xy 323.280497 -98.126964) (xy 323.239313 -98.091277) (xy 323.203627 -98.050091)
			(xy 323.174166 -98.004247) (xy 323.151528 -97.954676) (xy 323.136175 -97.902388) (xy 323.12842 -97.848448)
			(xy 322.620397 -97.848448) (xy 322.620385 -97.849128) (xy 322.612265 -97.904304) (xy 322.596197 -97.957711)
			(xy 322.572525 -98.008208) (xy 322.541752 -98.054721) (xy 322.504535 -98.096258) (xy 322.461667 -98.131933)
			(xy 322.414061 -98.160987) (xy 322.362732 -98.182799) (xy 322.308775 -98.196905) (xy 322.253338 -98.203005)
			(xy 322.197604 -98.200968) (xy 322.142761 -98.190838) (xy 322.089977 -98.172831) (xy 322.040377 -98.14733)
			(xy 321.995019 -98.114879) (xy 321.95487 -98.07617) (xy 321.920784 -98.032027) (xy 321.893488 -97.983392)
			(xy 321.873565 -97.931301) (xy 321.861439 -97.876864) (xy 321.857368 -97.821242) (xy 321.282991 -97.821242)
			(xy 321.297815 -97.870514) (xy 321.305935 -97.92569) (xy 321.306444 -97.953576) (xy 321.305935 -97.981462)
			(xy 321.297815 -98.036638) (xy 321.281747 -98.090045) (xy 321.258075 -98.140542) (xy 321.227302 -98.187055)
			(xy 321.190085 -98.228592) (xy 321.147217 -98.264267) (xy 321.099611 -98.293321) (xy 321.048282 -98.315133)
			(xy 320.994325 -98.329239) (xy 320.938888 -98.335339) (xy 320.883154 -98.333302) (xy 320.828311 -98.323172)
			(xy 320.775527 -98.305165) (xy 320.725927 -98.279664) (xy 320.680569 -98.247213) (xy 320.64042 -98.208504)
			(xy 320.606334 -98.164361) (xy 320.579038 -98.115726) (xy 320.559115 -98.063635) (xy 320.546989 -98.009198)
			(xy 320.542918 -97.953576) (xy 319.09766 -97.953576) (xy 319.09766 -98.759518) (xy 331.371194 -98.759518)
			(xy 331.371672 -98.732148) (xy 331.379487 -98.67797) (xy 331.394974 -98.625467) (xy 331.417813 -98.57572)
			(xy 331.447534 -98.529752) (xy 331.465174 -98.50882) (xy 331.465428 -98.508566) (xy 331.470996 -98.501467)
			(xy 331.477253 -98.48456) (xy 331.47762 -98.475546) (xy 331.47762 -98.40849) (xy 331.477263 -98.399473)
			(xy 331.471015 -98.382557) (xy 331.465428 -98.37547) (xy 331.465174 -98.37547) (xy 331.465174 -98.375216)
			(xy 331.447549 -98.35427) (xy 331.41782 -98.308306) (xy 331.394971 -98.258562) (xy 331.379471 -98.206061)
			(xy 331.37164 -98.151884) (xy 331.371638 -98.097143) (xy 331.379465 -98.042965) (xy 331.394961 -97.990464)
			(xy 331.417807 -97.940718) (xy 331.447533 -97.894752) (xy 331.465174 -97.87382) (xy 331.465428 -97.873566)
			(xy 331.470996 -97.866467) (xy 331.477253 -97.84956) (xy 331.47762 -97.840546) (xy 331.47762 -97.77349)
			(xy 331.477263 -97.764473) (xy 331.471015 -97.747557) (xy 331.465428 -97.74047) (xy 331.465174 -97.74047)
			(xy 331.465174 -97.740216) (xy 331.447525 -97.719292) (xy 331.417815 -97.673317) (xy 331.394982 -97.623567)
			(xy 331.379493 -97.571065) (xy 331.371667 -97.516888) (xy 331.371194 -97.489518) (xy 331.37168 -97.462267)
			(xy 331.379436 -97.408319) (xy 331.394791 -97.356024) (xy 331.417433 -97.306447) (xy 331.446899 -97.260597)
			(xy 331.48259 -97.219406) (xy 331.523781 -97.183715) (xy 331.569631 -97.154249) (xy 331.619208 -97.131607)
			(xy 331.671503 -97.116252) (xy 331.725451 -97.108496) (xy 331.779953 -97.108496) (xy 331.833901 -97.116252)
			(xy 331.886196 -97.131607) (xy 331.935773 -97.154249) (xy 331.981623 -97.183715) (xy 332.022814 -97.219406)
			(xy 332.058505 -97.260597) (xy 332.087971 -97.306447) (xy 332.110613 -97.356024) (xy 332.125968 -97.408319)
			(xy 332.133724 -97.462267) (xy 332.13421 -97.489518) (xy 332.133752 -97.516888) (xy 332.125932 -97.571068)
			(xy 332.110441 -97.623571) (xy 332.087597 -97.673318) (xy 332.057872 -97.719284) (xy 332.04023 -97.740216)
			(xy 332.039976 -97.74047) (xy 332.034393 -97.747559) (xy 332.028145 -97.764474) (xy 332.027784 -97.77349)
			(xy 332.027784 -97.840546) (xy 332.02817 -97.84956) (xy 332.034398 -97.866477) (xy 332.039976 -97.873566)
			(xy 332.04023 -97.873566) (xy 332.04023 -97.87382) (xy 332.05789 -97.894738) (xy 332.087617 -97.940707)
			(xy 332.110464 -97.990455) (xy 332.125961 -98.04296) (xy 332.133789 -98.097142) (xy 332.133787 -98.151886)
			(xy 332.125955 -98.206066) (xy 332.110455 -98.25857) (xy 332.087604 -98.308317) (xy 332.057874 -98.354284)
			(xy 332.04023 -98.375216) (xy 332.039976 -98.37547) (xy 332.034393 -98.382559) (xy 332.028145 -98.399474)
			(xy 332.027784 -98.40849) (xy 332.027784 -98.475546) (xy 332.02817 -98.48456) (xy 332.034398 -98.501477)
			(xy 332.036031 -98.503552) (xy 333.025963 -98.503552) (xy 333.025963 -98.449048) (xy 333.03372 -98.395097)
			(xy 333.049076 -98.3428) (xy 333.071718 -98.293221) (xy 333.101186 -98.247369) (xy 333.13688 -98.206177)
			(xy 333.178072 -98.170484) (xy 333.223924 -98.141017) (xy 333.273504 -98.118375) (xy 333.325801 -98.103019)
			(xy 333.379752 -98.095263) (xy 333.407004 -98.0948) (xy 333.433318 -98.095265) (xy 333.485447 -98.1025)
			(xy 333.536089 -98.11682) (xy 333.584288 -98.137953) (xy 333.629132 -98.165499) (xy 333.669771 -98.198938)
			(xy 333.687928 -98.21799) (xy 333.695439 -98.225404) (xy 333.714727 -98.233922) (xy 333.725266 -98.2345)
			(xy 333.799942 -98.2345) (xy 333.81049 -98.233953) (xy 333.829785 -98.225431) (xy 333.83728 -98.21799)
			(xy 333.85545 -98.198949) (xy 333.896077 -98.165491) (xy 333.940914 -98.13793) (xy 333.989112 -98.116789)
			(xy 334.039757 -98.102469) (xy 334.091889 -98.095241) (xy 334.118204 -98.0948) (xy 334.145456 -98.09527)
			(xy 334.199404 -98.103027) (xy 334.251699 -98.118383) (xy 334.301277 -98.141025) (xy 334.347128 -98.170492)
			(xy 334.388319 -98.206184) (xy 334.424011 -98.247375) (xy 334.453477 -98.293226) (xy 334.473172 -98.336354)
			(xy 335.049368 -98.336354) (xy 335.049849 -98.308984) (xy 335.057661 -98.254805) (xy 335.073145 -98.202301)
			(xy 335.095984 -98.152554) (xy 335.125707 -98.106587) (xy 335.143348 -98.085656) (xy 335.143602 -98.085402)
			(xy 335.149194 -98.078319) (xy 335.155437 -98.0614) (xy 335.155794 -98.052382) (xy 335.155794 -97.985326)
			(xy 335.155426 -97.97631) (xy 335.149186 -97.959393) (xy 335.143602 -97.952306) (xy 335.143348 -97.952306)
			(xy 335.143348 -97.952052) (xy 335.125661 -97.931156) (xy 335.095937 -97.885182) (xy 335.073093 -97.83543)
			(xy 335.057599 -97.782922) (xy 335.049775 -97.728738) (xy 335.049779 -97.673992) (xy 335.057614 -97.61981)
			(xy 335.073117 -97.567305) (xy 335.09597 -97.517557) (xy 335.125703 -97.471588) (xy 335.143348 -97.450656)
			(xy 335.143602 -97.450402) (xy 335.149194 -97.443319) (xy 335.155437 -97.4264) (xy 335.155794 -97.417382)
			(xy 335.155794 -97.350326) (xy 335.155426 -97.34131) (xy 335.149186 -97.324393) (xy 335.143602 -97.317306)
			(xy 335.143348 -97.317306) (xy 335.143348 -97.317052) (xy 335.125727 -97.296105) (xy 335.096011 -97.250137)
			(xy 335.073171 -97.200393) (xy 335.057676 -97.147896) (xy 335.049844 -97.093722) (xy 335.049368 -97.066354)
			(xy 335.049854 -97.039103) (xy 335.05761 -96.985155) (xy 335.072965 -96.93286) (xy 335.095607 -96.883283)
			(xy 335.125073 -96.837433) (xy 335.160764 -96.796242) (xy 335.201955 -96.760551) (xy 335.247805 -96.731085)
			(xy 335.297382 -96.708443) (xy 335.349677 -96.693088) (xy 335.403625 -96.685332) (xy 335.458127 -96.685332)
			(xy 335.512075 -96.693088) (xy 335.56437 -96.708443) (xy 335.613947 -96.731085) (xy 335.659797 -96.760551)
			(xy 335.700988 -96.796242) (xy 335.736679 -96.837433) (xy 335.766145 -96.883283) (xy 335.788787 -96.93286)
			(xy 335.804142 -96.985155) (xy 335.811898 -97.039103) (xy 335.812384 -97.066354) (xy 335.811895 -97.093723)
			(xy 335.804083 -97.147902) (xy 335.7886 -97.200405) (xy 335.765763 -97.250152) (xy 335.736043 -97.29612)
			(xy 335.718404 -97.317052) (xy 335.71815 -97.317306) (xy 335.712549 -97.324382) (xy 335.706312 -97.341307)
			(xy 335.705958 -97.350326) (xy 335.705958 -97.417382) (xy 335.706311 -97.4264) (xy 335.71256 -97.443317)
			(xy 335.71815 -97.450402) (xy 335.718404 -97.450402) (xy 335.718404 -97.450656) (xy 335.735998 -97.471626)
			(xy 335.765723 -97.517588) (xy 335.788569 -97.567328) (xy 335.804067 -97.619824) (xy 335.8119 -97.673997)
			(xy 335.811904 -97.728733) (xy 335.804082 -97.782908) (xy 335.788593 -97.835407) (xy 335.765756 -97.885151)
			(xy 335.73604 -97.931119) (xy 335.718404 -97.952052) (xy 335.71815 -97.952306) (xy 335.712549 -97.959382)
			(xy 335.706312 -97.976307) (xy 335.705958 -97.985326) (xy 335.705958 -98.052382) (xy 335.706311 -98.0614)
			(xy 335.71256 -98.078317) (xy 335.71815 -98.085402) (xy 335.718404 -98.085402) (xy 335.718404 -98.085656)
			(xy 335.736037 -98.106593) (xy 335.765749 -98.152565) (xy 335.788586 -98.202311) (xy 335.792404 -98.215249)
			(xy 337.158596 -98.215249) (xy 337.158596 -98.160751) (xy 337.166352 -98.106807) (xy 337.181705 -98.054516)
			(xy 337.204344 -98.004942) (xy 337.233808 -97.959095) (xy 337.269496 -97.917907) (xy 337.310682 -97.882217)
			(xy 337.356528 -97.852752) (xy 337.406101 -97.830111) (xy 337.458391 -97.814755) (xy 337.512335 -97.806997)
			(xy 337.539584 -97.80651) (xy 337.569852 -97.807077) (xy 337.629627 -97.816648) (xy 337.687141 -97.835535)
			(xy 337.740952 -97.863266) (xy 337.78971 -97.899145) (xy 337.811364 -97.920302) (xy 337.818785 -97.927252)
			(xy 337.837527 -97.935099) (xy 337.847686 -97.935542) (xy 337.919822 -97.935542) (xy 337.929984 -97.935129)
			(xy 337.94872 -97.927256) (xy 337.956144 -97.920302) (xy 337.977796 -97.899144) (xy 338.026551 -97.863261)
			(xy 338.080363 -97.83553) (xy 338.137879 -97.816648) (xy 338.197656 -97.807089) (xy 338.227924 -97.80651)
			(xy 338.25776 -97.807056) (xy 338.316701 -97.816363) (xy 338.373475 -97.83473) (xy 338.426699 -97.861709)
			(xy 338.475075 -97.896644) (xy 338.496656 -97.917254) (xy 338.503768 -97.924366) (xy 338.52231 -97.931986)
			(xy 338.614004 -97.931986) (xy 338.632546 -97.924366) (xy 338.639658 -97.917254) (xy 338.661247 -97.896655)
			(xy 338.709619 -97.861718) (xy 338.762841 -97.834741) (xy 338.819615 -97.816382) (xy 338.878556 -97.807088)
			(xy 338.90839 -97.80651) (xy 338.935645 -97.806936) (xy 338.989599 -97.814692) (xy 339.041901 -97.830048)
			(xy 339.091485 -97.852691) (xy 339.137341 -97.88216) (xy 339.178537 -97.917856) (xy 339.214234 -97.959051)
			(xy 339.243704 -98.004907) (xy 339.266348 -98.05449) (xy 339.281705 -98.106791) (xy 339.289463 -98.160745)
			(xy 339.289463 -98.215255) (xy 339.281705 -98.269209) (xy 339.266348 -98.32151) (xy 339.243704 -98.371093)
			(xy 339.214234 -98.416949) (xy 339.178537 -98.458144) (xy 339.137341 -98.49384) (xy 339.091485 -98.523309)
			(xy 339.041901 -98.545952) (xy 338.989599 -98.561308) (xy 338.935645 -98.569064) (xy 338.90839 -98.569526)
			(xy 338.878555 -98.56896) (xy 338.819615 -98.559657) (xy 338.762842 -98.541294) (xy 338.709617 -98.514319)
			(xy 338.66124 -98.47939) (xy 338.639658 -98.458782) (xy 338.632546 -98.45167) (xy 338.614004 -98.44405)
			(xy 338.52231 -98.44405) (xy 338.503768 -98.45167) (xy 338.496656 -98.458782) (xy 338.475094 -98.479412)
			(xy 338.426716 -98.514346) (xy 338.373487 -98.541319) (xy 338.316707 -98.559671) (xy 338.25776 -98.568954)
			(xy 338.227924 -98.569526) (xy 338.197657 -98.568944) (xy 338.137883 -98.559375) (xy 338.080369 -98.540491)
			(xy 338.026558 -98.512763) (xy 337.977799 -98.476889) (xy 337.956144 -98.455734) (xy 337.948716 -98.448792)
			(xy 337.92998 -98.440939) (xy 337.919822 -98.440494) (xy 337.847686 -98.440494) (xy 337.837523 -98.440902)
			(xy 337.818786 -98.448778) (xy 337.811364 -98.455734) (xy 337.789714 -98.476895) (xy 337.740958 -98.512776)
			(xy 337.687146 -98.540506) (xy 337.629629 -98.559387) (xy 337.569852 -98.568947) (xy 337.539584 -98.569526)
			(xy 337.512335 -98.569003) (xy 337.458391 -98.561245) (xy 337.406101 -98.545889) (xy 337.356528 -98.523248)
			(xy 337.310682 -98.493783) (xy 337.269496 -98.458093) (xy 337.233808 -98.416905) (xy 337.204344 -98.371058)
			(xy 337.181705 -98.321484) (xy 337.166352 -98.269193) (xy 337.158596 -98.215249) (xy 335.792404 -98.215249)
			(xy 335.804079 -98.25481) (xy 335.811909 -98.308985) (xy 335.812384 -98.336354) (xy 335.811898 -98.363605)
			(xy 335.804142 -98.417553) (xy 335.788787 -98.469848) (xy 335.766145 -98.519425) (xy 335.736679 -98.565275)
			(xy 335.700988 -98.606466) (xy 335.659797 -98.642157) (xy 335.613947 -98.671623) (xy 335.56437 -98.694265)
			(xy 335.512075 -98.70962) (xy 335.458127 -98.717376) (xy 335.403625 -98.717376) (xy 335.349677 -98.70962)
			(xy 335.297382 -98.694265) (xy 335.247805 -98.671623) (xy 335.201955 -98.642157) (xy 335.160764 -98.606466)
			(xy 335.125073 -98.565275) (xy 335.095607 -98.519425) (xy 335.072965 -98.469848) (xy 335.05761 -98.417553)
			(xy 335.049854 -98.363605) (xy 335.049368 -98.336354) (xy 334.473172 -98.336354) (xy 334.476118 -98.342804)
			(xy 334.491474 -98.3951) (xy 334.49923 -98.449048) (xy 334.49923 -98.503552) (xy 334.491474 -98.5575)
			(xy 334.476118 -98.609796) (xy 334.453477 -98.659374) (xy 334.424011 -98.705225) (xy 334.388319 -98.746416)
			(xy 334.347128 -98.782108) (xy 334.301277 -98.811575) (xy 334.251699 -98.834217) (xy 334.199404 -98.849573)
			(xy 334.145456 -98.85733) (xy 334.118204 -98.857816) (xy 334.09189 -98.857341) (xy 334.039762 -98.850107)
			(xy 333.98912 -98.835789) (xy 333.940921 -98.814658) (xy 333.896077 -98.787113) (xy 333.855437 -98.753677)
			(xy 333.83728 -98.734626) (xy 333.829764 -98.727217) (xy 333.81048 -98.718696) (xy 333.799942 -98.718116)
			(xy 333.725266 -98.718116) (xy 333.714718 -98.718663) (xy 333.695422 -98.727185) (xy 333.687928 -98.734626)
			(xy 333.669757 -98.753666) (xy 333.62913 -98.787123) (xy 333.584293 -98.814684) (xy 333.536095 -98.835825)
			(xy 333.485451 -98.850146) (xy 333.433319 -98.857375) (xy 333.407004 -98.857816) (xy 333.379752 -98.857337)
			(xy 333.325801 -98.849581) (xy 333.273504 -98.834225) (xy 333.223924 -98.811583) (xy 333.178072 -98.782116)
			(xy 333.13688 -98.746423) (xy 333.101186 -98.705231) (xy 333.071718 -98.659379) (xy 333.049076 -98.6098)
			(xy 333.03372 -98.557503) (xy 333.025963 -98.503552) (xy 332.036031 -98.503552) (xy 332.039976 -98.508566)
			(xy 332.04023 -98.509074) (xy 332.051175 -98.521807) (xy 332.071016 -98.548899) (xy 332.079854 -98.563176)
			(xy 332.085188 -98.572066) (xy 332.102206 -98.584258) (xy 332.195424 -98.604578) (xy 332.215998 -98.60026)
			(xy 332.224634 -98.594418) (xy 332.248689 -98.578403) (xy 332.300623 -98.553064) (xy 332.355784 -98.535842)
			(xy 332.412911 -98.527132) (xy 332.441804 -98.5266) (xy 332.469056 -98.52707) (xy 332.523004 -98.534827)
			(xy 332.575299 -98.550183) (xy 332.624877 -98.572825) (xy 332.670728 -98.602292) (xy 332.711919 -98.637984)
			(xy 332.747611 -98.679175) (xy 332.777077 -98.725026) (xy 332.799718 -98.774604) (xy 332.815074 -98.8269)
			(xy 332.82283 -98.880848) (xy 332.82283 -98.935352) (xy 332.815074 -98.9893) (xy 332.799718 -99.041596)
			(xy 332.777077 -99.091174) (xy 332.747611 -99.137025) (xy 332.711919 -99.178216) (xy 332.670728 -99.213908)
			(xy 332.624877 -99.243375) (xy 332.575299 -99.266017) (xy 332.523004 -99.281373) (xy 332.469056 -99.28913)
			(xy 332.441804 -99.289616) (xy 332.413713 -99.289119) (xy 332.358135 -99.280892) (xy 332.304367 -99.264601)
			(xy 332.253569 -99.240599) (xy 332.206842 -99.209405) (xy 332.165197 -99.171693) (xy 332.129535 -99.12828)
			(xy 332.114652 -99.10445) (xy 332.109318 -99.09556) (xy 332.0923 -99.083368) (xy 331.999082 -99.063048)
			(xy 331.978508 -99.067366) (xy 331.969872 -99.073208) (xy 331.945818 -99.089223) (xy 331.893883 -99.114562)
			(xy 331.838722 -99.131784) (xy 331.781595 -99.140494) (xy 331.752702 -99.141026) (xy 331.725452 -99.14052)
			(xy 331.671506 -99.132765) (xy 331.619212 -99.117411) (xy 331.569636 -99.094771) (xy 331.523787 -99.065307)
			(xy 331.482597 -99.029617) (xy 331.446905 -98.988429) (xy 331.417439 -98.942581) (xy 331.394796 -98.893007)
			(xy 331.37944 -98.840714) (xy 331.371681 -98.786768) (xy 331.371194 -98.759518) (xy 319.09766 -98.759518)
			(xy 319.09766 -99.449382) (xy 320.106038 -99.449382) (xy 320.110109 -99.39376) (xy 320.122235 -99.339323)
			(xy 320.142158 -99.287232) (xy 320.169454 -99.238597) (xy 320.20354 -99.194454) (xy 320.243689 -99.155745)
			(xy 320.289047 -99.123294) (xy 320.338647 -99.097793) (xy 320.391431 -99.079786) (xy 320.446274 -99.069656)
			(xy 320.502008 -99.067619) (xy 320.557445 -99.073719) (xy 320.611402 -99.087825) (xy 320.662731 -99.109637)
			(xy 320.710337 -99.138691) (xy 320.753205 -99.174366) (xy 320.790422 -99.215903) (xy 320.821195 -99.262416)
			(xy 320.844867 -99.312913) (xy 320.860935 -99.36632) (xy 320.869055 -99.421496) (xy 320.869564 -99.449382)
			(xy 320.869397 -99.458526) (xy 325.838564 -99.458526) (xy 325.842635 -99.402904) (xy 325.854761 -99.348467)
			(xy 325.874684 -99.296376) (xy 325.90198 -99.247741) (xy 325.936066 -99.203598) (xy 325.976215 -99.164889)
			(xy 326.021573 -99.132438) (xy 326.071173 -99.106937) (xy 326.123957 -99.08893) (xy 326.1788 -99.0788)
			(xy 326.234534 -99.076763) (xy 326.289971 -99.082863) (xy 326.343928 -99.096969) (xy 326.395257 -99.118781)
			(xy 326.442863 -99.147835) (xy 326.485731 -99.18351) (xy 326.522948 -99.225047) (xy 326.553721 -99.27156)
			(xy 326.577393 -99.322057) (xy 326.593461 -99.375464) (xy 326.601581 -99.43064) (xy 326.60209 -99.458526)
			(xy 326.601581 -99.486412) (xy 326.593461 -99.541588) (xy 326.577393 -99.594995) (xy 326.553721 -99.645492)
			(xy 326.522948 -99.692005) (xy 326.485731 -99.733542) (xy 326.442863 -99.769217) (xy 326.395257 -99.798271)
			(xy 326.343928 -99.820083) (xy 326.289971 -99.834189) (xy 326.234534 -99.840289) (xy 326.1788 -99.838252)
			(xy 326.123957 -99.828122) (xy 326.071173 -99.810115) (xy 326.021573 -99.784614) (xy 325.976215 -99.752163)
			(xy 325.936066 -99.713454) (xy 325.90198 -99.669311) (xy 325.874684 -99.620676) (xy 325.854761 -99.568585)
			(xy 325.842635 -99.514148) (xy 325.838564 -99.458526) (xy 320.869397 -99.458526) (xy 320.869055 -99.477268)
			(xy 320.860935 -99.532444) (xy 320.844867 -99.585851) (xy 320.821195 -99.636348) (xy 320.790422 -99.682861)
			(xy 320.753205 -99.724398) (xy 320.710337 -99.760073) (xy 320.662731 -99.789127) (xy 320.611402 -99.810939)
			(xy 320.557445 -99.825045) (xy 320.502008 -99.831145) (xy 320.446274 -99.829108) (xy 320.391431 -99.818978)
			(xy 320.338647 -99.800971) (xy 320.289047 -99.77547) (xy 320.243689 -99.743019) (xy 320.20354 -99.70431)
			(xy 320.169454 -99.660167) (xy 320.142158 -99.611532) (xy 320.122235 -99.559441) (xy 320.110109 -99.505004)
			(xy 320.106038 -99.449382) (xy 319.09766 -99.449382) (xy 319.09766 -101.18985) (xy 329.19339 -101.18985)
			(xy 329.19339 -101.13535) (xy 329.201146 -101.081404) (xy 329.216501 -101.029111) (xy 329.239141 -100.979536)
			(xy 329.268606 -100.933687) (xy 329.304297 -100.892498) (xy 329.345485 -100.856808) (xy 329.391334 -100.827342)
			(xy 329.440909 -100.804702) (xy 329.493202 -100.789347) (xy 329.547148 -100.78159) (xy 329.574398 -100.781104)
			(xy 329.601768 -100.78157) (xy 329.655947 -100.789388) (xy 329.708451 -100.804877) (xy 329.758197 -100.827719)
			(xy 329.804164 -100.857443) (xy 329.825096 -100.875084) (xy 329.82535 -100.875338) (xy 329.832444 -100.880914)
			(xy 329.849355 -100.887166) (xy 329.85837 -100.88753) (xy 329.925426 -100.88753) (xy 329.934443 -100.887179)
			(xy 329.95136 -100.880927) (xy 329.958446 -100.875338) (xy 329.958446 -100.875084) (xy 329.9587 -100.875084)
			(xy 329.979619 -100.857429) (xy 330.025596 -100.82772) (xy 330.075347 -100.804887) (xy 330.12785 -100.7894)
			(xy 330.182028 -100.781576) (xy 330.209398 -100.781104) (xy 330.236652 -100.781543) (xy 330.290605 -100.7893)
			(xy 330.342905 -100.804656) (xy 330.392487 -100.827299) (xy 330.438341 -100.856768) (xy 330.479536 -100.892463)
			(xy 330.515231 -100.933657) (xy 330.5447 -100.979512) (xy 330.567343 -101.029094) (xy 330.5827 -101.081393)
			(xy 330.590457 -101.135346) (xy 330.590457 -101.189854) (xy 330.5827 -101.243807) (xy 330.567343 -101.296106)
			(xy 330.5447 -101.345688) (xy 330.515231 -101.391543) (xy 330.479536 -101.432737) (xy 330.438341 -101.468432)
			(xy 330.392487 -101.497901) (xy 330.342905 -101.520544) (xy 330.290605 -101.5359) (xy 330.236652 -101.543657)
			(xy 330.209398 -101.54412) (xy 330.182027 -101.543675) (xy 330.127846 -101.535855) (xy 330.075342 -101.520362)
			(xy 330.025595 -101.497515) (xy 329.97963 -101.467784) (xy 329.9587 -101.45014) (xy 329.958446 -101.449886)
			(xy 329.951352 -101.444311) (xy 329.934441 -101.438058) (xy 329.925426 -101.437694) (xy 329.85837 -101.437694)
			(xy 329.849352 -101.438038) (xy 329.832435 -101.444295) (xy 329.82535 -101.449886) (xy 329.82535 -101.45014)
			(xy 329.825096 -101.45014) (xy 329.804182 -101.467801) (xy 329.758203 -101.497508) (xy 329.708451 -101.520339)
			(xy 329.655947 -101.535826) (xy 329.601768 -101.543649) (xy 329.574398 -101.54412) (xy 329.547148 -101.54361)
			(xy 329.493202 -101.535853) (xy 329.440909 -101.520498) (xy 329.391334 -101.497858) (xy 329.345485 -101.468392)
			(xy 329.304297 -101.432702) (xy 329.268606 -101.391513) (xy 329.239141 -101.345664) (xy 329.216501 -101.296089)
			(xy 329.201146 -101.243796) (xy 329.19339 -101.18985) (xy 319.09766 -101.18985) (xy 319.09766 -101.579172)
			(xy 319.970656 -101.579172) (xy 319.974727 -101.52355) (xy 319.986853 -101.469113) (xy 320.006776 -101.417022)
			(xy 320.034072 -101.368387) (xy 320.068158 -101.324244) (xy 320.108307 -101.285535) (xy 320.153665 -101.253084)
			(xy 320.203265 -101.227583) (xy 320.256049 -101.209576) (xy 320.310892 -101.199446) (xy 320.366626 -101.197409)
			(xy 320.422063 -101.203509) (xy 320.47602 -101.217615) (xy 320.527349 -101.239427) (xy 320.574955 -101.268481)
			(xy 320.617823 -101.304156) (xy 320.65504 -101.345693) (xy 320.685813 -101.392206) (xy 320.709485 -101.442703)
			(xy 320.725553 -101.49611) (xy 320.733673 -101.551286) (xy 320.734182 -101.579172) (xy 320.733673 -101.607058)
			(xy 320.725553 -101.662234) (xy 320.709485 -101.715641) (xy 320.685813 -101.766138) (xy 320.65504 -101.812651)
			(xy 320.617823 -101.854188) (xy 320.597905 -101.870764) (xy 325.439022 -101.870764) (xy 325.443093 -101.815142)
			(xy 325.455219 -101.760705) (xy 325.475142 -101.708614) (xy 325.502438 -101.659979) (xy 325.536524 -101.615836)
			(xy 325.576673 -101.577127) (xy 325.622031 -101.544676) (xy 325.671631 -101.519175) (xy 325.724415 -101.501168)
			(xy 325.779258 -101.491038) (xy 325.834992 -101.489001) (xy 325.890429 -101.495101) (xy 325.944386 -101.509207)
			(xy 325.995715 -101.531019) (xy 326.043321 -101.560073) (xy 326.086189 -101.595748) (xy 326.123406 -101.637285)
			(xy 326.154179 -101.683798) (xy 326.177851 -101.734295) (xy 326.193919 -101.787702) (xy 326.202039 -101.842878)
			(xy 326.202548 -101.870764) (xy 326.202039 -101.89865) (xy 326.193919 -101.953826) (xy 326.177851 -102.007233)
			(xy 326.154179 -102.05773) (xy 326.123406 -102.104243) (xy 326.099924 -102.130451) (xy 328.743052 -102.130451)
			(xy 328.743052 -102.075949) (xy 328.750808 -102.022001) (xy 328.766162 -101.969707) (xy 328.788801 -101.920129)
			(xy 328.818265 -101.874277) (xy 328.853954 -101.833086) (xy 328.895142 -101.797392) (xy 328.94099 -101.767922)
			(xy 328.990565 -101.745277) (xy 329.042858 -101.729917) (xy 329.096805 -101.722155) (xy 329.124056 -101.721666)
			(xy 329.151426 -101.722142) (xy 329.205605 -101.729955) (xy 329.258109 -101.745441) (xy 329.307856 -101.768281)
			(xy 329.353823 -101.798005) (xy 329.374754 -101.815646) (xy 329.375008 -101.8159) (xy 329.382088 -101.821496)
			(xy 329.39901 -101.827737) (xy 329.408028 -101.828092) (xy 329.475084 -101.828092) (xy 329.4841 -101.827729)
			(xy 329.501017 -101.821486) (xy 329.508104 -101.8159) (xy 329.508104 -101.815646) (xy 329.508358 -101.815646)
			(xy 329.529301 -101.79802) (xy 329.57527 -101.768305) (xy 329.625015 -101.745466) (xy 329.677513 -101.729972)
			(xy 329.731687 -101.722141) (xy 329.759056 -101.721666) (xy 329.786309 -101.722178) (xy 329.840261 -101.72993)
			(xy 329.892561 -101.745281) (xy 329.942143 -101.767919) (xy 329.987998 -101.797384) (xy 330.029194 -101.833075)
			(xy 330.06489 -101.874266) (xy 330.09436 -101.920118) (xy 330.117004 -101.969698) (xy 330.132361 -102.021996)
			(xy 330.140119 -102.075947) (xy 330.140119 -102.130453) (xy 330.132361 -102.184404) (xy 330.117004 -102.236702)
			(xy 330.09436 -102.286282) (xy 330.06489 -102.332134) (xy 330.029194 -102.373325) (xy 329.987998 -102.409016)
			(xy 329.942143 -102.438481) (xy 329.892561 -102.461119) (xy 329.840261 -102.47647) (xy 329.786309 -102.484222)
			(xy 329.759056 -102.484682) (xy 329.731687 -102.484187) (xy 329.677509 -102.476377) (xy 329.625006 -102.460895)
			(xy 329.575258 -102.438059) (xy 329.52929 -102.408341) (xy 329.508358 -102.390702) (xy 329.508104 -102.390448)
			(xy 329.501025 -102.384851) (xy 329.484102 -102.378612) (xy 329.475084 -102.378256) (xy 329.408028 -102.378256)
			(xy 329.399011 -102.378614) (xy 329.382093 -102.38486) (xy 329.375008 -102.390448) (xy 329.375008 -102.390702)
			(xy 329.374754 -102.390702) (xy 329.353813 -102.40833) (xy 329.307842 -102.438043) (xy 329.258097 -102.460881)
			(xy 329.205599 -102.476375) (xy 329.151425 -102.484206) (xy 329.124056 -102.484682) (xy 329.096805 -102.484245)
			(xy 329.042858 -102.476483) (xy 328.990565 -102.461123) (xy 328.94099 -102.438478) (xy 328.895142 -102.409008)
			(xy 328.853954 -102.373314) (xy 328.818265 -102.332123) (xy 328.788801 -102.286271) (xy 328.766162 -102.236693)
			(xy 328.750808 -102.184399) (xy 328.743052 -102.130451) (xy 326.099924 -102.130451) (xy 326.086189 -102.14578)
			(xy 326.043321 -102.181455) (xy 325.995715 -102.210509) (xy 325.944386 -102.232321) (xy 325.890429 -102.246427)
			(xy 325.834992 -102.252527) (xy 325.779258 -102.25049) (xy 325.724415 -102.24036) (xy 325.671631 -102.222353)
			(xy 325.622031 -102.196852) (xy 325.576673 -102.164401) (xy 325.536524 -102.125692) (xy 325.502438 -102.081549)
			(xy 325.475142 -102.032914) (xy 325.455219 -101.980823) (xy 325.443093 -101.926386) (xy 325.439022 -101.870764)
			(xy 320.597905 -101.870764) (xy 320.574955 -101.889863) (xy 320.527349 -101.918917) (xy 320.47602 -101.940729)
			(xy 320.422063 -101.954835) (xy 320.366626 -101.960935) (xy 320.310892 -101.958898) (xy 320.256049 -101.948768)
			(xy 320.203265 -101.930761) (xy 320.153665 -101.90526) (xy 320.108307 -101.872809) (xy 320.068158 -101.8341)
			(xy 320.034072 -101.789957) (xy 320.006776 -101.741322) (xy 319.986853 -101.689231) (xy 319.974727 -101.634794)
			(xy 319.970656 -101.579172) (xy 319.09766 -101.579172) (xy 319.09766 -101.991414) (xy 319.097914 -101.997256)
			(xy 319.09917 -102.005587) (xy 319.106426 -102.020782) (xy 319.112138 -102.026974) (xy 319.593468 -102.50805)
			(xy 319.611503 -102.52682) (xy 319.642088 -102.568936) (xy 319.665719 -102.615311) (xy 319.681818 -102.664809)
			(xy 319.689988 -102.716214) (xy 319.690496 -102.742238) (xy 319.690496 -103.13924) (xy 321.707 -103.13924)
			(xy 321.711071 -103.083618) (xy 321.723197 -103.029181) (xy 321.74312 -102.97709) (xy 321.770416 -102.928455)
			(xy 321.804502 -102.884312) (xy 321.844651 -102.845603) (xy 321.890009 -102.813152) (xy 321.939609 -102.787651)
			(xy 321.992393 -102.769644) (xy 322.047236 -102.759514) (xy 322.10297 -102.757477) (xy 322.158407 -102.763577)
			(xy 322.212364 -102.777683) (xy 322.263693 -102.799495) (xy 322.311299 -102.828549) (xy 322.354167 -102.864224)
			(xy 322.391384 -102.905761) (xy 322.422157 -102.952274) (xy 322.445829 -103.002771) (xy 322.461897 -103.056178)
			(xy 322.470017 -103.111354) (xy 322.470526 -103.13924) (xy 322.470017 -103.167126) (xy 322.461897 -103.222302)
			(xy 322.445829 -103.275709) (xy 322.422157 -103.326206) (xy 322.391384 -103.372719) (xy 322.354167 -103.414256)
			(xy 322.311299 -103.449931) (xy 322.263693 -103.478985) (xy 322.212364 -103.500797) (xy 322.158407 -103.514903)
			(xy 322.10297 -103.521003) (xy 322.047236 -103.518966) (xy 321.992393 -103.508836) (xy 321.939609 -103.490829)
			(xy 321.890009 -103.465328) (xy 321.844651 -103.432877) (xy 321.804502 -103.394168) (xy 321.770416 -103.350025)
			(xy 321.74312 -103.30139) (xy 321.723197 -103.249299) (xy 321.711071 -103.194862) (xy 321.707 -103.13924)
			(xy 319.690496 -103.13924) (xy 319.690496 -104.674924) (xy 320.759326 -104.674924) (xy 320.763397 -104.619302)
			(xy 320.775523 -104.564865) (xy 320.795446 -104.512774) (xy 320.822742 -104.464139) (xy 320.856828 -104.419996)
			(xy 320.896977 -104.381287) (xy 320.942335 -104.348836) (xy 320.991935 -104.323335) (xy 321.044719 -104.305328)
			(xy 321.099562 -104.295198) (xy 321.155296 -104.293161) (xy 321.210733 -104.299261) (xy 321.26469 -104.313367)
			(xy 321.316019 -104.335179) (xy 321.363625 -104.364233) (xy 321.406493 -104.399908) (xy 321.44371 -104.441445)
			(xy 321.474483 -104.487958) (xy 321.498155 -104.538455) (xy 321.514223 -104.591862) (xy 321.522343 -104.647038)
			(xy 321.522852 -104.674924) (xy 321.522343 -104.70281) (xy 321.514223 -104.757986) (xy 321.498155 -104.811393)
			(xy 321.474483 -104.86189) (xy 321.44371 -104.908403) (xy 321.406493 -104.94994) (xy 321.363625 -104.985615)
			(xy 321.316019 -105.014669) (xy 321.26469 -105.036481) (xy 321.210733 -105.050587) (xy 321.155296 -105.056687)
			(xy 321.099562 -105.05465) (xy 321.044719 -105.04452) (xy 320.991935 -105.026513) (xy 320.942335 -105.001012)
			(xy 320.896977 -104.968561) (xy 320.856828 -104.929852) (xy 320.822742 -104.885709) (xy 320.795446 -104.837074)
			(xy 320.775523 -104.784983) (xy 320.763397 -104.730546) (xy 320.759326 -104.674924) (xy 319.690496 -104.674924)
			(xy 319.690496 -107.058206) (xy 321.773804 -107.058206) (xy 321.77433 -107.029467) (xy 321.782952 -106.97264)
			(xy 321.800001 -106.917749) (xy 321.825093 -106.866037) (xy 321.857657 -106.818675) (xy 321.876928 -106.797348)
			(xy 321.883532 -106.79049) (xy 321.890644 -106.772456) (xy 321.890644 -106.683556) (xy 321.883532 -106.665522)
			(xy 321.876928 -106.658664) (xy 321.857663 -106.637332) (xy 321.825097 -106.589971) (xy 321.800005 -106.53826)
			(xy 321.782954 -106.48337) (xy 321.774331 -106.426543) (xy 321.77433 -106.369066) (xy 321.782952 -106.312239)
			(xy 321.800002 -106.257348) (xy 321.825093 -106.205637) (xy 321.857657 -106.158275) (xy 321.876928 -106.136948)
			(xy 321.883532 -106.13009) (xy 321.890644 -106.112056) (xy 321.890644 -106.023156) (xy 321.883532 -106.005122)
			(xy 321.876928 -105.998264) (xy 321.857659 -105.976936) (xy 321.825092 -105.929574) (xy 321.8 -105.877863)
			(xy 321.782949 -105.822972) (xy 321.774325 -105.766145) (xy 321.773804 -105.737406) (xy 321.77429 -105.710155)
			(xy 321.782046 -105.656207) (xy 321.797401 -105.603912) (xy 321.820043 -105.554335) (xy 321.849509 -105.508485)
			(xy 321.8852 -105.467294) (xy 321.926391 -105.431603) (xy 321.972241 -105.402137) (xy 322.021818 -105.379495)
			(xy 322.074113 -105.36414) (xy 322.128061 -105.356384) (xy 322.182563 -105.356384) (xy 322.236511 -105.36414)
			(xy 322.288806 -105.379495) (xy 322.338383 -105.402137) (xy 322.384233 -105.431603) (xy 322.425424 -105.467294)
			(xy 322.461115 -105.508485) (xy 322.490581 -105.554335) (xy 322.513223 -105.603912) (xy 322.528578 -105.656207)
			(xy 322.536334 -105.710155) (xy 322.53682 -105.737406) (xy 322.536295 -105.766145) (xy 322.527672 -105.822972)
			(xy 322.510622 -105.877862) (xy 322.485531 -105.929574) (xy 322.452966 -105.976937) (xy 322.433696 -105.998264)
			(xy 322.427092 -106.005122) (xy 322.41998 -106.023156) (xy 322.41998 -106.112056) (xy 322.427092 -106.13009)
			(xy 322.433696 -106.136948) (xy 322.452972 -106.15827) (xy 322.485535 -106.205634) (xy 322.510625 -106.257347)
			(xy 322.527674 -106.312238) (xy 322.536295 -106.369065) (xy 322.536295 -106.426543) (xy 322.527672 -106.483371)
			(xy 322.510622 -106.538262) (xy 322.485531 -106.589974) (xy 322.452966 -106.637337) (xy 322.433696 -106.658664)
			(xy 322.427092 -106.665522) (xy 322.41998 -106.683556) (xy 322.41998 -106.772456) (xy 322.427092 -106.79049)
			(xy 322.433696 -106.797348) (xy 322.452958 -106.818683) (xy 322.485528 -106.866041) (xy 322.510623 -106.917751)
			(xy 322.527676 -106.972641) (xy 322.536299 -107.029467) (xy 322.53682 -107.058206) (xy 322.536334 -107.085457)
			(xy 322.528578 -107.139405) (xy 322.513223 -107.1917) (xy 322.490581 -107.241277) (xy 322.461115 -107.287127)
			(xy 322.425424 -107.328318) (xy 322.384233 -107.364009) (xy 322.338383 -107.393475) (xy 322.288806 -107.416117)
			(xy 322.236511 -107.431472) (xy 322.182563 -107.439228) (xy 322.128061 -107.439228) (xy 322.074113 -107.431472)
			(xy 322.021818 -107.416117) (xy 321.972241 -107.393475) (xy 321.926391 -107.364009) (xy 321.8852 -107.328318)
			(xy 321.849509 -107.287127) (xy 321.820043 -107.241277) (xy 321.797401 -107.1917) (xy 321.782046 -107.139405)
			(xy 321.77429 -107.085457) (xy 321.773804 -107.058206) (xy 319.690496 -107.058206) (xy 319.690496 -108.379006)
			(xy 322.662804 -108.379006) (xy 322.66333 -108.350267) (xy 322.671952 -108.29344) (xy 322.689001 -108.238549)
			(xy 322.714093 -108.186837) (xy 322.746657 -108.139475) (xy 322.765928 -108.118148) (xy 322.772532 -108.11129)
			(xy 322.779644 -108.093256) (xy 322.779644 -108.004356) (xy 322.772532 -107.986322) (xy 322.765928 -107.979464)
			(xy 322.746663 -107.958132) (xy 322.714097 -107.910771) (xy 322.689005 -107.85906) (xy 322.671954 -107.80417)
			(xy 322.663331 -107.747343) (xy 322.66333 -107.689866) (xy 322.671952 -107.633039) (xy 322.689002 -107.578148)
			(xy 322.714093 -107.526437) (xy 322.746657 -107.479075) (xy 322.765928 -107.457748) (xy 322.772532 -107.45089)
			(xy 322.779644 -107.432856) (xy 322.779644 -107.343956) (xy 322.772532 -107.325922) (xy 322.765928 -107.319064)
			(xy 322.746663 -107.297732) (xy 322.714097 -107.250371) (xy 322.689005 -107.19866) (xy 322.671954 -107.14377)
			(xy 322.663331 -107.086943) (xy 322.66333 -107.029466) (xy 322.671952 -106.972639) (xy 322.689002 -106.917748)
			(xy 322.714093 -106.866037) (xy 322.746657 -106.818675) (xy 322.765928 -106.797348) (xy 322.772532 -106.79049)
			(xy 322.779644 -106.772456) (xy 322.779644 -106.683556) (xy 322.772532 -106.665522) (xy 322.765928 -106.658664)
			(xy 322.746663 -106.637332) (xy 322.714097 -106.589971) (xy 322.689005 -106.53826) (xy 322.671954 -106.48337)
			(xy 322.663331 -106.426543) (xy 322.66333 -106.369066) (xy 322.671952 -106.312239) (xy 322.689002 -106.257348)
			(xy 322.714093 -106.205637) (xy 322.746657 -106.158275) (xy 322.765928 -106.136948) (xy 322.772532 -106.13009)
			(xy 322.779644 -106.112056) (xy 322.779644 -106.023156) (xy 322.772532 -106.005122) (xy 322.765928 -105.998264)
			(xy 322.746663 -105.976932) (xy 322.714097 -105.929571) (xy 322.689005 -105.87786) (xy 322.671954 -105.82297)
			(xy 322.663331 -105.766143) (xy 322.66333 -105.708666) (xy 322.671952 -105.651839) (xy 322.689002 -105.596948)
			(xy 322.714093 -105.545237) (xy 322.746657 -105.497875) (xy 322.765928 -105.476548) (xy 322.772532 -105.46969)
			(xy 322.779644 -105.451656) (xy 322.779644 -105.362756) (xy 322.772532 -105.344722) (xy 322.765928 -105.337864)
			(xy 322.746663 -105.316532) (xy 322.714097 -105.269171) (xy 322.689005 -105.21746) (xy 322.671954 -105.16257)
			(xy 322.663331 -105.105743) (xy 322.66333 -105.048266) (xy 322.671952 -104.991439) (xy 322.689002 -104.936548)
			(xy 322.714093 -104.884837) (xy 322.746657 -104.837475) (xy 322.765928 -104.816148) (xy 322.772532 -104.80929)
			(xy 322.779644 -104.791256) (xy 322.779644 -104.702356) (xy 322.772532 -104.684322) (xy 322.765928 -104.677464)
			(xy 322.746663 -104.656132) (xy 322.714097 -104.608771) (xy 322.689005 -104.55706) (xy 322.671954 -104.50217)
			(xy 322.663331 -104.445343) (xy 322.66333 -104.387866) (xy 322.671952 -104.331039) (xy 322.689002 -104.276148)
			(xy 322.714093 -104.224437) (xy 322.746657 -104.177075) (xy 322.765928 -104.155748) (xy 322.772532 -104.14889)
			(xy 322.779644 -104.130856) (xy 322.779644 -104.041956) (xy 322.772532 -104.023922) (xy 322.765928 -104.017064)
			(xy 322.746663 -103.995732) (xy 322.714097 -103.948371) (xy 322.689005 -103.89666) (xy 322.671954 -103.84177)
			(xy 322.663331 -103.784943) (xy 322.66333 -103.727466) (xy 322.671952 -103.670639) (xy 322.689002 -103.615748)
			(xy 322.714093 -103.564037) (xy 322.746657 -103.516675) (xy 322.765928 -103.495348) (xy 322.772532 -103.48849)
			(xy 322.779644 -103.470456) (xy 322.779644 -103.381556) (xy 322.772532 -103.363522) (xy 322.765928 -103.356664)
			(xy 322.746659 -103.335336) (xy 322.714092 -103.287974) (xy 322.689 -103.236263) (xy 322.671949 -103.181372)
			(xy 322.663325 -103.124545) (xy 322.662804 -103.095806) (xy 322.663245 -103.068599) (xy 322.67097 -103.014735)
			(xy 322.686276 -102.962517) (xy 322.708854 -102.913007) (xy 322.738244 -102.867212) (xy 322.773848 -102.826063)
			(xy 322.814943 -102.790395) (xy 322.837556 -102.775258) (xy 322.845938 -102.769924) (xy 322.857114 -102.753668)
			(xy 322.875402 -102.674674) (xy 322.87721 -102.665045) (xy 322.874213 -102.645704) (xy 322.86956 -102.637082)
			(xy 322.869306 -102.637082) (xy 322.869306 -102.636574) (xy 322.856101 -102.614063) (xy 322.835245 -102.566221)
			(xy 322.821095 -102.515987) (xy 322.813911 -102.464294) (xy 322.813426 -102.4382) (xy 322.813912 -102.410949)
			(xy 322.821668 -102.357001) (xy 322.837023 -102.304706) (xy 322.859665 -102.255129) (xy 322.889131 -102.209279)
			(xy 322.924822 -102.168088) (xy 322.966013 -102.132397) (xy 323.011863 -102.102931) (xy 323.06144 -102.080289)
			(xy 323.113735 -102.064934) (xy 323.167683 -102.057178) (xy 323.222185 -102.057178) (xy 323.276133 -102.064934)
			(xy 323.328428 -102.080289) (xy 323.378005 -102.102931) (xy 323.423855 -102.132397) (xy 323.465046 -102.168088)
			(xy 323.500737 -102.209279) (xy 323.530203 -102.255129) (xy 323.552845 -102.304706) (xy 323.5682 -102.357001)
			(xy 323.575956 -102.410949) (xy 323.576442 -102.4382) (xy 323.575984 -102.465407) (xy 323.56826 -102.519269)
			(xy 323.552955 -102.571485) (xy 323.530379 -102.620994) (xy 323.500993 -102.666789) (xy 323.465392 -102.70794)
			(xy 323.424301 -102.743609) (xy 323.40169 -102.758748) (xy 323.393308 -102.764082) (xy 323.382132 -102.780338)
			(xy 323.363844 -102.859332) (xy 323.36204 -102.868962) (xy 323.365036 -102.888302) (xy 323.369686 -102.896924)
			(xy 323.36994 -102.896924) (xy 323.36994 -102.897432) (xy 323.383152 -102.919939) (xy 323.404005 -102.967783)
			(xy 323.418153 -103.018018) (xy 323.425335 -103.069712) (xy 323.42582 -103.095806) (xy 323.425295 -103.124545)
			(xy 323.416672 -103.181372) (xy 323.399622 -103.236262) (xy 323.374531 -103.287974) (xy 323.341966 -103.335337)
			(xy 323.322696 -103.356664) (xy 323.316092 -103.363522) (xy 323.30898 -103.381556) (xy 323.30898 -103.470456)
			(xy 323.316092 -103.48849) (xy 323.322696 -103.495348) (xy 323.341972 -103.51667) (xy 323.374535 -103.564034)
			(xy 323.399625 -103.615747) (xy 323.416674 -103.670638) (xy 323.425295 -103.727465) (xy 323.425295 -103.784943)
			(xy 323.416672 -103.841771) (xy 323.399622 -103.896662) (xy 323.374531 -103.948374) (xy 323.341966 -103.995737)
			(xy 323.322696 -104.017064) (xy 323.31707 -104.022906) (xy 328.065892 -104.022906) (xy 328.066366 -103.996592)
			(xy 328.0736 -103.944464) (xy 328.087918 -103.893822) (xy 328.109049 -103.845623) (xy 328.136594 -103.800779)
			(xy 328.170031 -103.760139) (xy 328.189082 -103.741982) (xy 328.196491 -103.734467) (xy 328.205012 -103.715182)
			(xy 328.205592 -103.704644) (xy 328.205592 -103.629968) (xy 328.205042 -103.619421) (xy 328.196522 -103.600125)
			(xy 328.189082 -103.59263) (xy 328.170045 -103.574456) (xy 328.136586 -103.53383) (xy 328.109025 -103.488994)
			(xy 328.087884 -103.440796) (xy 328.073563 -103.390152) (xy 328.066333 -103.338021) (xy 328.065892 -103.311706)
			(xy 328.066361 -103.284453) (xy 328.074117 -103.230503) (xy 328.089472 -103.178205) (xy 328.112114 -103.128625)
			(xy 328.141582 -103.082772) (xy 328.177275 -103.041579) (xy 328.218467 -103.005885) (xy 328.264319 -102.976417)
			(xy 328.313899 -102.953774) (xy 328.366197 -102.938418) (xy 328.420147 -102.930661) (xy 328.4474 -102.930198)
			(xy 328.475065 -102.930711) (xy 328.529814 -102.938711) (xy 328.582836 -102.954527) (xy 328.633019 -102.97783)
			(xy 328.679315 -103.008131) (xy 328.720753 -103.044796) (xy 328.756466 -103.087057) (xy 328.771504 -103.110284)
			(xy 328.77813 -103.11997) (xy 328.797999 -103.132408) (xy 328.809604 -103.13416) (xy 328.889614 -103.142034)
			(xy 328.901253 -103.142672) (xy 328.923091 -103.134588) (xy 328.931524 -103.12654) (xy 328.931778 -103.126286)
			(xy 328.949884 -103.107731) (xy 328.990211 -103.07515) (xy 329.03458 -103.048334) (xy 329.082173 -103.027777)
			(xy 329.132113 -103.013858) (xy 329.183478 -103.006834) (xy 329.2094 -103.006398) (xy 329.236653 -103.006855)
			(xy 329.290605 -103.014612) (xy 329.342903 -103.029969) (xy 329.392483 -103.052612) (xy 329.438337 -103.08208)
			(xy 329.47953 -103.117775) (xy 329.515223 -103.158968) (xy 329.544691 -103.204822) (xy 329.567333 -103.254403)
			(xy 329.582689 -103.306701) (xy 329.590445 -103.360653) (xy 329.590908 -103.387906) (xy 329.590443 -103.415276)
			(xy 329.582625 -103.469455) (xy 329.567135 -103.521958) (xy 329.544293 -103.571705) (xy 329.514569 -103.617672)
			(xy 329.496928 -103.638604) (xy 329.496674 -103.638858) (xy 329.491096 -103.64595) (xy 329.484845 -103.662863)
			(xy 329.484482 -103.671878) (xy 329.484482 -103.685654) (xy 340.692671 -103.685654) (xy 340.692671 -103.631146)
			(xy 340.700429 -103.577194) (xy 340.715787 -103.524895) (xy 340.738431 -103.475315) (xy 340.767901 -103.429462)
			(xy 340.803598 -103.38827) (xy 340.844794 -103.352577) (xy 340.89065 -103.323112) (xy 340.940233 -103.300473)
			(xy 340.992533 -103.285121) (xy 341.046486 -103.277369) (xy 341.07374 -103.276908) (xy 341.100055 -103.277346)
			(xy 341.152185 -103.284587) (xy 341.202828 -103.298911) (xy 341.251027 -103.320049) (xy 341.29587 -103.347601)
			(xy 341.336508 -103.381044) (xy 341.354664 -103.400098) (xy 341.362197 -103.407485) (xy 341.381469 -103.416018)
			(xy 341.392002 -103.416608) (xy 341.466678 -103.416608) (xy 341.477227 -103.416078) (xy 341.496523 -103.407543)
			(xy 341.504016 -103.400098) (xy 341.523836 -103.37931) (xy 341.568608 -103.343335) (xy 341.618266 -103.314475)
			(xy 341.671688 -103.293382) (xy 341.727667 -103.280533) (xy 341.78494 -103.276218) (xy 341.842213 -103.280533)
			(xy 341.898192 -103.293382) (xy 341.951614 -103.314475) (xy 342.001272 -103.343335) (xy 342.046044 -103.37931)
			(xy 342.065864 -103.400098) (xy 342.073397 -103.407485) (xy 342.092669 -103.416018) (xy 342.103202 -103.416608)
			(xy 342.177878 -103.416608) (xy 342.188427 -103.416078) (xy 342.207723 -103.407543) (xy 342.215216 -103.400098)
			(xy 342.23337 -103.381041) (xy 342.274 -103.347584) (xy 342.318841 -103.320026) (xy 342.367042 -103.298887)
			(xy 342.41769 -103.28457) (xy 342.469824 -103.277346) (xy 342.49614 -103.276908) (xy 342.523391 -103.277365)
			(xy 342.577336 -103.285126) (xy 342.629628 -103.300485) (xy 342.679203 -103.32313) (xy 342.72505 -103.352598)
			(xy 342.766237 -103.388291) (xy 342.801926 -103.429482) (xy 342.83139 -103.475333) (xy 342.854029 -103.524909)
			(xy 342.869383 -103.577203) (xy 342.877138 -103.631149) (xy 342.877138 -103.685651) (xy 342.869383 -103.739597)
			(xy 342.854029 -103.791891) (xy 342.83139 -103.841467) (xy 342.801926 -103.887318) (xy 342.766237 -103.928509)
			(xy 342.72505 -103.964202) (xy 342.679203 -103.99367) (xy 342.629628 -104.016315) (xy 342.577336 -104.031674)
			(xy 342.523391 -104.039435) (xy 342.49614 -104.039924) (xy 342.469825 -104.039489) (xy 342.417695 -104.032246)
			(xy 342.367052 -104.01792) (xy 342.318854 -103.996782) (xy 342.274011 -103.969231) (xy 342.233372 -103.935787)
			(xy 342.215216 -103.916734) (xy 342.207686 -103.909342) (xy 342.188413 -103.900811) (xy 342.177878 -103.900224)
			(xy 342.103202 -103.900224) (xy 342.09265 -103.900734) (xy 342.073354 -103.909282) (xy 342.065864 -103.916734)
			(xy 342.046044 -103.937522) (xy 342.001272 -103.973497) (xy 341.951614 -104.002357) (xy 341.898192 -104.02345)
			(xy 341.842213 -104.036299) (xy 341.78494 -104.040614) (xy 341.727667 -104.036299) (xy 341.671688 -104.02345)
			(xy 341.618266 -104.002357) (xy 341.568608 -103.973497) (xy 341.523836 -103.937522) (xy 341.504016 -103.916734)
			(xy 341.496486 -103.909342) (xy 341.477213 -103.900811) (xy 341.466678 -103.900224) (xy 341.392002 -103.900224)
			(xy 341.38145 -103.900734) (xy 341.362154 -103.909282) (xy 341.354664 -103.916734) (xy 341.336526 -103.935806)
			(xy 341.295891 -103.969261) (xy 341.251047 -103.996817) (xy 341.202843 -104.017952) (xy 341.152193 -104.032266)
			(xy 341.100057 -104.039487) (xy 341.07374 -104.039924) (xy 341.046486 -104.039431) (xy 340.992533 -104.031679)
			(xy 340.940233 -104.016327) (xy 340.89065 -103.993688) (xy 340.844794 -103.964223) (xy 340.803598 -103.92853)
			(xy 340.767901 -103.887338) (xy 340.738431 -103.841485) (xy 340.715787 -103.791905) (xy 340.700429 -103.739606)
			(xy 340.692671 -103.685654) (xy 329.484482 -103.685654) (xy 329.484482 -103.738934) (xy 329.484826 -103.747952)
			(xy 329.491083 -103.764869) (xy 329.496674 -103.771954) (xy 329.496928 -103.771954) (xy 329.496928 -103.772208)
			(xy 329.514589 -103.793123) (xy 329.544296 -103.839101) (xy 329.567128 -103.888853) (xy 329.582614 -103.941357)
			(xy 329.590437 -103.995536) (xy 329.590908 -104.022906) (xy 329.590428 -104.050157) (xy 329.58267 -104.104105)
			(xy 329.567315 -104.1564) (xy 329.544673 -104.205977) (xy 329.515206 -104.251828) (xy 329.479514 -104.293018)
			(xy 329.438323 -104.328709) (xy 329.392472 -104.358176) (xy 329.342895 -104.380817) (xy 329.290599 -104.396172)
			(xy 329.236651 -104.403928) (xy 329.2094 -104.404414) (xy 329.180481 -104.403928) (xy 329.123307 -104.395197)
			(xy 329.068106 -104.377935) (xy 329.016144 -104.352537) (xy 328.968611 -104.319586) (xy 328.926598 -104.279837)
			(xy 328.90841 -104.257348) (xy 328.900798 -104.248546) (xy 328.879901 -104.238362) (xy 328.868278 -104.23779)
			(xy 328.788522 -104.23779) (xy 328.776894 -104.23836) (xy 328.755985 -104.248527) (xy 328.74839 -104.257348)
			(xy 328.730217 -104.279846) (xy 328.688192 -104.319578) (xy 328.640653 -104.352514) (xy 328.588688 -104.3779)
			(xy 328.533488 -104.395153) (xy 328.476317 -104.40388) (xy 328.4474 -104.404414) (xy 328.420149 -104.403922)
			(xy 328.366202 -104.396166) (xy 328.313908 -104.380811) (xy 328.264331 -104.35817) (xy 328.218481 -104.328705)
			(xy 328.177291 -104.293014) (xy 328.141599 -104.251824) (xy 328.112133 -104.205975) (xy 328.089491 -104.156398)
			(xy 328.074135 -104.104104) (xy 328.066378 -104.050157) (xy 328.065892 -104.022906) (xy 323.31707 -104.022906)
			(xy 323.316092 -104.023922) (xy 323.30898 -104.041956) (xy 323.30898 -104.130856) (xy 323.316092 -104.14889)
			(xy 323.322696 -104.155748) (xy 323.341972 -104.17707) (xy 323.374535 -104.224434) (xy 323.399625 -104.276147)
			(xy 323.416674 -104.331038) (xy 323.425295 -104.387865) (xy 323.425295 -104.445343) (xy 323.416672 -104.502171)
			(xy 323.399622 -104.557062) (xy 323.374531 -104.608774) (xy 323.341966 -104.656137) (xy 323.322696 -104.677464)
			(xy 323.316092 -104.684322) (xy 323.30898 -104.702356) (xy 323.30898 -104.791256) (xy 323.316092 -104.80929)
			(xy 323.322696 -104.816148) (xy 323.341972 -104.83747) (xy 323.374535 -104.884834) (xy 323.399625 -104.936547)
			(xy 323.416674 -104.991438) (xy 323.425295 -105.048265) (xy 323.425295 -105.08445) (xy 327.943972 -105.08445)
			(xy 327.943972 -105.02995) (xy 327.951728 -104.976003) (xy 327.967082 -104.92371) (xy 327.989721 -104.874134)
			(xy 328.019185 -104.828284) (xy 328.054874 -104.787094) (xy 328.096062 -104.751402) (xy 328.141909 -104.721934)
			(xy 328.191484 -104.699291) (xy 328.243776 -104.683934) (xy 328.297722 -104.676174) (xy 328.324972 -104.675686)
			(xy 328.352341 -104.676172) (xy 328.40652 -104.683985) (xy 328.459022 -104.69947) (xy 328.50877 -104.722307)
			(xy 328.554737 -104.752027) (xy 328.57567 -104.769666) (xy 328.575924 -104.76992) (xy 328.582998 -104.775525)
			(xy 328.599924 -104.78176) (xy 328.608944 -104.782112) (xy 328.676 -104.782112) (xy 328.685017 -104.781752)
			(xy 328.701933 -104.775506) (xy 328.70902 -104.76992) (xy 328.70902 -104.769666) (xy 328.709274 -104.769666)
			(xy 328.730207 -104.752025) (xy 328.776175 -104.722301) (xy 328.825921 -104.699455) (xy 328.878423 -104.683959)
			(xy 328.932601 -104.67613) (xy 328.987343 -104.67613) (xy 329.041521 -104.683959) (xy 329.094023 -104.699455)
			(xy 329.143769 -104.722301) (xy 329.189737 -104.752025) (xy 329.21067 -104.769666) (xy 329.210924 -104.76992)
			(xy 329.217998 -104.775525) (xy 329.234924 -104.78176) (xy 329.243944 -104.782112) (xy 329.311 -104.782112)
			(xy 329.320017 -104.781752) (xy 329.336933 -104.775506) (xy 329.34402 -104.76992) (xy 329.34402 -104.769666)
			(xy 329.344274 -104.769666) (xy 329.365207 -104.752025) (xy 329.411175 -104.722301) (xy 329.460921 -104.699455)
			(xy 329.513423 -104.683959) (xy 329.567601 -104.67613) (xy 329.622343 -104.67613) (xy 329.676521 -104.683959)
			(xy 329.729023 -104.699455) (xy 329.778769 -104.722301) (xy 329.824737 -104.752025) (xy 329.84567 -104.769666)
			(xy 329.845924 -104.76992) (xy 329.852998 -104.775525) (xy 329.869924 -104.78176) (xy 329.878944 -104.782112)
			(xy 329.946 -104.782112) (xy 329.955017 -104.781752) (xy 329.971933 -104.775506) (xy 329.97902 -104.76992)
			(xy 329.97902 -104.769666) (xy 329.979274 -104.769666) (xy 330.000201 -104.75202) (xy 330.046176 -104.722311)
			(xy 330.095924 -104.699477) (xy 330.148426 -104.683987) (xy 330.202603 -104.67616) (xy 330.229972 -104.675686)
			(xy 330.257226 -104.676159) (xy 330.311179 -104.683913) (xy 330.363479 -104.699266) (xy 330.413062 -104.721907)
			(xy 330.458918 -104.751374) (xy 330.500113 -104.787067) (xy 330.535809 -104.82826) (xy 330.56528 -104.874113)
			(xy 330.587924 -104.923695) (xy 330.603281 -104.975994) (xy 330.611039 -105.029946) (xy 330.611039 -105.084454)
			(xy 330.603281 -105.138406) (xy 330.587924 -105.190705) (xy 330.56528 -105.240287) (xy 330.535809 -105.28614)
			(xy 330.500113 -105.327333) (xy 330.458918 -105.363026) (xy 330.413062 -105.392493) (xy 330.363479 -105.415134)
			(xy 330.311179 -105.430487) (xy 330.257226 -105.438241) (xy 330.229972 -105.438702) (xy 330.202601 -105.438252)
			(xy 330.148421 -105.43043) (xy 330.095918 -105.414937) (xy 330.046172 -105.392092) (xy 330.000205 -105.362365)
			(xy 329.979274 -105.344722) (xy 329.97902 -105.344468) (xy 329.971935 -105.33888) (xy 329.955017 -105.332635)
			(xy 329.946 -105.332276) (xy 329.878944 -105.332276) (xy 329.86993 -105.332659) (xy 329.853013 -105.338889)
			(xy 329.845924 -105.344468) (xy 329.84567 -105.344722) (xy 329.824737 -105.362363) (xy 329.778769 -105.392087)
			(xy 329.729023 -105.414933) (xy 329.676521 -105.430429) (xy 329.622343 -105.438258) (xy 329.567601 -105.438258)
			(xy 329.513423 -105.430429) (xy 329.460921 -105.414933) (xy 329.411175 -105.392087) (xy 329.365207 -105.362363)
			(xy 329.344274 -105.344722) (xy 329.34402 -105.344468) (xy 329.336935 -105.33888) (xy 329.320017 -105.332635)
			(xy 329.311 -105.332276) (xy 329.243944 -105.332276) (xy 329.23493 -105.332659) (xy 329.218013 -105.338889)
			(xy 329.210924 -105.344468) (xy 329.210924 -105.344722) (xy 329.21067 -105.344722) (xy 329.189737 -105.362363)
			(xy 329.143769 -105.392087) (xy 329.094023 -105.414933) (xy 329.041521 -105.430429) (xy 328.987343 -105.438258)
			(xy 328.932601 -105.438258) (xy 328.878423 -105.430429) (xy 328.825921 -105.414933) (xy 328.776175 -105.392087)
			(xy 328.730207 -105.362363) (xy 328.709274 -105.344722) (xy 328.70902 -105.344468) (xy 328.701935 -105.33888)
			(xy 328.685017 -105.332635) (xy 328.676 -105.332276) (xy 328.608944 -105.332276) (xy 328.59993 -105.332659)
			(xy 328.583013 -105.338889) (xy 328.575924 -105.344468) (xy 328.575924 -105.344722) (xy 328.57567 -105.344722)
			(xy 328.554725 -105.362345) (xy 328.508756 -105.392059) (xy 328.459011 -105.414897) (xy 328.406514 -105.430392)
			(xy 328.35234 -105.438225) (xy 328.324972 -105.438702) (xy 328.297722 -105.438226) (xy 328.243776 -105.430466)
			(xy 328.191484 -105.415109) (xy 328.141909 -105.392466) (xy 328.096062 -105.362998) (xy 328.054874 -105.327306)
			(xy 328.019185 -105.286116) (xy 327.989721 -105.240266) (xy 327.967082 -105.19069) (xy 327.951728 -105.138397)
			(xy 327.943972 -105.08445) (xy 323.425295 -105.08445) (xy 323.425295 -105.105743) (xy 323.416672 -105.162571)
			(xy 323.399622 -105.217462) (xy 323.374531 -105.269174) (xy 323.341966 -105.316537) (xy 323.322696 -105.337864)
			(xy 323.316092 -105.344722) (xy 323.30898 -105.362756) (xy 323.30898 -105.451656) (xy 323.316092 -105.46969)
			(xy 323.322696 -105.476548) (xy 323.341972 -105.49787) (xy 323.374535 -105.545234) (xy 323.399625 -105.596947)
			(xy 323.416674 -105.651838) (xy 323.425295 -105.708665) (xy 323.425295 -105.766143) (xy 323.416672 -105.822971)
			(xy 323.399622 -105.877862) (xy 323.374531 -105.929574) (xy 323.341966 -105.976937) (xy 323.322696 -105.998264)
			(xy 323.316092 -106.005122) (xy 323.30898 -106.023156) (xy 323.30898 -106.112056) (xy 323.316092 -106.13009)
			(xy 323.322696 -106.136948) (xy 323.341972 -106.15827) (xy 323.374535 -106.205634) (xy 323.399625 -106.257347)
			(xy 323.416674 -106.312238) (xy 323.425295 -106.369065) (xy 323.425295 -106.426543) (xy 323.416672 -106.483371)
			(xy 323.399622 -106.538262) (xy 323.374531 -106.589974) (xy 323.341966 -106.637337) (xy 323.322696 -106.658664)
			(xy 323.316092 -106.665522) (xy 323.30898 -106.683556) (xy 323.30898 -106.772456) (xy 323.316092 -106.79049)
			(xy 323.322696 -106.797348) (xy 323.327305 -106.802446) (xy 340.620928 -106.802446) (xy 340.620928 -106.747954)
			(xy 340.628682 -106.694017) (xy 340.644033 -106.641733) (xy 340.666668 -106.592165) (xy 340.696127 -106.546323)
			(xy 340.731809 -106.505139) (xy 340.772989 -106.469452) (xy 340.818828 -106.439989) (xy 340.868393 -106.417348)
			(xy 340.920676 -106.401991) (xy 340.974612 -106.394231) (xy 341.001858 -106.393742) (xy 341.028174 -106.394157)
			(xy 341.080305 -106.401401) (xy 341.130949 -106.415729) (xy 341.179149 -106.436871) (xy 341.223991 -106.464427)
			(xy 341.264627 -106.497876) (xy 341.282782 -106.516932) (xy 341.290317 -106.524318) (xy 341.309587 -106.532854)
			(xy 341.32012 -106.533442) (xy 341.394796 -106.533442) (xy 341.405345 -106.532912) (xy 341.42464 -106.524376)
			(xy 341.432134 -106.516932) (xy 341.451954 -106.496144) (xy 341.496726 -106.460169) (xy 341.546384 -106.431309)
			(xy 341.599806 -106.410216) (xy 341.655785 -106.397367) (xy 341.713058 -106.393052) (xy 341.770331 -106.397367)
			(xy 341.82631 -106.410216) (xy 341.879732 -106.431309) (xy 341.92939 -106.460169) (xy 341.974162 -106.496144)
			(xy 341.993982 -106.516932) (xy 342.001517 -106.524318) (xy 342.020787 -106.532854) (xy 342.03132 -106.533442)
			(xy 342.105996 -106.533442) (xy 342.116545 -106.532912) (xy 342.13584 -106.524376) (xy 342.143334 -106.516932)
			(xy 342.161486 -106.497873) (xy 342.202116 -106.464415) (xy 342.246957 -106.436856) (xy 342.295158 -106.415718)
			(xy 342.345807 -106.401402) (xy 342.397942 -106.394179) (xy 342.424258 -106.393742) (xy 342.451516 -106.394102)
			(xy 342.505479 -106.401855) (xy 342.557789 -106.41721) (xy 342.607381 -106.439853) (xy 342.653245 -106.469324)
			(xy 342.694448 -106.505022) (xy 342.730151 -106.546221) (xy 342.759627 -106.592082) (xy 342.782276 -106.641672)
			(xy 342.797636 -106.69398) (xy 342.805395 -106.747942) (xy 342.805395 -106.802458) (xy 342.797636 -106.85642)
			(xy 342.782276 -106.908728) (xy 342.759627 -106.958318) (xy 342.730151 -107.004179) (xy 342.694448 -107.045378)
			(xy 342.653245 -107.081076) (xy 342.607381 -107.110547) (xy 342.557789 -107.13319) (xy 342.505479 -107.148545)
			(xy 342.451516 -107.156298) (xy 342.424258 -107.156758) (xy 342.397942 -107.156332) (xy 342.345812 -107.149091)
			(xy 342.295168 -107.134764) (xy 342.246968 -107.113624) (xy 342.202126 -107.08607) (xy 342.161489 -107.052623)
			(xy 342.143334 -107.033568) (xy 342.135793 -107.026189) (xy 342.116528 -107.017649) (xy 342.105996 -107.017058)
			(xy 342.03132 -107.017058) (xy 342.020772 -107.017597) (xy 342.001477 -107.026127) (xy 341.993982 -107.033568)
			(xy 341.974162 -107.054356) (xy 341.92939 -107.090331) (xy 341.879732 -107.119191) (xy 341.82631 -107.140284)
			(xy 341.770331 -107.153133) (xy 341.713058 -107.157448) (xy 341.655785 -107.153133) (xy 341.599806 -107.140284)
			(xy 341.546384 -107.119191) (xy 341.496726 -107.090331) (xy 341.451954 -107.054356) (xy 341.432134 -107.033568)
			(xy 341.424593 -107.026189) (xy 341.405328 -107.017649) (xy 341.394796 -107.017058) (xy 341.32012 -107.017058)
			(xy 341.309572 -107.017597) (xy 341.290277 -107.026127) (xy 341.282782 -107.033568) (xy 341.264622 -107.052619)
			(xy 341.223994 -107.086078) (xy 341.179155 -107.113638) (xy 341.130955 -107.134778) (xy 341.080308 -107.149095)
			(xy 341.028174 -107.15632) (xy 341.001858 -107.156758) (xy 340.974612 -107.156169) (xy 340.920676 -107.148409)
			(xy 340.868393 -107.133052) (xy 340.818828 -107.110411) (xy 340.772989 -107.080948) (xy 340.731809 -107.045261)
			(xy 340.696127 -107.004077) (xy 340.666668 -106.958235) (xy 340.644033 -106.908667) (xy 340.628682 -106.856383)
			(xy 340.620928 -106.802446) (xy 323.327305 -106.802446) (xy 323.341972 -106.81867) (xy 323.374535 -106.866034)
			(xy 323.399625 -106.917747) (xy 323.416674 -106.972638) (xy 323.425295 -107.029465) (xy 323.425295 -107.086943)
			(xy 323.416672 -107.143771) (xy 323.399622 -107.198662) (xy 323.374531 -107.250374) (xy 323.341966 -107.297737)
			(xy 323.322696 -107.319064) (xy 323.316092 -107.325922) (xy 323.30898 -107.343956) (xy 323.30898 -107.432856)
			(xy 323.316092 -107.45089) (xy 323.322696 -107.457748) (xy 323.341972 -107.47907) (xy 323.374535 -107.526434)
			(xy 323.399625 -107.578147) (xy 323.416674 -107.633038) (xy 323.425295 -107.689865) (xy 323.425295 -107.740249)
			(xy 327.884296 -107.740249) (xy 327.884296 -107.685751) (xy 327.892052 -107.631807) (xy 327.907405 -107.579517)
			(xy 327.930044 -107.529943) (xy 327.959507 -107.484096) (xy 327.995195 -107.442908) (xy 328.036381 -107.407218)
			(xy 328.082227 -107.377753) (xy 328.1318 -107.355112) (xy 328.18409 -107.339756) (xy 328.238033 -107.331997)
			(xy 328.265282 -107.33151) (xy 328.292652 -107.331984) (xy 328.346831 -107.3398) (xy 328.399334 -107.355287)
			(xy 328.449081 -107.378127) (xy 328.495048 -107.40785) (xy 328.51598 -107.42549) (xy 328.516234 -107.425744)
			(xy 328.523331 -107.431314) (xy 328.54024 -107.43757) (xy 328.549254 -107.437936) (xy 328.61631 -107.437936)
			(xy 328.625326 -107.437576) (xy 328.642243 -107.43133) (xy 328.64933 -107.425744) (xy 328.64933 -107.42549)
			(xy 328.649584 -107.42549) (xy 328.670517 -107.407849) (xy 328.716485 -107.378125) (xy 328.766231 -107.355279)
			(xy 328.818733 -107.339783) (xy 328.872911 -107.331954) (xy 328.927653 -107.331954) (xy 328.981831 -107.339783)
			(xy 329.034333 -107.355279) (xy 329.084079 -107.378125) (xy 329.130047 -107.407849) (xy 329.15098 -107.42549)
			(xy 329.151234 -107.425744) (xy 329.158331 -107.431314) (xy 329.17524 -107.43757) (xy 329.184254 -107.437936)
			(xy 329.25131 -107.437936) (xy 329.260326 -107.437576) (xy 329.277243 -107.43133) (xy 329.28433 -107.425744)
			(xy 329.28433 -107.42549) (xy 329.284584 -107.42549) (xy 329.305517 -107.407849) (xy 329.351485 -107.378125)
			(xy 329.401231 -107.355279) (xy 329.453733 -107.339783) (xy 329.507911 -107.331954) (xy 329.562653 -107.331954)
			(xy 329.616831 -107.339783) (xy 329.669333 -107.355279) (xy 329.719079 -107.378125) (xy 329.765047 -107.407849)
			(xy 329.78598 -107.42549) (xy 329.786234 -107.425744) (xy 329.793331 -107.431314) (xy 329.81024 -107.43757)
			(xy 329.819254 -107.437936) (xy 329.88631 -107.437936) (xy 329.895326 -107.437576) (xy 329.912243 -107.43133)
			(xy 329.91933 -107.425744) (xy 329.91933 -107.42549) (xy 329.919584 -107.42549) (xy 329.94051 -107.407843)
			(xy 329.986485 -107.378133) (xy 330.036234 -107.355299) (xy 330.088736 -107.339809) (xy 330.142912 -107.331983)
			(xy 330.170282 -107.33151) (xy 330.197537 -107.331936) (xy 330.251492 -107.339691) (xy 330.303795 -107.355046)
			(xy 330.35338 -107.377689) (xy 330.399237 -107.407158) (xy 330.440434 -107.442853) (xy 330.476132 -107.484048)
			(xy 330.505603 -107.529904) (xy 330.528248 -107.579488) (xy 330.543605 -107.63179) (xy 330.551363 -107.685745)
			(xy 330.551363 -107.740255) (xy 330.543605 -107.79421) (xy 330.528248 -107.846512) (xy 330.505603 -107.896096)
			(xy 330.476132 -107.941952) (xy 330.440434 -107.983147) (xy 330.399237 -108.018842) (xy 330.35338 -108.048311)
			(xy 330.303795 -108.070954) (xy 330.251492 -108.086309) (xy 330.197537 -108.094064) (xy 330.170282 -108.094526)
			(xy 330.142911 -108.094089) (xy 330.088729 -108.086267) (xy 330.036225 -108.070772) (xy 329.986479 -108.047923)
			(xy 329.940514 -108.018191) (xy 329.919584 -108.000546) (xy 329.91933 -108.000292) (xy 329.91224 -107.994711)
			(xy 329.895326 -107.988461) (xy 329.88631 -107.9881) (xy 329.819254 -107.9881) (xy 329.81024 -107.988483)
			(xy 329.793323 -107.994713) (xy 329.786234 -108.000292) (xy 329.78598 -108.000546) (xy 329.765047 -108.018187)
			(xy 329.719079 -108.047911) (xy 329.669333 -108.070757) (xy 329.616831 -108.086253) (xy 329.562653 -108.094082)
			(xy 329.507911 -108.094082) (xy 329.453733 -108.086253) (xy 329.401231 -108.070757) (xy 329.351485 -108.047911)
			(xy 329.305517 -108.018187) (xy 329.284584 -108.000546) (xy 329.28433 -108.000292) (xy 329.27724 -107.994711)
			(xy 329.260326 -107.988461) (xy 329.25131 -107.9881) (xy 329.184254 -107.9881) (xy 329.17524 -107.988483)
			(xy 329.158323 -107.994713) (xy 329.151234 -108.000292) (xy 329.151234 -108.000546) (xy 329.15098 -108.000546)
			(xy 329.130047 -108.018187) (xy 329.084079 -108.047911) (xy 329.034333 -108.070757) (xy 328.981831 -108.086253)
			(xy 328.927653 -108.094082) (xy 328.872911 -108.094082) (xy 328.818733 -108.086253) (xy 328.766231 -108.070757)
			(xy 328.716485 -108.047911) (xy 328.670517 -108.018187) (xy 328.649584 -108.000546) (xy 328.64933 -108.000292)
			(xy 328.64224 -107.994711) (xy 328.625326 -107.988461) (xy 328.61631 -107.9881) (xy 328.549254 -107.9881)
			(xy 328.54024 -107.988483) (xy 328.523323 -107.994713) (xy 328.516234 -108.000292) (xy 328.516234 -108.000546)
			(xy 328.51598 -108.000546) (xy 328.495022 -108.018153) (xy 328.449057 -108.047871) (xy 328.399316 -108.070714)
			(xy 328.346821 -108.086213) (xy 328.29265 -108.094048) (xy 328.265282 -108.094526) (xy 328.238033 -108.094003)
			(xy 328.18409 -108.086244) (xy 328.1318 -108.070888) (xy 328.082227 -108.048247) (xy 328.036381 -108.018782)
			(xy 327.995195 -107.983092) (xy 327.959507 -107.941904) (xy 327.930044 -107.896057) (xy 327.907405 -107.846483)
			(xy 327.892052 -107.794193) (xy 327.884296 -107.740249) (xy 323.425295 -107.740249) (xy 323.425295 -107.747343)
			(xy 323.416672 -107.804171) (xy 323.399622 -107.859062) (xy 323.374531 -107.910774) (xy 323.341966 -107.958137)
			(xy 323.322696 -107.979464) (xy 323.316092 -107.986322) (xy 323.30898 -108.004356) (xy 323.30898 -108.093256)
			(xy 323.316092 -108.11129) (xy 323.322696 -108.118148) (xy 323.341958 -108.139483) (xy 323.374528 -108.186841)
			(xy 323.399623 -108.238551) (xy 323.416676 -108.293441) (xy 323.425299 -108.350267) (xy 323.42582 -108.379006)
			(xy 323.425334 -108.406257) (xy 323.417578 -108.460205) (xy 323.402223 -108.5125) (xy 323.379581 -108.562077)
			(xy 323.374807 -108.569506) (xy 339.061044 -108.569506) (xy 339.061503 -108.542135) (xy 339.069321 -108.487956)
			(xy 339.084811 -108.435452) (xy 339.107655 -108.385705) (xy 339.137381 -108.339739) (xy 339.155024 -108.318808)
			(xy 339.155278 -108.318554) (xy 339.160857 -108.311463) (xy 339.167106 -108.294549) (xy 339.16747 -108.285534)
			(xy 339.16747 -108.218478) (xy 339.16713 -108.209459) (xy 339.160871 -108.192542) (xy 339.155278 -108.185458)
			(xy 339.155024 -108.185458) (xy 339.155024 -108.185204) (xy 339.137377 -108.164278) (xy 339.107666 -108.118304)
			(xy 339.084831 -108.068555) (xy 339.069342 -108.016053) (xy 339.061516 -107.961876) (xy 339.061044 -107.934506)
			(xy 339.06153 -107.907255) (xy 339.069286 -107.853307) (xy 339.084641 -107.801012) (xy 339.107283 -107.751435)
			(xy 339.136749 -107.705585) (xy 339.17244 -107.664394) (xy 339.213631 -107.628703) (xy 339.259481 -107.599237)
			(xy 339.309058 -107.576595) (xy 339.361353 -107.56124) (xy 339.415301 -107.553484) (xy 339.469803 -107.553484)
			(xy 339.523751 -107.56124) (xy 339.576046 -107.576595) (xy 339.625623 -107.599237) (xy 339.671473 -107.628703)
			(xy 339.712664 -107.664394) (xy 339.748355 -107.705585) (xy 339.777821 -107.751435) (xy 339.800463 -107.801012)
			(xy 339.815818 -107.853307) (xy 339.823574 -107.907255) (xy 339.82406 -107.934506) (xy 339.823607 -107.961877)
			(xy 339.815788 -108.016057) (xy 339.800296 -108.068561) (xy 339.777451 -108.118307) (xy 339.747723 -108.164273)
			(xy 339.73008 -108.185204) (xy 339.729826 -108.185458) (xy 339.724242 -108.192546) (xy 339.717996 -108.209462)
			(xy 339.717634 -108.218478) (xy 339.717634 -108.285534) (xy 339.717967 -108.294553) (xy 339.724231 -108.311471)
			(xy 339.729826 -108.318554) (xy 339.73008 -108.318554) (xy 339.73008 -108.318808) (xy 339.747733 -108.339729)
			(xy 339.777444 -108.385704) (xy 339.800277 -108.435455) (xy 339.815765 -108.487958) (xy 339.823589 -108.542136)
			(xy 339.82406 -108.569506) (xy 339.823574 -108.596757) (xy 339.815818 -108.650705) (xy 339.800463 -108.703)
			(xy 339.777821 -108.752577) (xy 339.748355 -108.798427) (xy 339.712664 -108.839618) (xy 339.671473 -108.875309)
			(xy 339.625623 -108.904775) (xy 339.576046 -108.927417) (xy 339.523751 -108.942772) (xy 339.469803 -108.950528)
			(xy 339.415301 -108.950528) (xy 339.361353 -108.942772) (xy 339.309058 -108.927417) (xy 339.259481 -108.904775)
			(xy 339.213631 -108.875309) (xy 339.17244 -108.839618) (xy 339.136749 -108.798427) (xy 339.107283 -108.752577)
			(xy 339.084641 -108.703) (xy 339.069286 -108.650705) (xy 339.06153 -108.596757) (xy 339.061044 -108.569506)
			(xy 323.374807 -108.569506) (xy 323.350115 -108.607927) (xy 323.314424 -108.649118) (xy 323.273233 -108.684809)
			(xy 323.227383 -108.714275) (xy 323.177806 -108.736917) (xy 323.125511 -108.752272) (xy 323.071563 -108.760028)
			(xy 323.017061 -108.760028) (xy 322.963113 -108.752272) (xy 322.910818 -108.736917) (xy 322.861241 -108.714275)
			(xy 322.815391 -108.684809) (xy 322.7742 -108.649118) (xy 322.738509 -108.607927) (xy 322.709043 -108.562077)
			(xy 322.686401 -108.5125) (xy 322.671046 -108.460205) (xy 322.66329 -108.406257) (xy 322.662804 -108.379006)
			(xy 319.690496 -108.379006) (xy 319.690496 -109.502448) (xy 341.614504 -109.502448) (xy 341.618575 -109.446826)
			(xy 341.630701 -109.392389) (xy 341.650624 -109.340298) (xy 341.67792 -109.291663) (xy 341.712006 -109.24752)
			(xy 341.752155 -109.208811) (xy 341.797513 -109.17636) (xy 341.847113 -109.150859) (xy 341.899897 -109.132852)
			(xy 341.95474 -109.122722) (xy 342.010474 -109.120685) (xy 342.065911 -109.126785) (xy 342.119868 -109.140891)
			(xy 342.171197 -109.162703) (xy 342.218803 -109.191757) (xy 342.261671 -109.227432) (xy 342.298888 -109.268969)
			(xy 342.329661 -109.315482) (xy 342.353333 -109.365979) (xy 342.369401 -109.419386) (xy 342.377521 -109.474562)
			(xy 342.37803 -109.502448) (xy 342.377521 -109.530334) (xy 342.369401 -109.58551) (xy 342.353333 -109.638917)
			(xy 342.329661 -109.689414) (xy 342.298888 -109.735927) (xy 342.261671 -109.777464) (xy 342.218803 -109.813139)
			(xy 342.171197 -109.842193) (xy 342.119868 -109.864005) (xy 342.065911 -109.878111) (xy 342.010474 -109.884211)
			(xy 341.95474 -109.882174) (xy 341.899897 -109.872044) (xy 341.847113 -109.854037) (xy 341.797513 -109.828536)
			(xy 341.752155 -109.796085) (xy 341.712006 -109.757376) (xy 341.67792 -109.713233) (xy 341.650624 -109.664598)
			(xy 341.630701 -109.612507) (xy 341.618575 -109.55807) (xy 341.614504 -109.502448) (xy 319.690496 -109.502448)
			(xy 319.690496 -110.621572) (xy 322.761102 -110.621572) (xy 322.76155 -110.595257) (xy 322.768789 -110.543128)
			(xy 322.783112 -110.492485) (xy 322.804248 -110.444286) (xy 322.831797 -110.399443) (xy 322.865239 -110.358804)
			(xy 322.884292 -110.340648) (xy 322.891717 -110.333147) (xy 322.900228 -110.313851) (xy 322.900802 -110.30331)
			(xy 322.900802 -110.228634) (xy 322.900267 -110.218085) (xy 322.891736 -110.19879) (xy 322.884292 -110.191296)
			(xy 322.86524 -110.173137) (xy 322.831783 -110.132508) (xy 322.804224 -110.087668) (xy 322.783085 -110.039468)
			(xy 322.768767 -109.988821) (xy 322.761541 -109.936688) (xy 322.761102 -109.910372) (xy 322.761588 -109.883121)
			(xy 322.769344 -109.829173) (xy 322.784699 -109.776878) (xy 322.807341 -109.727301) (xy 322.836807 -109.681451)
			(xy 322.872498 -109.64026) (xy 322.913689 -109.604569) (xy 322.959539 -109.575103) (xy 323.009116 -109.552461)
			(xy 323.061411 -109.537106) (xy 323.115359 -109.52935) (xy 323.169861 -109.52935) (xy 323.223809 -109.537106)
			(xy 323.276104 -109.552461) (xy 323.325681 -109.575103) (xy 323.371531 -109.604569) (xy 323.412722 -109.64026)
			(xy 323.448413 -109.681451) (xy 323.477879 -109.727301) (xy 323.500521 -109.776878) (xy 323.515876 -109.829173)
			(xy 323.523632 -109.883121) (xy 323.524118 -109.910372) (xy 323.523693 -109.936687) (xy 323.516449 -109.988817)
			(xy 323.502121 -110.039461) (xy 323.48098 -110.087659) (xy 323.453427 -110.132502) (xy 323.419982 -110.17314)
			(xy 323.400928 -110.191296) (xy 323.39353 -110.198821) (xy 323.385003 -110.218098) (xy 323.384418 -110.228634)
			(xy 323.384418 -110.30331) (xy 323.384923 -110.313863) (xy 323.393475 -110.333158) (xy 323.400928 -110.340648)
			(xy 323.420005 -110.358782) (xy 323.453459 -110.399417) (xy 323.481015 -110.444262) (xy 323.502149 -110.492467)
			(xy 323.516462 -110.543118) (xy 323.523682 -110.595255) (xy 323.524118 -110.621572) (xy 323.523632 -110.648823)
			(xy 323.515876 -110.702771) (xy 323.500521 -110.755066) (xy 323.477879 -110.804643) (xy 323.448413 -110.850493)
			(xy 323.412722 -110.891684) (xy 323.371531 -110.927375) (xy 323.325681 -110.956841) (xy 323.276104 -110.979483)
			(xy 323.223809 -110.994838) (xy 323.169861 -111.002594) (xy 323.115359 -111.002594) (xy 323.061411 -110.994838)
			(xy 323.009116 -110.979483) (xy 322.959539 -110.956841) (xy 322.913689 -110.927375) (xy 322.872498 -110.891684)
			(xy 322.836807 -110.850493) (xy 322.807341 -110.804643) (xy 322.784699 -110.755066) (xy 322.769344 -110.702771)
			(xy 322.761588 -110.648823) (xy 322.761102 -110.621572) (xy 319.690496 -110.621572) (xy 319.690496 -112.297972)
			(xy 325.26986 -112.297972) (xy 325.27029 -112.271657) (xy 325.277529 -112.219526) (xy 325.291855 -112.168881)
			(xy 325.312994 -112.120682) (xy 325.340548 -112.07584) (xy 325.373994 -112.035203) (xy 325.39305 -112.017048)
			(xy 325.400469 -112.009541) (xy 325.408985 -111.99025) (xy 325.40956 -111.97971) (xy 325.40956 -111.905034)
			(xy 325.409038 -111.894483) (xy 325.400499 -111.875187) (xy 325.39305 -111.867696) (xy 325.37399 -111.849545)
			(xy 325.340535 -111.808913) (xy 325.312978 -111.764072) (xy 325.291841 -111.71587) (xy 325.277524 -111.665222)
			(xy 325.270299 -111.613088) (xy 325.26986 -111.586772) (xy 325.270346 -111.559521) (xy 325.278102 -111.505573)
			(xy 325.293457 -111.453278) (xy 325.316099 -111.403701) (xy 325.345565 -111.357851) (xy 325.381256 -111.31666)
			(xy 325.422447 -111.280969) (xy 325.468297 -111.251503) (xy 325.517874 -111.228861) (xy 325.570169 -111.213506)
			(xy 325.624117 -111.20575) (xy 325.678619 -111.20575) (xy 325.732567 -111.213506) (xy 325.784862 -111.228861)
			(xy 325.834439 -111.251503) (xy 325.880289 -111.280969) (xy 325.92148 -111.31666) (xy 325.957171 -111.357851)
			(xy 325.986637 -111.403701) (xy 326.009279 -111.453278) (xy 326.024634 -111.505573) (xy 326.03239 -111.559521)
			(xy 326.032876 -111.586772) (xy 326.032464 -111.613088) (xy 326.025219 -111.665219) (xy 326.01089 -111.715863)
			(xy 325.989747 -111.764062) (xy 325.962191 -111.808904) (xy 325.928742 -111.849541) (xy 325.909686 -111.867696)
			(xy 325.902282 -111.875215) (xy 325.893759 -111.894497) (xy 325.893176 -111.905034) (xy 325.893176 -111.97971)
			(xy 325.893693 -111.990261) (xy 325.902238 -112.009556) (xy 325.909686 -112.017048) (xy 325.928755 -112.03519)
			(xy 325.962212 -112.075822) (xy 325.989769 -112.120665) (xy 326.010905 -112.168869) (xy 326.025219 -112.219519)
			(xy 326.03244 -112.271655) (xy 326.032876 -112.297972) (xy 327.30186 -112.297972) (xy 327.30229 -112.271657)
			(xy 327.309529 -112.219526) (xy 327.323855 -112.168881) (xy 327.344994 -112.120682) (xy 327.372548 -112.07584)
			(xy 327.405994 -112.035203) (xy 327.42505 -112.017048) (xy 327.432469 -112.009541) (xy 327.440985 -111.99025)
			(xy 327.44156 -111.97971) (xy 327.44156 -111.905034) (xy 327.441038 -111.894483) (xy 327.432499 -111.875187)
			(xy 327.42505 -111.867696) (xy 327.40599 -111.849545) (xy 327.372535 -111.808913) (xy 327.344978 -111.764072)
			(xy 327.323841 -111.71587) (xy 327.309524 -111.665222) (xy 327.302299 -111.613088) (xy 327.30186 -111.586772)
			(xy 327.302346 -111.559521) (xy 327.310102 -111.505573) (xy 327.325457 -111.453278) (xy 327.348099 -111.403701)
			(xy 327.377565 -111.357851) (xy 327.413256 -111.31666) (xy 327.454447 -111.280969) (xy 327.500297 -111.251503)
			(xy 327.549874 -111.228861) (xy 327.602169 -111.213506) (xy 327.656117 -111.20575) (xy 327.710619 -111.20575)
			(xy 327.764567 -111.213506) (xy 327.816862 -111.228861) (xy 327.866439 -111.251503) (xy 327.912289 -111.280969)
			(xy 327.95348 -111.31666) (xy 327.989171 -111.357851) (xy 328.018637 -111.403701) (xy 328.041279 -111.453278)
			(xy 328.056634 -111.505573) (xy 328.06439 -111.559521) (xy 328.064876 -111.586772) (xy 328.064464 -111.613088)
			(xy 328.057219 -111.665219) (xy 328.04289 -111.715863) (xy 328.021747 -111.764062) (xy 327.994191 -111.808904)
			(xy 327.960742 -111.849541) (xy 327.941686 -111.867696) (xy 327.934282 -111.875215) (xy 327.925759 -111.894497)
			(xy 327.925176 -111.905034) (xy 327.925176 -111.97971) (xy 327.925693 -111.990261) (xy 327.934238 -112.009556)
			(xy 327.941686 -112.017048) (xy 327.960755 -112.03519) (xy 327.962752 -112.037615) (xy 329.756103 -112.037615)
			(xy 329.760416 -111.980345) (xy 329.773262 -111.924368) (xy 329.79435 -111.870948) (xy 329.823205 -111.821291)
			(xy 329.859175 -111.776519) (xy 329.87996 -111.756698) (xy 329.887358 -111.749174) (xy 329.895886 -111.729896)
			(xy 329.89647 -111.71936) (xy 329.89647 -111.644684) (xy 329.895972 -111.63413) (xy 329.887416 -111.614835)
			(xy 329.87996 -111.607346) (xy 329.860878 -111.589218) (xy 329.827424 -111.548581) (xy 329.79987 -111.503735)
			(xy 329.778736 -111.455529) (xy 329.764425 -111.404877) (xy 329.757206 -111.35274) (xy 329.75677 -111.326422)
			(xy 329.757256 -111.299171) (xy 329.765012 -111.245223) (xy 329.780367 -111.192928) (xy 329.803009 -111.143351)
			(xy 329.832475 -111.097501) (xy 329.868166 -111.05631) (xy 329.909357 -111.020619) (xy 329.955207 -110.991153)
			(xy 330.004784 -110.968511) (xy 330.057079 -110.953156) (xy 330.111027 -110.9454) (xy 330.165529 -110.9454)
			(xy 330.219477 -110.953156) (xy 330.271772 -110.968511) (xy 330.321349 -110.991153) (xy 330.367199 -111.020619)
			(xy 330.40839 -111.05631) (xy 330.444081 -111.097501) (xy 330.473547 -111.143351) (xy 330.496189 -111.192928)
			(xy 330.511544 -111.245223) (xy 330.5193 -111.299171) (xy 330.519786 -111.326422) (xy 330.519338 -111.352737)
			(xy 330.5121 -111.404866) (xy 330.497777 -111.455509) (xy 330.476641 -111.503708) (xy 330.449091 -111.548551)
			(xy 330.415649 -111.58919) (xy 330.396596 -111.607346) (xy 330.389172 -111.614848) (xy 330.380661 -111.634143)
			(xy 330.380086 -111.644684) (xy 330.380086 -111.71936) (xy 330.380627 -111.729908) (xy 330.389154 -111.749203)
			(xy 330.396596 -111.756698) (xy 330.417407 -111.776495) (xy 330.453384 -111.82127) (xy 330.482245 -111.870931)
			(xy 330.503337 -111.924356) (xy 330.516186 -111.980339) (xy 330.520499 -112.037615) (xy 332.294318 -112.037615)
			(xy 332.298631 -111.980344) (xy 332.311478 -111.924367) (xy 332.332567 -111.870947) (xy 332.361424 -111.82129)
			(xy 332.397396 -111.776518) (xy 332.418182 -111.756698) (xy 332.425584 -111.749177) (xy 332.434109 -111.729897)
			(xy 332.434692 -111.71936) (xy 332.434692 -111.644684) (xy 332.434188 -111.634131) (xy 332.425635 -111.614836)
			(xy 332.418182 -111.607346) (xy 332.399104 -111.589213) (xy 332.365649 -111.548578) (xy 332.338094 -111.503733)
			(xy 332.316959 -111.455528) (xy 332.302647 -111.404877) (xy 332.295428 -111.352739) (xy 332.294992 -111.326422)
			(xy 332.295478 -111.299171) (xy 332.303234 -111.245223) (xy 332.318589 -111.192928) (xy 332.341231 -111.143351)
			(xy 332.370697 -111.097501) (xy 332.406388 -111.05631) (xy 332.447579 -111.020619) (xy 332.493429 -110.991153)
			(xy 332.543006 -110.968511) (xy 332.595301 -110.953156) (xy 332.649249 -110.9454) (xy 332.703751 -110.9454)
			(xy 332.757699 -110.953156) (xy 332.809994 -110.968511) (xy 332.859571 -110.991153) (xy 332.905421 -111.020619)
			(xy 332.946612 -111.05631) (xy 332.982303 -111.097501) (xy 333.011769 -111.143351) (xy 333.034411 -111.192928)
			(xy 333.049766 -111.245223) (xy 333.057522 -111.299171) (xy 333.058008 -111.326422) (xy 333.057553 -111.352736)
			(xy 333.050315 -111.404865) (xy 333.035993 -111.455508) (xy 333.014859 -111.503707) (xy 332.987311 -111.54855)
			(xy 332.95387 -111.58919) (xy 332.934818 -111.607346) (xy 332.927397 -111.614851) (xy 332.918883 -111.634144)
			(xy 332.918308 -111.644684) (xy 332.918308 -111.71936) (xy 332.918843 -111.729909) (xy 332.927374 -111.749205)
			(xy 332.934818 -111.756698) (xy 332.955628 -111.776496) (xy 332.991603 -111.821272) (xy 333.020462 -111.870933)
			(xy 333.041553 -111.924357) (xy 333.054401 -111.98034) (xy 333.055424 -111.993923) (xy 336.497253 -111.993923)
			(xy 336.501565 -111.936653) (xy 336.514411 -111.880675) (xy 336.535502 -111.827255) (xy 336.564359 -111.777599)
			(xy 336.600333 -111.732829) (xy 336.62112 -111.71301) (xy 336.628522 -111.705489) (xy 336.637046 -111.686208)
			(xy 336.63763 -111.675672) (xy 336.63763 -111.600996) (xy 336.637108 -111.590446) (xy 336.628567 -111.571151)
			(xy 336.62112 -111.563658) (xy 336.600364 -111.543805) (xy 336.564385 -111.499039) (xy 336.535522 -111.449386)
			(xy 336.514425 -111.395969) (xy 336.501572 -111.339993) (xy 336.497253 -111.282723) (xy 336.501565 -111.225453)
			(xy 336.514411 -111.169475) (xy 336.535502 -111.116055) (xy 336.564359 -111.066399) (xy 336.600333 -111.021629)
			(xy 336.62112 -111.00181) (xy 336.628522 -110.994289) (xy 336.637046 -110.975008) (xy 336.63763 -110.964472)
			(xy 336.63763 -110.889796) (xy 336.637108 -110.879246) (xy 336.628567 -110.859951) (xy 336.62112 -110.852458)
			(xy 336.602055 -110.834312) (xy 336.568598 -110.793681) (xy 336.54104 -110.748839) (xy 336.519903 -110.700636)
			(xy 336.505588 -110.649986) (xy 336.498366 -110.597851) (xy 336.49793 -110.571534) (xy 336.498387 -110.54428)
			(xy 336.50614 -110.490327) (xy 336.521494 -110.438027) (xy 336.544135 -110.388444) (xy 336.573603 -110.342589)
			(xy 336.609298 -110.301395) (xy 336.650492 -110.265701) (xy 336.696348 -110.236233) (xy 336.745931 -110.213593)
			(xy 336.798231 -110.19824) (xy 336.852184 -110.190487) (xy 336.879438 -110.190026) (xy 336.905753 -110.19046)
			(xy 336.957884 -110.1977) (xy 337.008527 -110.212025) (xy 337.056726 -110.233164) (xy 337.101569 -110.260717)
			(xy 337.142207 -110.294161) (xy 337.160362 -110.313216) (xy 337.167894 -110.320605) (xy 337.187166 -110.329136)
			(xy 337.1977 -110.329726) (xy 337.272376 -110.329726) (xy 337.282925 -110.32919) (xy 337.30222 -110.320659)
			(xy 337.309714 -110.313216) (xy 337.327873 -110.294164) (xy 337.368502 -110.260706) (xy 337.413341 -110.233146)
			(xy 337.461541 -110.212007) (xy 337.512188 -110.197689) (xy 337.564322 -110.190464) (xy 337.590638 -110.190026)
			(xy 337.617892 -110.190443) (xy 337.671844 -110.198205) (xy 337.724142 -110.213567) (xy 337.773721 -110.236215)
			(xy 337.813342 -110.261683) (xy 339.114448 -110.261683) (xy 339.114448 -110.209717) (xy 339.122577 -110.158392)
			(xy 339.138635 -110.108969) (xy 339.162226 -110.062667) (xy 339.192769 -110.020626) (xy 339.229514 -109.98388)
			(xy 339.271554 -109.953334) (xy 339.317854 -109.929741) (xy 339.367276 -109.913681) (xy 339.418601 -109.905549)
			(xy 339.444584 -109.905038) (xy 339.47123 -109.905495) (xy 339.523833 -109.914032) (xy 339.574384 -109.930903)
			(xy 339.62157 -109.955671) (xy 339.664168 -109.987694) (xy 339.701072 -110.026139) (xy 339.716618 -110.047786)
			(xy 339.724982 -110.059072) (xy 339.746655 -110.076927) (xy 339.772369 -110.08821) (xy 339.800184 -110.092068)
			(xy 339.827999 -110.08821) (xy 339.853713 -110.076927) (xy 339.875386 -110.059072) (xy 339.88375 -110.047786)
			(xy 339.899313 -110.026158) (xy 339.936232 -109.987742) (xy 339.978833 -109.955743) (xy 340.026014 -109.930989)
			(xy 340.076553 -109.91412) (xy 340.129144 -109.905574) (xy 340.155784 -109.905038) (xy 340.181778 -109.905428)
			(xy 340.233125 -109.913558) (xy 340.282569 -109.929622) (xy 340.328891 -109.953222) (xy 340.37095 -109.983778)
			(xy 340.407712 -110.020538) (xy 340.43827 -110.062596) (xy 340.461872 -110.108916) (xy 340.477938 -110.158359)
			(xy 340.486071 -110.209706) (xy 340.486071 -110.261694) (xy 340.477938 -110.313041) (xy 340.461872 -110.362484)
			(xy 340.43827 -110.408804) (xy 340.407712 -110.450862) (xy 340.37095 -110.487622) (xy 340.332365 -110.515654)
			(xy 343.028014 -110.515654) (xy 343.032085 -110.460032) (xy 343.044211 -110.405595) (xy 343.064134 -110.353504)
			(xy 343.09143 -110.304869) (xy 343.125516 -110.260726) (xy 343.165665 -110.222017) (xy 343.211023 -110.189566)
			(xy 343.260623 -110.164065) (xy 343.313407 -110.146058) (xy 343.36825 -110.135928) (xy 343.423984 -110.133891)
			(xy 343.479421 -110.139991) (xy 343.533378 -110.154097) (xy 343.584707 -110.175909) (xy 343.632313 -110.204963)
			(xy 343.675181 -110.240638) (xy 343.712398 -110.282175) (xy 343.743171 -110.328688) (xy 343.766843 -110.379185)
			(xy 343.782911 -110.432592) (xy 343.791031 -110.487768) (xy 343.79154 -110.515654) (xy 343.791031 -110.54354)
			(xy 343.782911 -110.598716) (xy 343.766843 -110.652123) (xy 343.743171 -110.70262) (xy 343.712398 -110.749133)
			(xy 343.675181 -110.79067) (xy 343.632313 -110.826345) (xy 343.584707 -110.855399) (xy 343.533378 -110.877211)
			(xy 343.479421 -110.891317) (xy 343.423984 -110.897417) (xy 343.36825 -110.89538) (xy 343.313407 -110.88525)
			(xy 343.260623 -110.867243) (xy 343.211023 -110.841742) (xy 343.165665 -110.809291) (xy 343.125516 -110.770582)
			(xy 343.09143 -110.726439) (xy 343.064134 -110.677804) (xy 343.044211 -110.625713) (xy 343.032085 -110.571276)
			(xy 343.028014 -110.515654) (xy 340.332365 -110.515654) (xy 340.328891 -110.518178) (xy 340.282569 -110.541778)
			(xy 340.233125 -110.557842) (xy 340.181778 -110.565972) (xy 340.155784 -110.566454) (xy 340.12914 -110.56595)
			(xy 340.076539 -110.557423) (xy 340.025989 -110.540562) (xy 339.978802 -110.515803) (xy 339.936203 -110.483788)
			(xy 339.899297 -110.44535) (xy 339.88375 -110.423706) (xy 339.875386 -110.41242) (xy 339.853713 -110.394565)
			(xy 339.827999 -110.383282) (xy 339.800184 -110.379424) (xy 339.772369 -110.383282) (xy 339.746655 -110.394565)
			(xy 339.724982 -110.41242) (xy 339.716618 -110.423706) (xy 339.701011 -110.4453) (xy 339.664101 -110.483718)
			(xy 339.621509 -110.515721) (xy 339.574337 -110.540481) (xy 339.523805 -110.557357) (xy 339.471222 -110.565912)
			(xy 339.444584 -110.566454) (xy 339.418601 -110.565851) (xy 339.367276 -110.557719) (xy 339.317854 -110.541659)
			(xy 339.271554 -110.518066) (xy 339.229514 -110.48752) (xy 339.192769 -110.450774) (xy 339.162226 -110.408733)
			(xy 339.138635 -110.362431) (xy 339.122577 -110.313008) (xy 339.114448 -110.261683) (xy 337.813342 -110.261683)
			(xy 337.819573 -110.265688) (xy 337.860764 -110.301387) (xy 337.896455 -110.342584) (xy 337.92592 -110.388442)
			(xy 337.948558 -110.438026) (xy 337.96391 -110.490327) (xy 337.971663 -110.54428) (xy 337.972146 -110.571534)
			(xy 337.971718 -110.59785) (xy 337.964478 -110.64998) (xy 337.950152 -110.700625) (xy 337.929012 -110.748824)
			(xy 337.901458 -110.793666) (xy 337.868012 -110.834303) (xy 337.848956 -110.852458) (xy 337.841579 -110.860001)
			(xy 337.833039 -110.879264) (xy 337.832446 -110.889796) (xy 337.832446 -110.964472) (xy 337.832963 -110.975023)
			(xy 337.841505 -110.994319) (xy 337.848956 -111.00181) (xy 337.869776 -111.021597) (xy 337.905747 -111.066376)
			(xy 337.934603 -111.116039) (xy 337.9527 -111.161885) (xy 339.114423 -111.161885) (xy 339.114423 -111.109915)
			(xy 339.122553 -111.058586) (xy 339.138612 -111.00916) (xy 339.162205 -110.962855) (xy 339.192751 -110.92081)
			(xy 339.229498 -110.884061) (xy 339.271541 -110.853513) (xy 339.317845 -110.829918) (xy 339.36727 -110.813857)
			(xy 339.418599 -110.805725) (xy 339.444584 -110.805214) (xy 339.471229 -110.805681) (xy 339.523832 -110.814218)
			(xy 339.574382 -110.831088) (xy 339.621568 -110.855854) (xy 339.664166 -110.887874) (xy 339.701071 -110.926316)
			(xy 339.716618 -110.947962) (xy 339.724982 -110.959248) (xy 339.746655 -110.977103) (xy 339.772369 -110.988386)
			(xy 339.800184 -110.992244) (xy 339.827999 -110.988386) (xy 339.853713 -110.977103) (xy 339.875386 -110.959248)
			(xy 339.88375 -110.947962) (xy 339.899306 -110.926329) (xy 339.936227 -110.887914) (xy 339.97883 -110.855916)
			(xy 340.026012 -110.831163) (xy 340.076552 -110.814296) (xy 340.129144 -110.80575) (xy 340.155784 -110.805214)
			(xy 340.181776 -110.805652) (xy 340.23312 -110.813782) (xy 340.28256 -110.829844) (xy 340.328878 -110.853442)
			(xy 340.370935 -110.883996) (xy 340.407693 -110.920753) (xy 340.438249 -110.962808) (xy 340.46185 -111.009126)
			(xy 340.477914 -111.058565) (xy 340.486047 -111.109908) (xy 340.486047 -111.161892) (xy 340.477914 -111.213235)
			(xy 340.46185 -111.262674) (xy 340.438249 -111.308992) (xy 340.407693 -111.351047) (xy 340.370935 -111.387804)
			(xy 340.328878 -111.418358) (xy 340.28256 -111.441956) (xy 340.23312 -111.458018) (xy 340.181776 -111.466148)
			(xy 340.155784 -111.46663) (xy 340.129139 -111.466136) (xy 340.076537 -111.457609) (xy 340.025987 -111.440746)
			(xy 339.9788 -111.415985) (xy 339.936201 -111.383968) (xy 339.899296 -111.345527) (xy 339.88375 -111.323882)
			(xy 339.875386 -111.312596) (xy 339.853713 -111.294741) (xy 339.827999 -111.283458) (xy 339.800184 -111.2796)
			(xy 339.772369 -111.283458) (xy 339.746655 -111.294741) (xy 339.724982 -111.312596) (xy 339.716618 -111.323882)
			(xy 339.701033 -111.345493) (xy 339.664116 -111.383906) (xy 339.621519 -111.415905) (xy 339.574343 -111.440661)
			(xy 339.523808 -111.457534) (xy 339.471222 -111.466088) (xy 339.444584 -111.46663) (xy 339.418599 -111.466075)
			(xy 339.36727 -111.457943) (xy 339.317845 -111.441882) (xy 339.271541 -111.418287) (xy 339.229498 -111.387739)
			(xy 339.192751 -111.35099) (xy 339.162205 -111.308945) (xy 339.138612 -111.26264) (xy 339.122553 -111.213214)
			(xy 339.114423 -111.161885) (xy 337.9527 -111.161885) (xy 337.955692 -111.169465) (xy 337.968537 -111.225448)
			(xy 337.972849 -111.282723) (xy 337.96853 -111.339998) (xy 337.955678 -111.395979) (xy 337.934583 -111.449403)
			(xy 337.905721 -111.499063) (xy 337.869745 -111.543837) (xy 337.848956 -111.563658) (xy 337.841579 -111.571201)
			(xy 337.833039 -111.590464) (xy 337.832446 -111.600996) (xy 337.832446 -111.675672) (xy 337.832963 -111.686223)
			(xy 337.841505 -111.705519) (xy 337.848956 -111.71301) (xy 337.869776 -111.732797) (xy 337.905747 -111.777576)
			(xy 337.934603 -111.827239) (xy 337.955692 -111.880665) (xy 337.968537 -111.936648) (xy 337.972849 -111.993923)
			(xy 337.96853 -112.051198) (xy 337.9661 -112.061783) (xy 339.114446 -112.061783) (xy 339.114446 -112.009817)
			(xy 339.122575 -111.958491) (xy 339.138633 -111.909069) (xy 339.162224 -111.862766) (xy 339.192768 -111.820725)
			(xy 339.229512 -111.783978) (xy 339.271553 -111.753432) (xy 339.317854 -111.729839) (xy 339.367275 -111.713779)
			(xy 339.418601 -111.705647) (xy 339.444584 -111.705136) (xy 339.47123 -111.705594) (xy 339.523833 -111.714131)
			(xy 339.574384 -111.731002) (xy 339.62157 -111.75577) (xy 339.664168 -111.787792) (xy 339.701072 -111.826237)
			(xy 339.716618 -111.847884) (xy 339.724982 -111.85917) (xy 339.746655 -111.877025) (xy 339.772369 -111.888308)
			(xy 339.800184 -111.892166) (xy 339.827999 -111.888308) (xy 339.853713 -111.877025) (xy 339.875386 -111.85917)
			(xy 339.88375 -111.847884) (xy 339.899312 -111.826256) (xy 339.936231 -111.78784) (xy 339.978832 -111.755841)
			(xy 340.026013 -111.731087) (xy 340.076553 -111.714218) (xy 340.129144 -111.705672) (xy 340.155784 -111.705136)
			(xy 340.181778 -111.70553) (xy 340.233125 -111.71366) (xy 340.282568 -111.729723) (xy 340.32889 -111.753323)
			(xy 340.370949 -111.783879) (xy 340.372724 -111.785654) (xy 341.657684 -111.785654) (xy 341.661755 -111.730032)
			(xy 341.673881 -111.675595) (xy 341.693804 -111.623504) (xy 341.7211 -111.574869) (xy 341.755186 -111.530726)
			(xy 341.795335 -111.492017) (xy 341.840693 -111.459566) (xy 341.890293 -111.434065) (xy 341.943077 -111.416058)
			(xy 341.99792 -111.405928) (xy 342.053654 -111.403891) (xy 342.109091 -111.409991) (xy 342.163048 -111.424097)
			(xy 342.214377 -111.445909) (xy 342.261983 -111.474963) (xy 342.304851 -111.510638) (xy 342.342068 -111.552175)
			(xy 342.372841 -111.598688) (xy 342.396513 -111.649185) (xy 342.412581 -111.702592) (xy 342.420701 -111.757768)
			(xy 342.42121 -111.785654) (xy 342.420701 -111.81354) (xy 342.412581 -111.868716) (xy 342.396513 -111.922123)
			(xy 342.372841 -111.97262) (xy 342.342068 -112.019133) (xy 342.304851 -112.06067) (xy 342.261983 -112.096345)
			(xy 342.214377 -112.125399) (xy 342.163048 -112.147211) (xy 342.109091 -112.161317) (xy 342.053654 -112.167417)
			(xy 341.99792 -112.16538) (xy 341.943077 -112.15525) (xy 341.890293 -112.137243) (xy 341.840693 -112.111742)
			(xy 341.795335 -112.079291) (xy 341.755186 -112.040582) (xy 341.7211 -111.996439) (xy 341.693804 -111.947804)
			(xy 341.673881 -111.895713) (xy 341.661755 -111.841276) (xy 341.657684 -111.785654) (xy 340.372724 -111.785654)
			(xy 340.40771 -111.820639) (xy 340.438268 -111.862697) (xy 340.461871 -111.909017) (xy 340.477936 -111.95846)
			(xy 340.486069 -112.009806) (xy 340.486069 -112.061794) (xy 340.477936 -112.11314) (xy 340.461871 -112.162583)
			(xy 340.438268 -112.208903) (xy 340.40771 -112.250961) (xy 340.370949 -112.287721) (xy 340.358237 -112.296956)
			(xy 343.094816 -112.296956) (xy 343.098887 -112.241334) (xy 343.111013 -112.186897) (xy 343.130936 -112.134806)
			(xy 343.158232 -112.086171) (xy 343.192318 -112.042028) (xy 343.232467 -112.003319) (xy 343.277825 -111.970868)
			(xy 343.327425 -111.945367) (xy 343.380209 -111.92736) (xy 343.435052 -111.91723) (xy 343.490786 -111.915193)
			(xy 343.546223 -111.921293) (xy 343.60018 -111.935399) (xy 343.651509 -111.957211) (xy 343.699115 -111.986265)
			(xy 343.741983 -112.02194) (xy 343.7792 -112.063477) (xy 343.809973 -112.10999) (xy 343.833645 -112.160487)
			(xy 343.849713 -112.213894) (xy 343.857833 -112.26907) (xy 343.858342 -112.296956) (xy 343.857833 -112.324842)
			(xy 343.849713 -112.380018) (xy 343.833645 -112.433425) (xy 343.809973 -112.483922) (xy 343.7792 -112.530435)
			(xy 343.741983 -112.571972) (xy 343.699115 -112.607647) (xy 343.651509 -112.636701) (xy 343.60018 -112.658513)
			(xy 343.546223 -112.672619) (xy 343.490786 -112.678719) (xy 343.435052 -112.676682) (xy 343.380209 -112.666552)
			(xy 343.327425 -112.648545) (xy 343.277825 -112.623044) (xy 343.232467 -112.590593) (xy 343.192318 -112.551884)
			(xy 343.158232 -112.507741) (xy 343.130936 -112.459106) (xy 343.111013 -112.407015) (xy 343.098887 -112.352578)
			(xy 343.094816 -112.296956) (xy 340.358237 -112.296956) (xy 340.32889 -112.318277) (xy 340.282568 -112.341877)
			(xy 340.233125 -112.35794) (xy 340.181778 -112.36607) (xy 340.155784 -112.366552) (xy 340.12914 -112.366049)
			(xy 340.076538 -112.357522) (xy 340.025989 -112.34066) (xy 339.978802 -112.315901) (xy 339.936203 -112.283887)
			(xy 339.899297 -112.245448) (xy 339.88375 -112.223804) (xy 339.875386 -112.212518) (xy 339.853713 -112.194663)
			(xy 339.827999 -112.18338) (xy 339.800184 -112.179522) (xy 339.772369 -112.18338) (xy 339.746655 -112.194663)
			(xy 339.724982 -112.212518) (xy 339.716618 -112.223804) (xy 339.70101 -112.245398) (xy 339.664101 -112.283816)
			(xy 339.621509 -112.315819) (xy 339.574337 -112.340579) (xy 339.523805 -112.357455) (xy 339.471221 -112.36601)
			(xy 339.444584 -112.366552) (xy 339.418601 -112.365953) (xy 339.367275 -112.357821) (xy 339.317854 -112.341761)
			(xy 339.271553 -112.318168) (xy 339.229512 -112.287622) (xy 339.192768 -112.250875) (xy 339.162224 -112.208834)
			(xy 339.138633 -112.162531) (xy 339.122575 -112.113109) (xy 339.114446 -112.061783) (xy 337.9661 -112.061783)
			(xy 337.955678 -112.107179) (xy 337.934583 -112.160603) (xy 337.905721 -112.210263) (xy 337.869745 -112.255037)
			(xy 337.848956 -112.274858) (xy 337.841579 -112.282401) (xy 337.833039 -112.301664) (xy 337.832446 -112.312196)
			(xy 337.832446 -112.386872) (xy 337.832963 -112.397423) (xy 337.841505 -112.416719) (xy 337.848956 -112.42421)
			(xy 337.86802 -112.442357) (xy 337.901474 -112.48299) (xy 337.929031 -112.527832) (xy 337.950167 -112.576034)
			(xy 337.964483 -112.626683) (xy 337.971708 -112.678818) (xy 337.972146 -112.705134) (xy 337.971654 -112.732384)
			(xy 337.963894 -112.78633) (xy 337.948536 -112.838622) (xy 337.925894 -112.888197) (xy 337.896428 -112.934045)
			(xy 337.872387 -112.961789) (xy 339.114368 -112.961789) (xy 339.114368 -112.909811) (xy 339.122498 -112.858473)
			(xy 339.13856 -112.809038) (xy 339.162157 -112.762725) (xy 339.192708 -112.720674) (xy 339.229461 -112.683919)
			(xy 339.271512 -112.653365) (xy 339.317824 -112.629766) (xy 339.367257 -112.613702) (xy 339.418595 -112.605569)
			(xy 339.444584 -112.605058) (xy 339.47123 -112.605507) (xy 339.523835 -112.614044) (xy 339.574386 -112.630917)
			(xy 339.621572 -112.655686) (xy 339.66417 -112.68771) (xy 339.701073 -112.726158) (xy 339.716618 -112.747806)
			(xy 339.724982 -112.759092) (xy 339.746655 -112.776947) (xy 339.772369 -112.78823) (xy 339.800184 -112.792088)
			(xy 339.827999 -112.78823) (xy 339.853713 -112.776947) (xy 339.875386 -112.759092) (xy 339.88375 -112.747806)
			(xy 339.899289 -112.726161) (xy 339.936216 -112.687749) (xy 339.978822 -112.655755) (xy 340.026008 -112.631004)
			(xy 340.07655 -112.614139) (xy 340.129143 -112.605594) (xy 340.155784 -112.605058) (xy 340.181771 -112.605608)
			(xy 340.233107 -112.613736) (xy 340.282538 -112.629795) (xy 340.328849 -112.65339) (xy 340.370898 -112.683939)
			(xy 340.407651 -112.72069) (xy 340.438202 -112.762737) (xy 340.461798 -112.809047) (xy 340.47786 -112.858478)
			(xy 340.485991 -112.909813) (xy 340.485991 -112.961787) (xy 340.47786 -113.013122) (xy 340.461798 -113.062553)
			(xy 340.438202 -113.108863) (xy 340.407651 -113.15091) (xy 340.370898 -113.187661) (xy 340.328849 -113.21821)
			(xy 340.282538 -113.241805) (xy 340.233107 -113.257864) (xy 340.181771 -113.265992) (xy 340.155784 -113.266474)
			(xy 340.12914 -113.265961) (xy 340.07654 -113.257435) (xy 340.025991 -113.240575) (xy 339.978804 -113.215817)
			(xy 339.936205 -113.183805) (xy 339.899297 -113.145369) (xy 339.88375 -113.123726) (xy 339.875386 -113.11244)
			(xy 339.853713 -113.094585) (xy 339.827999 -113.083302) (xy 339.800184 -113.079444) (xy 339.772369 -113.083302)
			(xy 339.746655 -113.094585) (xy 339.724982 -113.11244) (xy 339.716618 -113.123726) (xy 339.701017 -113.145325)
			(xy 339.664105 -113.183741) (xy 339.621512 -113.215743) (xy 339.574339 -113.240502) (xy 339.523806 -113.257377)
			(xy 339.471222 -113.265932) (xy 339.444584 -113.266474) (xy 339.418595 -113.266031) (xy 339.367257 -113.257898)
			(xy 339.317824 -113.241834) (xy 339.271512 -113.218235) (xy 339.229461 -113.187681) (xy 339.192708 -113.150926)
			(xy 339.162157 -113.108875) (xy 339.13856 -113.062562) (xy 339.122498 -113.013127) (xy 339.114368 -112.961789)
			(xy 337.872387 -112.961789) (xy 337.860737 -112.975234) (xy 337.819549 -113.010925) (xy 337.773701 -113.040392)
			(xy 337.724126 -113.063035) (xy 337.671834 -113.078393) (xy 337.617888 -113.086154) (xy 337.590638 -113.086642)
			(xy 337.564322 -113.086234) (xy 337.51219 -113.07899) (xy 337.461545 -113.06466) (xy 337.413346 -113.043517)
			(xy 337.368504 -113.015959) (xy 337.327868 -112.982509) (xy 337.309714 -112.963452) (xy 337.302182 -112.956062)
			(xy 337.28291 -112.947529) (xy 337.272376 -112.946942) (xy 337.1977 -112.946942) (xy 337.187147 -112.947445)
			(xy 337.167851 -112.955997) (xy 337.160362 -112.963452) (xy 337.142228 -112.982529) (xy 337.101593 -113.015982)
			(xy 337.056747 -113.043537) (xy 337.008543 -113.064671) (xy 336.957892 -113.078985) (xy 336.905755 -113.086205)
			(xy 336.879438 -113.086642) (xy 336.852188 -113.086109) (xy 336.798241 -113.078359) (xy 336.745946 -113.063009)
			(xy 336.696369 -113.040373) (xy 336.650517 -113.010913) (xy 336.609325 -112.975226) (xy 336.573631 -112.934041)
			(xy 336.544161 -112.888195) (xy 336.521516 -112.838621) (xy 336.506157 -112.786329) (xy 336.498396 -112.732384)
			(xy 336.49793 -112.705134) (xy 336.498344 -112.678818) (xy 336.505588 -112.626687) (xy 336.519917 -112.576043)
			(xy 336.54106 -112.527844) (xy 336.568616 -112.483002) (xy 336.602064 -112.442365) (xy 336.62112 -112.42421)
			(xy 336.628522 -112.416689) (xy 336.637046 -112.397408) (xy 336.63763 -112.386872) (xy 336.63763 -112.312196)
			(xy 336.637108 -112.301646) (xy 336.628567 -112.282351) (xy 336.62112 -112.274858) (xy 336.600364 -112.255005)
			(xy 336.564385 -112.210239) (xy 336.535522 -112.160586) (xy 336.514425 -112.107169) (xy 336.501572 -112.051193)
			(xy 336.497253 -111.993923) (xy 333.055424 -111.993923) (xy 333.058714 -112.037615) (xy 333.054396 -112.09489)
			(xy 333.041544 -112.150871) (xy 333.020449 -112.204294) (xy 332.991586 -112.253953) (xy 332.955607 -112.298726)
			(xy 332.934818 -112.318546) (xy 332.927397 -112.326051) (xy 332.918883 -112.345344) (xy 332.918308 -112.355884)
			(xy 332.918308 -112.43056) (xy 332.918843 -112.441109) (xy 332.927374 -112.460405) (xy 332.934818 -112.467898)
			(xy 332.953869 -112.486058) (xy 332.987326 -112.526687) (xy 333.014885 -112.571527) (xy 333.036024 -112.619726)
			(xy 333.050343 -112.670373) (xy 333.057569 -112.722506) (xy 333.058008 -112.748822) (xy 333.057522 -112.776073)
			(xy 333.049766 -112.830021) (xy 333.034411 -112.882316) (xy 333.011769 -112.931893) (xy 332.982303 -112.977743)
			(xy 332.946612 -113.018934) (xy 332.905421 -113.054625) (xy 332.859571 -113.084091) (xy 332.809994 -113.106733)
			(xy 332.757699 -113.122088) (xy 332.703751 -113.129844) (xy 332.649249 -113.129844) (xy 332.595301 -113.122088)
			(xy 332.543006 -113.106733) (xy 332.493429 -113.084091) (xy 332.447579 -113.054625) (xy 332.406388 -113.018934)
			(xy 332.370697 -112.977743) (xy 332.341231 -112.931893) (xy 332.318589 -112.882316) (xy 332.303234 -112.830021)
			(xy 332.295478 -112.776073) (xy 332.294992 -112.748822) (xy 332.295477 -112.722509) (xy 332.302708 -112.670381)
			(xy 332.317024 -112.619739) (xy 332.338153 -112.57154) (xy 332.365696 -112.526696) (xy 332.399132 -112.486055)
			(xy 332.418182 -112.467898) (xy 332.425584 -112.460377) (xy 332.434109 -112.441097) (xy 332.434692 -112.43056)
			(xy 332.434692 -112.355884) (xy 332.434188 -112.345331) (xy 332.425635 -112.326036) (xy 332.418182 -112.318546)
			(xy 332.397416 -112.298704) (xy 332.361441 -112.253935) (xy 332.33258 -112.20428) (xy 332.311487 -112.150861)
			(xy 332.298636 -112.094885) (xy 332.294318 -112.037615) (xy 330.520499 -112.037615) (xy 330.516181 -112.094891)
			(xy 330.503328 -112.150872) (xy 330.482232 -112.204296) (xy 330.453367 -112.253954) (xy 330.417387 -112.298727)
			(xy 330.396596 -112.318546) (xy 330.389172 -112.326048) (xy 330.380661 -112.345343) (xy 330.380086 -112.355884)
			(xy 330.380086 -112.43056) (xy 330.380627 -112.441108) (xy 330.389154 -112.460403) (xy 330.396596 -112.467898)
			(xy 330.415643 -112.486062) (xy 330.449101 -112.52669) (xy 330.476661 -112.571528) (xy 330.497801 -112.619728)
			(xy 330.51212 -112.670374) (xy 330.519347 -112.722506) (xy 330.519786 -112.748822) (xy 330.5193 -112.776073)
			(xy 330.511544 -112.830021) (xy 330.496189 -112.882316) (xy 330.473547 -112.931893) (xy 330.444081 -112.977743)
			(xy 330.40839 -113.018934) (xy 330.367199 -113.054625) (xy 330.321349 -113.084091) (xy 330.271772 -113.106733)
			(xy 330.219477 -113.122088) (xy 330.165529 -113.129844) (xy 330.111027 -113.129844) (xy 330.057079 -113.122088)
			(xy 330.004784 -113.106733) (xy 329.955207 -113.084091) (xy 329.909357 -113.054625) (xy 329.868166 -113.018934)
			(xy 329.832475 -112.977743) (xy 329.803009 -112.931893) (xy 329.780367 -112.882316) (xy 329.765012 -112.830021)
			(xy 329.757256 -112.776073) (xy 329.75677 -112.748822) (xy 329.757262 -112.722509) (xy 329.764493 -112.670382)
			(xy 329.778808 -112.61974) (xy 329.799936 -112.571541) (xy 329.827477 -112.526697) (xy 329.860911 -112.486056)
			(xy 329.87996 -112.467898) (xy 329.887358 -112.460374) (xy 329.895886 -112.441096) (xy 329.89647 -112.43056)
			(xy 329.89647 -112.355884) (xy 329.895972 -112.34533) (xy 329.887416 -112.326035) (xy 329.87996 -112.318546)
			(xy 329.859195 -112.298703) (xy 329.823222 -112.253933) (xy 329.794363 -112.204279) (xy 329.773271 -112.15086)
			(xy 329.760421 -112.094884) (xy 329.756103 -112.037615) (xy 327.962752 -112.037615) (xy 327.994212 -112.075822)
			(xy 328.021769 -112.120665) (xy 328.042905 -112.168869) (xy 328.057219 -112.219519) (xy 328.06444 -112.271655)
			(xy 328.064876 -112.297972) (xy 328.06439 -112.325223) (xy 328.056634 -112.379171) (xy 328.041279 -112.431466)
			(xy 328.018637 -112.481043) (xy 327.989171 -112.526893) (xy 327.95348 -112.568084) (xy 327.912289 -112.603775)
			(xy 327.866439 -112.633241) (xy 327.816862 -112.655883) (xy 327.764567 -112.671238) (xy 327.710619 -112.678994)
			(xy 327.656117 -112.678994) (xy 327.602169 -112.671238) (xy 327.549874 -112.655883) (xy 327.500297 -112.633241)
			(xy 327.454447 -112.603775) (xy 327.413256 -112.568084) (xy 327.377565 -112.526893) (xy 327.348099 -112.481043)
			(xy 327.325457 -112.431466) (xy 327.310102 -112.379171) (xy 327.302346 -112.325223) (xy 327.30186 -112.297972)
			(xy 326.032876 -112.297972) (xy 326.03239 -112.325223) (xy 326.024634 -112.379171) (xy 326.009279 -112.431466)
			(xy 325.986637 -112.481043) (xy 325.957171 -112.526893) (xy 325.92148 -112.568084) (xy 325.880289 -112.603775)
			(xy 325.834439 -112.633241) (xy 325.784862 -112.655883) (xy 325.732567 -112.671238) (xy 325.678619 -112.678994)
			(xy 325.624117 -112.678994) (xy 325.570169 -112.671238) (xy 325.517874 -112.655883) (xy 325.468297 -112.633241)
			(xy 325.422447 -112.603775) (xy 325.381256 -112.568084) (xy 325.345565 -112.526893) (xy 325.316099 -112.481043)
			(xy 325.293457 -112.431466) (xy 325.278102 -112.379171) (xy 325.270346 -112.325223) (xy 325.26986 -112.297972)
			(xy 319.690496 -112.297972) (xy 319.690496 -114.084612) (xy 321.649282 -114.084612) (xy 321.649288 -114.03011)
			(xy 321.65705 -113.976164) (xy 321.672411 -113.923871) (xy 321.695057 -113.874297) (xy 321.724528 -113.82845)
			(xy 321.760223 -113.787264) (xy 321.801417 -113.751578) (xy 321.84727 -113.722117) (xy 321.896849 -113.699481)
			(xy 321.949145 -113.684132) (xy 322.003093 -113.676382) (xy 322.030344 -113.675922) (xy 322.064564 -113.676721)
			(xy 322.131897 -113.688991) (xy 322.164202 -113.700306) (xy 322.172392 -113.702978) (xy 322.189602 -113.703321)
			(xy 322.205949 -113.697929) (xy 322.21297 -113.69294) (xy 322.291964 -113.632488) (xy 322.302378 -113.608358)
			(xy 322.301108 -113.595404) (xy 322.29933 -113.558574) (xy 322.299731 -113.531319) (xy 322.307492 -113.477364)
			(xy 322.322854 -113.425062) (xy 322.345502 -113.375479) (xy 322.374976 -113.329624) (xy 322.410676 -113.288431)
			(xy 322.451876 -113.252738) (xy 322.497736 -113.223271) (xy 322.547322 -113.200631) (xy 322.599626 -113.185279)
			(xy 322.653583 -113.177526) (xy 322.680838 -113.177066) (xy 322.709754 -113.177604) (xy 322.766926 -113.186326)
			(xy 322.822125 -113.203578) (xy 322.874088 -113.228966) (xy 322.921622 -113.261907) (xy 322.963638 -113.301647)
			(xy 322.981828 -113.324132) (xy 322.989427 -113.332947) (xy 323.010334 -113.343125) (xy 323.02196 -113.34369)
			(xy 323.101716 -113.34369) (xy 323.113348 -113.343149) (xy 323.134258 -113.332962) (xy 323.141848 -113.324132)
			(xy 323.160076 -113.30168) (xy 323.202087 -113.261941) (xy 323.249614 -113.228998) (xy 323.301568 -113.203604)
			(xy 323.35676 -113.186341) (xy 323.413924 -113.177605) (xy 323.442838 -113.177066) (xy 323.470089 -113.177542)
			(xy 323.524036 -113.185303) (xy 323.576329 -113.200662) (xy 323.625905 -113.223306) (xy 323.671754 -113.252774)
			(xy 323.712943 -113.288466) (xy 323.748634 -113.329656) (xy 323.7781 -113.375506) (xy 323.800742 -113.425082)
			(xy 323.816099 -113.477376) (xy 323.823858 -113.531323) (xy 323.824346 -113.558574) (xy 323.824161 -113.568734)
			(xy 343.089736 -113.568734) (xy 343.093807 -113.513112) (xy 343.105933 -113.458675) (xy 343.125856 -113.406584)
			(xy 343.153152 -113.357949) (xy 343.187238 -113.313806) (xy 343.227387 -113.275097) (xy 343.272745 -113.242646)
			(xy 343.322345 -113.217145) (xy 343.375129 -113.199138) (xy 343.429972 -113.189008) (xy 343.485706 -113.186971)
			(xy 343.541143 -113.193071) (xy 343.5951 -113.207177) (xy 343.646429 -113.228989) (xy 343.694035 -113.258043)
			(xy 343.736903 -113.293718) (xy 343.77412 -113.335255) (xy 343.804893 -113.381768) (xy 343.828565 -113.432265)
			(xy 343.844633 -113.485672) (xy 343.852753 -113.540848) (xy 343.853262 -113.568734) (xy 343.852753 -113.59662)
			(xy 343.844633 -113.651796) (xy 343.828565 -113.705203) (xy 343.804893 -113.7557) (xy 343.77412 -113.802213)
			(xy 343.736903 -113.84375) (xy 343.694035 -113.879425) (xy 343.646429 -113.908479) (xy 343.5951 -113.930291)
			(xy 343.541143 -113.944397) (xy 343.485706 -113.950497) (xy 343.429972 -113.94846) (xy 343.375129 -113.93833)
			(xy 343.322345 -113.920323) (xy 343.272745 -113.894822) (xy 343.227387 -113.862371) (xy 343.187238 -113.823662)
			(xy 343.153152 -113.779519) (xy 343.125856 -113.730884) (xy 343.105933 -113.678793) (xy 343.093807 -113.624356)
			(xy 343.089736 -113.568734) (xy 323.824161 -113.568734) (xy 323.823808 -113.58812) (xy 323.814708 -113.646506)
			(xy 323.796706 -113.702788) (xy 323.770234 -113.755618) (xy 323.735926 -113.80373) (xy 323.694604 -113.84597)
			(xy 323.647258 -113.881327) (xy 323.6214 -113.895632) (xy 323.611313 -113.901734) (xy 323.597673 -113.920928)
			(xy 323.595238 -113.932462) (xy 323.580506 -114.025172) (xy 323.587872 -114.048032) (xy 323.596254 -114.056414)
			(xy 323.603701 -114.064122) (xy 323.617806 -114.080261) (xy 323.624448 -114.088672) (xy 323.632032 -114.097503)
			(xy 323.652951 -114.107671) (xy 323.66458 -114.10823) (xy 323.744336 -114.10823) (xy 323.755972 -114.107722)
			(xy 323.776883 -114.097513) (xy 323.784468 -114.088672) (xy 323.80267 -114.066198) (xy 323.844688 -114.026463)
			(xy 323.892221 -113.993524) (xy 323.94418 -113.968134) (xy 323.999375 -113.950876) (xy 324.056543 -113.942143)
			(xy 324.085458 -113.941606) (xy 324.112714 -113.942038) (xy 324.166671 -113.94979) (xy 324.218976 -113.965143)
			(xy 324.268564 -113.987784) (xy 324.314424 -114.017252) (xy 324.327376 -114.028474) (xy 337.205064 -114.028474)
			(xy 337.209135 -113.972852) (xy 337.221261 -113.918415) (xy 337.241184 -113.866324) (xy 337.26848 -113.817689)
			(xy 337.302566 -113.773546) (xy 337.342715 -113.734837) (xy 337.388073 -113.702386) (xy 337.437673 -113.676885)
			(xy 337.490457 -113.658878) (xy 337.5453 -113.648748) (xy 337.601034 -113.646711) (xy 337.656471 -113.652811)
			(xy 337.710428 -113.666917) (xy 337.761757 -113.688729) (xy 337.809363 -113.717783) (xy 337.852231 -113.753458)
			(xy 337.889448 -113.794995) (xy 337.920221 -113.841508) (xy 337.943893 -113.892005) (xy 337.959961 -113.945412)
			(xy 337.968081 -114.000588) (xy 337.96859 -114.028474) (xy 337.968081 -114.05636) (xy 337.959961 -114.111536)
			(xy 337.943893 -114.164943) (xy 337.920221 -114.21544) (xy 337.889448 -114.261953) (xy 337.852231 -114.30349)
			(xy 337.809363 -114.339165) (xy 337.761757 -114.368219) (xy 337.710428 -114.390031) (xy 337.656471 -114.404137)
			(xy 337.601034 -114.410237) (xy 337.5453 -114.4082) (xy 337.490457 -114.39807) (xy 337.437673 -114.380063)
			(xy 337.388073 -114.354562) (xy 337.342715 -114.322111) (xy 337.302566 -114.283402) (xy 337.26848 -114.239259)
			(xy 337.241184 -114.190624) (xy 337.221261 -114.138533) (xy 337.209135 -114.084096) (xy 337.205064 -114.028474)
			(xy 324.327376 -114.028474) (xy 324.355623 -114.052947) (xy 324.391322 -114.094143) (xy 324.420795 -114.14)
			(xy 324.443442 -114.189584) (xy 324.458801 -114.241888) (xy 324.466559 -114.295844) (xy 324.466559 -114.350356)
			(xy 324.458801 -114.404312) (xy 324.443442 -114.456616) (xy 324.420795 -114.5062) (xy 324.391322 -114.552057)
			(xy 324.355623 -114.593253) (xy 324.314424 -114.628948) (xy 324.268564 -114.658416) (xy 324.218976 -114.681057)
			(xy 324.166671 -114.69641) (xy 324.112714 -114.704162) (xy 324.085458 -114.704622) (xy 324.056541 -114.704091)
			(xy 323.999369 -114.695369) (xy 323.944169 -114.678115) (xy 323.892207 -114.652726) (xy 323.844673 -114.619783)
			(xy 323.802657 -114.580042) (xy 323.784468 -114.557556) (xy 323.776872 -114.548737) (xy 323.755963 -114.538562)
			(xy 323.744336 -114.537998) (xy 323.66458 -114.537998) (xy 323.652949 -114.538541) (xy 323.632039 -114.548727)
			(xy 323.624448 -114.557556) (xy 323.606219 -114.580007) (xy 323.564208 -114.619747) (xy 323.516682 -114.652691)
			(xy 323.464728 -114.678085) (xy 323.409536 -114.695348) (xy 323.352372 -114.704084) (xy 323.323458 -114.704622)
			(xy 323.296206 -114.704161) (xy 323.242258 -114.696399) (xy 323.189964 -114.68104) (xy 323.140388 -114.658395)
			(xy 323.094538 -114.628925) (xy 323.053349 -114.593231) (xy 323.017658 -114.552039) (xy 322.988192 -114.506188)
			(xy 322.965551 -114.45661) (xy 322.950195 -114.404314) (xy 322.942437 -114.350366) (xy 322.94195 -114.323114)
			(xy 322.942428 -114.293565) (xy 322.951532 -114.235174) (xy 322.969541 -114.178888) (xy 322.996022 -114.126056)
			(xy 323.030341 -114.077944) (xy 323.071675 -114.035707) (xy 323.119032 -114.000356) (xy 323.144896 -113.986056)
			(xy 323.154987 -113.979959) (xy 323.168625 -113.960762) (xy 323.171058 -113.949226) (xy 323.18579 -113.856516)
			(xy 323.178424 -113.833656) (xy 323.170042 -113.825274) (xy 323.162595 -113.817567) (xy 323.14849 -113.801427)
			(xy 323.141848 -113.793016) (xy 323.134225 -113.784226) (xy 323.113336 -113.774036) (xy 323.101716 -113.773458)
			(xy 323.02196 -113.773458) (xy 323.010324 -113.773968) (xy 322.989413 -113.784175) (xy 322.981828 -113.793016)
			(xy 322.963625 -113.815489) (xy 322.921607 -113.855225) (xy 322.874075 -113.888164) (xy 322.822116 -113.913554)
			(xy 322.766921 -113.930813) (xy 322.709753 -113.939545) (xy 322.680838 -113.940082) (xy 322.646618 -113.939287)
			(xy 322.579285 -113.927015) (xy 322.54698 -113.915698) (xy 322.538794 -113.913011) (xy 322.521581 -113.912674)
			(xy 322.505233 -113.918072) (xy 322.498212 -113.923064) (xy 322.419218 -113.983516) (xy 322.408804 -114.007646)
			(xy 322.410074 -114.0206) (xy 322.411852 -114.05743) (xy 322.411313 -114.084681) (xy 322.403552 -114.138627)
			(xy 322.388193 -114.19092) (xy 322.365548 -114.240495) (xy 322.336078 -114.286342) (xy 322.300383 -114.327529)
			(xy 322.259191 -114.363217) (xy 322.213338 -114.392679) (xy 322.16376 -114.415315) (xy 322.111464 -114.430666)
			(xy 322.057516 -114.438417) (xy 322.003014 -114.438412) (xy 321.949068 -114.430651) (xy 321.896775 -114.415291)
			(xy 321.847201 -114.392645) (xy 321.801354 -114.363175) (xy 321.760167 -114.32748) (xy 321.72448 -114.286287)
			(xy 321.695019 -114.240434) (xy 321.672383 -114.190855) (xy 321.657033 -114.13856) (xy 321.649282 -114.084612)
			(xy 319.690496 -114.084612) (xy 319.690496 -114.952018) (xy 319.697608 -114.959638) (xy 319.740788 -114.997484)
			(xy 319.752726 -115.007898) (xy 319.761362 -115.014248) (xy 319.763394 -115.015518) (xy 319.769269 -115.018668)
			(xy 319.782132 -115.022156) (xy 319.788794 -115.022376) (xy 319.794382 -115.022376) (xy 319.79743 -115.022122)
			(xy 319.80869 -115.020841) (xy 319.83131 -115.019443) (xy 319.842642 -115.019328) (xy 319.869889 -115.019817)
			(xy 319.923827 -115.027578) (xy 319.976111 -115.042935) (xy 320.025679 -115.065576) (xy 320.071519 -115.095041)
			(xy 320.112701 -115.130729) (xy 320.148384 -115.171914) (xy 320.177844 -115.217758) (xy 320.20048 -115.267328)
			(xy 320.215831 -115.319614) (xy 320.223126 -115.370356) (xy 321.561204 -115.370356) (xy 321.565275 -115.314734)
			(xy 321.577401 -115.260297) (xy 321.597324 -115.208206) (xy 321.62462 -115.159571) (xy 321.658706 -115.115428)
			(xy 321.698855 -115.076719) (xy 321.744213 -115.044268) (xy 321.793813 -115.018767) (xy 321.846597 -115.00076)
			(xy 321.90144 -114.99063) (xy 321.957174 -114.988593) (xy 322.012611 -114.994693) (xy 322.066568 -115.008799)
			(xy 322.07162 -115.010946) (xy 338.819742 -115.010946) (xy 338.823813 -114.955324) (xy 338.835939 -114.900887)
			(xy 338.855862 -114.848796) (xy 338.883158 -114.800161) (xy 338.917244 -114.756018) (xy 338.957393 -114.717309)
			(xy 339.002751 -114.684858) (xy 339.052351 -114.659357) (xy 339.105135 -114.64135) (xy 339.159978 -114.63122)
			(xy 339.215712 -114.629183) (xy 339.271149 -114.635283) (xy 339.325106 -114.649389) (xy 339.376435 -114.671201)
			(xy 339.424041 -114.700255) (xy 339.466909 -114.73593) (xy 339.504126 -114.777467) (xy 339.534899 -114.82398)
			(xy 339.558571 -114.874477) (xy 339.574639 -114.927884) (xy 339.582759 -114.98306) (xy 339.583268 -115.010946)
			(xy 339.582759 -115.038832) (xy 339.579835 -115.058698) (xy 340.186262 -115.058698) (xy 340.190333 -115.003076)
			(xy 340.202459 -114.948639) (xy 340.222382 -114.896548) (xy 340.249678 -114.847913) (xy 340.283764 -114.80377)
			(xy 340.323913 -114.765061) (xy 340.369271 -114.73261) (xy 340.418871 -114.707109) (xy 340.471655 -114.689102)
			(xy 340.526498 -114.678972) (xy 340.582232 -114.676935) (xy 340.637669 -114.683035) (xy 340.691626 -114.697141)
			(xy 340.742955 -114.718953) (xy 340.790561 -114.748007) (xy 340.833429 -114.783682) (xy 340.870646 -114.825219)
			(xy 340.901419 -114.871732) (xy 340.925091 -114.922229) (xy 340.941159 -114.975636) (xy 340.943328 -114.990372)
			(xy 341.564974 -114.990372) (xy 341.569045 -114.93475) (xy 341.581171 -114.880313) (xy 341.601094 -114.828222)
			(xy 341.62839 -114.779587) (xy 341.662476 -114.735444) (xy 341.702625 -114.696735) (xy 341.747983 -114.664284)
			(xy 341.797583 -114.638783) (xy 341.850367 -114.620776) (xy 341.90521 -114.610646) (xy 341.960944 -114.608609)
			(xy 342.016381 -114.614709) (xy 342.070338 -114.628815) (xy 342.121667 -114.650627) (xy 342.169273 -114.679681)
			(xy 342.212141 -114.715356) (xy 342.249358 -114.756893) (xy 342.280131 -114.803406) (xy 342.303803 -114.853903)
			(xy 342.319871 -114.90731) (xy 342.327721 -114.960654) (xy 343.091768 -114.960654) (xy 343.095839 -114.905032)
			(xy 343.107965 -114.850595) (xy 343.127888 -114.798504) (xy 343.155184 -114.749869) (xy 343.18927 -114.705726)
			(xy 343.229419 -114.667017) (xy 343.274777 -114.634566) (xy 343.324377 -114.609065) (xy 343.377161 -114.591058)
			(xy 343.432004 -114.580928) (xy 343.487738 -114.578891) (xy 343.543175 -114.584991) (xy 343.597132 -114.599097)
			(xy 343.648461 -114.620909) (xy 343.696067 -114.649963) (xy 343.738935 -114.685638) (xy 343.776152 -114.727175)
			(xy 343.806925 -114.773688) (xy 343.830597 -114.824185) (xy 343.846665 -114.877592) (xy 343.854785 -114.932768)
			(xy 343.855294 -114.960654) (xy 343.854785 -114.98854) (xy 343.846665 -115.043716) (xy 343.830597 -115.097123)
			(xy 343.806925 -115.14762) (xy 343.776152 -115.194133) (xy 343.738935 -115.23567) (xy 343.696067 -115.271345)
			(xy 343.648461 -115.300399) (xy 343.597132 -115.322211) (xy 343.543175 -115.336317) (xy 343.487738 -115.342417)
			(xy 343.432004 -115.34038) (xy 343.377161 -115.33025) (xy 343.324377 -115.312243) (xy 343.274777 -115.286742)
			(xy 343.229419 -115.254291) (xy 343.18927 -115.215582) (xy 343.155184 -115.171439) (xy 343.127888 -115.122804)
			(xy 343.107965 -115.070713) (xy 343.095839 -115.016276) (xy 343.091768 -114.960654) (xy 342.327721 -114.960654)
			(xy 342.327991 -114.962486) (xy 342.3285 -114.990372) (xy 342.327991 -115.018258) (xy 342.319871 -115.073434)
			(xy 342.303803 -115.126841) (xy 342.280131 -115.177338) (xy 342.249358 -115.223851) (xy 342.212141 -115.265388)
			(xy 342.169273 -115.301063) (xy 342.121667 -115.330117) (xy 342.070338 -115.351929) (xy 342.016381 -115.366035)
			(xy 341.960944 -115.372135) (xy 341.90521 -115.370098) (xy 341.850367 -115.359968) (xy 341.797583 -115.341961)
			(xy 341.747983 -115.31646) (xy 341.702625 -115.284009) (xy 341.662476 -115.2453) (xy 341.62839 -115.201157)
			(xy 341.601094 -115.152522) (xy 341.581171 -115.100431) (xy 341.569045 -115.045994) (xy 341.564974 -114.990372)
			(xy 340.943328 -114.990372) (xy 340.949279 -115.030812) (xy 340.949788 -115.058698) (xy 340.949279 -115.086584)
			(xy 340.941159 -115.14176) (xy 340.925091 -115.195167) (xy 340.901419 -115.245664) (xy 340.870646 -115.292177)
			(xy 340.833429 -115.333714) (xy 340.790561 -115.369389) (xy 340.742955 -115.398443) (xy 340.691626 -115.420255)
			(xy 340.637669 -115.434361) (xy 340.582232 -115.440461) (xy 340.526498 -115.438424) (xy 340.471655 -115.428294)
			(xy 340.418871 -115.410287) (xy 340.369271 -115.384786) (xy 340.323913 -115.352335) (xy 340.283764 -115.313626)
			(xy 340.249678 -115.269483) (xy 340.222382 -115.220848) (xy 340.202459 -115.168757) (xy 340.190333 -115.11432)
			(xy 340.186262 -115.058698) (xy 339.579835 -115.058698) (xy 339.574639 -115.094008) (xy 339.558571 -115.147415)
			(xy 339.534899 -115.197912) (xy 339.504126 -115.244425) (xy 339.466909 -115.285962) (xy 339.424041 -115.321637)
			(xy 339.376435 -115.350691) (xy 339.325106 -115.372503) (xy 339.271149 -115.386609) (xy 339.215712 -115.392709)
			(xy 339.159978 -115.390672) (xy 339.105135 -115.380542) (xy 339.052351 -115.362535) (xy 339.002751 -115.337034)
			(xy 338.957393 -115.304583) (xy 338.917244 -115.265874) (xy 338.883158 -115.221731) (xy 338.855862 -115.173096)
			(xy 338.835939 -115.121005) (xy 338.823813 -115.066568) (xy 338.819742 -115.010946) (xy 322.07162 -115.010946)
			(xy 322.117897 -115.030611) (xy 322.165503 -115.059665) (xy 322.208371 -115.09534) (xy 322.245588 -115.136877)
			(xy 322.276361 -115.18339) (xy 322.300033 -115.233887) (xy 322.316101 -115.287294) (xy 322.324221 -115.34247)
			(xy 322.32473 -115.370356) (xy 322.324221 -115.398242) (xy 322.316101 -115.453418) (xy 322.300033 -115.506825)
			(xy 322.276361 -115.557322) (xy 322.245588 -115.603835) (xy 322.208371 -115.645372) (xy 322.165503 -115.681047)
			(xy 322.117897 -115.710101) (xy 322.066568 -115.731913) (xy 322.012611 -115.746019) (xy 321.957174 -115.752119)
			(xy 321.90144 -115.750082) (xy 321.846597 -115.739952) (xy 321.793813 -115.721945) (xy 321.744213 -115.696444)
			(xy 321.698855 -115.663993) (xy 321.658706 -115.625284) (xy 321.62462 -115.581141) (xy 321.597324 -115.532506)
			(xy 321.577401 -115.480415) (xy 321.565275 -115.425978) (xy 321.561204 -115.370356) (xy 320.223126 -115.370356)
			(xy 320.223586 -115.373553) (xy 320.223586 -115.428047) (xy 320.215831 -115.481986) (xy 320.20048 -115.534272)
			(xy 320.177844 -115.583842) (xy 320.148384 -115.629686) (xy 320.112701 -115.670871) (xy 320.071519 -115.706559)
			(xy 320.025679 -115.736024) (xy 319.976111 -115.758665) (xy 319.923827 -115.774022) (xy 319.869889 -115.781783)
			(xy 319.842642 -115.782344) (xy 319.830671 -115.782244) (xy 319.806777 -115.780717) (xy 319.79489 -115.779296)
			(xy 319.79235 -115.779042) (xy 319.78318 -115.778782) (xy 319.765602 -115.783981) (xy 319.75806 -115.789202)
			(xy 319.755266 -115.791488) (xy 319.708328 -115.832636) (xy 325.17918 -115.832636) (xy 325.183251 -115.777014)
			(xy 325.195377 -115.722577) (xy 325.2153 -115.670486) (xy 325.242596 -115.621851) (xy 325.276682 -115.577708)
			(xy 325.316831 -115.538999) (xy 325.362189 -115.506548) (xy 325.411789 -115.481047) (xy 325.464573 -115.46304)
			(xy 325.519416 -115.45291) (xy 325.57515 -115.450873) (xy 325.630587 -115.456973) (xy 325.684544 -115.471079)
			(xy 325.735873 -115.492891) (xy 325.783479 -115.521945) (xy 325.826347 -115.55762) (xy 325.863564 -115.599157)
			(xy 325.894337 -115.64567) (xy 325.918009 -115.696167) (xy 325.934077 -115.749574) (xy 325.942197 -115.80475)
			(xy 325.942706 -115.832636) (xy 325.942197 -115.860522) (xy 325.934077 -115.915698) (xy 325.918009 -115.969105)
			(xy 325.894337 -116.019602) (xy 325.863564 -116.066115) (xy 325.826347 -116.107652) (xy 325.783479 -116.143327)
			(xy 325.735873 -116.172381) (xy 325.684544 -116.194193) (xy 325.630587 -116.208299) (xy 325.57515 -116.214399)
			(xy 325.519416 -116.212362) (xy 325.464573 -116.202232) (xy 325.411789 -116.184225) (xy 325.362189 -116.158724)
			(xy 325.316831 -116.126273) (xy 325.276682 -116.087564) (xy 325.242596 -116.043421) (xy 325.2153 -115.994786)
			(xy 325.195377 -115.942695) (xy 325.183251 -115.888258) (xy 325.17918 -115.832636) (xy 319.708328 -115.832636)
			(xy 319.697608 -115.842034) (xy 319.690496 -115.849654) (xy 319.690496 -116.66982) (xy 321.573142 -116.66982)
			(xy 321.577213 -116.614198) (xy 321.589339 -116.559761) (xy 321.609262 -116.50767) (xy 321.636558 -116.459035)
			(xy 321.670644 -116.414892) (xy 321.710793 -116.376183) (xy 321.756151 -116.343732) (xy 321.805751 -116.318231)
			(xy 321.858535 -116.300224) (xy 321.913378 -116.290094) (xy 321.969112 -116.288057) (xy 322.024549 -116.294157)
			(xy 322.078506 -116.308263) (xy 322.129835 -116.330075) (xy 322.177441 -116.359129) (xy 322.220309 -116.394804)
			(xy 322.257526 -116.436341) (xy 322.288299 -116.482854) (xy 322.311971 -116.533351) (xy 322.328039 -116.586758)
			(xy 322.334282 -116.62918) (xy 337.337906 -116.62918) (xy 337.341977 -116.573558) (xy 337.354103 -116.519121)
			(xy 337.374026 -116.46703) (xy 337.401322 -116.418395) (xy 337.435408 -116.374252) (xy 337.475557 -116.335543)
			(xy 337.520915 -116.303092) (xy 337.570515 -116.277591) (xy 337.623299 -116.259584) (xy 337.678142 -116.249454)
			(xy 337.733876 -116.247417) (xy 337.789313 -116.253517) (xy 337.84327 -116.267623) (xy 337.894599 -116.289435)
			(xy 337.942205 -116.318489) (xy 337.985073 -116.354164) (xy 338.02229 -116.395701) (xy 338.053063 -116.442214)
			(xy 338.076735 -116.492711) (xy 338.092803 -116.546118) (xy 338.100923 -116.601294) (xy 338.101432 -116.62918)
			(xy 338.100923 -116.657066) (xy 338.092803 -116.712242) (xy 338.076735 -116.765649) (xy 338.053063 -116.816146)
			(xy 338.02229 -116.862659) (xy 337.985073 -116.904196) (xy 337.942205 -116.939871) (xy 337.894599 -116.968925)
			(xy 337.84327 -116.990737) (xy 337.789313 -117.004843) (xy 337.733876 -117.010943) (xy 337.678142 -117.008906)
			(xy 337.623299 -116.998776) (xy 337.570515 -116.980769) (xy 337.520915 -116.955268) (xy 337.475557 -116.922817)
			(xy 337.435408 -116.884108) (xy 337.401322 -116.839965) (xy 337.374026 -116.79133) (xy 337.354103 -116.739239)
			(xy 337.341977 -116.684802) (xy 337.337906 -116.62918) (xy 322.334282 -116.62918) (xy 322.336159 -116.641934)
			(xy 322.336668 -116.66982) (xy 322.336159 -116.697706) (xy 322.328039 -116.752882) (xy 322.311971 -116.806289)
			(xy 322.288299 -116.856786) (xy 322.257526 -116.903299) (xy 322.220309 -116.944836) (xy 322.177441 -116.980511)
			(xy 322.129835 -117.009565) (xy 322.078506 -117.031377) (xy 322.024549 -117.045483) (xy 321.969112 -117.051583)
			(xy 321.913378 -117.049546) (xy 321.858535 -117.039416) (xy 321.805751 -117.021409) (xy 321.756151 -116.995908)
			(xy 321.710793 -116.963457) (xy 321.670644 -116.924748) (xy 321.636558 -116.880605) (xy 321.609262 -116.83197)
			(xy 321.589339 -116.779879) (xy 321.577213 -116.725442) (xy 321.573142 -116.66982) (xy 319.690496 -116.66982)
			(xy 319.690496 -117.390446) (xy 322.942518 -117.390446) (xy 322.942518 -117.335954) (xy 322.950273 -117.282015)
			(xy 322.965624 -117.229729) (xy 322.98826 -117.18016) (xy 323.017719 -117.134317) (xy 323.053402 -117.093132)
			(xy 323.094583 -117.057444) (xy 323.140423 -117.02798) (xy 323.18999 -117.005339) (xy 323.242274 -116.989982)
			(xy 323.296212 -116.982221) (xy 323.323458 -116.981732) (xy 323.352374 -116.982268) (xy 323.409545 -116.990992)
			(xy 323.464744 -117.008245) (xy 323.516706 -117.033634) (xy 323.564241 -117.066575) (xy 323.606258 -117.106313)
			(xy 323.624448 -117.128798) (xy 323.632044 -117.137617) (xy 323.652953 -117.147794) (xy 323.66458 -117.148356)
			(xy 323.744336 -117.148356) (xy 323.755971 -117.147839) (xy 323.776881 -117.137636) (xy 323.784468 -117.128798)
			(xy 323.802677 -117.106329) (xy 323.844693 -117.066593) (xy 323.892224 -117.033653) (xy 323.944182 -117.008262)
			(xy 323.999376 -116.991002) (xy 324.056543 -116.982269) (xy 324.085458 -116.981732) (xy 324.112716 -116.982112)
			(xy 324.166677 -116.989865) (xy 324.218985 -117.005219) (xy 324.268576 -117.027862) (xy 324.314439 -117.057332)
			(xy 324.355641 -117.093029) (xy 324.363966 -117.102636) (xy 325.17918 -117.102636) (xy 325.183251 -117.047014)
			(xy 325.195377 -116.992577) (xy 325.2153 -116.940486) (xy 325.242596 -116.891851) (xy 325.276682 -116.847708)
			(xy 325.316831 -116.808999) (xy 325.362189 -116.776548) (xy 325.411789 -116.751047) (xy 325.464573 -116.73304)
			(xy 325.519416 -116.72291) (xy 325.57515 -116.720873) (xy 325.630587 -116.726973) (xy 325.684544 -116.741079)
			(xy 325.735873 -116.762891) (xy 325.783479 -116.791945) (xy 325.826347 -116.82762) (xy 325.863564 -116.869157)
			(xy 325.894337 -116.91567) (xy 325.918009 -116.966167) (xy 325.934077 -117.019574) (xy 325.942197 -117.07475)
			(xy 325.942706 -117.102636) (xy 325.942197 -117.130522) (xy 325.934077 -117.185698) (xy 325.918009 -117.239105)
			(xy 325.913756 -117.248178) (xy 339.938866 -117.248178) (xy 339.942937 -117.192556) (xy 339.955063 -117.138119)
			(xy 339.974986 -117.086028) (xy 340.002282 -117.037393) (xy 340.036368 -116.99325) (xy 340.076517 -116.954541)
			(xy 340.121875 -116.92209) (xy 340.171475 -116.896589) (xy 340.224259 -116.878582) (xy 340.279102 -116.868452)
			(xy 340.334836 -116.866415) (xy 340.390273 -116.872515) (xy 340.44423 -116.886621) (xy 340.495559 -116.908433)
			(xy 340.543165 -116.937487) (xy 340.586033 -116.973162) (xy 340.62325 -117.014699) (xy 340.654023 -117.061212)
			(xy 340.677695 -117.111709) (xy 340.693763 -117.165116) (xy 340.701883 -117.220292) (xy 340.702392 -117.248178)
			(xy 340.954866 -117.248178) (xy 340.958937 -117.192556) (xy 340.971063 -117.138119) (xy 340.990986 -117.086028)
			(xy 341.018282 -117.037393) (xy 341.052368 -116.99325) (xy 341.092517 -116.954541) (xy 341.137875 -116.92209)
			(xy 341.187475 -116.896589) (xy 341.240259 -116.878582) (xy 341.295102 -116.868452) (xy 341.350836 -116.866415)
			(xy 341.406273 -116.872515) (xy 341.46023 -116.886621) (xy 341.511559 -116.908433) (xy 341.559165 -116.937487)
			(xy 341.602033 -116.973162) (xy 341.63925 -117.014699) (xy 341.670023 -117.061212) (xy 341.693695 -117.111709)
			(xy 341.709763 -117.165116) (xy 341.717883 -117.220292) (xy 341.718392 -117.248178) (xy 341.970866 -117.248178)
			(xy 341.974937 -117.192556) (xy 341.987063 -117.138119) (xy 342.006986 -117.086028) (xy 342.034282 -117.037393)
			(xy 342.068368 -116.99325) (xy 342.108517 -116.954541) (xy 342.153875 -116.92209) (xy 342.203475 -116.896589)
			(xy 342.256259 -116.878582) (xy 342.311102 -116.868452) (xy 342.366836 -116.866415) (xy 342.422273 -116.872515)
			(xy 342.47623 -116.886621) (xy 342.527559 -116.908433) (xy 342.575165 -116.937487) (xy 342.618033 -116.973162)
			(xy 342.65525 -117.014699) (xy 342.686023 -117.061212) (xy 342.709695 -117.111709) (xy 342.725763 -117.165116)
			(xy 342.733883 -117.220292) (xy 342.734392 -117.248178) (xy 342.733883 -117.276064) (xy 342.725763 -117.33124)
			(xy 342.709695 -117.384647) (xy 342.686023 -117.435144) (xy 342.65525 -117.481657) (xy 342.618033 -117.523194)
			(xy 342.575165 -117.558869) (xy 342.527559 -117.587923) (xy 342.47623 -117.609735) (xy 342.422273 -117.623841)
			(xy 342.366836 -117.629941) (xy 342.311102 -117.627904) (xy 342.256259 -117.617774) (xy 342.203475 -117.599767)
			(xy 342.153875 -117.574266) (xy 342.108517 -117.541815) (xy 342.068368 -117.503106) (xy 342.034282 -117.458963)
			(xy 342.006986 -117.410328) (xy 341.987063 -117.358237) (xy 341.974937 -117.3038) (xy 341.970866 -117.248178)
			(xy 341.718392 -117.248178) (xy 341.717883 -117.276064) (xy 341.709763 -117.33124) (xy 341.693695 -117.384647)
			(xy 341.670023 -117.435144) (xy 341.63925 -117.481657) (xy 341.602033 -117.523194) (xy 341.559165 -117.558869)
			(xy 341.511559 -117.587923) (xy 341.46023 -117.609735) (xy 341.406273 -117.623841) (xy 341.350836 -117.629941)
			(xy 341.295102 -117.627904) (xy 341.240259 -117.617774) (xy 341.187475 -117.599767) (xy 341.137875 -117.574266)
			(xy 341.092517 -117.541815) (xy 341.052368 -117.503106) (xy 341.018282 -117.458963) (xy 340.990986 -117.410328)
			(xy 340.971063 -117.358237) (xy 340.958937 -117.3038) (xy 340.954866 -117.248178) (xy 340.702392 -117.248178)
			(xy 340.701883 -117.276064) (xy 340.693763 -117.33124) (xy 340.677695 -117.384647) (xy 340.654023 -117.435144)
			(xy 340.62325 -117.481657) (xy 340.586033 -117.523194) (xy 340.543165 -117.558869) (xy 340.495559 -117.587923)
			(xy 340.44423 -117.609735) (xy 340.390273 -117.623841) (xy 340.334836 -117.629941) (xy 340.279102 -117.627904)
			(xy 340.224259 -117.617774) (xy 340.171475 -117.599767) (xy 340.121875 -117.574266) (xy 340.076517 -117.541815)
			(xy 340.036368 -117.503106) (xy 340.002282 -117.458963) (xy 339.974986 -117.410328) (xy 339.955063 -117.358237)
			(xy 339.942937 -117.3038) (xy 339.938866 -117.248178) (xy 325.913756 -117.248178) (xy 325.894337 -117.289602)
			(xy 325.863564 -117.336115) (xy 325.826347 -117.377652) (xy 325.783479 -117.413327) (xy 325.735873 -117.442381)
			(xy 325.684544 -117.464193) (xy 325.630587 -117.478299) (xy 325.57515 -117.484399) (xy 325.519416 -117.482362)
			(xy 325.464573 -117.472232) (xy 325.411789 -117.454225) (xy 325.362189 -117.428724) (xy 325.316831 -117.396273)
			(xy 325.276682 -117.357564) (xy 325.242596 -117.313421) (xy 325.2153 -117.264786) (xy 325.195377 -117.212695)
			(xy 325.183251 -117.158258) (xy 325.17918 -117.102636) (xy 324.363966 -117.102636) (xy 324.391343 -117.134227)
			(xy 324.420818 -117.180087) (xy 324.443466 -117.229675) (xy 324.458826 -117.281982) (xy 324.466585 -117.335942)
			(xy 324.466585 -117.390458) (xy 324.458826 -117.444418) (xy 324.443466 -117.496725) (xy 324.420818 -117.546313)
			(xy 324.391343 -117.592173) (xy 324.355641 -117.633371) (xy 324.314439 -117.669068) (xy 324.268576 -117.698538)
			(xy 324.218985 -117.721181) (xy 324.166677 -117.736535) (xy 324.112716 -117.744288) (xy 324.085458 -117.744748)
			(xy 324.056542 -117.744208) (xy 323.999371 -117.735486) (xy 323.944171 -117.718234) (xy 323.892209 -117.692847)
			(xy 323.844675 -117.659906) (xy 323.802658 -117.620167) (xy 323.784468 -117.597682) (xy 323.776868 -117.588867)
			(xy 323.755962 -117.578688) (xy 323.744336 -117.578124) (xy 323.66458 -117.578124) (xy 323.652947 -117.578657)
			(xy 323.632037 -117.588849) (xy 323.624448 -117.597682) (xy 323.606225 -117.620139) (xy 323.564213 -117.659876)
			(xy 323.516685 -117.692819) (xy 323.464729 -117.718212) (xy 323.409537 -117.735474) (xy 323.352372 -117.74421)
			(xy 323.323458 -117.744748) (xy 323.296212 -117.744179) (xy 323.242274 -117.736418) (xy 323.18999 -117.721061)
			(xy 323.140423 -117.69842) (xy 323.094583 -117.668956) (xy 323.053402 -117.633268) (xy 323.017719 -117.592083)
			(xy 322.98826 -117.54624) (xy 322.965624 -117.496671) (xy 322.950273 -117.444385) (xy 322.942518 -117.390446)
			(xy 319.690496 -117.390446) (xy 319.690496 -117.682518) (xy 319.691004 -117.689122) (xy 319.692338 -117.697221)
			(xy 319.699464 -117.711994) (xy 319.704974 -117.718078) (xy 320.444876 -118.457726) (xy 320.454634 -118.467886)
			(xy 329.682346 -118.467886) (xy 329.686417 -118.412264) (xy 329.698543 -118.357827) (xy 329.718466 -118.305736)
			(xy 329.745762 -118.257101) (xy 329.779848 -118.212958) (xy 329.819997 -118.174249) (xy 329.865355 -118.141798)
			(xy 329.914955 -118.116297) (xy 329.967739 -118.09829) (xy 330.022582 -118.08816) (xy 330.078316 -118.086123)
			(xy 330.133753 -118.092223) (xy 330.18771 -118.106329) (xy 330.239039 -118.128141) (xy 330.286645 -118.157195)
			(xy 330.329513 -118.19287) (xy 330.36673 -118.234407) (xy 330.397503 -118.28092) (xy 330.421175 -118.331417)
			(xy 330.437243 -118.384824) (xy 330.445363 -118.44) (xy 330.445872 -118.467886) (xy 330.445363 -118.495772)
			(xy 330.437243 -118.550948) (xy 330.421175 -118.604355) (xy 330.397503 -118.654852) (xy 330.36673 -118.701365)
			(xy 330.329513 -118.742902) (xy 330.308679 -118.76024) (xy 334.764378 -118.76024) (xy 334.768449 -118.704618)
			(xy 334.780575 -118.650181) (xy 334.800498 -118.59809) (xy 334.827794 -118.549455) (xy 334.86188 -118.505312)
			(xy 334.902029 -118.466603) (xy 334.947387 -118.434152) (xy 334.996987 -118.408651) (xy 335.049771 -118.390644)
			(xy 335.104614 -118.380514) (xy 335.160348 -118.378477) (xy 335.215785 -118.384577) (xy 335.269742 -118.398683)
			(xy 335.321071 -118.420495) (xy 335.368677 -118.449549) (xy 335.411545 -118.485224) (xy 335.448762 -118.526761)
			(xy 335.479535 -118.573274) (xy 335.503207 -118.623771) (xy 335.519275 -118.677178) (xy 335.527395 -118.732354)
			(xy 335.527904 -118.76024) (xy 335.527395 -118.788126) (xy 335.519275 -118.843302) (xy 335.503207 -118.896709)
			(xy 335.479535 -118.947206) (xy 335.448762 -118.993719) (xy 335.411545 -119.035256) (xy 335.368677 -119.070931)
			(xy 335.321071 -119.099985) (xy 335.269742 -119.121797) (xy 335.215785 -119.135903) (xy 335.160348 -119.142003)
			(xy 335.104614 -119.139966) (xy 335.049771 -119.129836) (xy 334.996987 -119.111829) (xy 334.947387 -119.086328)
			(xy 334.902029 -119.053877) (xy 334.86188 -119.015168) (xy 334.827794 -118.971025) (xy 334.800498 -118.92239)
			(xy 334.780575 -118.870299) (xy 334.768449 -118.815862) (xy 334.764378 -118.76024) (xy 330.308679 -118.76024)
			(xy 330.286645 -118.778577) (xy 330.239039 -118.807631) (xy 330.18771 -118.829443) (xy 330.133753 -118.843549)
			(xy 330.078316 -118.849649) (xy 330.022582 -118.847612) (xy 329.967739 -118.837482) (xy 329.914955 -118.819475)
			(xy 329.865355 -118.793974) (xy 329.819997 -118.761523) (xy 329.779848 -118.722814) (xy 329.745762 -118.678671)
			(xy 329.718466 -118.630036) (xy 329.698543 -118.577945) (xy 329.686417 -118.523508) (xy 329.682346 -118.467886)
			(xy 320.454634 -118.467886) (xy 320.462906 -118.476498) (xy 320.49348 -118.518616) (xy 320.517101 -118.564992)
			(xy 320.533188 -118.614489) (xy 320.541346 -118.665892) (xy 320.541904 -118.691914) (xy 320.541904 -119.407557)
			(xy 326.699509 -119.407557) (xy 326.699509 -119.353043) (xy 326.707268 -119.299083) (xy 326.722627 -119.246777)
			(xy 326.745274 -119.197189) (xy 326.774748 -119.151329) (xy 326.810449 -119.11013) (xy 326.85165 -119.074432)
			(xy 326.897512 -119.044962) (xy 326.947101 -119.022318) (xy 326.999408 -119.006962) (xy 327.053369 -118.999207)
			(xy 327.080626 -118.998746) (xy 327.107997 -118.999186) (xy 327.162178 -119.007008) (xy 327.214682 -119.022503)
			(xy 327.264428 -119.045351) (xy 327.310394 -119.075082) (xy 327.331324 -119.092726) (xy 327.331578 -119.09298)
			(xy 327.33866 -119.098573) (xy 327.355581 -119.104814) (xy 327.364598 -119.105172) (xy 327.431654 -119.105172)
			(xy 327.440669 -119.104799) (xy 327.457587 -119.098563) (xy 327.464674 -119.09298) (xy 327.464674 -119.092726)
			(xy 327.464928 -119.092726) (xy 327.48588 -119.075111) (xy 327.531847 -119.045395) (xy 327.581589 -119.022554)
			(xy 327.634086 -119.007057) (xy 327.688258 -118.999223) (xy 327.715626 -118.998746) (xy 327.742873 -118.999326)
			(xy 327.796811 -119.007085) (xy 327.849096 -119.02244) (xy 327.898664 -119.04508) (xy 327.944506 -119.074543)
			(xy 327.985688 -119.11023) (xy 328.021372 -119.151415) (xy 328.050833 -119.197259) (xy 328.073469 -119.246828)
			(xy 328.088821 -119.299114) (xy 328.096576 -119.353053) (xy 328.096576 -119.407547) (xy 328.088821 -119.461486)
			(xy 328.084258 -119.477028) (xy 331.808072 -119.477028) (xy 331.812143 -119.421406) (xy 331.824269 -119.366969)
			(xy 331.844192 -119.314878) (xy 331.871488 -119.266243) (xy 331.905574 -119.2221) (xy 331.945723 -119.183391)
			(xy 331.991081 -119.15094) (xy 332.040681 -119.125439) (xy 332.093465 -119.107432) (xy 332.148308 -119.097302)
			(xy 332.204042 -119.095265) (xy 332.259479 -119.101365) (xy 332.313436 -119.115471) (xy 332.364765 -119.137283)
			(xy 332.412371 -119.166337) (xy 332.455239 -119.202012) (xy 332.492456 -119.243549) (xy 332.523229 -119.290062)
			(xy 332.546901 -119.340559) (xy 332.562969 -119.393966) (xy 332.571089 -119.449142) (xy 332.571598 -119.477028)
			(xy 332.571089 -119.504914) (xy 332.562969 -119.56009) (xy 332.546901 -119.613497) (xy 332.523229 -119.663994)
			(xy 332.492456 -119.710507) (xy 332.455239 -119.752044) (xy 332.426164 -119.77624) (xy 332.735934 -119.77624)
			(xy 332.740005 -119.720618) (xy 332.752131 -119.666181) (xy 332.772054 -119.61409) (xy 332.79935 -119.565455)
			(xy 332.833436 -119.521312) (xy 332.873585 -119.482603) (xy 332.918943 -119.450152) (xy 332.968543 -119.424651)
			(xy 333.021327 -119.406644) (xy 333.07617 -119.396514) (xy 333.131904 -119.394477) (xy 333.187341 -119.400577)
			(xy 333.241298 -119.414683) (xy 333.292627 -119.436495) (xy 333.340233 -119.465549) (xy 333.383101 -119.501224)
			(xy 333.420318 -119.542761) (xy 333.451091 -119.589274) (xy 333.474763 -119.639771) (xy 333.490831 -119.693178)
			(xy 333.494607 -119.718836) (xy 339.736428 -119.718836) (xy 339.740499 -119.663214) (xy 339.752625 -119.608777)
			(xy 339.772548 -119.556686) (xy 339.799844 -119.508051) (xy 339.83393 -119.463908) (xy 339.874079 -119.425199)
			(xy 339.919437 -119.392748) (xy 339.969037 -119.367247) (xy 340.021821 -119.34924) (xy 340.076664 -119.33911)
			(xy 340.132398 -119.337073) (xy 340.187835 -119.343173) (xy 340.241792 -119.357279) (xy 340.293121 -119.379091)
			(xy 340.340727 -119.408145) (xy 340.383595 -119.44382) (xy 340.420812 -119.485357) (xy 340.451585 -119.53187)
			(xy 340.475257 -119.582367) (xy 340.491325 -119.635774) (xy 340.499445 -119.69095) (xy 340.499954 -119.718836)
			(xy 340.499445 -119.746722) (xy 340.491325 -119.801898) (xy 340.475257 -119.855305) (xy 340.451585 -119.905802)
			(xy 340.420812 -119.952315) (xy 340.383595 -119.993852) (xy 340.340727 -120.029527) (xy 340.293121 -120.058581)
			(xy 340.241792 -120.080393) (xy 340.187835 -120.094499) (xy 340.132398 -120.100599) (xy 340.076664 -120.098562)
			(xy 340.021821 -120.088432) (xy 339.969037 -120.070425) (xy 339.919437 -120.044924) (xy 339.874079 -120.012473)
			(xy 339.83393 -119.973764) (xy 339.799844 -119.929621) (xy 339.772548 -119.880986) (xy 339.752625 -119.828895)
			(xy 339.740499 -119.774458) (xy 339.736428 -119.718836) (xy 333.494607 -119.718836) (xy 333.498951 -119.748354)
			(xy 333.49946 -119.77624) (xy 333.498951 -119.804126) (xy 333.490831 -119.859302) (xy 333.474763 -119.912709)
			(xy 333.451091 -119.963206) (xy 333.420318 -120.009719) (xy 333.383101 -120.051256) (xy 333.340233 -120.086931)
			(xy 333.292627 -120.115985) (xy 333.241298 -120.137797) (xy 333.187341 -120.151903) (xy 333.131904 -120.158003)
			(xy 333.07617 -120.155966) (xy 333.021327 -120.145836) (xy 332.968543 -120.127829) (xy 332.918943 -120.102328)
			(xy 332.873585 -120.069877) (xy 332.833436 -120.031168) (xy 332.79935 -119.987025) (xy 332.772054 -119.93839)
			(xy 332.752131 -119.886299) (xy 332.740005 -119.831862) (xy 332.735934 -119.77624) (xy 332.426164 -119.77624)
			(xy 332.412371 -119.787719) (xy 332.364765 -119.816773) (xy 332.313436 -119.838585) (xy 332.259479 -119.852691)
			(xy 332.204042 -119.858791) (xy 332.148308 -119.856754) (xy 332.093465 -119.846624) (xy 332.040681 -119.828617)
			(xy 331.991081 -119.803116) (xy 331.945723 -119.770665) (xy 331.905574 -119.731956) (xy 331.871488 -119.687813)
			(xy 331.844192 -119.639178) (xy 331.824269 -119.587087) (xy 331.812143 -119.53265) (xy 331.808072 -119.477028)
			(xy 328.084258 -119.477028) (xy 328.073469 -119.513772) (xy 328.050833 -119.563341) (xy 328.021372 -119.609185)
			(xy 327.985688 -119.65037) (xy 327.944506 -119.686057) (xy 327.898664 -119.71552) (xy 327.849096 -119.73816)
			(xy 327.796811 -119.753515) (xy 327.742873 -119.761274) (xy 327.715626 -119.761762) (xy 327.688256 -119.76129)
			(xy 327.634077 -119.753475) (xy 327.581573 -119.737988) (xy 327.531826 -119.715147) (xy 327.48586 -119.685423)
			(xy 327.464928 -119.667782) (xy 327.464674 -119.667528) (xy 327.457577 -119.661958) (xy 327.440668 -119.655703)
			(xy 327.431654 -119.655336) (xy 327.364598 -119.655336) (xy 327.35558 -119.655684) (xy 327.338663 -119.661937)
			(xy 327.331578 -119.667528) (xy 327.331578 -119.667782) (xy 327.331324 -119.667782) (xy 327.310391 -119.685421)
			(xy 327.264419 -119.715133) (xy 327.214672 -119.737969) (xy 327.162171 -119.753461) (xy 327.107995 -119.761288)
			(xy 327.080626 -119.761762) (xy 327.053369 -119.761393) (xy 326.999408 -119.753638) (xy 326.947101 -119.738282)
			(xy 326.897512 -119.715638) (xy 326.85165 -119.686168) (xy 326.810449 -119.65047) (xy 326.774748 -119.609271)
			(xy 326.745274 -119.563411) (xy 326.722627 -119.513823) (xy 326.707268 -119.461517) (xy 326.699509 -119.407557)
			(xy 320.541904 -119.407557) (xy 320.541904 -119.89308) (xy 329.76896 -119.89308) (xy 329.773031 -119.837458)
			(xy 329.785157 -119.783021) (xy 329.80508 -119.73093) (xy 329.832376 -119.682295) (xy 329.866462 -119.638152)
			(xy 329.906611 -119.599443) (xy 329.951969 -119.566992) (xy 330.001569 -119.541491) (xy 330.054353 -119.523484)
			(xy 330.109196 -119.513354) (xy 330.16493 -119.511317) (xy 330.220367 -119.517417) (xy 330.274324 -119.531523)
			(xy 330.325653 -119.553335) (xy 330.373259 -119.582389) (xy 330.416127 -119.618064) (xy 330.453344 -119.659601)
			(xy 330.484117 -119.706114) (xy 330.507789 -119.756611) (xy 330.523857 -119.810018) (xy 330.531977 -119.865194)
			(xy 330.532486 -119.89308) (xy 330.531977 -119.920966) (xy 330.523857 -119.976142) (xy 330.507789 -120.029549)
			(xy 330.484117 -120.080046) (xy 330.453344 -120.126559) (xy 330.416127 -120.168096) (xy 330.373259 -120.203771)
			(xy 330.325653 -120.232825) (xy 330.274324 -120.254637) (xy 330.220367 -120.268743) (xy 330.16493 -120.274843)
			(xy 330.109196 -120.272806) (xy 330.054353 -120.262676) (xy 330.001569 -120.244669) (xy 329.951969 -120.219168)
			(xy 329.906611 -120.186717) (xy 329.866462 -120.148008) (xy 329.832376 -120.103865) (xy 329.80508 -120.05523)
			(xy 329.785157 -120.003139) (xy 329.773031 -119.948702) (xy 329.76896 -119.89308) (xy 320.541904 -119.89308)
			(xy 320.541904 -122.192034) (xy 321.650614 -122.192034) (xy 321.651097 -122.164664) (xy 321.65891 -122.110486)
			(xy 321.674395 -122.057983) (xy 321.697233 -122.008236) (xy 321.726954 -121.962268) (xy 321.744594 -121.941336)
			(xy 321.744848 -121.941082) (xy 321.750454 -121.934009) (xy 321.756688 -121.917082) (xy 321.75704 -121.908062)
			(xy 321.75704 -121.841006) (xy 321.756693 -121.831988) (xy 321.75044 -121.81507) (xy 321.744848 -121.807986)
			(xy 321.744594 -121.807986) (xy 321.744594 -121.807732) (xy 321.726988 -121.786772) (xy 321.697264 -121.740808)
			(xy 321.674419 -121.691066) (xy 321.658922 -121.638568) (xy 321.65109 -121.584394) (xy 321.651087 -121.529657)
			(xy 321.658911 -121.475482) (xy 321.674401 -121.422982) (xy 321.69724 -121.373237) (xy 321.726957 -121.327269)
			(xy 321.744594 -121.306336) (xy 321.744848 -121.306082) (xy 321.750454 -121.299009) (xy 321.756688 -121.282082)
			(xy 321.75704 -121.273062) (xy 321.75704 -121.206006) (xy 321.756693 -121.196988) (xy 321.75044 -121.18007)
			(xy 321.744848 -121.172986) (xy 321.744594 -121.172986) (xy 321.744594 -121.172732) (xy 321.726988 -121.151772)
			(xy 321.697264 -121.105808) (xy 321.674419 -121.056066) (xy 321.658922 -121.003568) (xy 321.65109 -120.949394)
			(xy 321.651087 -120.894657) (xy 321.658911 -120.840482) (xy 321.674401 -120.787982) (xy 321.69724 -120.738237)
			(xy 321.726957 -120.692269) (xy 321.744594 -120.671336) (xy 321.744848 -120.671082) (xy 321.750454 -120.664009)
			(xy 321.756688 -120.647082) (xy 321.75704 -120.638062) (xy 321.75704 -120.571006) (xy 321.756693 -120.561988)
			(xy 321.75044 -120.54507) (xy 321.744848 -120.537986) (xy 321.744594 -120.537986) (xy 321.744594 -120.537732)
			(xy 321.726956 -120.516799) (xy 321.697244 -120.470827) (xy 321.674408 -120.421079) (xy 321.658917 -120.368579)
			(xy 321.651088 -120.314403) (xy 321.650614 -120.287034) (xy 321.6511 -120.259783) (xy 321.658856 -120.205835)
			(xy 321.674211 -120.15354) (xy 321.696853 -120.103963) (xy 321.726319 -120.058113) (xy 321.76201 -120.016922)
			(xy 321.803201 -119.981231) (xy 321.849051 -119.951765) (xy 321.898628 -119.929123) (xy 321.950923 -119.913768)
			(xy 322.004871 -119.906012) (xy 322.059373 -119.906012) (xy 322.113321 -119.913768) (xy 322.165616 -119.929123)
			(xy 322.215193 -119.951765) (xy 322.261043 -119.981231) (xy 322.302234 -120.016922) (xy 322.337925 -120.058113)
			(xy 322.367391 -120.103963) (xy 322.390033 -120.15354) (xy 322.405388 -120.205835) (xy 322.413144 -120.259783)
			(xy 322.41363 -120.287034) (xy 322.413201 -120.314406) (xy 322.405377 -120.368587) (xy 322.38988 -120.421091)
			(xy 322.36703 -120.470838) (xy 322.352675 -120.493028) (xy 331.804008 -120.493028) (xy 331.808079 -120.437406)
			(xy 331.820205 -120.382969) (xy 331.840128 -120.330878) (xy 331.867424 -120.282243) (xy 331.90151 -120.2381)
			(xy 331.941659 -120.199391) (xy 331.987017 -120.16694) (xy 332.036617 -120.141439) (xy 332.089401 -120.123432)
			(xy 332.144244 -120.113302) (xy 332.199978 -120.111265) (xy 332.255415 -120.117365) (xy 332.309372 -120.131471)
			(xy 332.360701 -120.153283) (xy 332.408307 -120.182337) (xy 332.451175 -120.218012) (xy 332.488392 -120.259549)
			(xy 332.519165 -120.306062) (xy 332.542837 -120.356559) (xy 332.558905 -120.409966) (xy 332.567025 -120.465142)
			(xy 332.567534 -120.493028) (xy 332.567025 -120.520914) (xy 332.558905 -120.57609) (xy 332.542837 -120.629497)
			(xy 332.519165 -120.679994) (xy 332.488392 -120.726507) (xy 332.451175 -120.768044) (xy 332.4221 -120.79224)
			(xy 332.735934 -120.79224) (xy 332.740005 -120.736618) (xy 332.752131 -120.682181) (xy 332.772054 -120.63009)
			(xy 332.79935 -120.581455) (xy 332.833436 -120.537312) (xy 332.873585 -120.498603) (xy 332.918943 -120.466152)
			(xy 332.968543 -120.440651) (xy 333.021327 -120.422644) (xy 333.07617 -120.412514) (xy 333.131904 -120.410477)
			(xy 333.187341 -120.416577) (xy 333.241298 -120.430683) (xy 333.292627 -120.452495) (xy 333.340233 -120.481549)
			(xy 333.383101 -120.517224) (xy 333.420318 -120.558761) (xy 333.451091 -120.605274) (xy 333.474763 -120.655771)
			(xy 333.490831 -120.709178) (xy 333.498951 -120.764354) (xy 333.49946 -120.79224) (xy 334.891378 -120.79224)
			(xy 334.895449 -120.736618) (xy 334.907575 -120.682181) (xy 334.927498 -120.63009) (xy 334.954794 -120.581455)
			(xy 334.98888 -120.537312) (xy 335.029029 -120.498603) (xy 335.074387 -120.466152) (xy 335.123987 -120.440651)
			(xy 335.176771 -120.422644) (xy 335.231614 -120.412514) (xy 335.287348 -120.410477) (xy 335.342785 -120.416577)
			(xy 335.396742 -120.430683) (xy 335.448071 -120.452495) (xy 335.495677 -120.481549) (xy 335.538545 -120.517224)
			(xy 335.546679 -120.526302) (xy 338.193378 -120.526302) (xy 338.197449 -120.47068) (xy 338.209575 -120.416243)
			(xy 338.229498 -120.364152) (xy 338.256794 -120.315517) (xy 338.29088 -120.271374) (xy 338.331029 -120.232665)
			(xy 338.376387 -120.200214) (xy 338.425987 -120.174713) (xy 338.478771 -120.156706) (xy 338.533614 -120.146576)
			(xy 338.589348 -120.144539) (xy 338.644785 -120.150639) (xy 338.698742 -120.164745) (xy 338.750071 -120.186557)
			(xy 338.797677 -120.215611) (xy 338.840545 -120.251286) (xy 338.877762 -120.292823) (xy 338.908535 -120.339336)
			(xy 338.932207 -120.389833) (xy 338.948275 -120.44324) (xy 338.956395 -120.498416) (xy 338.956904 -120.526302)
			(xy 338.956395 -120.554188) (xy 338.948275 -120.609364) (xy 338.932207 -120.662771) (xy 338.908535 -120.713268)
			(xy 338.877762 -120.759781) (xy 338.840545 -120.801318) (xy 338.797677 -120.836993) (xy 338.750071 -120.866047)
			(xy 338.698742 -120.887859) (xy 338.644785 -120.901965) (xy 338.589348 -120.908065) (xy 338.533614 -120.906028)
			(xy 338.478771 -120.895898) (xy 338.425987 -120.877891) (xy 338.376387 -120.85239) (xy 338.331029 -120.819939)
			(xy 338.29088 -120.78123) (xy 338.256794 -120.737087) (xy 338.229498 -120.688452) (xy 338.209575 -120.636361)
			(xy 338.197449 -120.581924) (xy 338.193378 -120.526302) (xy 335.546679 -120.526302) (xy 335.575762 -120.558761)
			(xy 335.606535 -120.605274) (xy 335.630207 -120.655771) (xy 335.646275 -120.709178) (xy 335.654395 -120.764354)
			(xy 335.654904 -120.79224) (xy 335.654395 -120.820126) (xy 335.646275 -120.875302) (xy 335.630207 -120.928709)
			(xy 335.606535 -120.979206) (xy 335.575762 -121.025719) (xy 335.538545 -121.067256) (xy 335.495677 -121.102931)
			(xy 335.448071 -121.131985) (xy 335.396742 -121.153797) (xy 335.342785 -121.167903) (xy 335.287348 -121.174003)
			(xy 335.231614 -121.171966) (xy 335.176771 -121.161836) (xy 335.123987 -121.143829) (xy 335.074387 -121.118328)
			(xy 335.029029 -121.085877) (xy 334.98888 -121.047168) (xy 334.954794 -121.003025) (xy 334.927498 -120.95439)
			(xy 334.907575 -120.902299) (xy 334.895449 -120.847862) (xy 334.891378 -120.79224) (xy 333.49946 -120.79224)
			(xy 333.498951 -120.820126) (xy 333.490831 -120.875302) (xy 333.474763 -120.928709) (xy 333.451091 -120.979206)
			(xy 333.420318 -121.025719) (xy 333.383101 -121.067256) (xy 333.340233 -121.102931) (xy 333.292627 -121.131985)
			(xy 333.241298 -121.153797) (xy 333.187341 -121.167903) (xy 333.131904 -121.174003) (xy 333.07617 -121.171966)
			(xy 333.021327 -121.161836) (xy 332.968543 -121.143829) (xy 332.918943 -121.118328) (xy 332.873585 -121.085877)
			(xy 332.833436 -121.047168) (xy 332.79935 -121.003025) (xy 332.772054 -120.95439) (xy 332.752131 -120.902299)
			(xy 332.740005 -120.847862) (xy 332.735934 -120.79224) (xy 332.4221 -120.79224) (xy 332.408307 -120.803719)
			(xy 332.360701 -120.832773) (xy 332.309372 -120.854585) (xy 332.255415 -120.868691) (xy 332.199978 -120.874791)
			(xy 332.144244 -120.872754) (xy 332.089401 -120.862624) (xy 332.036617 -120.844617) (xy 331.987017 -120.819116)
			(xy 331.941659 -120.786665) (xy 331.90151 -120.747956) (xy 331.867424 -120.703813) (xy 331.840128 -120.655178)
			(xy 331.820205 -120.603087) (xy 331.808079 -120.54865) (xy 331.804008 -120.493028) (xy 322.352675 -120.493028)
			(xy 322.337296 -120.516802) (xy 322.31965 -120.537732) (xy 322.319396 -120.537986) (xy 322.313809 -120.545072)
			(xy 322.307563 -120.561989) (xy 322.307204 -120.571006) (xy 322.307204 -120.638062) (xy 322.307579 -120.647077)
			(xy 322.313814 -120.663994) (xy 322.319396 -120.671082) (xy 322.31965 -120.671082) (xy 322.31965 -120.671336)
			(xy 322.337325 -120.692241) (xy 322.36705 -120.738213) (xy 322.389895 -120.787964) (xy 322.40539 -120.84047)
			(xy 322.413215 -120.894653) (xy 322.413212 -120.949398) (xy 322.405379 -121.00358) (xy 322.389877 -121.056084)
			(xy 322.367025 -121.105832) (xy 322.337294 -121.1518) (xy 322.31965 -121.172732) (xy 322.319396 -121.172986)
			(xy 322.313809 -121.180072) (xy 322.307563 -121.196989) (xy 322.307493 -121.198756) (xy 322.685317 -121.198756)
			(xy 322.685317 -121.144244) (xy 322.693075 -121.090287) (xy 322.708433 -121.037983) (xy 322.731079 -120.988397)
			(xy 322.76055 -120.942539) (xy 322.796249 -120.901342) (xy 322.837447 -120.865644) (xy 322.883306 -120.836174)
			(xy 322.932892 -120.81353) (xy 322.985196 -120.798173) (xy 323.039154 -120.790416) (xy 323.06641 -120.789954)
			(xy 323.093781 -120.790401) (xy 323.147962 -120.798221) (xy 323.200465 -120.813714) (xy 323.250212 -120.836561)
			(xy 323.296177 -120.86629) (xy 323.317108 -120.883934) (xy 323.317362 -120.884188) (xy 323.324456 -120.889763)
			(xy 323.341367 -120.896017) (xy 323.350382 -120.89638) (xy 323.417438 -120.89638) (xy 323.426457 -120.896045)
			(xy 323.443374 -120.889783) (xy 323.450458 -120.884188) (xy 323.450458 -120.883934) (xy 323.450712 -120.883934)
			(xy 323.471671 -120.866328) (xy 323.517636 -120.83661) (xy 323.567376 -120.813767) (xy 323.619871 -120.798268)
			(xy 323.674043 -120.790432) (xy 323.70141 -120.789954) (xy 323.728658 -120.790517) (xy 323.782599 -120.798274)
			(xy 323.834888 -120.813628) (xy 323.884458 -120.836268) (xy 323.930303 -120.865731) (xy 323.971488 -120.901419)
			(xy 324.007175 -120.942605) (xy 324.036637 -120.98845) (xy 324.059275 -121.038022) (xy 324.074628 -121.090311)
			(xy 324.082384 -121.144252) (xy 324.082384 -121.198748) (xy 324.074628 -121.252689) (xy 324.059275 -121.304978)
			(xy 324.036637 -121.35455) (xy 324.007175 -121.400395) (xy 323.971488 -121.441581) (xy 323.930303 -121.477269)
			(xy 323.884458 -121.506732) (xy 323.834888 -121.529372) (xy 323.782599 -121.544726) (xy 323.728658 -121.552483)
			(xy 323.70141 -121.55297) (xy 323.67404 -121.552505) (xy 323.61986 -121.544688) (xy 323.567357 -121.529199)
			(xy 323.51761 -121.506357) (xy 323.471643 -121.476632) (xy 323.450712 -121.45899) (xy 323.450458 -121.458736)
			(xy 323.443364 -121.45316) (xy 323.426453 -121.446909) (xy 323.417438 -121.446544) (xy 323.350382 -121.446544)
			(xy 323.341363 -121.446883) (xy 323.324446 -121.453142) (xy 323.317362 -121.458736) (xy 323.317362 -121.45899)
			(xy 323.317108 -121.45899) (xy 323.296182 -121.476637) (xy 323.250208 -121.506348) (xy 323.200459 -121.529183)
			(xy 323.147957 -121.544672) (xy 323.09378 -121.552497) (xy 323.06641 -121.55297) (xy 323.039154 -121.552584)
			(xy 322.985197 -121.544827) (xy 322.932892 -121.52947) (xy 322.883306 -121.506826) (xy 322.837447 -121.477356)
			(xy 322.796249 -121.441658) (xy 322.76055 -121.400461) (xy 322.731079 -121.354603) (xy 322.708433 -121.305017)
			(xy 322.693075 -121.252713) (xy 322.685317 -121.198756) (xy 322.307493 -121.198756) (xy 322.307204 -121.206006)
			(xy 322.307204 -121.273062) (xy 322.307579 -121.282077) (xy 322.313814 -121.298994) (xy 322.319396 -121.306082)
			(xy 322.31965 -121.306082) (xy 322.31965 -121.306336) (xy 322.337325 -121.327241) (xy 322.36705 -121.373213)
			(xy 322.389895 -121.422964) (xy 322.40539 -121.47547) (xy 322.413215 -121.529653) (xy 322.413212 -121.584398)
			(xy 322.405968 -121.634504) (xy 324.20433 -121.634504) (xy 324.204791 -121.607134) (xy 324.212609 -121.552954)
			(xy 324.228099 -121.50045) (xy 324.250942 -121.450704) (xy 324.280668 -121.404737) (xy 324.29831 -121.383806)
			(xy 324.298564 -121.383552) (xy 324.304143 -121.37646) (xy 324.310392 -121.359547) (xy 324.310756 -121.350532)
			(xy 324.310756 -121.283476) (xy 324.31042 -121.274457) (xy 324.304159 -121.257539) (xy 324.298564 -121.250456)
			(xy 324.29831 -121.250456) (xy 324.29831 -121.250202) (xy 324.28066 -121.229279) (xy 324.250949 -121.183304)
			(xy 324.228115 -121.133554) (xy 324.212627 -121.081051) (xy 324.204802 -121.026874) (xy 324.20433 -120.999504)
			(xy 324.204759 -120.97225) (xy 324.212517 -120.918295) (xy 324.227874 -120.865995) (xy 324.250519 -120.816412)
			(xy 324.27999 -120.770557) (xy 324.315687 -120.729363) (xy 324.356884 -120.69367) (xy 324.402742 -120.664203)
			(xy 324.452326 -120.641562) (xy 324.504629 -120.626209) (xy 324.558583 -120.618457) (xy 324.585838 -120.617996)
			(xy 324.61496 -120.618546) (xy 324.672531 -120.627378) (xy 324.72809 -120.64486) (xy 324.780344 -120.670586)
			(xy 324.82808 -120.703959) (xy 324.870186 -120.744201) (xy 324.905684 -120.790378) (xy 324.933748 -120.841415)
			(xy 324.953726 -120.896126) (xy 324.95998 -120.924574) (xy 324.962266 -120.936258) (xy 324.976744 -120.955054)
			(xy 325.060818 -120.99544) (xy 325.071632 -121.000003) (xy 325.095071 -120.999743) (xy 325.105776 -120.994932)
			(xy 325.106284 -120.994932) (xy 325.13334 -120.981644) (xy 325.190617 -120.962868) (xy 325.250136 -120.953351)
			(xy 325.280274 -120.952768) (xy 325.307525 -120.953279) (xy 325.361473 -120.961032) (xy 325.413769 -120.976384)
			(xy 325.463347 -120.999021) (xy 325.509199 -121.028485) (xy 325.550391 -121.064173) (xy 325.586085 -121.105361)
			(xy 325.615555 -121.151209) (xy 325.638199 -121.200785) (xy 325.649355 -121.238772) (xy 329.7842 -121.238772)
			(xy 329.788271 -121.18315) (xy 329.800397 -121.128713) (xy 329.82032 -121.076622) (xy 329.847616 -121.027987)
			(xy 329.881702 -120.983844) (xy 329.921851 -120.945135) (xy 329.967209 -120.912684) (xy 330.016809 -120.887183)
			(xy 330.069593 -120.869176) (xy 330.124436 -120.859046) (xy 330.18017 -120.857009) (xy 330.235607 -120.863109)
			(xy 330.289564 -120.877215) (xy 330.340893 -120.899027) (xy 330.388499 -120.928081) (xy 330.431367 -120.963756)
			(xy 330.468584 -121.005293) (xy 330.499357 -121.051806) (xy 330.523029 -121.102303) (xy 330.539097 -121.15571)
			(xy 330.547217 -121.210886) (xy 330.547726 -121.238772) (xy 330.547217 -121.266658) (xy 330.539097 -121.321834)
			(xy 330.523029 -121.375241) (xy 330.499357 -121.425738) (xy 330.468584 -121.472251) (xy 330.431367 -121.513788)
			(xy 330.388499 -121.549463) (xy 330.340893 -121.578517) (xy 330.289564 -121.600329) (xy 330.235607 -121.614435)
			(xy 330.18017 -121.620535) (xy 330.124436 -121.618498) (xy 330.069593 -121.608368) (xy 330.016809 -121.590361)
			(xy 329.967209 -121.56486) (xy 329.921851 -121.532409) (xy 329.881702 -121.4937) (xy 329.847616 -121.449557)
			(xy 329.82032 -121.400922) (xy 329.800397 -121.348831) (xy 329.788271 -121.294394) (xy 329.7842 -121.238772)
			(xy 325.649355 -121.238772) (xy 325.653557 -121.253078) (xy 325.661317 -121.307025) (xy 325.661782 -121.334276)
			(xy 325.661306 -121.361646) (xy 325.653491 -121.415825) (xy 325.638005 -121.468328) (xy 325.615165 -121.518075)
			(xy 325.585442 -121.564042) (xy 325.567802 -121.584974) (xy 325.567548 -121.585228) (xy 325.561979 -121.592327)
			(xy 325.555723 -121.609234) (xy 325.555356 -121.618248) (xy 325.555356 -121.685304) (xy 325.555699 -121.694323)
			(xy 325.561955 -121.71124) (xy 325.567548 -121.718324) (xy 325.567802 -121.718324) (xy 325.567802 -121.718578)
			(xy 325.585445 -121.739507) (xy 325.615156 -121.785481) (xy 325.637991 -121.835229) (xy 325.653481 -121.88773)
			(xy 325.661309 -121.941907) (xy 325.661782 -121.969276) (xy 325.661322 -121.996529) (xy 325.653568 -122.050482)
			(xy 325.638214 -122.102781) (xy 325.615572 -122.152363) (xy 325.586104 -122.198218) (xy 325.55041 -122.239411)
			(xy 325.509216 -122.275105) (xy 325.463361 -122.304573) (xy 325.413779 -122.327214) (xy 325.36148 -122.342568)
			(xy 325.307527 -122.350322) (xy 325.280274 -122.350784) (xy 325.251151 -122.350239) (xy 325.193579 -122.341409)
			(xy 325.13802 -122.323927) (xy 325.085764 -122.2982) (xy 325.038028 -122.264827) (xy 324.995922 -122.224584)
			(xy 324.960424 -122.178406) (xy 324.932361 -122.127367) (xy 324.912385 -122.072655) (xy 324.906132 -122.044206)
			(xy 324.903846 -122.032522) (xy 324.889368 -122.013726) (xy 324.805294 -121.97334) (xy 324.794479 -121.968779)
			(xy 324.77104 -121.969034) (xy 324.760336 -121.973848) (xy 324.759828 -121.973848) (xy 324.732769 -121.98713)
			(xy 324.675494 -122.005909) (xy 324.615975 -122.015428) (xy 324.585838 -122.016012) (xy 324.558586 -122.015509)
			(xy 324.504637 -122.007758) (xy 324.45234 -121.992407) (xy 324.40276 -121.969769) (xy 324.356907 -121.940305)
			(xy 324.315714 -121.904616) (xy 324.28002 -121.863426) (xy 324.250551 -121.817577) (xy 324.227908 -121.767999)
			(xy 324.212551 -121.715704) (xy 324.204794 -121.661756) (xy 324.20433 -121.634504) (xy 322.405968 -121.634504)
			(xy 322.405379 -121.63858) (xy 322.389877 -121.691084) (xy 322.367025 -121.740832) (xy 322.337294 -121.7868)
			(xy 322.31965 -121.807732) (xy 322.319396 -121.807986) (xy 322.313809 -121.815072) (xy 322.307563 -121.831989)
			(xy 322.307204 -121.841006) (xy 322.307204 -121.908062) (xy 322.307579 -121.917077) (xy 322.313814 -121.933994)
			(xy 322.319396 -121.941082) (xy 322.31965 -121.941082) (xy 322.31965 -121.941336) (xy 322.337265 -121.962288)
			(xy 322.366982 -122.008254) (xy 322.389823 -122.057997) (xy 322.40532 -122.110493) (xy 322.413153 -122.164666)
			(xy 322.41363 -122.192034) (xy 322.413144 -122.219285) (xy 322.405388 -122.273233) (xy 322.390033 -122.325528)
			(xy 322.367391 -122.375105) (xy 322.337925 -122.420955) (xy 322.302234 -122.462146) (xy 322.261043 -122.497837)
			(xy 322.215193 -122.527303) (xy 322.165616 -122.549945) (xy 322.113321 -122.5653) (xy 322.059373 -122.573056)
			(xy 322.004871 -122.573056) (xy 321.950923 -122.5653) (xy 321.898628 -122.549945) (xy 321.849051 -122.527303)
			(xy 321.803201 -122.497837) (xy 321.76201 -122.462146) (xy 321.726319 -122.420955) (xy 321.696853 -122.375105)
			(xy 321.674211 -122.325528) (xy 321.658856 -122.273233) (xy 321.6511 -122.219285) (xy 321.650614 -122.192034)
			(xy 320.541904 -122.192034) (xy 320.541904 -123.364548) (xy 326.264298 -123.364548) (xy 326.264298 -123.310052)
			(xy 326.272053 -123.256109) (xy 326.287406 -123.20382) (xy 326.310044 -123.154247) (xy 326.339506 -123.108401)
			(xy 326.375192 -123.067214) (xy 326.416377 -123.031524) (xy 326.462221 -123.002058) (xy 326.511792 -122.979417)
			(xy 326.56408 -122.96406) (xy 326.618022 -122.9563) (xy 326.64527 -122.955812) (xy 326.67264 -122.956293)
			(xy 326.726818 -122.964107) (xy 326.779321 -122.979592) (xy 326.829068 -123.002431) (xy 326.875036 -123.032152)
			(xy 326.895968 -123.049792) (xy 326.896222 -123.050046) (xy 326.903294 -123.055653) (xy 326.920222 -123.061886)
			(xy 326.929242 -123.062238) (xy 326.996298 -123.062238) (xy 327.005314 -123.061872) (xy 327.02223 -123.055629)
			(xy 327.029318 -123.050046) (xy 327.029318 -123.049792) (xy 327.029572 -123.049792) (xy 327.050505 -123.032151)
			(xy 327.096473 -123.002427) (xy 327.146219 -122.979581) (xy 327.198721 -122.964085) (xy 327.252899 -122.956256)
			(xy 327.307641 -122.956256) (xy 327.361819 -122.964085) (xy 327.414321 -122.979581) (xy 327.464067 -123.002427)
			(xy 327.510035 -123.032151) (xy 327.530968 -123.049792) (xy 327.531222 -123.050046) (xy 327.538294 -123.055653)
			(xy 327.555222 -123.061886) (xy 327.564242 -123.062238) (xy 327.631298 -123.062238) (xy 327.640314 -123.061872)
			(xy 327.65723 -123.055629) (xy 327.664318 -123.050046) (xy 327.664318 -123.049792) (xy 327.664572 -123.049792)
			(xy 327.685503 -123.032151) (xy 327.731476 -123.00244) (xy 327.781224 -122.979604) (xy 327.833725 -122.964114)
			(xy 327.887901 -122.956286) (xy 327.91527 -122.955812) (xy 327.942526 -122.956233) (xy 327.996483 -122.963987)
			(xy 328.048787 -122.979341) (xy 328.098374 -123.001983) (xy 328.144233 -123.031452) (xy 328.185431 -123.067147)
			(xy 328.22113 -123.108343) (xy 328.250603 -123.1542) (xy 328.273248 -123.203785) (xy 328.288607 -123.256088)
			(xy 328.296365 -123.310044) (xy 328.296365 -123.364556) (xy 328.288607 -123.418512) (xy 328.273248 -123.470815)
			(xy 328.250603 -123.5204) (xy 328.22113 -123.566257) (xy 328.185431 -123.607453) (xy 328.144233 -123.643148)
			(xy 328.098374 -123.672617) (xy 328.048787 -123.695259) (xy 327.996483 -123.710613) (xy 327.942526 -123.718367)
			(xy 327.91527 -123.718828) (xy 327.887898 -123.718397) (xy 327.833717 -123.710573) (xy 327.781213 -123.695077)
			(xy 327.731466 -123.672227) (xy 327.685502 -123.642494) (xy 327.664572 -123.624848) (xy 327.664318 -123.624594)
			(xy 327.657231 -123.619008) (xy 327.640315 -123.612761) (xy 327.631298 -123.612402) (xy 327.564242 -123.612402)
			(xy 327.555227 -123.612779) (xy 327.53831 -123.619013) (xy 327.531222 -123.624594) (xy 327.530968 -123.624848)
			(xy 327.510035 -123.642489) (xy 327.464067 -123.672213) (xy 327.414321 -123.695059) (xy 327.361819 -123.710555)
			(xy 327.307641 -123.718384) (xy 327.252899 -123.718384) (xy 327.198721 -123.710555) (xy 327.146219 -123.695059)
			(xy 327.096473 -123.672213) (xy 327.050505 -123.642489) (xy 327.029572 -123.624848) (xy 327.029318 -123.624594)
			(xy 327.022231 -123.619008) (xy 327.005315 -123.612761) (xy 326.996298 -123.612402) (xy 326.929242 -123.612402)
			(xy 326.920227 -123.612779) (xy 326.90331 -123.619013) (xy 326.896222 -123.624594) (xy 326.896222 -123.624848)
			(xy 326.895968 -123.624848) (xy 326.875014 -123.642461) (xy 326.829048 -123.672178) (xy 326.779306 -123.69502)
			(xy 326.72681 -123.710517) (xy 326.672638 -123.718351) (xy 326.64527 -123.718828) (xy 326.618022 -123.7183)
			(xy 326.56408 -123.71054) (xy 326.511792 -123.695183) (xy 326.462221 -123.672542) (xy 326.416377 -123.643076)
			(xy 326.375192 -123.607386) (xy 326.339506 -123.566199) (xy 326.310044 -123.520353) (xy 326.287406 -123.47078)
			(xy 326.272053 -123.418491) (xy 326.264298 -123.364548) (xy 320.541904 -123.364548) (xy 320.541904 -123.822229)
			(xy 329.642205 -123.822229) (xy 329.642208 -123.767731) (xy 329.649966 -123.713788) (xy 329.665323 -123.661498)
			(xy 329.687965 -123.611926) (xy 329.717431 -123.566081) (xy 329.753121 -123.524896) (xy 329.79431 -123.489209)
			(xy 329.840158 -123.459747) (xy 329.889732 -123.43711) (xy 329.942023 -123.421759) (xy 329.995967 -123.414005)
			(xy 330.023216 -123.41352) (xy 330.023724 -123.41352) (xy 330.034096 -123.4136) (xy 330.054808 -123.414744)
			(xy 330.065126 -123.415806) (xy 330.079675 -123.416857) (xy 330.108365 -123.411664) (xy 330.134422 -123.398584)
			(xy 330.155726 -123.378679) (xy 330.170544 -123.35357) (xy 330.177672 -123.325299) (xy 330.176529 -123.296165)
			(xy 330.172314 -123.282202) (xy 330.162954 -123.252595) (xy 330.152876 -123.191327) (xy 330.152248 -123.160282)
			(xy 330.152248 -123.160028) (xy 330.152725 -123.132772) (xy 330.160479 -123.078814) (xy 330.175834 -123.02651)
			(xy 330.198476 -122.976922) (xy 330.227945 -122.931063) (xy 330.263641 -122.889864) (xy 330.304837 -122.854164)
			(xy 330.350694 -122.824691) (xy 330.40028 -122.802045) (xy 330.452583 -122.786686) (xy 330.50654 -122.778927)
			(xy 330.561052 -122.778927) (xy 330.615009 -122.786684) (xy 330.667313 -122.802042) (xy 330.716899 -122.824688)
			(xy 330.762757 -122.85416) (xy 330.803953 -122.889858) (xy 330.83965 -122.931056) (xy 330.86912 -122.976915)
			(xy 330.891763 -123.026502) (xy 330.907119 -123.078807) (xy 330.914874 -123.132764) (xy 330.914872 -123.187276)
			(xy 330.907111 -123.241233) (xy 330.891749 -123.293535) (xy 330.869101 -123.34312) (xy 330.839626 -123.388976)
			(xy 330.803925 -123.43017) (xy 330.762725 -123.465864) (xy 330.716863 -123.495332) (xy 330.667275 -123.517972)
			(xy 330.61497 -123.533324) (xy 330.561012 -123.541076) (xy 330.533756 -123.541536) (xy 330.533248 -123.541536)
			(xy 330.522876 -123.541459) (xy 330.502164 -123.540313) (xy 330.491846 -123.53925) (xy 330.477298 -123.538232)
			(xy 330.448617 -123.543429) (xy 330.422569 -123.556508) (xy 330.40127 -123.576406) (xy 330.386452 -123.601506)
			(xy 330.379319 -123.629767) (xy 330.380451 -123.658893) (xy 330.384658 -123.672854) (xy 330.39401 -123.702463)
			(xy 330.404093 -123.763729) (xy 330.404724 -123.794774) (xy 330.404724 -123.795028) (xy 330.404192 -123.822277)
			(xy 330.396432 -123.87622) (xy 330.381074 -123.928509) (xy 330.358432 -123.978081) (xy 330.328965 -124.023925)
			(xy 330.293273 -124.06511) (xy 330.252084 -124.100796) (xy 330.206235 -124.130257) (xy 330.15666 -124.152893)
			(xy 330.104369 -124.168243) (xy 330.050425 -124.175996) (xy 329.995927 -124.175992) (xy 329.941984 -124.168233)
			(xy 329.889695 -124.152876) (xy 329.840123 -124.130234) (xy 329.794278 -124.100767) (xy 329.753093 -124.065076)
			(xy 329.717407 -124.023887) (xy 329.687945 -123.978039) (xy 329.665309 -123.928464) (xy 329.649958 -123.876173)
			(xy 329.642205 -123.822229) (xy 320.541904 -123.822229) (xy 320.541904 -124.215144) (xy 326.806558 -124.215144)
			(xy 326.810629 -124.159522) (xy 326.822755 -124.105085) (xy 326.842678 -124.052994) (xy 326.869974 -124.004359)
			(xy 326.90406 -123.960216) (xy 326.944209 -123.921507) (xy 326.989567 -123.889056) (xy 327.039167 -123.863555)
			(xy 327.091951 -123.845548) (xy 327.146794 -123.835418) (xy 327.202528 -123.833381) (xy 327.257965 -123.839481)
			(xy 327.311922 -123.853587) (xy 327.363251 -123.875399) (xy 327.410857 -123.904453) (xy 327.453725 -123.940128)
			(xy 327.490942 -123.981665) (xy 327.521715 -124.028178) (xy 327.545387 -124.078675) (xy 327.561455 -124.132082)
			(xy 327.569575 -124.187258) (xy 327.570084 -124.215144) (xy 327.569575 -124.24303) (xy 327.561455 -124.298206)
			(xy 327.545387 -124.351613) (xy 327.521715 -124.40211) (xy 327.490942 -124.448623) (xy 327.453725 -124.49016)
			(xy 327.410857 -124.525835) (xy 327.363251 -124.554889) (xy 327.311922 -124.576701) (xy 327.257965 -124.590807)
			(xy 327.202528 -124.596907) (xy 327.146794 -124.59487) (xy 327.091951 -124.58474) (xy 327.039167 -124.566733)
			(xy 326.989567 -124.541232) (xy 326.944209 -124.508781) (xy 326.90406 -124.470072) (xy 326.869974 -124.425929)
			(xy 326.842678 -124.377294) (xy 326.822755 -124.325203) (xy 326.810629 -124.270766) (xy 326.806558 -124.215144)
			(xy 320.541904 -124.215144) (xy 320.541904 -125.891544) (xy 327.375012 -125.891544) (xy 327.375438 -125.865229)
			(xy 327.382681 -125.813098) (xy 327.397008 -125.762454) (xy 327.418148 -125.714256) (xy 327.445702 -125.669413)
			(xy 327.479147 -125.628775) (xy 327.498202 -125.61062) (xy 327.505597 -125.603093) (xy 327.514125 -125.583817)
			(xy 327.514712 -125.573282) (xy 327.514712 -125.498606) (xy 327.51419 -125.488056) (xy 327.505649 -125.46876)
			(xy 327.498202 -125.461268) (xy 327.479138 -125.443121) (xy 327.445682 -125.402489) (xy 327.418124 -125.357647)
			(xy 327.396987 -125.309445) (xy 327.382671 -125.258796) (xy 327.375449 -125.206661) (xy 327.375012 -125.180344)
			(xy 327.375498 -125.153093) (xy 327.383254 -125.099145) (xy 327.398609 -125.04685) (xy 327.421251 -124.997273)
			(xy 327.450717 -124.951423) (xy 327.486408 -124.910232) (xy 327.527599 -124.874541) (xy 327.573449 -124.845075)
			(xy 327.623026 -124.822433) (xy 327.675321 -124.807078) (xy 327.729269 -124.799322) (xy 327.783771 -124.799322)
			(xy 327.837719 -124.807078) (xy 327.890014 -124.822433) (xy 327.939591 -124.845075) (xy 327.985441 -124.874541)
			(xy 328.026632 -124.910232) (xy 328.062323 -124.951423) (xy 328.091789 -124.997273) (xy 328.114431 -125.04685)
			(xy 328.129786 -125.099145) (xy 328.137542 -125.153093) (xy 328.138028 -125.180344) (xy 328.137581 -125.206659)
			(xy 328.130341 -125.258788) (xy 328.116017 -125.30943) (xy 328.094881 -125.357629) (xy 328.067331 -125.402472)
			(xy 328.03389 -125.443111) (xy 328.014838 -125.461268) (xy 328.007454 -125.468805) (xy 327.998919 -125.488073)
			(xy 327.998328 -125.498606) (xy 327.998328 -125.573282) (xy 327.998845 -125.583833) (xy 328.007388 -125.603129)
			(xy 328.014838 -125.61062) (xy 328.033903 -125.628765) (xy 328.067358 -125.669398) (xy 328.094915 -125.714241)
			(xy 328.116052 -125.762443) (xy 328.130367 -125.813092) (xy 328.13759 -125.865227) (xy 328.138028 -125.891544)
			(xy 328.137542 -125.918795) (xy 328.129786 -125.972743) (xy 328.114431 -126.025038) (xy 328.091789 -126.074615)
			(xy 328.062323 -126.120465) (xy 328.026632 -126.161656) (xy 327.985441 -126.197347) (xy 327.939591 -126.226813)
			(xy 327.890014 -126.249455) (xy 327.837719 -126.26481) (xy 327.783771 -126.272566) (xy 327.729269 -126.272566)
			(xy 327.675321 -126.26481) (xy 327.623026 -126.249455) (xy 327.573449 -126.226813) (xy 327.527599 -126.197347)
			(xy 327.486408 -126.161656) (xy 327.450717 -126.120465) (xy 327.421251 -126.074615) (xy 327.398609 -126.025038)
			(xy 327.383254 -125.972743) (xy 327.375498 -125.918795) (xy 327.375012 -125.891544) (xy 320.541904 -125.891544)
			(xy 320.541904 -130.369056) (xy 320.542001 -130.373201) (xy 320.543408 -130.381371) (xy 320.544698 -130.385312)
			(xy 320.546669 -130.390753) (xy 320.552702 -130.400625) (xy 320.556636 -130.40487) (xy 323.008609 -132.856732)
			(xy 334.376522 -132.856732) (xy 334.37699 -132.829866) (xy 334.384514 -132.776664) (xy 334.399431 -132.725045)
			(xy 334.421446 -132.67603) (xy 334.450122 -132.630591) (xy 334.484893 -132.589627) (xy 334.52507 -132.553949)
			(xy 334.54721 -132.538724) (xy 334.557116 -132.53212) (xy 334.569054 -132.512054) (xy 334.575658 -132.419852)
			(xy 334.575959 -132.408145) (xy 334.567209 -132.386445) (xy 334.558894 -132.378196) (xy 334.55864 -132.378196)
			(xy 334.538953 -132.360013) (xy 334.504355 -132.319088) (xy 334.475824 -132.273724) (xy 334.45392 -132.224814)
			(xy 334.439076 -132.173321) (xy 334.431583 -132.120257) (xy 334.431132 -132.093462) (xy 334.43152 -132.066206)
			(xy 334.439283 -132.012251) (xy 334.454646 -131.959949) (xy 334.477296 -131.910366) (xy 334.506771 -131.864511)
			(xy 334.542473 -131.823318) (xy 334.583673 -131.787625) (xy 334.629534 -131.758158) (xy 334.679122 -131.735518)
			(xy 334.731427 -131.720166) (xy 334.785384 -131.712414) (xy 334.81264 -131.711954) (xy 334.83921 -131.712399)
			(xy 334.891838 -131.719755) (xy 334.942935 -131.734347) (xy 334.991512 -131.755891) (xy 335.036627 -131.783971)
			(xy 335.077406 -131.818043) (xy 335.11306 -131.857446) (xy 335.142897 -131.901419) (xy 335.155032 -131.92506)
			(xy 335.159221 -131.932932) (xy 335.172043 -131.945312) (xy 335.188329 -131.952554) (xy 335.197196 -131.953508)
			(xy 335.29905 -131.960112) (xy 335.32318 -131.948174) (xy 335.3308 -131.936744) (xy 335.346033 -131.914676)
			(xy 335.381682 -131.87462) (xy 335.422592 -131.839955) (xy 335.467957 -131.811365) (xy 335.51688 -131.789413)
			(xy 335.568396 -131.774534) (xy 335.621489 -131.76702) (xy 335.6483 -131.766564) (xy 335.67555 -131.767078)
			(xy 335.729495 -131.774833) (xy 335.781788 -131.790187) (xy 335.831363 -131.812826) (xy 335.877212 -131.84229)
			(xy 335.918402 -131.877978) (xy 335.954093 -131.919165) (xy 335.98356 -131.965012) (xy 336.006203 -132.014586)
			(xy 336.021561 -132.066877) (xy 336.02932 -132.120822) (xy 336.029808 -132.148072) (xy 336.02942 -132.174168)
			(xy 336.022308 -132.225873) (xy 336.008212 -132.276126) (xy 335.987397 -132.323988) (xy 335.960251 -132.368565)
			(xy 335.92728 -132.409024) (xy 335.889101 -132.44461) (xy 335.86801 -132.459984) (xy 335.858866 -132.466334)
			(xy 335.84769 -132.485384) (xy 335.839054 -132.57276) (xy 335.838439 -132.583664) (xy 335.845421 -132.604335)
			(xy 335.852516 -132.612638) (xy 335.85277 -132.612892) (xy 335.872282 -132.634241) (xy 335.905237 -132.68177)
			(xy 335.930637 -132.733729) (xy 335.9479 -132.788929) (xy 335.95663 -132.846102) (xy 335.957164 -132.87502)
			(xy 335.956764 -132.902275) (xy 335.949003 -132.956231) (xy 335.933642 -133.008533) (xy 335.910994 -133.058116)
			(xy 335.88152 -133.103971) (xy 335.845819 -133.145165) (xy 335.80462 -133.180858) (xy 335.75876 -133.210325)
			(xy 335.709173 -133.232964) (xy 335.656868 -133.248316) (xy 335.602911 -133.256068) (xy 335.575656 -133.256528)
			(xy 335.547526 -133.256047) (xy 335.491876 -133.247779) (xy 335.438044 -133.231429) (xy 335.387197 -133.207351)
			(xy 335.340436 -133.176068) (xy 335.298776 -133.138257) (xy 335.26312 -133.094738) (xy 335.24825 -133.070854)
			(xy 335.243565 -133.06368) (xy 335.230426 -133.052701) (xy 335.214385 -133.046713) (xy 335.205832 -133.046216)
			(xy 335.119726 -133.044184) (xy 335.111156 -133.044304) (xy 335.094879 -133.049653) (xy 335.081274 -133.060067)
			(xy 335.076292 -133.067044) (xy 335.061094 -133.08925) (xy 335.025422 -133.129536) (xy 334.984442 -133.164408)
			(xy 334.938966 -133.193173) (xy 334.889897 -133.215259) (xy 334.838212 -133.230228) (xy 334.784935 -133.237783)
			(xy 334.75803 -133.23824) (xy 334.730781 -133.237694) (xy 334.676837 -133.229942) (xy 334.624545 -133.214593)
			(xy 334.574971 -133.191957) (xy 334.529122 -133.162497) (xy 334.487932 -133.126812) (xy 334.45224 -133.085628)
			(xy 334.422772 -133.039784) (xy 334.400129 -132.990213) (xy 334.384771 -132.937924) (xy 334.37701 -132.883981)
			(xy 334.376522 -132.856732) (xy 323.008609 -132.856732) (xy 326.161146 -136.009126) (xy 326.166499 -136.014004)
			(xy 326.179265 -136.02083) (xy 326.186292 -136.022588) (xy 326.196706 -136.023604) (xy 336.15503 -136.023604)
			(xy 336.181117 -136.024092) (xy 336.232646 -136.032262) (xy 336.282263 -136.048397) (xy 336.328742 -136.072097)
			(xy 336.37094 -136.10278) (xy 336.389726 -136.120886) (xy 340.594696 -140.325856) (xy 340.612729 -140.344627)
			(xy 340.643311 -140.386743) (xy 340.66694 -140.433119) (xy 340.683036 -140.482616) (xy 340.691204 -140.53402)
			(xy 340.691724 -140.560044) (xy 340.691724 -141.066266) (xy 340.699323 -141.075379) (xy 340.720514 -141.085993)
			(xy 340.732364 -141.086586) (xy 341.85098 -141.086586) (xy 341.859108 -141.085824) (xy 341.859616 -141.085824)
			(xy 341.867136 -141.084226) (xy 341.88083 -141.077255) (xy 341.88654 -141.072108) (xy 342.731344 -140.227304)
			(xy 342.734051 -140.224454) (xy 342.738646 -140.218076) (xy 342.740488 -140.214604) (xy 342.743066 -140.209176)
			(xy 342.745878 -140.197496) (xy 342.746076 -140.19149) (xy 342.746076 -125.946916) (xy 342.746606 -125.920894)
			(xy 342.754778 -125.869493) (xy 342.770877 -125.82) (xy 342.794508 -125.773628) (xy 342.825091 -125.731516)
			(xy 342.843104 -125.712728) (xy 343.08034 -125.475492) (xy 343.080848 -125.46838) (xy 343.080848 -125.420628)
			(xy 343.081286 -125.410565) (xy 343.089024 -125.391984) (xy 343.095834 -125.38456) (xy 349.614998 -118.865396)
			(xy 349.615506 -118.864888) (xy 349.619824 -118.859808) (xy 349.619824 -110.957868) (xy 349.617264 -110.954598)
			(xy 349.611261 -110.948859) (xy 349.607886 -110.946438) (xy 349.538798 -110.899194) (xy 349.53829 -110.899194)
			(xy 349.53067 -110.89386) (xy 349.4913 -110.89386) (xy 349.482918 -110.896908) (xy 349.451192 -110.907822)
			(xy 349.385144 -110.919584) (xy 349.3516 -110.920276) (xy 349.323864 -110.919771) (xy 349.268979 -110.911727)
			(xy 349.215836 -110.895822) (xy 349.165556 -110.872392) (xy 349.119197 -110.841929) (xy 349.077736 -110.805077)
			(xy 349.042046 -110.762611) (xy 349.01288 -110.715426) (xy 348.990851 -110.664515) (xy 348.976425 -110.610953)
			(xy 348.972632 -110.583472) (xy 348.970854 -110.568232) (xy 348.969838 -110.538768) (xy 348.969838 -110.538514)
			(xy 348.970289 -110.51175) (xy 348.97777 -110.458748) (xy 348.992587 -110.407312) (xy 349.01445 -110.358453)
			(xy 349.042928 -110.31313) (xy 349.077462 -110.272233) (xy 349.097092 -110.254034) (xy 349.101156 -110.250478)
			(xy 349.109538 -110.239048) (xy 349.11284 -110.23473) (xy 349.123 -110.212378) (xy 349.12554 -110.202472)
			(xy 349.12554 -110.201456) (xy 349.126048 -110.198662) (xy 349.125794 -110.167674) (xy 349.125794 -110.167166)
			(xy 349.125032 -110.137194) (xy 349.124749 -110.13165) (xy 349.122051 -110.120886) (xy 349.119698 -110.115858)
			(xy 349.110046 -110.096046) (xy 349.101664 -110.08487) (xy 349.099124 -110.08233) (xy 349.097346 -110.080806)
			(xy 349.076257 -110.062577) (xy 349.039074 -110.021048) (xy 349.008326 -109.974554) (xy 348.984667 -109.924082)
			(xy 348.968599 -109.870706) (xy 348.960465 -109.815561) (xy 348.959932 -109.78769) (xy 348.959932 -109.78007)
			(xy 348.960912 -109.753164) (xy 348.969506 -109.700015) (xy 348.985488 -109.648602) (xy 349.008541 -109.599947)
			(xy 349.038207 -109.555018) (xy 349.073895 -109.514706) (xy 349.114898 -109.479814) (xy 349.1604 -109.451034)
			(xy 349.209497 -109.428938) (xy 349.261213 -109.413966) (xy 349.31452 -109.406415) (xy 349.34144 -109.405928)
			(xy 349.341694 -109.405928) (xy 349.365361 -109.406283) (xy 349.41233 -109.412147) (xy 349.458208 -109.423799)
			(xy 349.480378 -109.43209) (xy 349.488506 -109.435392) (xy 349.492824 -109.436916) (xy 349.503045 -109.439886)
			(xy 349.524219 -109.437908) (xy 349.533718 -109.433106) (xy 349.537528 -109.431074) (xy 349.571818 -109.407452)
			(xy 349.572326 -109.407452) (xy 349.607378 -109.384084) (xy 349.610926 -109.381589) (xy 349.617188 -109.37559)
			(xy 349.619824 -109.372146) (xy 349.619824 -108.700824) (xy 349.61957 -108.694728) (xy 349.618258 -108.686378)
			(xy 349.610856 -108.671193) (xy 349.605092 -108.66501) (xy 349.205296 -108.265468) (xy 349.195644 -108.257848)
			(xy 349.180658 -108.248958) (xy 349.18015 -108.248704) (xy 349.154583 -108.240256) (xy 349.105934 -108.217176)
			(xy 349.061011 -108.187491) (xy 349.020705 -108.151787) (xy 348.985815 -108.110775) (xy 348.957034 -108.065267)
			(xy 348.934933 -108.016166) (xy 348.919949 -107.964448) (xy 348.912382 -107.911137) (xy 348.911926 -107.884214)
			(xy 348.91202 -107.870515) (xy 348.913928 -107.843184) (xy 348.915736 -107.829604) (xy 348.91599 -107.827826)
			(xy 348.916752 -107.82427) (xy 348.921684 -107.79654) (xy 348.938628 -107.742828) (xy 348.963278 -107.692188)
			(xy 348.9951 -107.645719) (xy 349.033404 -107.604429) (xy 349.077357 -107.569213) (xy 349.126007 -107.540837)
			(xy 349.151956 -107.529884) (xy 349.16513 -107.524767) (xy 349.192082 -107.516252) (xy 349.205804 -107.512866)
			(xy 349.209106 -107.512104) (xy 349.220536 -107.507786) (xy 349.226378 -107.505246) (xy 349.237554 -107.499404)
			(xy 349.240094 -107.498134) (xy 349.252794 -107.483148) (xy 349.255842 -107.473242) (xy 349.256096 -107.472734)
			(xy 349.26397 -107.447588) (xy 349.26397 -107.447334) (xy 349.26651 -107.439968) (xy 349.276162 -107.406948)
			(xy 349.276162 -107.40644) (xy 349.28175 -107.38612) (xy 349.282716 -107.38142) (xy 349.283092 -107.371833)
			(xy 349.282512 -107.36707) (xy 349.211392 -107.296204) (xy 349.17634 -107.261152) (xy 349.166688 -107.258104)
			(xy 349.140925 -107.249782) (xy 349.091868 -107.22688) (xy 349.046538 -107.197279) (xy 349.005845 -107.161571)
			(xy 348.970603 -107.120473) (xy 348.941521 -107.074808) (xy 348.919181 -107.025493) (xy 348.904032 -106.973517)
			(xy 348.896377 -106.919921) (xy 348.895924 -106.892852) (xy 348.896414 -106.865604) (xy 348.904176 -106.811663)
			(xy 348.919535 -106.759376) (xy 348.94218 -106.709807) (xy 348.971648 -106.663965) (xy 349.00734 -106.622783)
			(xy 349.048529 -106.5871) (xy 349.094377 -106.557641) (xy 349.143951 -106.535007) (xy 349.196241 -106.519659)
			(xy 349.250184 -106.511908) (xy 349.277432 -106.511344) (xy 349.302817 -106.511757) (xy 349.35314 -106.518479)
			(xy 349.402127 -106.531814) (xy 349.448914 -106.551526) (xy 349.492674 -106.577267) (xy 349.51289 -106.592624)
			(xy 349.51797 -106.596434) (xy 349.522678 -106.599104) (xy 349.532926 -106.602574) (xy 349.53829 -106.603292)
			(xy 349.548958 -106.603292) (xy 349.552612 -106.602852) (xy 349.559749 -106.601062) (xy 349.563182 -106.599736)
			(xy 349.64243 -106.561636) (xy 349.65132 -106.557318) (xy 349.658893 -106.552682) (xy 349.670541 -106.5393)
			(xy 349.67692 -106.522746) (xy 349.677482 -106.513884) (xy 349.677482 -101.429058) (xy 349.677211 -101.421094)
			(xy 349.672289 -101.405945) (xy 349.66783 -101.39934) (xy 349.66783 -101.399086) (xy 349.665063 -101.395396)
			(xy 349.658419 -101.389003) (xy 349.654622 -101.386386) (xy 349.643954 -101.38283) (xy 349.618796 -101.374034)
			(xy 349.571 -101.350459) (xy 349.526934 -101.320485) (xy 349.48745 -101.28469) (xy 349.453311 -101.243767)
			(xy 349.425175 -101.198505) (xy 349.403587 -101.149779) (xy 349.388964 -101.09853) (xy 349.381588 -101.045749)
			(xy 349.381064 -101.019102) (xy 349.381064 -101.018594) (xy 349.381165 -101.005471) (xy 349.382942 -100.979286)
			(xy 349.38462 -100.96627) (xy 349.384874 -100.964492) (xy 349.385382 -100.957634) (xy 349.385023 -100.949092)
			(xy 349.379324 -100.932985) (xy 349.374206 -100.926138) (xy 349.367348 -100.918264) (xy 349.367856 -100.898198)
			(xy 349.368525 -100.88871) (xy 349.375956 -100.871217) (xy 349.382334 -100.864162) (xy 349.465138 -100.779326)
			(xy 349.467932 -100.776024) (xy 349.485307 -100.755562) (xy 349.524823 -100.719229) (xy 349.546672 -100.703634)
			(xy 349.56911 -100.688775) (xy 349.617298 -100.664816) (xy 349.642684 -100.655882) (xy 349.649796 -100.653596)
			(xy 349.651066 -100.653088) (xy 349.654726 -100.650973) (xy 349.661358 -100.645734) (xy 349.664274 -100.642674)
			(xy 349.66529 -100.641404) (xy 349.665798 -100.640896) (xy 349.671201 -100.633884) (xy 349.677176 -100.617232)
			(xy 349.677482 -100.608384) (xy 349.677482 -99.747324) (xy 349.677897 -99.737298) (xy 349.685562 -99.71877)
			(xy 349.699735 -99.704586) (xy 349.718257 -99.696906) (xy 349.728282 -99.696524) (xy 350.897444 -99.696524)
			(xy 350.909286 -99.695896) (xy 350.930465 -99.685293) (xy 350.938084 -99.676204) (xy 350.938084 -95.784924)
			(xy 350.937576 -95.77832) (xy 350.936237 -95.770224) (xy 350.929106 -95.755455) (xy 350.923606 -95.749364)
			(xy 350.146112 -94.972124) (xy 350.12808 -94.953353) (xy 350.0975 -94.911236) (xy 350.073873 -94.86486)
			(xy 350.05778 -94.815363) (xy 350.049614 -94.76396) (xy 350.049084 -94.737936) (xy 350.049084 -84.665058)
			(xy 350.049009 -84.660584) (xy 350.047469 -84.651771) (xy 350.046036 -84.647532) (xy 350.044026 -84.642437)
			(xy 350.038132 -84.633208) (xy 350.034352 -84.629244) (xy 342.26373 -76.858876) (xy 342.245615 -76.840097)
			(xy 342.214925 -76.797901) (xy 342.19122 -76.75142) (xy 342.175086 -76.701801) (xy 342.166919 -76.650268)
			(xy 342.166448 -76.62418) (xy 342.166448 -67.554856) (xy 342.16467 -67.551554) (xy 342.149734 -67.523266)
			(xy 342.128499 -67.462929) (xy 342.117644 -67.399892) (xy 342.116918 -67.367912) (xy 342.116918 -67.364102)
			(xy 342.117548 -67.33712) (xy 342.125476 -67.283735) (xy 342.14085 -67.232) (xy 342.163361 -67.182949)
			(xy 342.192561 -67.137559) (xy 342.227867 -67.096739) (xy 342.268573 -67.061301) (xy 342.313868 -67.031955)
			(xy 342.362847 -67.009285) (xy 342.414531 -66.993745) (xy 342.467891 -66.985644) (xy 342.49487 -66.98488)
			(xy 342.500712 -66.98488) (xy 342.523027 -66.985271) (xy 342.567338 -66.990616) (xy 342.589104 -66.995548)
			(xy 342.589866 -66.995802) (xy 342.593422 -66.996564) (xy 342.60028 -66.997326) (xy 342.609432 -66.997866)
			(xy 342.627146 -66.99319) (xy 342.634824 -66.988182) (xy 342.638888 -66.985134) (xy 342.683338 -66.95059)
			(xy 342.699848 -66.93789) (xy 342.700356 -66.937382) (xy 342.701118 -66.936874) (xy 342.701372 -66.93662)
			(xy 342.708992 -66.928492) (xy 342.708992 -58.727594) (xy 342.708941 -58.723522) (xy 342.70767 -58.715478)
			(xy 342.706452 -58.711592) (xy 342.704442 -58.70607) (xy 342.698276 -58.696071) (xy 342.69426 -58.69178)
			(xy 337.434936 -53.43271) (xy 337.425284 -53.42509) (xy 337.410298 -53.4162) (xy 337.40979 -53.415946)
			(xy 337.384223 -53.407499) (xy 337.335574 -53.384422) (xy 337.290652 -53.354737) (xy 337.250346 -53.319033)
			(xy 337.215458 -53.27802) (xy 337.18668 -53.232511) (xy 337.164583 -53.183409) (xy 337.149606 -53.13169)
			(xy 337.142045 -53.078378) (xy 337.141566 -53.051456) (xy 337.142055 -53.024206) (xy 337.149816 -52.970262)
			(xy 337.165175 -52.917971) (xy 337.187818 -52.868397) (xy 337.217285 -52.822551) (xy 337.252976 -52.781364)
			(xy 337.294165 -52.745674) (xy 337.340013 -52.71621) (xy 337.389588 -52.693569) (xy 337.441879 -52.678212)
			(xy 337.495824 -52.670453) (xy 337.523074 -52.669948) (xy 337.549986 -52.670409) (xy 337.603276 -52.677973)
			(xy 337.654973 -52.692956) (xy 337.70405 -52.715059) (xy 337.749531 -52.743843) (xy 337.790513 -52.778736)
			(xy 337.826182 -52.819045) (xy 337.855828 -52.863969) (xy 337.878863 -52.912615) (xy 337.88731 -52.938172)
			(xy 337.88858 -52.941982) (xy 337.89239 -52.949348) (xy 337.899756 -52.958746) (xy 338.437565 -53.496555)
			(xy 354.433541 -53.496555) (xy 354.433541 -53.442045) (xy 354.441299 -53.388089) (xy 354.456657 -53.335787)
			(xy 354.479303 -53.286202) (xy 354.508775 -53.240346) (xy 354.544474 -53.199151) (xy 354.585672 -53.163456)
			(xy 354.63153 -53.133988) (xy 354.681117 -53.111346) (xy 354.73342 -53.095992) (xy 354.787377 -53.088239)
			(xy 354.814632 -53.087778) (xy 354.842004 -53.088206) (xy 354.896185 -53.09603) (xy 354.94869 -53.111527)
			(xy 354.998436 -53.134378) (xy 355.0444 -53.164112) (xy 355.06533 -53.181758) (xy 355.065584 -53.182012)
			(xy 355.07267 -53.187599) (xy 355.089587 -53.193845) (xy 355.098604 -53.194204) (xy 355.16566 -53.194204)
			(xy 355.174675 -53.193827) (xy 355.191592 -53.187593) (xy 355.19868 -53.182012) (xy 355.19868 -53.181758)
			(xy 355.198934 -53.181758) (xy 355.219874 -53.164129) (xy 355.265846 -53.134417) (xy 355.315591 -53.11158)
			(xy 355.36809 -53.096086) (xy 355.422264 -53.088254) (xy 355.449632 -53.087778) (xy 355.476881 -53.088294)
			(xy 355.530823 -53.096054) (xy 355.583112 -53.111412) (xy 355.632683 -53.134054) (xy 355.678528 -53.16352)
			(xy 355.719713 -53.19921) (xy 355.755399 -53.240398) (xy 355.784862 -53.286245) (xy 355.8075 -53.335818)
			(xy 355.822852 -53.388108) (xy 355.830608 -53.442051) (xy 355.830608 -53.496549) (xy 355.822852 -53.550492)
			(xy 355.8075 -53.602782) (xy 355.784862 -53.652355) (xy 355.755399 -53.698202) (xy 355.719713 -53.73939)
			(xy 355.678528 -53.77508) (xy 355.632683 -53.804546) (xy 355.583112 -53.827188) (xy 355.530823 -53.842546)
			(xy 355.476881 -53.850306) (xy 355.449632 -53.850794) (xy 355.422262 -53.850311) (xy 355.368084 -53.842497)
			(xy 355.315581 -53.827012) (xy 355.265834 -53.804174) (xy 355.219866 -53.774453) (xy 355.198934 -53.756814)
			(xy 355.19868 -53.75656) (xy 355.191607 -53.750954) (xy 355.17468 -53.74472) (xy 355.16566 -53.744368)
			(xy 355.098604 -53.744368) (xy 355.089588 -53.744734) (xy 355.072672 -53.750976) (xy 355.065584 -53.75656)
			(xy 355.065584 -53.756814) (xy 355.06533 -53.756814) (xy 355.044399 -53.774455) (xy 354.998426 -53.804166)
			(xy 354.948678 -53.827001) (xy 354.896177 -53.842492) (xy 354.842001 -53.85032) (xy 354.814632 -53.850794)
			(xy 354.787377 -53.850361) (xy 354.73342 -53.842608) (xy 354.681117 -53.827254) (xy 354.63153 -53.804612)
			(xy 354.585672 -53.775144) (xy 354.544474 -53.739449) (xy 354.508775 -53.698254) (xy 354.479303 -53.652398)
			(xy 354.456657 -53.602813) (xy 354.441299 -53.550511) (xy 354.433541 -53.496555) (xy 338.437565 -53.496555)
			(xy 339.930065 -54.989055) (xy 352.201145 -54.989055) (xy 352.201145 -54.934545) (xy 352.208903 -54.880591)
			(xy 352.224261 -54.828289) (xy 352.246906 -54.778706) (xy 352.276377 -54.73285) (xy 352.312074 -54.691656)
			(xy 352.353271 -54.655961) (xy 352.399129 -54.626493) (xy 352.448714 -54.603851) (xy 352.501016 -54.588497)
			(xy 352.554971 -54.580743) (xy 352.582226 -54.580282) (xy 352.610318 -54.580756) (xy 352.665896 -54.588987)
			(xy 352.719666 -54.605282) (xy 352.770463 -54.629288) (xy 352.81719 -54.660486) (xy 352.858835 -54.698201)
			(xy 352.894496 -54.741616) (xy 352.909378 -54.765448) (xy 352.914712 -54.774338) (xy 352.93173 -54.78653)
			(xy 353.024948 -54.80685) (xy 353.045522 -54.802532) (xy 353.054158 -54.79669) (xy 353.078231 -54.780705)
			(xy 353.130159 -54.755359) (xy 353.185314 -54.738129) (xy 353.242436 -54.729409) (xy 353.271328 -54.728872)
			(xy 353.298579 -54.729352) (xy 353.352526 -54.737112) (xy 353.40482 -54.752469) (xy 353.454396 -54.775112)
			(xy 353.500245 -54.804579) (xy 353.541434 -54.840271) (xy 353.577125 -54.881462) (xy 353.606592 -54.927311)
			(xy 353.629234 -54.976888) (xy 353.64459 -55.029182) (xy 353.652349 -55.083129) (xy 353.652836 -55.11038)
			(xy 353.652374 -55.137751) (xy 353.644557 -55.19193) (xy 353.629068 -55.244434) (xy 353.606225 -55.294181)
			(xy 353.576499 -55.340147) (xy 353.558856 -55.361078) (xy 353.558602 -55.361332) (xy 353.553038 -55.368434)
			(xy 353.546778 -55.385339) (xy 353.54641 -55.394352) (xy 353.54641 -55.461408) (xy 353.546761 -55.470426)
			(xy 353.553012 -55.487343) (xy 353.558602 -55.494428) (xy 353.558856 -55.494428) (xy 353.558856 -55.494682)
			(xy 353.576478 -55.51563) (xy 353.606205 -55.561595) (xy 353.629052 -55.611339) (xy 353.644551 -55.663838)
			(xy 353.652382 -55.718015) (xy 353.652384 -55.772755) (xy 353.644557 -55.826932) (xy 353.629063 -55.879433)
			(xy 353.606219 -55.929179) (xy 353.576496 -55.975146) (xy 353.558856 -55.996078) (xy 353.558602 -55.996332)
			(xy 353.553038 -56.003434) (xy 353.546778 -56.020339) (xy 353.54641 -56.029352) (xy 353.54641 -56.096408)
			(xy 353.546761 -56.105426) (xy 353.553012 -56.122343) (xy 353.558602 -56.129428) (xy 353.558856 -56.129428)
			(xy 353.558856 -56.129682) (xy 353.576493 -56.150616) (xy 353.606207 -56.196587) (xy 353.629044 -56.246334)
			(xy 353.644535 -56.298835) (xy 353.652363 -56.353011) (xy 353.652836 -56.38038) (xy 353.65235 -56.407631)
			(xy 353.644594 -56.461579) (xy 353.629239 -56.513874) (xy 353.606597 -56.563451) (xy 353.577131 -56.609301)
			(xy 353.54144 -56.650492) (xy 353.500249 -56.686183) (xy 353.454399 -56.715649) (xy 353.404822 -56.738291)
			(xy 353.352527 -56.753646) (xy 353.298579 -56.761402) (xy 353.244077 -56.761402) (xy 353.190129 -56.753646)
			(xy 353.137834 -56.738291) (xy 353.088257 -56.715649) (xy 353.042407 -56.686183) (xy 353.001216 -56.650492)
			(xy 352.965525 -56.609301) (xy 352.936059 -56.563451) (xy 352.913417 -56.513874) (xy 352.898062 -56.461579)
			(xy 352.890306 -56.407631) (xy 352.88982 -56.38038) (xy 352.890269 -56.353009) (xy 352.898091 -56.298829)
			(xy 352.913583 -56.246326) (xy 352.936429 -56.196579) (xy 352.966157 -56.150613) (xy 352.9838 -56.129682)
			(xy 352.984054 -56.129428) (xy 352.989641 -56.122342) (xy 352.995886 -56.105425) (xy 352.996246 -56.096408)
			(xy 352.996246 -56.029352) (xy 352.995876 -56.020336) (xy 352.989639 -56.003418) (xy 352.984054 -55.996332)
			(xy 352.9838 -55.996332) (xy 352.9838 -55.996078) (xy 352.966141 -55.975161) (xy 352.936419 -55.929189)
			(xy 352.913576 -55.879441) (xy 352.898083 -55.826936) (xy 352.890257 -55.772756) (xy 352.890259 -55.718014)
			(xy 352.898089 -55.663834) (xy 352.913587 -55.611331) (xy 352.936433 -55.561584) (xy 352.966159 -55.515615)
			(xy 352.9838 -55.494682) (xy 352.984054 -55.494428) (xy 352.989641 -55.487342) (xy 352.995886 -55.470425)
			(xy 352.996246 -55.461408) (xy 352.996246 -55.394352) (xy 352.995876 -55.385336) (xy 352.989639 -55.368418)
			(xy 352.984054 -55.361332) (xy 352.9838 -55.360824) (xy 352.972856 -55.348089) (xy 352.953015 -55.320998)
			(xy 352.944176 -55.306722) (xy 352.938842 -55.297832) (xy 352.921824 -55.28564) (xy 352.828606 -55.26532)
			(xy 352.808032 -55.269638) (xy 352.799396 -55.27548) (xy 352.775333 -55.291482) (xy 352.723402 -55.316825)
			(xy 352.668243 -55.33405) (xy 352.611119 -55.342764) (xy 352.582226 -55.343298) (xy 352.554971 -55.342857)
			(xy 352.501016 -55.335103) (xy 352.448714 -55.319749) (xy 352.399129 -55.297107) (xy 352.353271 -55.267639)
			(xy 352.312074 -55.231944) (xy 352.276377 -55.19075) (xy 352.246906 -55.144894) (xy 352.224261 -55.095311)
			(xy 352.208903 -55.043009) (xy 352.201145 -54.989055) (xy 339.930065 -54.989055) (xy 340.361865 -55.420855)
			(xy 350.524745 -55.420855) (xy 350.524745 -55.366345) (xy 350.532503 -55.312391) (xy 350.547861 -55.260089)
			(xy 350.570506 -55.210506) (xy 350.599977 -55.16465) (xy 350.635674 -55.123456) (xy 350.676871 -55.087761)
			(xy 350.722729 -55.058293) (xy 350.772314 -55.035651) (xy 350.824616 -55.020297) (xy 350.878571 -55.012543)
			(xy 350.905826 -55.012082) (xy 350.93214 -55.012538) (xy 350.984269 -55.019776) (xy 351.034912 -55.034098)
			(xy 351.083111 -55.055232) (xy 351.127954 -55.08278) (xy 351.168593 -55.11622) (xy 351.18675 -55.135272)
			(xy 351.194255 -55.142694) (xy 351.213547 -55.151208) (xy 351.224088 -55.151782) (xy 351.298764 -55.151782)
			(xy 351.309314 -55.151252) (xy 351.32861 -55.142718) (xy 351.336102 -55.135272) (xy 351.354258 -55.116217)
			(xy 351.394888 -55.082761) (xy 351.439729 -55.055203) (xy 351.487929 -55.034064) (xy 351.538576 -55.019747)
			(xy 351.59071 -55.012521) (xy 351.617026 -55.012082) (xy 351.644275 -55.01259) (xy 351.698219 -55.020349)
			(xy 351.750509 -55.035706) (xy 351.800082 -55.058348) (xy 351.845927 -55.087814) (xy 351.887113 -55.123505)
			(xy 351.922801 -55.164693) (xy 351.952264 -55.210541) (xy 351.974903 -55.260115) (xy 351.990256 -55.312407)
			(xy 351.998012 -55.366351) (xy 351.998012 -55.420849) (xy 351.990256 -55.474793) (xy 351.974903 -55.527085)
			(xy 351.952264 -55.576659) (xy 351.922801 -55.622507) (xy 351.887113 -55.663695) (xy 351.845927 -55.699386)
			(xy 351.800082 -55.728852) (xy 351.750509 -55.751494) (xy 351.698219 -55.766851) (xy 351.644275 -55.77461)
			(xy 351.617026 -55.775098) (xy 351.590713 -55.774614) (xy 351.538585 -55.767383) (xy 351.487942 -55.753067)
			(xy 351.439743 -55.731937) (xy 351.394899 -55.704394) (xy 351.354259 -55.670958) (xy 351.336102 -55.651908)
			(xy 351.32858 -55.644507) (xy 351.3093 -55.635982) (xy 351.298764 -55.635398) (xy 351.224088 -55.635398)
			(xy 351.213536 -55.635908) (xy 351.194241 -55.644457) (xy 351.18675 -55.651908) (xy 351.168613 -55.670982)
			(xy 351.127979 -55.704437) (xy 351.083135 -55.731994) (xy 351.034931 -55.753129) (xy 350.98428 -55.767442)
			(xy 350.932143 -55.774662) (xy 350.905826 -55.775098) (xy 350.878571 -55.774657) (xy 350.824616 -55.766903)
			(xy 350.772314 -55.751549) (xy 350.722729 -55.728907) (xy 350.676871 -55.699439) (xy 350.635674 -55.663744)
			(xy 350.599977 -55.62255) (xy 350.570506 -55.576694) (xy 350.547861 -55.527111) (xy 350.532503 -55.474809)
			(xy 350.524745 -55.420855) (xy 340.361865 -55.420855) (xy 342.42629 -57.48528) (xy 352.906074 -57.48528)
			(xy 352.910145 -57.429658) (xy 352.922271 -57.375221) (xy 352.942194 -57.32313) (xy 352.96949 -57.274495)
			(xy 353.003576 -57.230352) (xy 353.043725 -57.191643) (xy 353.089083 -57.159192) (xy 353.138683 -57.133691)
			(xy 353.191467 -57.115684) (xy 353.24631 -57.105554) (xy 353.302044 -57.103517) (xy 353.357481 -57.109617)
			(xy 353.411438 -57.123723) (xy 353.462767 -57.145535) (xy 353.510373 -57.174589) (xy 353.553241 -57.210264)
			(xy 353.590458 -57.251801) (xy 353.621231 -57.298314) (xy 353.644903 -57.348811) (xy 353.660971 -57.402218)
			(xy 353.669091 -57.457394) (xy 353.6696 -57.48528) (xy 353.669091 -57.513166) (xy 353.660971 -57.568342)
			(xy 353.644903 -57.621749) (xy 353.621231 -57.672246) (xy 353.590458 -57.718759) (xy 353.553241 -57.760296)
			(xy 353.510373 -57.795971) (xy 353.462767 -57.825025) (xy 353.411438 -57.846837) (xy 353.357481 -57.860943)
			(xy 353.302044 -57.867043) (xy 353.24631 -57.865006) (xy 353.191467 -57.854876) (xy 353.138683 -57.836869)
			(xy 353.089083 -57.811368) (xy 353.043725 -57.778917) (xy 353.003576 -57.740208) (xy 352.96949 -57.696065)
			(xy 352.942194 -57.64743) (xy 352.922271 -57.595339) (xy 352.910145 -57.540902) (xy 352.906074 -57.48528)
			(xy 342.42629 -57.48528) (xy 343.017094 -58.076084) (xy 353.658168 -58.076084) (xy 353.662239 -58.020462)
			(xy 353.674365 -57.966025) (xy 353.694288 -57.913934) (xy 353.721584 -57.865299) (xy 353.75567 -57.821156)
			(xy 353.795819 -57.782447) (xy 353.841177 -57.749996) (xy 353.890777 -57.724495) (xy 353.943561 -57.706488)
			(xy 353.998404 -57.696358) (xy 354.054138 -57.694321) (xy 354.109575 -57.700421) (xy 354.163532 -57.714527)
			(xy 354.214861 -57.736339) (xy 354.262467 -57.765393) (xy 354.305335 -57.801068) (xy 354.342552 -57.842605)
			(xy 354.358888 -57.867296) (xy 355.943152 -57.867296) (xy 355.947223 -57.811674) (xy 355.959349 -57.757237)
			(xy 355.979272 -57.705146) (xy 356.006568 -57.656511) (xy 356.040654 -57.612368) (xy 356.080803 -57.573659)
			(xy 356.126161 -57.541208) (xy 356.175761 -57.515707) (xy 356.228545 -57.4977) (xy 356.283388 -57.48757)
			(xy 356.339122 -57.485533) (xy 356.394559 -57.491633) (xy 356.448516 -57.505739) (xy 356.499845 -57.527551)
			(xy 356.547451 -57.556605) (xy 356.590319 -57.59228) (xy 356.627536 -57.633817) (xy 356.658309 -57.68033)
			(xy 356.681981 -57.730827) (xy 356.698049 -57.784234) (xy 356.706169 -57.83941) (xy 356.706678 -57.867296)
			(xy 356.706169 -57.895182) (xy 356.698049 -57.950358) (xy 356.681981 -58.003765) (xy 356.658309 -58.054262)
			(xy 356.627536 -58.100775) (xy 356.590319 -58.142312) (xy 356.547451 -58.177987) (xy 356.499845 -58.207041)
			(xy 356.448516 -58.228853) (xy 356.394559 -58.242959) (xy 356.339122 -58.249059) (xy 356.283388 -58.247022)
			(xy 356.228545 -58.236892) (xy 356.175761 -58.218885) (xy 356.126161 -58.193384) (xy 356.080803 -58.160933)
			(xy 356.040654 -58.122224) (xy 356.006568 -58.078081) (xy 355.979272 -58.029446) (xy 355.959349 -57.977355)
			(xy 355.947223 -57.922918) (xy 355.943152 -57.867296) (xy 354.358888 -57.867296) (xy 354.373325 -57.889118)
			(xy 354.396997 -57.939615) (xy 354.413065 -57.993022) (xy 354.421185 -58.048198) (xy 354.421694 -58.076084)
			(xy 354.421185 -58.10397) (xy 354.413065 -58.159146) (xy 354.396997 -58.212553) (xy 354.373325 -58.26305)
			(xy 354.342552 -58.309563) (xy 354.305335 -58.3511) (xy 354.262467 -58.386775) (xy 354.214861 -58.415829)
			(xy 354.163532 -58.437641) (xy 354.109575 -58.451747) (xy 354.054138 -58.457847) (xy 353.998404 -58.45581)
			(xy 353.943561 -58.44568) (xy 353.890777 -58.427673) (xy 353.841177 -58.402172) (xy 353.795819 -58.369721)
			(xy 353.75567 -58.331012) (xy 353.721584 -58.286869) (xy 353.694288 -58.238234) (xy 353.674365 -58.186143)
			(xy 353.662239 -58.131706) (xy 353.658168 -58.076084) (xy 343.017094 -58.076084) (xy 343.275412 -58.334402)
			(xy 343.293446 -58.353172) (xy 343.324029 -58.395287) (xy 343.347658 -58.441664) (xy 343.363752 -58.491162)
			(xy 343.371915 -58.542566) (xy 343.372291 -58.561224) (xy 354.862382 -58.561224) (xy 354.866453 -58.505602)
			(xy 354.878579 -58.451165) (xy 354.898502 -58.399074) (xy 354.925798 -58.350439) (xy 354.959884 -58.306296)
			(xy 355.000033 -58.267587) (xy 355.045391 -58.235136) (xy 355.094991 -58.209635) (xy 355.147775 -58.191628)
			(xy 355.202618 -58.181498) (xy 355.258352 -58.179461) (xy 355.313789 -58.185561) (xy 355.367746 -58.199667)
			(xy 355.419075 -58.221479) (xy 355.466681 -58.250533) (xy 355.509549 -58.286208) (xy 355.546766 -58.327745)
			(xy 355.577539 -58.374258) (xy 355.601211 -58.424755) (xy 355.617279 -58.478162) (xy 355.625399 -58.533338)
			(xy 355.625908 -58.561224) (xy 355.625399 -58.58911) (xy 355.617279 -58.644286) (xy 355.601211 -58.697693)
			(xy 355.577539 -58.74819) (xy 355.546766 -58.794703) (xy 355.509549 -58.83624) (xy 355.466681 -58.871915)
			(xy 355.419075 -58.900969) (xy 355.367746 -58.922781) (xy 355.313789 -58.936887) (xy 355.258352 -58.942987)
			(xy 355.202618 -58.94095) (xy 355.147775 -58.93082) (xy 355.094991 -58.912813) (xy 355.045391 -58.887312)
			(xy 355.000033 -58.854861) (xy 354.959884 -58.816152) (xy 354.925798 -58.772009) (xy 354.898502 -58.723374)
			(xy 354.878579 -58.671283) (xy 354.866453 -58.616846) (xy 354.862382 -58.561224) (xy 343.372291 -58.561224)
			(xy 343.37244 -58.56859) (xy 343.37244 -59.174634) (xy 353.393246 -59.174634) (xy 353.397317 -59.119012)
			(xy 353.409443 -59.064575) (xy 353.429366 -59.012484) (xy 353.456662 -58.963849) (xy 353.490748 -58.919706)
			(xy 353.530897 -58.880997) (xy 353.576255 -58.848546) (xy 353.625855 -58.823045) (xy 353.678639 -58.805038)
			(xy 353.733482 -58.794908) (xy 353.789216 -58.792871) (xy 353.844653 -58.798971) (xy 353.89861 -58.813077)
			(xy 353.949939 -58.834889) (xy 353.997545 -58.863943) (xy 354.040413 -58.899618) (xy 354.07763 -58.941155)
			(xy 354.108403 -58.987668) (xy 354.132075 -59.038165) (xy 354.148143 -59.091572) (xy 354.156263 -59.146748)
			(xy 354.156772 -59.174634) (xy 354.156263 -59.20252) (xy 354.148143 -59.257696) (xy 354.132075 -59.311103)
			(xy 354.108403 -59.3616) (xy 354.07763 -59.408113) (xy 354.040413 -59.44965) (xy 353.997545 -59.485325)
			(xy 353.949939 -59.514379) (xy 353.89861 -59.536191) (xy 353.844653 -59.550297) (xy 353.789216 -59.556397)
			(xy 353.733482 -59.55436) (xy 353.678639 -59.54423) (xy 353.625855 -59.526223) (xy 353.576255 -59.500722)
			(xy 353.530897 -59.468271) (xy 353.490748 -59.429562) (xy 353.456662 -59.385419) (xy 353.429366 -59.336784)
			(xy 353.409443 -59.284693) (xy 353.397317 -59.230256) (xy 353.393246 -59.174634) (xy 343.37244 -59.174634)
			(xy 343.37244 -60.633356) (xy 356.097076 -60.633356) (xy 356.101147 -60.577734) (xy 356.113273 -60.523297)
			(xy 356.133196 -60.471206) (xy 356.160492 -60.422571) (xy 356.194578 -60.378428) (xy 356.234727 -60.339719)
			(xy 356.280085 -60.307268) (xy 356.329685 -60.281767) (xy 356.382469 -60.26376) (xy 356.437312 -60.25363)
			(xy 356.493046 -60.251593) (xy 356.548483 -60.257693) (xy 356.60244 -60.271799) (xy 356.653769 -60.293611)
			(xy 356.701375 -60.322665) (xy 356.744243 -60.35834) (xy 356.78146 -60.399877) (xy 356.812233 -60.44639)
			(xy 356.835905 -60.496887) (xy 356.851973 -60.550294) (xy 356.860093 -60.60547) (xy 356.860602 -60.633356)
			(xy 356.860093 -60.661242) (xy 356.851973 -60.716418) (xy 356.835905 -60.769825) (xy 356.812233 -60.820322)
			(xy 356.78146 -60.866835) (xy 356.744243 -60.908372) (xy 356.701375 -60.944047) (xy 356.653769 -60.973101)
			(xy 356.60244 -60.994913) (xy 356.548483 -61.009019) (xy 356.493046 -61.015119) (xy 356.437312 -61.013082)
			(xy 356.382469 -61.002952) (xy 356.329685 -60.984945) (xy 356.280085 -60.959444) (xy 356.234727 -60.926993)
			(xy 356.194578 -60.888284) (xy 356.160492 -60.844141) (xy 356.133196 -60.795506) (xy 356.113273 -60.743415)
			(xy 356.101147 -60.688978) (xy 356.097076 -60.633356) (xy 343.37244 -60.633356) (xy 343.37244 -61.487812)
			(xy 354.604572 -61.487812) (xy 354.608643 -61.43219) (xy 354.620769 -61.377753) (xy 354.640692 -61.325662)
			(xy 354.667988 -61.277027) (xy 354.702074 -61.232884) (xy 354.742223 -61.194175) (xy 354.787581 -61.161724)
			(xy 354.837181 -61.136223) (xy 354.889965 -61.118216) (xy 354.944808 -61.108086) (xy 355.000542 -61.106049)
			(xy 355.055979 -61.112149) (xy 355.109936 -61.126255) (xy 355.161265 -61.148067) (xy 355.208871 -61.177121)
			(xy 355.251739 -61.212796) (xy 355.288956 -61.254333) (xy 355.319729 -61.300846) (xy 355.343401 -61.351343)
			(xy 355.359469 -61.40475) (xy 355.367589 -61.459926) (xy 355.368098 -61.487812) (xy 355.367589 -61.515698)
			(xy 355.359469 -61.570874) (xy 355.343401 -61.624281) (xy 355.319729 -61.674778) (xy 355.288956 -61.721291)
			(xy 355.251739 -61.762828) (xy 355.208871 -61.798503) (xy 355.161265 -61.827557) (xy 355.109936 -61.849369)
			(xy 355.055979 -61.863475) (xy 355.000542 -61.869575) (xy 354.944808 -61.867538) (xy 354.889965 -61.857408)
			(xy 354.837181 -61.839401) (xy 354.787581 -61.8139) (xy 354.742223 -61.781449) (xy 354.702074 -61.74274)
			(xy 354.667988 -61.698597) (xy 354.640692 -61.649962) (xy 354.620769 -61.597871) (xy 354.608643 -61.543434)
			(xy 354.604572 -61.487812) (xy 343.37244 -61.487812) (xy 343.37244 -62.121034) (xy 352.542346 -62.121034)
			(xy 352.546417 -62.065412) (xy 352.558543 -62.010975) (xy 352.578466 -61.958884) (xy 352.605762 -61.910249)
			(xy 352.639848 -61.866106) (xy 352.679997 -61.827397) (xy 352.725355 -61.794946) (xy 352.774955 -61.769445)
			(xy 352.827739 -61.751438) (xy 352.882582 -61.741308) (xy 352.938316 -61.739271) (xy 352.993753 -61.745371)
			(xy 353.04771 -61.759477) (xy 353.099039 -61.781289) (xy 353.146645 -61.810343) (xy 353.189513 -61.846018)
			(xy 353.22673 -61.887555) (xy 353.257503 -61.934068) (xy 353.281175 -61.984565) (xy 353.297243 -62.037972)
			(xy 353.305363 -62.093148) (xy 353.305872 -62.121034) (xy 353.305363 -62.14892) (xy 353.297243 -62.204096)
			(xy 353.281175 -62.257503) (xy 353.257503 -62.308) (xy 353.22673 -62.354513) (xy 353.189513 -62.39605)
			(xy 353.146645 -62.431725) (xy 353.099039 -62.460779) (xy 353.04771 -62.482591) (xy 352.993753 -62.496697)
			(xy 352.938316 -62.502797) (xy 352.882582 -62.50076) (xy 352.827739 -62.49063) (xy 352.774955 -62.472623)
			(xy 352.725355 -62.447122) (xy 352.679997 -62.414671) (xy 352.639848 -62.375962) (xy 352.605762 -62.331819)
			(xy 352.578466 -62.283184) (xy 352.558543 -62.231093) (xy 352.546417 -62.176656) (xy 352.542346 -62.121034)
			(xy 343.37244 -62.121034) (xy 343.37244 -62.678772) (xy 355.966272 -62.678772) (xy 355.974025 -62.624824)
			(xy 355.989377 -62.572528) (xy 356.012015 -62.52295) (xy 356.041478 -62.477097) (xy 356.077166 -62.435905)
			(xy 356.118354 -62.400211) (xy 356.164202 -62.370741) (xy 356.213777 -62.348096) (xy 356.26607 -62.332737)
			(xy 356.320017 -62.324976) (xy 356.347268 -62.324488) (xy 356.370823 -62.324856) (xy 356.417567 -62.330721)
			(xy 356.440486 -62.336172) (xy 356.454255 -62.339149) (xy 356.4824 -62.338306) (xy 356.509246 -62.329811)
			(xy 356.532752 -62.31431) (xy 356.551133 -62.292979) (xy 356.562992 -62.26744) (xy 356.567427 -62.239634)
			(xy 356.564103 -62.211673) (xy 356.559104 -62.198504) (xy 356.549791 -62.175116) (xy 356.536667 -62.126514)
			(xy 356.530045 -62.076609) (xy 356.52964 -62.051438) (xy 356.530037 -62.024184) (xy 356.537789 -61.970231)
			(xy 356.55314 -61.917929) (xy 356.575778 -61.868345) (xy 356.605243 -61.822487) (xy 356.640933 -61.78129)
			(xy 356.682124 -61.74559) (xy 356.727975 -61.716117) (xy 356.777555 -61.693468) (xy 356.829853 -61.678106)
			(xy 356.883805 -61.670343) (xy 356.938313 -61.670337) (xy 356.992266 -61.678088) (xy 357.044568 -61.693439)
			(xy 357.094152 -61.716077) (xy 357.14001 -61.745541) (xy 357.181208 -61.781231) (xy 357.216908 -61.822421)
			(xy 357.246382 -61.868273) (xy 357.269031 -61.917852) (xy 357.284393 -61.97015) (xy 357.292157 -62.024102)
			(xy 357.292163 -62.078609) (xy 357.284412 -62.132563) (xy 357.269062 -62.184864) (xy 357.246425 -62.234449)
			(xy 357.216961 -62.280307) (xy 357.181271 -62.321506) (xy 357.140082 -62.357206) (xy 357.09423 -62.38668)
			(xy 357.044651 -62.40933) (xy 356.992354 -62.424693) (xy 356.938402 -62.432457) (xy 356.911148 -62.432946)
			(xy 356.887593 -62.432575) (xy 356.840849 -62.426712) (xy 356.81793 -62.421262) (xy 356.804165 -62.418255)
			(xy 356.776013 -62.419093) (xy 356.749159 -62.427588) (xy 356.725647 -62.443094) (xy 356.707262 -62.464431)
			(xy 356.695404 -62.489978) (xy 356.690974 -62.517792) (xy 356.694308 -62.545759) (xy 356.699312 -62.55893)
			(xy 356.708637 -62.582314) (xy 356.721756 -62.630918) (xy 356.728373 -62.680824) (xy 356.728776 -62.705996)
			(xy 356.728327 -62.733247) (xy 356.720571 -62.787195) (xy 356.705216 -62.839489) (xy 356.682576 -62.889067)
			(xy 356.653111 -62.934918) (xy 356.617421 -62.976108) (xy 356.576231 -63.011801) (xy 356.530382 -63.041268)
			(xy 356.480806 -63.06391) (xy 356.428512 -63.079267) (xy 356.374564 -63.087025) (xy 356.320062 -63.087027)
			(xy 356.266114 -63.079273) (xy 356.213819 -63.06392) (xy 356.164241 -63.041281) (xy 356.11839 -63.011817)
			(xy 356.077198 -62.976127) (xy 356.041505 -62.934939) (xy 356.012037 -62.88909) (xy 355.989393 -62.839514)
			(xy 355.974035 -62.787221) (xy 355.966275 -62.733274) (xy 355.966272 -62.678772) (xy 343.37244 -62.678772)
			(xy 343.37244 -63.086234) (xy 349.68764 -63.086234) (xy 349.691711 -63.030612) (xy 349.703837 -62.976175)
			(xy 349.72376 -62.924084) (xy 349.751056 -62.875449) (xy 349.785142 -62.831306) (xy 349.825291 -62.792597)
			(xy 349.870649 -62.760146) (xy 349.920249 -62.734645) (xy 349.973033 -62.716638) (xy 350.027876 -62.706508)
			(xy 350.08361 -62.704471) (xy 350.139047 -62.710571) (xy 350.193004 -62.724677) (xy 350.244333 -62.746489)
			(xy 350.291939 -62.775543) (xy 350.334807 -62.811218) (xy 350.372024 -62.852755) (xy 350.402797 -62.899268)
			(xy 350.426469 -62.949765) (xy 350.442537 -63.003172) (xy 350.450657 -63.058348) (xy 350.451166 -63.086234)
			(xy 350.450657 -63.11412) (xy 350.442537 -63.169296) (xy 350.426469 -63.222703) (xy 350.402797 -63.2732)
			(xy 350.402644 -63.273432) (xy 351.876866 -63.273432) (xy 351.880937 -63.21781) (xy 351.893063 -63.163373)
			(xy 351.912986 -63.111282) (xy 351.940282 -63.062647) (xy 351.974368 -63.018504) (xy 352.014517 -62.979795)
			(xy 352.059875 -62.947344) (xy 352.109475 -62.921843) (xy 352.162259 -62.903836) (xy 352.217102 -62.893706)
			(xy 352.272836 -62.891669) (xy 352.328273 -62.897769) (xy 352.38223 -62.911875) (xy 352.433559 -62.933687)
			(xy 352.481165 -62.962741) (xy 352.524033 -62.998416) (xy 352.56125 -63.039953) (xy 352.592023 -63.086466)
			(xy 352.615695 -63.136963) (xy 352.631763 -63.19037) (xy 352.639883 -63.245546) (xy 352.640392 -63.273432)
			(xy 352.639883 -63.301318) (xy 352.631763 -63.356494) (xy 352.615695 -63.409901) (xy 352.592023 -63.460398)
			(xy 352.56125 -63.506911) (xy 352.524033 -63.548448) (xy 352.481165 -63.584123) (xy 352.433559 -63.613177)
			(xy 352.38223 -63.634989) (xy 352.328273 -63.649095) (xy 352.272836 -63.655195) (xy 352.217102 -63.653158)
			(xy 352.162259 -63.643028) (xy 352.109475 -63.625021) (xy 352.059875 -63.59952) (xy 352.014517 -63.567069)
			(xy 351.974368 -63.52836) (xy 351.940282 -63.484217) (xy 351.912986 -63.435582) (xy 351.893063 -63.383491)
			(xy 351.880937 -63.329054) (xy 351.876866 -63.273432) (xy 350.402644 -63.273432) (xy 350.372024 -63.319713)
			(xy 350.334807 -63.36125) (xy 350.291939 -63.396925) (xy 350.244333 -63.425979) (xy 350.193004 -63.447791)
			(xy 350.139047 -63.461897) (xy 350.08361 -63.467997) (xy 350.027876 -63.46596) (xy 349.973033 -63.45583)
			(xy 349.920249 -63.437823) (xy 349.870649 -63.412322) (xy 349.825291 -63.379871) (xy 349.785142 -63.341162)
			(xy 349.751056 -63.297019) (xy 349.72376 -63.248384) (xy 349.703837 -63.196293) (xy 349.691711 -63.141856)
			(xy 349.68764 -63.086234) (xy 343.37244 -63.086234) (xy 343.37244 -65.124076) (xy 354.407468 -65.124076)
			(xy 354.411539 -65.068454) (xy 354.423665 -65.014017) (xy 354.443588 -64.961926) (xy 354.470884 -64.913291)
			(xy 354.50497 -64.869148) (xy 354.545119 -64.830439) (xy 354.590477 -64.797988) (xy 354.640077 -64.772487)
			(xy 354.692861 -64.75448) (xy 354.747704 -64.74435) (xy 354.803438 -64.742313) (xy 354.858875 -64.748413)
			(xy 354.912832 -64.762519) (xy 354.964161 -64.784331) (xy 355.011767 -64.813385) (xy 355.054635 -64.84906)
			(xy 355.091852 -64.890597) (xy 355.122625 -64.93711) (xy 355.146297 -64.987607) (xy 355.162365 -65.041014)
			(xy 355.170485 -65.09619) (xy 355.170994 -65.124076) (xy 355.170485 -65.151962) (xy 355.162365 -65.207138)
			(xy 355.146297 -65.260545) (xy 355.122625 -65.311042) (xy 355.091852 -65.357555) (xy 355.054635 -65.399092)
			(xy 355.011767 -65.434767) (xy 354.964161 -65.463821) (xy 354.912832 -65.485633) (xy 354.858875 -65.499739)
			(xy 354.803438 -65.505839) (xy 354.747704 -65.503802) (xy 354.692861 -65.493672) (xy 354.640077 -65.475665)
			(xy 354.590477 -65.450164) (xy 354.545119 -65.417713) (xy 354.50497 -65.379004) (xy 354.470884 -65.334861)
			(xy 354.443588 -65.286226) (xy 354.423665 -65.234135) (xy 354.411539 -65.179698) (xy 354.407468 -65.124076)
			(xy 343.37244 -65.124076) (xy 343.37244 -76.386436) (xy 343.372514 -76.39091) (xy 343.374054 -76.399723)
			(xy 343.375488 -76.403962) (xy 343.377498 -76.409057) (xy 343.383394 -76.418285) (xy 343.387172 -76.42225)
			(xy 348.466324 -81.501234) (xy 351.221292 -81.501234) (xy 351.225363 -81.445612) (xy 351.237489 -81.391175)
			(xy 351.257412 -81.339084) (xy 351.284708 -81.290449) (xy 351.318794 -81.246306) (xy 351.358943 -81.207597)
			(xy 351.404301 -81.175146) (xy 351.453901 -81.149645) (xy 351.506685 -81.131638) (xy 351.561528 -81.121508)
			(xy 351.617262 -81.119471) (xy 351.672699 -81.125571) (xy 351.726656 -81.139677) (xy 351.777985 -81.161489)
			(xy 351.825591 -81.190543) (xy 351.868459 -81.226218) (xy 351.905676 -81.267755) (xy 351.936449 -81.314268)
			(xy 351.960121 -81.364765) (xy 351.975044 -81.414366) (xy 354.132386 -81.414366) (xy 354.136457 -81.358744)
			(xy 354.148583 -81.304307) (xy 354.168506 -81.252216) (xy 354.195802 -81.203581) (xy 354.229888 -81.159438)
			(xy 354.270037 -81.120729) (xy 354.315395 -81.088278) (xy 354.364995 -81.062777) (xy 354.417779 -81.04477)
			(xy 354.472622 -81.03464) (xy 354.528356 -81.032603) (xy 354.583793 -81.038703) (xy 354.63775 -81.052809)
			(xy 354.689079 -81.074621) (xy 354.736685 -81.103675) (xy 354.779553 -81.13935) (xy 354.81677 -81.180887)
			(xy 354.847543 -81.2274) (xy 354.871215 -81.277897) (xy 354.887283 -81.331304) (xy 354.895403 -81.38648)
			(xy 354.895912 -81.414366) (xy 354.895403 -81.442252) (xy 354.887283 -81.497428) (xy 354.871215 -81.550835)
			(xy 354.847543 -81.601332) (xy 354.81677 -81.647845) (xy 354.779553 -81.689382) (xy 354.736685 -81.725057)
			(xy 354.689079 -81.754111) (xy 354.63775 -81.775923) (xy 354.583793 -81.790029) (xy 354.528356 -81.796129)
			(xy 354.472622 -81.794092) (xy 354.417779 -81.783962) (xy 354.364995 -81.765955) (xy 354.315395 -81.740454)
			(xy 354.270037 -81.708003) (xy 354.229888 -81.669294) (xy 354.195802 -81.625151) (xy 354.168506 -81.576516)
			(xy 354.148583 -81.524425) (xy 354.136457 -81.469988) (xy 354.132386 -81.414366) (xy 351.975044 -81.414366)
			(xy 351.976189 -81.418172) (xy 351.984309 -81.473348) (xy 351.984818 -81.501234) (xy 351.984309 -81.52912)
			(xy 351.976189 -81.584296) (xy 351.960121 -81.637703) (xy 351.936449 -81.6882) (xy 351.905676 -81.734713)
			(xy 351.868459 -81.77625) (xy 351.825591 -81.811925) (xy 351.777985 -81.840979) (xy 351.726656 -81.862791)
			(xy 351.672699 -81.876897) (xy 351.617262 -81.882997) (xy 351.561528 -81.88096) (xy 351.506685 -81.87083)
			(xy 351.453901 -81.852823) (xy 351.404301 -81.827322) (xy 351.358943 -81.794871) (xy 351.318794 -81.756162)
			(xy 351.284708 -81.712019) (xy 351.257412 -81.663384) (xy 351.237489 -81.611293) (xy 351.225363 -81.556856)
			(xy 351.221292 -81.501234) (xy 348.466324 -81.501234) (xy 349.609362 -82.644234) (xy 351.221292 -82.644234)
			(xy 351.225363 -82.588612) (xy 351.237489 -82.534175) (xy 351.257412 -82.482084) (xy 351.284708 -82.433449)
			(xy 351.318794 -82.389306) (xy 351.358943 -82.350597) (xy 351.404301 -82.318146) (xy 351.453901 -82.292645)
			(xy 351.506685 -82.274638) (xy 351.561528 -82.264508) (xy 351.617262 -82.262471) (xy 351.672699 -82.268571)
			(xy 351.726656 -82.282677) (xy 351.777985 -82.304489) (xy 351.825591 -82.333543) (xy 351.868459 -82.369218)
			(xy 351.905676 -82.410755) (xy 351.936449 -82.457268) (xy 351.960121 -82.507765) (xy 351.976189 -82.561172)
			(xy 351.984309 -82.616348) (xy 351.984818 -82.644234) (xy 351.984309 -82.67212) (xy 351.982507 -82.684366)
			(xy 354.092254 -82.684366) (xy 354.096325 -82.628744) (xy 354.108451 -82.574307) (xy 354.128374 -82.522216)
			(xy 354.15567 -82.473581) (xy 354.189756 -82.429438) (xy 354.229905 -82.390729) (xy 354.275263 -82.358278)
			(xy 354.324863 -82.332777) (xy 354.377647 -82.31477) (xy 354.43249 -82.30464) (xy 354.488224 -82.302603)
			(xy 354.543661 -82.308703) (xy 354.597618 -82.322809) (xy 354.648947 -82.344621) (xy 354.696553 -82.373675)
			(xy 354.739421 -82.40935) (xy 354.776638 -82.450887) (xy 354.807411 -82.4974) (xy 354.831083 -82.547897)
			(xy 354.847151 -82.601304) (xy 354.855271 -82.65648) (xy 354.85578 -82.684366) (xy 354.855271 -82.712252)
			(xy 354.847151 -82.767428) (xy 354.831083 -82.820835) (xy 354.807411 -82.871332) (xy 354.776638 -82.917845)
			(xy 354.739421 -82.959382) (xy 354.696553 -82.995057) (xy 354.648947 -83.024111) (xy 354.597618 -83.045923)
			(xy 354.543661 -83.060029) (xy 354.488224 -83.066129) (xy 354.43249 -83.064092) (xy 354.377647 -83.053962)
			(xy 354.324863 -83.035955) (xy 354.275263 -83.010454) (xy 354.229905 -82.978003) (xy 354.189756 -82.939294)
			(xy 354.15567 -82.895151) (xy 354.128374 -82.846516) (xy 354.108451 -82.794425) (xy 354.096325 -82.739988)
			(xy 354.092254 -82.684366) (xy 351.982507 -82.684366) (xy 351.976189 -82.727296) (xy 351.960121 -82.780703)
			(xy 351.936449 -82.8312) (xy 351.905676 -82.877713) (xy 351.868459 -82.91925) (xy 351.825591 -82.954925)
			(xy 351.777985 -82.983979) (xy 351.726656 -83.005791) (xy 351.672699 -83.019897) (xy 351.617262 -83.025997)
			(xy 351.561528 -83.02396) (xy 351.506685 -83.01383) (xy 351.453901 -82.995823) (xy 351.404301 -82.970322)
			(xy 351.358943 -82.937871) (xy 351.318794 -82.899162) (xy 351.284708 -82.855019) (xy 351.257412 -82.806384)
			(xy 351.237489 -82.754293) (xy 351.225363 -82.699856) (xy 351.221292 -82.644234) (xy 349.609362 -82.644234)
			(xy 350.7524 -83.787234) (xy 351.221292 -83.787234) (xy 351.225363 -83.731612) (xy 351.237489 -83.677175)
			(xy 351.257412 -83.625084) (xy 351.284708 -83.576449) (xy 351.318794 -83.532306) (xy 351.358943 -83.493597)
			(xy 351.404301 -83.461146) (xy 351.453901 -83.435645) (xy 351.506685 -83.417638) (xy 351.561528 -83.407508)
			(xy 351.617262 -83.405471) (xy 351.672699 -83.411571) (xy 351.726656 -83.425677) (xy 351.777985 -83.447489)
			(xy 351.825591 -83.476543) (xy 351.868459 -83.512218) (xy 351.905676 -83.553755) (xy 351.936449 -83.600268)
			(xy 351.960121 -83.650765) (xy 351.976189 -83.704172) (xy 351.984309 -83.759348) (xy 351.984818 -83.787234)
			(xy 351.984309 -83.81512) (xy 351.976189 -83.870296) (xy 351.960121 -83.923703) (xy 351.945747 -83.954366)
			(xy 354.132386 -83.954366) (xy 354.136457 -83.898744) (xy 354.148583 -83.844307) (xy 354.168506 -83.792216)
			(xy 354.195802 -83.743581) (xy 354.229888 -83.699438) (xy 354.270037 -83.660729) (xy 354.315395 -83.628278)
			(xy 354.364995 -83.602777) (xy 354.417779 -83.58477) (xy 354.472622 -83.57464) (xy 354.528356 -83.572603)
			(xy 354.583793 -83.578703) (xy 354.63775 -83.592809) (xy 354.689079 -83.614621) (xy 354.736685 -83.643675)
			(xy 354.779553 -83.67935) (xy 354.81677 -83.720887) (xy 354.847543 -83.7674) (xy 354.871215 -83.817897)
			(xy 354.887283 -83.871304) (xy 354.895403 -83.92648) (xy 354.895912 -83.954366) (xy 354.895403 -83.982252)
			(xy 354.887283 -84.037428) (xy 354.871215 -84.090835) (xy 354.847543 -84.141332) (xy 354.81677 -84.187845)
			(xy 354.779553 -84.229382) (xy 354.736685 -84.265057) (xy 354.689079 -84.294111) (xy 354.63775 -84.315923)
			(xy 354.583793 -84.330029) (xy 354.528356 -84.336129) (xy 354.472622 -84.334092) (xy 354.417779 -84.323962)
			(xy 354.364995 -84.305955) (xy 354.315395 -84.280454) (xy 354.270037 -84.248003) (xy 354.229888 -84.209294)
			(xy 354.195802 -84.165151) (xy 354.168506 -84.116516) (xy 354.148583 -84.064425) (xy 354.136457 -84.009988)
			(xy 354.132386 -83.954366) (xy 351.945747 -83.954366) (xy 351.936449 -83.9742) (xy 351.905676 -84.020713)
			(xy 351.868459 -84.06225) (xy 351.825591 -84.097925) (xy 351.777985 -84.126979) (xy 351.726656 -84.148791)
			(xy 351.672699 -84.162897) (xy 351.617262 -84.168997) (xy 351.561528 -84.16696) (xy 351.506685 -84.15683)
			(xy 351.453901 -84.138823) (xy 351.404301 -84.113322) (xy 351.358943 -84.080871) (xy 351.318794 -84.042162)
			(xy 351.284708 -83.998019) (xy 351.257412 -83.949384) (xy 351.237489 -83.897293) (xy 351.225363 -83.842856)
			(xy 351.221292 -83.787234) (xy 350.7524 -83.787234) (xy 351.054924 -84.089748) (xy 351.072961 -84.108517)
			(xy 351.10355 -84.150631) (xy 351.127185 -84.197007) (xy 351.143286 -84.246505) (xy 351.151458 -84.297911)
			(xy 351.151952 -84.323936) (xy 351.151952 -84.638134) (xy 351.156401 -84.64371) (xy 351.167746 -84.652347)
			(xy 351.174304 -84.655152) (xy 351.236026 -84.679028) (xy 351.262188 -84.689188) (xy 351.270802 -84.692121)
			(xy 351.288986 -84.69234) (xy 351.306096 -84.686183) (xy 351.313242 -84.680552) (xy 351.318068 -84.676488)
			(xy 351.320354 -84.673948) (xy 351.338001 -84.655119) (xy 351.377496 -84.621907) (xy 351.421106 -84.594317)
			(xy 351.468034 -84.572852) (xy 351.517426 -84.557904) (xy 351.568381 -84.549745) (xy 351.594166 -84.548726)
			(xy 351.605596 -84.548726) (xy 351.621598 -84.54898) (xy 351.63125 -84.549742) (xy 351.659716 -84.552344)
			(xy 351.715459 -84.56499) (xy 351.768692 -84.585811) (xy 351.818222 -84.614341) (xy 351.862942 -84.649942)
			(xy 351.901849 -84.691816) (xy 351.934073 -84.739027) (xy 351.958894 -84.790517) (xy 351.975754 -84.845133)
			(xy 351.984277 -84.901654) (xy 351.984818 -84.930234) (xy 351.98433 -84.957484) (xy 351.97657 -85.011429)
			(xy 351.961212 -85.06372) (xy 351.938569 -85.113293) (xy 351.909102 -85.15914) (xy 351.87341 -85.200327)
			(xy 351.845666 -85.224366) (xy 354.134926 -85.224366) (xy 354.138997 -85.168744) (xy 354.151123 -85.114307)
			(xy 354.171046 -85.062216) (xy 354.198342 -85.013581) (xy 354.232428 -84.969438) (xy 354.272577 -84.930729)
			(xy 354.317935 -84.898278) (xy 354.367535 -84.872777) (xy 354.420319 -84.85477) (xy 354.475162 -84.84464)
			(xy 354.530896 -84.842603) (xy 354.586333 -84.848703) (xy 354.64029 -84.862809) (xy 354.691619 -84.884621)
			(xy 354.739225 -84.913675) (xy 354.782093 -84.94935) (xy 354.81931 -84.990887) (xy 354.850083 -85.0374)
			(xy 354.873755 -85.087897) (xy 354.889823 -85.141304) (xy 354.897943 -85.19648) (xy 354.898452 -85.224366)
			(xy 354.897943 -85.252252) (xy 354.889823 -85.307428) (xy 354.873755 -85.360835) (xy 354.850083 -85.411332)
			(xy 354.81931 -85.457845) (xy 354.782093 -85.499382) (xy 354.739225 -85.535057) (xy 354.691619 -85.564111)
			(xy 354.64029 -85.585923) (xy 354.586333 -85.600029) (xy 354.530896 -85.606129) (xy 354.475162 -85.604092)
			(xy 354.420319 -85.593962) (xy 354.367535 -85.575955) (xy 354.317935 -85.550454) (xy 354.272577 -85.518003)
			(xy 354.232428 -85.479294) (xy 354.198342 -85.435151) (xy 354.171046 -85.386516) (xy 354.151123 -85.334425)
			(xy 354.138997 -85.279988) (xy 354.134926 -85.224366) (xy 351.845666 -85.224366) (xy 351.832221 -85.236016)
			(xy 351.786372 -85.26548) (xy 351.736797 -85.28812) (xy 351.684505 -85.303475) (xy 351.63056 -85.311232)
			(xy 351.60331 -85.311742) (xy 351.593404 -85.311742) (xy 351.565718 -85.309964) (xy 351.560638 -85.309456)
			(xy 351.560384 -85.309456) (xy 351.545144 -85.307932) (xy 351.535238 -85.306154) (xy 351.531936 -85.305646)
			(xy 351.51949 -85.302852) (xy 351.507948 -85.300112) (xy 351.485199 -85.293373) (xy 351.474024 -85.28939)
			(xy 351.450837 -85.280622) (xy 351.406755 -85.257945) (xy 351.38614 -85.244178) (xy 351.371408 -85.233764)
			(xy 351.367852 -85.23097) (xy 351.3582 -85.222842) (xy 351.345246 -85.211412) (xy 351.344992 -85.211158)
			(xy 351.319084 -85.18525) (xy 351.311972 -85.177376) (xy 351.292414 -85.16874) (xy 351.277428 -85.16874)
			(xy 351.273219 -85.168818) (xy 351.264917 -85.170219) (xy 351.260918 -85.171534) (xy 351.240344 -85.179916)
			(xy 351.239836 -85.179916) (xy 351.174304 -85.205316) (xy 351.167741 -85.208114) (xy 351.156396 -85.216753)
			(xy 351.151952 -85.222334) (xy 351.151952 -85.384386) (xy 351.154509 -85.38766) (xy 351.160508 -85.393405)
			(xy 351.16389 -85.395816) (xy 351.23374 -85.443568) (xy 351.23892 -85.446944) (xy 351.250481 -85.451319)
			(xy 351.2566 -85.452204) (xy 351.269046 -85.453474) (xy 351.280984 -85.448648) (xy 351.303454 -85.440124)
			(xy 351.349995 -85.428145) (xy 351.397671 -85.422095) (xy 351.4217 -85.421724) (xy 351.435416 -85.421724)
			(xy 351.43821 -85.421978) (xy 351.439226 -85.422232) (xy 351.441258 -85.422232) (xy 351.470204 -85.424244)
			(xy 351.527037 -85.435927) (xy 351.581446 -85.45608) (xy 351.632176 -85.484238) (xy 351.678059 -85.519753)
			(xy 351.718035 -85.561804) (xy 351.751184 -85.609423) (xy 351.776742 -85.661513) (xy 351.794118 -85.716871)
			(xy 351.802913 -85.774221) (xy 351.803462 -85.803232) (xy 351.802984 -85.830345) (xy 351.795302 -85.884024)
			(xy 351.780099 -85.936074) (xy 351.757679 -85.985448) (xy 351.728495 -86.03115) (xy 351.693134 -86.072261)
			(xy 351.65231 -86.107951) (xy 351.606844 -86.137502) (xy 351.557652 -86.160318) (xy 351.505725 -86.17594)
			(xy 351.45211 -86.184053) (xy 351.425002 -86.18474) (xy 351.423224 -86.18474) (xy 351.399756 -86.184493)
			(xy 351.353155 -86.178924) (xy 351.307592 -86.167668) (xy 351.285556 -86.159594) (xy 351.282254 -86.158324)
			(xy 351.270824 -86.155784) (xy 351.260896 -86.154294) (xy 351.241254 -86.158363) (xy 351.232724 -86.163658)
			(xy 351.163128 -86.210902) (xy 351.159973 -86.213238) (xy 351.154362 -86.218726) (xy 351.151952 -86.221824)
			(xy 351.151952 -86.494366) (xy 354.132386 -86.494366) (xy 354.136457 -86.438744) (xy 354.148583 -86.384307)
			(xy 354.168506 -86.332216) (xy 354.195802 -86.283581) (xy 354.229888 -86.239438) (xy 354.270037 -86.200729)
			(xy 354.315395 -86.168278) (xy 354.364995 -86.142777) (xy 354.417779 -86.12477) (xy 354.472622 -86.11464)
			(xy 354.528356 -86.112603) (xy 354.583793 -86.118703) (xy 354.63775 -86.132809) (xy 354.689079 -86.154621)
			(xy 354.736685 -86.183675) (xy 354.779553 -86.21935) (xy 354.81677 -86.260887) (xy 354.847543 -86.3074)
			(xy 354.871215 -86.357897) (xy 354.887283 -86.411304) (xy 354.895403 -86.46648) (xy 354.895912 -86.494366)
			(xy 354.895403 -86.522252) (xy 354.887283 -86.577428) (xy 354.871215 -86.630835) (xy 354.847543 -86.681332)
			(xy 354.81677 -86.727845) (xy 354.779553 -86.769382) (xy 354.736685 -86.805057) (xy 354.689079 -86.834111)
			(xy 354.63775 -86.855923) (xy 354.583793 -86.870029) (xy 354.528356 -86.876129) (xy 354.472622 -86.874092)
			(xy 354.417779 -86.863962) (xy 354.364995 -86.845955) (xy 354.315395 -86.820454) (xy 354.270037 -86.788003)
			(xy 354.229888 -86.749294) (xy 354.195802 -86.705151) (xy 354.168506 -86.656516) (xy 354.148583 -86.604425)
			(xy 354.136457 -86.549988) (xy 354.132386 -86.494366) (xy 351.151952 -86.494366) (xy 351.151952 -86.653116)
			(xy 351.154754 -86.656666) (xy 351.161395 -86.662804) (xy 351.16516 -86.665308) (xy 351.195132 -86.684612)
			(xy 351.199958 -86.68766) (xy 351.20961 -86.695534) (xy 351.212658 -86.698836) (xy 351.220128 -86.706175)
			(xy 351.239283 -86.714583) (xy 351.249742 -86.715092) (xy 351.28073 -86.715092) (xy 351.290128 -86.711028)
			(xy 351.313737 -86.701538) (xy 351.362837 -86.688185) (xy 351.413276 -86.681471) (xy 351.438718 -86.681056)
			(xy 351.438972 -86.681056) (xy 351.43948 -86.681056) (xy 351.439988 -86.681056) (xy 351.443036 -86.681056)
			(xy 351.470288 -86.681544) (xy 351.524237 -86.689306) (xy 351.576532 -86.704665) (xy 351.62611 -86.727311)
			(xy 351.67196 -86.756781) (xy 351.71315 -86.792476) (xy 351.748841 -86.833669) (xy 351.778307 -86.879522)
			(xy 351.800947 -86.929101) (xy 351.816302 -86.981398) (xy 351.824058 -87.035348) (xy 351.824058 -87.089852)
			(xy 351.816302 -87.143802) (xy 351.800947 -87.196099) (xy 351.778307 -87.245678) (xy 351.748841 -87.291531)
			(xy 351.71315 -87.332724) (xy 351.67196 -87.368419) (xy 351.62611 -87.397889) (xy 351.576532 -87.420535)
			(xy 351.524237 -87.435894) (xy 351.470288 -87.443656) (xy 351.443036 -87.444072) (xy 351.442274 -87.444072)
			(xy 351.416039 -87.44364) (xy 351.364065 -87.436451) (xy 351.313569 -87.4222) (xy 351.289366 -87.412068)
			(xy 351.284794 -87.410036) (xy 351.274888 -87.40775) (xy 351.267436 -87.406318) (xy 351.252312 -87.407473)
			(xy 351.24517 -87.410036) (xy 351.236026 -87.414608) (xy 351.201482 -87.436706) (xy 351.200974 -87.436706)
			(xy 351.169478 -87.457026) (xy 351.16135 -87.46363) (xy 351.159572 -87.465408) (xy 351.155762 -87.474552)
			(xy 351.153983 -87.479179) (xy 351.152054 -87.4889) (xy 351.151952 -87.493856) (xy 351.151952 -87.764366)
			(xy 354.132386 -87.764366) (xy 354.136457 -87.708744) (xy 354.148583 -87.654307) (xy 354.168506 -87.602216)
			(xy 354.195802 -87.553581) (xy 354.229888 -87.509438) (xy 354.270037 -87.470729) (xy 354.315395 -87.438278)
			(xy 354.364995 -87.412777) (xy 354.417779 -87.39477) (xy 354.472622 -87.38464) (xy 354.528356 -87.382603)
			(xy 354.583793 -87.388703) (xy 354.63775 -87.402809) (xy 354.689079 -87.424621) (xy 354.736685 -87.453675)
			(xy 354.779553 -87.48935) (xy 354.81677 -87.530887) (xy 354.847543 -87.5774) (xy 354.871215 -87.627897)
			(xy 354.887283 -87.681304) (xy 354.895403 -87.73648) (xy 354.895912 -87.764366) (xy 354.895403 -87.792252)
			(xy 354.887283 -87.847428) (xy 354.871215 -87.900835) (xy 354.847543 -87.951332) (xy 354.81677 -87.997845)
			(xy 354.779553 -88.039382) (xy 354.736685 -88.075057) (xy 354.689079 -88.104111) (xy 354.63775 -88.125923)
			(xy 354.583793 -88.140029) (xy 354.528356 -88.146129) (xy 354.472622 -88.144092) (xy 354.417779 -88.133962)
			(xy 354.364995 -88.115955) (xy 354.315395 -88.090454) (xy 354.270037 -88.058003) (xy 354.229888 -88.019294)
			(xy 354.195802 -87.975151) (xy 354.168506 -87.926516) (xy 354.148583 -87.874425) (xy 354.136457 -87.819988)
			(xy 354.132386 -87.764366) (xy 351.151952 -87.764366) (xy 351.151952 -88.333072) (xy 351.15627 -88.338152)
			(xy 351.16262 -88.344502) (xy 351.195894 -88.36787) (xy 351.196402 -88.36787) (xy 351.233994 -88.394032)
			(xy 351.237628 -88.396107) (xy 351.245415 -88.399166) (xy 351.249488 -88.400128) (xy 351.253751 -88.400986)
			(xy 351.262438 -88.401372) (xy 351.26676 -88.40089) (xy 351.275904 -88.399112) (xy 351.279714 -88.397842)
			(xy 351.311166 -88.387188) (xy 351.376562 -88.375695) (xy 351.409762 -88.374982) (xy 351.41027 -88.374982)
			(xy 351.437561 -88.375444) (xy 351.491587 -88.383207) (xy 351.543958 -88.398581) (xy 351.593608 -88.421252)
			(xy 351.639526 -88.450759) (xy 351.680778 -88.4865) (xy 351.716522 -88.527748) (xy 351.746032 -88.573664)
			(xy 351.768708 -88.623312) (xy 351.784086 -88.675682) (xy 351.791854 -88.729707) (xy 351.792286 -88.756998)
			(xy 351.791883 -88.782114) (xy 351.785296 -88.831914) (xy 351.772249 -88.880423) (xy 351.752966 -88.926807)
			(xy 351.727778 -88.970269) (xy 351.712784 -88.990424) (xy 351.71126 -88.992202) (xy 351.706688 -88.999568)
			(xy 351.70618 -89.00033) (xy 351.704148 -89.004394) (xy 351.700084 -89.0143) (xy 351.700084 -89.031572)
			(xy 351.700475 -89.034366) (xy 354.132386 -89.034366) (xy 354.136457 -88.978744) (xy 354.148583 -88.924307)
			(xy 354.168506 -88.872216) (xy 354.195802 -88.823581) (xy 354.229888 -88.779438) (xy 354.270037 -88.740729)
			(xy 354.315395 -88.708278) (xy 354.364995 -88.682777) (xy 354.417779 -88.66477) (xy 354.472622 -88.65464)
			(xy 354.528356 -88.652603) (xy 354.583793 -88.658703) (xy 354.63775 -88.672809) (xy 354.689079 -88.694621)
			(xy 354.736685 -88.723675) (xy 354.779553 -88.75935) (xy 354.81677 -88.800887) (xy 354.847543 -88.8474)
			(xy 354.871215 -88.897897) (xy 354.887283 -88.951304) (xy 354.895403 -89.00648) (xy 354.895912 -89.034366)
			(xy 354.895403 -89.062252) (xy 354.887283 -89.117428) (xy 354.871215 -89.170835) (xy 354.847543 -89.221332)
			(xy 354.81677 -89.267845) (xy 354.779553 -89.309382) (xy 354.736685 -89.345057) (xy 354.689079 -89.374111)
			(xy 354.63775 -89.395923) (xy 354.583793 -89.410029) (xy 354.528356 -89.416129) (xy 354.472622 -89.414092)
			(xy 354.417779 -89.403962) (xy 354.364995 -89.385955) (xy 354.315395 -89.360454) (xy 354.270037 -89.328003)
			(xy 354.229888 -89.289294) (xy 354.195802 -89.245151) (xy 354.168506 -89.196516) (xy 354.148583 -89.144425)
			(xy 354.136457 -89.089988) (xy 354.132386 -89.034366) (xy 351.700475 -89.034366) (xy 351.701862 -89.044272)
			(xy 351.717356 -89.10447) (xy 351.719024 -89.110055) (xy 351.724535 -89.120323) (xy 351.728278 -89.12479)
			(xy 351.750122 -89.149936) (xy 351.75698 -89.152984) (xy 351.782035 -89.164539) (xy 351.828809 -89.1938)
			(xy 351.870878 -89.229495) (xy 351.907366 -89.270879) (xy 351.93751 -89.317089) (xy 351.960681 -89.367161)
			(xy 351.976395 -89.420048) (xy 351.984326 -89.474648) (xy 351.984818 -89.502234) (xy 351.98433 -89.529484)
			(xy 351.97657 -89.583429) (xy 351.961212 -89.63572) (xy 351.938569 -89.685293) (xy 351.909102 -89.73114)
			(xy 351.87341 -89.772327) (xy 351.832221 -89.808016) (xy 351.786372 -89.83748) (xy 351.736797 -89.86012)
			(xy 351.684505 -89.875475) (xy 351.63056 -89.883232) (xy 351.60331 -89.883742) (xy 351.593404 -89.883742)
			(xy 351.565718 -89.881964) (xy 351.560638 -89.881456) (xy 351.560384 -89.881456) (xy 351.545144 -89.879932)
			(xy 351.535238 -89.878154) (xy 351.531936 -89.877646) (xy 351.51949 -89.874852) (xy 351.507948 -89.872112)
			(xy 351.485199 -89.865373) (xy 351.474024 -89.86139) (xy 351.450837 -89.852622) (xy 351.406755 -89.829945)
			(xy 351.38614 -89.816178) (xy 351.371408 -89.805764) (xy 351.367852 -89.80297) (xy 351.3582 -89.794842)
			(xy 351.345246 -89.783412) (xy 351.344992 -89.783158) (xy 351.319084 -89.75725) (xy 351.311972 -89.749376)
			(xy 351.292414 -89.74074) (xy 351.277428 -89.74074) (xy 351.273219 -89.740818) (xy 351.264917 -89.742219)
			(xy 351.260918 -89.743534) (xy 351.240344 -89.751916) (xy 351.239836 -89.751916) (xy 351.174304 -89.777316)
			(xy 351.167741 -89.780114) (xy 351.156396 -89.788753) (xy 351.151952 -89.794334) (xy 351.151952 -90.304366)
			(xy 354.132386 -90.304366) (xy 354.136457 -90.248744) (xy 354.148583 -90.194307) (xy 354.168506 -90.142216)
			(xy 354.195802 -90.093581) (xy 354.229888 -90.049438) (xy 354.270037 -90.010729) (xy 354.315395 -89.978278)
			(xy 354.364995 -89.952777) (xy 354.417779 -89.93477) (xy 354.472622 -89.92464) (xy 354.528356 -89.922603)
			(xy 354.583793 -89.928703) (xy 354.63775 -89.942809) (xy 354.689079 -89.964621) (xy 354.736685 -89.993675)
			(xy 354.779553 -90.02935) (xy 354.81677 -90.070887) (xy 354.847543 -90.1174) (xy 354.871215 -90.167897)
			(xy 354.887283 -90.221304) (xy 354.895403 -90.27648) (xy 354.895912 -90.304366) (xy 354.895403 -90.332252)
			(xy 354.887283 -90.387428) (xy 354.871215 -90.440835) (xy 354.847543 -90.491332) (xy 354.81677 -90.537845)
			(xy 354.779553 -90.579382) (xy 354.736685 -90.615057) (xy 354.689079 -90.644111) (xy 354.63775 -90.665923)
			(xy 354.583793 -90.680029) (xy 354.528356 -90.686129) (xy 354.472622 -90.684092) (xy 354.417779 -90.673962)
			(xy 354.364995 -90.655955) (xy 354.315395 -90.630454) (xy 354.270037 -90.598003) (xy 354.229888 -90.559294)
			(xy 354.195802 -90.515151) (xy 354.168506 -90.466516) (xy 354.148583 -90.414425) (xy 354.136457 -90.359988)
			(xy 354.132386 -90.304366) (xy 351.151952 -90.304366) (xy 351.151952 -91.574366) (xy 354.132386 -91.574366)
			(xy 354.136457 -91.518744) (xy 354.148583 -91.464307) (xy 354.168506 -91.412216) (xy 354.195802 -91.363581)
			(xy 354.229888 -91.319438) (xy 354.270037 -91.280729) (xy 354.315395 -91.248278) (xy 354.364995 -91.222777)
			(xy 354.417779 -91.20477) (xy 354.472622 -91.19464) (xy 354.528356 -91.192603) (xy 354.583793 -91.198703)
			(xy 354.63775 -91.212809) (xy 354.689079 -91.234621) (xy 354.736685 -91.263675) (xy 354.779553 -91.29935)
			(xy 354.81677 -91.340887) (xy 354.847543 -91.3874) (xy 354.871215 -91.437897) (xy 354.887283 -91.491304)
			(xy 354.895403 -91.54648) (xy 354.895912 -91.574366) (xy 354.895403 -91.602252) (xy 354.887283 -91.657428)
			(xy 354.871215 -91.710835) (xy 354.847543 -91.761332) (xy 354.81677 -91.807845) (xy 354.779553 -91.849382)
			(xy 354.736685 -91.885057) (xy 354.689079 -91.914111) (xy 354.63775 -91.935923) (xy 354.583793 -91.950029)
			(xy 354.528356 -91.956129) (xy 354.472622 -91.954092) (xy 354.417779 -91.943962) (xy 354.364995 -91.925955)
			(xy 354.315395 -91.900454) (xy 354.270037 -91.868003) (xy 354.229888 -91.829294) (xy 354.195802 -91.785151)
			(xy 354.168506 -91.736516) (xy 354.148583 -91.684425) (xy 354.136457 -91.629988) (xy 354.132386 -91.574366)
			(xy 351.151952 -91.574366) (xy 351.151952 -92.774516) (xy 351.155234 -92.778631) (xy 351.163178 -92.785537)
			(xy 351.1677 -92.788232) (xy 351.18167 -92.795344) (xy 351.248218 -92.828872) (xy 351.257642 -92.833083)
			(xy 351.278221 -92.834411) (xy 351.288096 -92.831412) (xy 351.2947 -92.829126) (xy 351.305368 -92.823792)
			(xy 351.312734 -92.818966) (xy 351.313242 -92.818966) (xy 351.325688 -92.810838) (xy 351.334578 -92.805758)
			(xy 351.335848 -92.804996) (xy 351.336356 -92.804742) (xy 351.337626 -92.80398) (xy 351.359299 -92.792083)
			(xy 351.405059 -92.773363) (xy 351.452853 -92.76071) (xy 351.501881 -92.754337) (xy 351.526602 -92.753942)
			(xy 351.55385 -92.754428) (xy 351.60779 -92.762184) (xy 351.660078 -92.777537) (xy 351.709648 -92.800176)
			(xy 351.755492 -92.829638) (xy 351.796677 -92.865325) (xy 351.832363 -92.90651) (xy 351.861825 -92.952354)
			(xy 351.884463 -93.001924) (xy 351.899816 -93.054212) (xy 351.907572 -93.108152) (xy 351.907572 -93.14434)
			(xy 352.13112 -93.14434) (xy 352.135191 -93.088718) (xy 352.147317 -93.034281) (xy 352.16724 -92.98219)
			(xy 352.194536 -92.933555) (xy 352.228622 -92.889412) (xy 352.268771 -92.850703) (xy 352.314129 -92.818252)
			(xy 352.363729 -92.792751) (xy 352.416513 -92.774744) (xy 352.471356 -92.764614) (xy 352.52709 -92.762577)
			(xy 352.582527 -92.768677) (xy 352.636484 -92.782783) (xy 352.687813 -92.804595) (xy 352.735419 -92.833649)
			(xy 352.748297 -92.844366) (xy 353.159566 -92.844366) (xy 353.163637 -92.788744) (xy 353.175763 -92.734307)
			(xy 353.195686 -92.682216) (xy 353.222982 -92.633581) (xy 353.257068 -92.589438) (xy 353.297217 -92.550729)
			(xy 353.342575 -92.518278) (xy 353.392175 -92.492777) (xy 353.444959 -92.47477) (xy 353.499802 -92.46464)
			(xy 353.555536 -92.462603) (xy 353.610973 -92.468703) (xy 353.66493 -92.482809) (xy 353.716259 -92.504621)
			(xy 353.763865 -92.533675) (xy 353.806733 -92.56935) (xy 353.84395 -92.610887) (xy 353.874723 -92.6574)
			(xy 353.898395 -92.707897) (xy 353.914463 -92.761304) (xy 353.922583 -92.81648) (xy 353.923092 -92.844366)
			(xy 353.922583 -92.872252) (xy 353.914463 -92.927428) (xy 353.898395 -92.980835) (xy 353.874723 -93.031332)
			(xy 353.84395 -93.077845) (xy 353.806733 -93.119382) (xy 353.763865 -93.155057) (xy 353.716259 -93.184111)
			(xy 353.66493 -93.205923) (xy 353.610973 -93.220029) (xy 353.555536 -93.226129) (xy 353.499802 -93.224092)
			(xy 353.444959 -93.213962) (xy 353.392175 -93.195955) (xy 353.342575 -93.170454) (xy 353.297217 -93.138003)
			(xy 353.257068 -93.099294) (xy 353.222982 -93.055151) (xy 353.195686 -93.006516) (xy 353.175763 -92.954425)
			(xy 353.163637 -92.899988) (xy 353.159566 -92.844366) (xy 352.748297 -92.844366) (xy 352.778287 -92.869324)
			(xy 352.815504 -92.910861) (xy 352.846277 -92.957374) (xy 352.869949 -93.007871) (xy 352.886017 -93.061278)
			(xy 352.894137 -93.116454) (xy 352.894646 -93.14434) (xy 352.894137 -93.172226) (xy 352.886017 -93.227402)
			(xy 352.869949 -93.280809) (xy 352.846277 -93.331306) (xy 352.815504 -93.377819) (xy 352.778287 -93.419356)
			(xy 352.735419 -93.455031) (xy 352.687813 -93.484085) (xy 352.636484 -93.505897) (xy 352.582527 -93.520003)
			(xy 352.52709 -93.526103) (xy 352.471356 -93.524066) (xy 352.416513 -93.513936) (xy 352.363729 -93.495929)
			(xy 352.314129 -93.470428) (xy 352.268771 -93.437977) (xy 352.228622 -93.399268) (xy 352.194536 -93.355125)
			(xy 352.16724 -93.30649) (xy 352.147317 -93.254399) (xy 352.135191 -93.199962) (xy 352.13112 -93.14434)
			(xy 351.907572 -93.14434) (xy 351.907572 -93.162648) (xy 351.899816 -93.216588) (xy 351.884463 -93.268876)
			(xy 351.861825 -93.318446) (xy 351.832363 -93.36429) (xy 351.796677 -93.405475) (xy 351.755492 -93.441162)
			(xy 351.709648 -93.470624) (xy 351.660078 -93.493263) (xy 351.60779 -93.508616) (xy 351.55385 -93.516372)
			(xy 351.526602 -93.516958) (xy 351.496731 -93.516378) (xy 351.437721 -93.507063) (xy 351.380885 -93.48866)
			(xy 351.327614 -93.461619) (xy 351.303082 -93.444568) (xy 351.299526 -93.442028) (xy 351.294414 -93.439154)
			(xy 351.283257 -93.435552) (xy 351.277428 -93.434916) (xy 351.263458 -93.4339) (xy 351.208848 -93.461586)
			(xy 351.169478 -93.481652) (xy 351.167954 -93.482414) (xy 351.16333 -93.485123) (xy 351.155255 -93.492164)
			(xy 351.151952 -93.496384) (xy 351.151952 -94.396814) (xy 351.15246 -94.403418) (xy 351.153791 -94.411518)
			(xy 351.160913 -94.426297) (xy 351.16643 -94.432374) (xy 351.943924 -95.209614) (xy 351.961957 -95.228384)
			(xy 351.992537 -95.270501) (xy 352.016163 -95.316877) (xy 352.032255 -95.366375) (xy 352.040416 -95.417778)
			(xy 352.040952 -95.443802) (xy 352.040952 -99.676204) (xy 352.048556 -99.685307) (xy 352.069747 -99.695901)
			(xy 352.081592 -99.696524) (xy 356.100634 -99.696524) (xy 356.110639 -99.696031) (xy 356.129123 -99.688366)
			(xy 356.143271 -99.674215) (xy 356.150933 -99.655729) (xy 356.151434 -99.645724) (xy 356.151434 -99.467162)
			(xy 356.150164 -99.455986) (xy 356.146354 -99.445064) (xy 356.13721 -99.426268) (xy 356.134601 -99.421358)
			(xy 356.12755 -99.412763) (xy 356.12324 -99.40925) (xy 356.122986 -99.408996) (xy 356.120446 -99.406964)
			(xy 356.112105 -99.400378) (xy 356.096092 -99.386401) (xy 356.088442 -99.379024) (xy 356.087934 -99.378516)
			(xy 356.085648 -99.37623) (xy 356.083108 -99.374198) (xy 356.07625 -99.368864) (xy 356.059994 -99.363022)
			(xy 356.049834 -99.363022) (xy 355.974396 -99.365308) (xy 355.969922 -99.365754) (xy 355.96123 -99.368049)
			(xy 355.957124 -99.36988) (xy 355.94798 -99.374198) (xy 355.940868 -99.381818) (xy 355.922713 -99.401099)
			(xy 355.881995 -99.434965) (xy 355.836984 -99.46287) (xy 355.788543 -99.484278) (xy 355.737607 -99.498777)
			(xy 355.685154 -99.506088) (xy 355.658674 -99.506532) (xy 355.631422 -99.506044) (xy 355.577474 -99.498284)
			(xy 355.525179 -99.482926) (xy 355.475602 -99.460282) (xy 355.429752 -99.430813) (xy 355.388562 -99.395119)
			(xy 355.352871 -99.353927) (xy 355.323406 -99.308075) (xy 355.300765 -99.258497) (xy 355.28541 -99.206201)
			(xy 355.277654 -99.152252) (xy 355.277654 -99.097748) (xy 355.28541 -99.043799) (xy 355.300765 -98.991503)
			(xy 355.323406 -98.941925) (xy 355.352871 -98.896073) (xy 355.388562 -98.854881) (xy 355.429752 -98.819187)
			(xy 355.475602 -98.789718) (xy 355.525179 -98.767074) (xy 355.577474 -98.751716) (xy 355.631422 -98.743956)
			(xy 355.658674 -98.743516) (xy 355.68689 -98.744029) (xy 355.742705 -98.752349) (xy 355.796687 -98.768797)
			(xy 355.847659 -98.793013) (xy 355.894509 -98.824471) (xy 355.915722 -98.843084) (xy 355.915976 -98.843338)
			(xy 355.919278 -98.846132) (xy 355.927406 -98.84918) (xy 355.931754 -98.850723) (xy 355.940828 -98.852384)
			(xy 355.94544 -98.852482) (xy 355.962712 -98.852482) (xy 355.970332 -98.859594) (xy 355.978968 -98.862896)
			(xy 355.982906 -98.864221) (xy 355.991073 -98.865745) (xy 355.995224 -98.865944) (xy 356.02037 -98.865182)
			(xy 356.020878 -98.865182) (xy 356.038658 -98.86442) (xy 356.042989 -98.86398) (xy 356.051417 -98.861808)
			(xy 356.055422 -98.860102) (xy 356.064566 -98.855784) (xy 356.071678 -98.848164) (xy 356.089835 -98.828886)
			(xy 356.130554 -98.795027) (xy 356.175566 -98.767128) (xy 356.224007 -98.745727) (xy 356.274942 -98.731235)
			(xy 356.327393 -98.72393) (xy 356.353872 -98.72345) (xy 356.354126 -98.72345) (xy 356.391464 -98.725228)
			(xy 356.39629 -98.725736) (xy 356.405906 -98.72556) (xy 356.423951 -98.718947) (xy 356.438319 -98.706183)
			(xy 356.443026 -98.697796) (xy 356.464108 -98.653346) (xy 356.464108 -98.652838) (xy 356.482142 -98.6155)
			(xy 356.485444 -98.605086) (xy 356.485444 -98.604832) (xy 356.485952 -98.6028) (xy 356.486754 -98.595904)
			(xy 356.485074 -98.582128) (xy 356.48265 -98.575622) (xy 354.666804 -96.759522) (xy 354.64871 -96.740718)
			(xy 354.618013 -96.698521) (xy 354.594281 -96.652049) (xy 354.578095 -96.602442) (xy 354.569852 -96.550916)
			(xy 354.569268 -96.524826) (xy 354.569268 -96.524318) (xy 354.569776 -96.509586) (xy 354.569776 -92.804996)
			(xy 354.570328 -92.777997) (xy 354.579107 -92.724715) (xy 354.596386 -92.673554) (xy 354.621709 -92.62586)
			(xy 354.654409 -92.582887) (xy 354.673662 -92.56395) (xy 354.674678 -92.562934) (xy 355.995478 -91.242134)
			(xy 356.000463 -91.236634) (xy 356.0073 -91.223466) (xy 356.00894 -91.216226) (xy 356.009956 -91.206574)
			(xy 356.009956 -82.07883) (xy 356.008178 -82.075528) (xy 355.993243 -82.04724) (xy 355.972012 -81.986903)
			(xy 355.961162 -81.923866) (xy 355.960426 -81.891886) (xy 355.960426 -81.882742) (xy 355.961462 -81.854985)
			(xy 355.970574 -81.800193) (xy 355.987534 -81.747302) (xy 356.011985 -81.697429) (xy 356.043408 -81.651628)
			(xy 356.08114 -81.610868) (xy 356.124384 -81.576009) (xy 356.172225 -81.547789) (xy 356.223652 -81.526804)
			(xy 356.277579 -81.513498) (xy 356.332865 -81.508151) (xy 356.388342 -81.510878) (xy 356.442838 -81.521619)
			(xy 356.4952 -81.540149) (xy 356.544322 -81.566076) (xy 356.589165 -81.598851) (xy 356.628783 -81.637781)
			(xy 356.662337 -81.682045) (xy 356.689118 -81.730707) (xy 356.70856 -81.782737) (xy 356.720252 -81.837036)
			(xy 356.72268 -81.864708) (xy 356.723442 -81.887314) (xy 356.723442 -81.890616) (xy 356.722768 -81.922806)
			(xy 356.711963 -81.986273) (xy 356.690679 -82.047032) (xy 356.67569 -82.075528) (xy 356.673912 -82.07883)
			(xy 356.673912 -91.36507) (xy 356.673575 -91.386848) (xy 356.667879 -91.430029) (xy 356.65657 -91.47209)
			(xy 356.648512 -91.492324) (xy 356.639622 -91.513406) (xy 356.643686 -91.524328) (xy 356.64902 -91.534996)
			(xy 356.652322 -91.539314) (xy 356.652576 -91.539568) (xy 356.691692 -91.590368) (xy 356.70236 -91.604084)
			(xy 356.708376 -91.610536) (xy 356.723711 -91.619227) (xy 356.732332 -91.621102) (xy 356.73792 -91.621864)
			(xy 356.74681 -91.621864) (xy 356.749604 -91.62161) (xy 356.759419 -91.620656) (xy 356.779113 -91.619642)
			(xy 356.788974 -91.619578) (xy 356.79253 -91.619578) (xy 356.819724 -91.620147) (xy 356.87354 -91.628046)
			(xy 356.925688 -91.643507) (xy 356.975111 -91.666218) (xy 357.020809 -91.695717) (xy 357.061853 -91.731408)
			(xy 357.097413 -91.772566) (xy 357.126767 -91.818357) (xy 357.149319 -91.867853) (xy 357.164614 -91.92005)
			(xy 357.172341 -91.97389) (xy 357.172768 -92.001086) (xy 357.172282 -92.028337) (xy 357.164526 -92.082285)
			(xy 357.149171 -92.13458) (xy 357.126529 -92.184157) (xy 357.097063 -92.230007) (xy 357.061372 -92.271198)
			(xy 357.020181 -92.306889) (xy 356.974331 -92.336355) (xy 356.924754 -92.358997) (xy 356.872459 -92.374352)
			(xy 356.818511 -92.382108) (xy 356.764009 -92.382108) (xy 356.710061 -92.374352) (xy 356.657766 -92.358997)
			(xy 356.608189 -92.336355) (xy 356.562339 -92.306889) (xy 356.521148 -92.271198) (xy 356.485457 -92.230007)
			(xy 356.455991 -92.184157) (xy 356.433349 -92.13458) (xy 356.417994 -92.082285) (xy 356.410238 -92.028337)
			(xy 356.409752 -92.001086) (xy 356.409752 -91.997784) (xy 356.40922 -91.987831) (xy 356.401559 -91.96945)
			(xy 356.387504 -91.955344) (xy 356.37851 -91.951048) (xy 356.330504 -91.930982) (xy 356.289864 -91.913964)
			(xy 356.280974 -91.911424) (xy 356.277063 -91.910828) (xy 356.269154 -91.910704) (xy 356.265226 -91.91117)
			(xy 355.440996 -92.735146) (xy 355.440488 -92.746322) (xy 355.44125 -92.75699) (xy 355.471222 -92.82049)
			(xy 355.471222 -92.820998) (xy 355.48697 -92.85478) (xy 355.489256 -92.85859) (xy 355.496823 -92.868056)
			(xy 355.518307 -92.879196) (xy 355.530404 -92.879926) (xy 355.531674 -92.879926) (xy 355.534976 -92.879672)
			(xy 355.56825 -92.878402) (xy 355.572314 -92.878402) (xy 355.59948 -92.879011) (xy 355.653231 -92.886977)
			(xy 355.705308 -92.902488) (xy 355.754657 -92.925232) (xy 355.80028 -92.954748) (xy 355.841253 -92.990439)
			(xy 355.876747 -93.031582) (xy 355.906044 -93.077345) (xy 355.928552 -93.126802) (xy 355.943815 -93.178953)
			(xy 355.951523 -93.232741) (xy 355.952044 -93.25991) (xy 355.951558 -93.287162) (xy 355.9438 -93.34111)
			(xy 355.928444 -93.393406) (xy 355.905803 -93.442984) (xy 355.876337 -93.488836) (xy 355.840646 -93.530028)
			(xy 355.799457 -93.565722) (xy 355.753607 -93.595191) (xy 355.70403 -93.617835) (xy 355.651736 -93.633195)
			(xy 355.597788 -93.640956) (xy 355.570536 -93.641418) (xy 355.570028 -93.641418) (xy 355.539173 -93.640788)
			(xy 355.478276 -93.630788) (xy 355.419781 -93.611124) (xy 355.392228 -93.597222) (xy 355.39172 -93.596968)
			(xy 355.38283 -93.592396) (xy 355.376734 -93.590872) (xy 355.363272 -93.589094) (xy 355.33965 -93.589602)
			(xy 355.334824 -93.589856) (xy 355.322632 -93.59011) (xy 355.262688 -93.6244) (xy 355.24313 -93.635576)
			(xy 355.233732 -93.644974) (xy 355.233732 -96.365314) (xy 355.234748 -96.374966) (xy 355.236378 -96.382209)
			(xy 355.243224 -96.395374) (xy 355.24821 -96.400874) (xy 355.673914 -96.826578) (xy 357.466898 -96.826578)
			(xy 357.470969 -96.770956) (xy 357.483095 -96.716519) (xy 357.503018 -96.664428) (xy 357.530314 -96.615793)
			(xy 357.5644 -96.57165) (xy 357.604549 -96.532941) (xy 357.649907 -96.50049) (xy 357.699507 -96.474989)
			(xy 357.752291 -96.456982) (xy 357.807134 -96.446852) (xy 357.862868 -96.444815) (xy 357.918305 -96.450915)
			(xy 357.972262 -96.465021) (xy 358.023591 -96.486833) (xy 358.071197 -96.515887) (xy 358.114065 -96.551562)
			(xy 358.151282 -96.593099) (xy 358.182055 -96.639612) (xy 358.205727 -96.690109) (xy 358.221795 -96.743516)
			(xy 358.229915 -96.798692) (xy 358.230424 -96.826578) (xy 358.229915 -96.854464) (xy 358.226917 -96.874838)
			(xy 359.401362 -96.874838) (xy 359.405433 -96.819216) (xy 359.417559 -96.764779) (xy 359.437482 -96.712688)
			(xy 359.464778 -96.664053) (xy 359.498864 -96.61991) (xy 359.539013 -96.581201) (xy 359.584371 -96.54875)
			(xy 359.633971 -96.523249) (xy 359.686755 -96.505242) (xy 359.741598 -96.495112) (xy 359.797332 -96.493075)
			(xy 359.852769 -96.499175) (xy 359.906726 -96.513281) (xy 359.958055 -96.535093) (xy 360.005661 -96.564147)
			(xy 360.048529 -96.599822) (xy 360.085746 -96.641359) (xy 360.116519 -96.687872) (xy 360.140191 -96.738369)
			(xy 360.156259 -96.791776) (xy 360.164379 -96.846952) (xy 360.164888 -96.874838) (xy 360.164379 -96.902724)
			(xy 360.156259 -96.9579) (xy 360.140191 -97.011307) (xy 360.116519 -97.061804) (xy 360.085746 -97.108317)
			(xy 360.048529 -97.149854) (xy 360.005661 -97.185529) (xy 359.958055 -97.214583) (xy 359.906726 -97.236395)
			(xy 359.852769 -97.250501) (xy 359.797332 -97.256601) (xy 359.741598 -97.254564) (xy 359.686755 -97.244434)
			(xy 359.633971 -97.226427) (xy 359.584371 -97.200926) (xy 359.539013 -97.168475) (xy 359.498864 -97.129766)
			(xy 359.464778 -97.085623) (xy 359.437482 -97.036988) (xy 359.417559 -96.984897) (xy 359.405433 -96.93046)
			(xy 359.401362 -96.874838) (xy 358.226917 -96.874838) (xy 358.221795 -96.90964) (xy 358.205727 -96.963047)
			(xy 358.182055 -97.013544) (xy 358.151282 -97.060057) (xy 358.114065 -97.101594) (xy 358.071197 -97.137269)
			(xy 358.023591 -97.166323) (xy 357.972262 -97.188135) (xy 357.918305 -97.202241) (xy 357.862868 -97.208341)
			(xy 357.807134 -97.206304) (xy 357.752291 -97.196174) (xy 357.699507 -97.178167) (xy 357.649907 -97.152666)
			(xy 357.604549 -97.120215) (xy 357.5644 -97.081506) (xy 357.530314 -97.037363) (xy 357.503018 -96.988728)
			(xy 357.483095 -96.936637) (xy 357.470969 -96.8822) (xy 357.466898 -96.826578) (xy 355.673914 -96.826578)
			(xy 357.120698 -98.273362) (xy 359.51363 -98.273362) (xy 359.517701 -98.21774) (xy 359.529827 -98.163303)
			(xy 359.54975 -98.111212) (xy 359.577046 -98.062577) (xy 359.611132 -98.018434) (xy 359.651281 -97.979725)
			(xy 359.696639 -97.947274) (xy 359.746239 -97.921773) (xy 359.799023 -97.903766) (xy 359.853866 -97.893636)
			(xy 359.9096 -97.891599) (xy 359.965037 -97.897699) (xy 360.018994 -97.911805) (xy 360.070323 -97.933617)
			(xy 360.117929 -97.962671) (xy 360.160797 -97.998346) (xy 360.198014 -98.039883) (xy 360.228787 -98.086396)
			(xy 360.252459 -98.136893) (xy 360.268527 -98.1903) (xy 360.276647 -98.245476) (xy 360.277156 -98.273362)
			(xy 360.276647 -98.301248) (xy 360.268527 -98.356424) (xy 360.252459 -98.409831) (xy 360.228787 -98.460328)
			(xy 360.198014 -98.506841) (xy 360.160797 -98.548378) (xy 360.117929 -98.584053) (xy 360.070323 -98.613107)
			(xy 360.018994 -98.634919) (xy 359.965037 -98.649025) (xy 359.9096 -98.655125) (xy 359.853866 -98.653088)
			(xy 359.799023 -98.642958) (xy 359.746239 -98.624951) (xy 359.696639 -98.59945) (xy 359.651281 -98.566999)
			(xy 359.611132 -98.52829) (xy 359.577046 -98.484147) (xy 359.54975 -98.435512) (xy 359.529827 -98.383421)
			(xy 359.517701 -98.328984) (xy 359.51363 -98.273362) (xy 357.120698 -98.273362) (xy 358.543352 -99.696016)
			(xy 358.549702 -99.696524) (xy 359.019602 -99.696524) (xy 359.029672 -99.696948) (xy 359.048273 -99.704666)
			(xy 359.05567 -99.71151) (xy 360.508296 -101.164136) (xy 360.515137 -101.171536) (xy 360.522859 -101.190134)
			(xy 360.523282 -101.200204) (xy 360.523282 -103.164386) (xy 360.523624 -103.171898) (xy 360.528142 -103.186232)
			(xy 360.532172 -103.19258) (xy 360.532172 -103.193088) (xy 360.536236 -103.198168) (xy 360.554524 -103.210106)
			(xy 360.556556 -103.21163) (xy 360.559858 -103.213408) (xy 360.561636 -103.21417) (xy 360.56189 -103.214424)
			(xy 360.603292 -103.233982) (xy 360.611674 -103.238046) (xy 360.624882 -103.244142) (xy 360.635042 -103.248968)
			(xy 360.661458 -103.248968) (xy 360.665466 -103.248901) (xy 360.673381 -103.247629) (xy 360.677206 -103.246428)
			(xy 360.69016 -103.241856) (xy 360.697018 -103.236268) (xy 360.717206 -103.22067) (xy 360.76096 -103.194434)
			(xy 360.807821 -103.174267) (xy 360.856953 -103.160526) (xy 360.907478 -103.153457) (xy 360.932984 -103.152956)
			(xy 360.94035 -103.152956) (xy 360.967364 -103.153784) (xy 361.020763 -103.162119) (xy 361.07245 -103.177908)
			(xy 361.121392 -103.200834) (xy 361.166609 -103.230438) (xy 361.207194 -103.266127) (xy 361.242336 -103.307187)
			(xy 361.271331 -103.352796) (xy 361.293599 -103.402041) (xy 361.308693 -103.453936) (xy 361.316312 -103.507441)
			(xy 361.316778 -103.534464) (xy 361.31631 -103.561403) (xy 361.308722 -103.614743) (xy 361.293707 -103.666487)
			(xy 361.271562 -103.715603) (xy 361.242729 -103.761116) (xy 361.20778 -103.802121) (xy 361.16741 -103.837801)
			(xy 361.122423 -103.867449) (xy 361.073713 -103.890473) (xy 361.022249 -103.906417) (xy 360.969053 -103.914963)
			(xy 360.942128 -103.915972) (xy 360.941112 -103.915972) (xy 360.93654 -103.916226) (xy 360.932984 -103.916226)
			(xy 360.906885 -103.915645) (xy 360.855213 -103.908216) (xy 360.80504 -103.8938) (xy 360.757305 -103.872668)
			(xy 360.734864 -103.85933) (xy 360.724913 -103.853062) (xy 360.705723 -103.839461) (xy 360.69651 -103.832152)
			(xy 360.69016 -103.827072) (xy 360.670348 -103.819706) (xy 360.661676 -103.81711) (xy 360.643589 -103.817488)
			(xy 360.635042 -103.820468) (xy 360.62539 -103.82504) (xy 360.624882 -103.825294) (xy 360.61396 -103.830374)
			(xy 360.566208 -103.852472) (xy 360.552492 -103.858822) (xy 360.541953 -103.864479) (xy 360.527238 -103.883296)
			(xy 360.524298 -103.89489) (xy 360.524298 -103.895398) (xy 360.523282 -103.904796) (xy 360.523282 -111.674148)
			(xy 360.524044 -111.678212) (xy 360.526327 -111.693412) (xy 360.528744 -111.724056) (xy 360.52887 -111.739426)
			(xy 360.528749 -111.754796) (xy 360.526331 -111.78544) (xy 360.524044 -111.80064) (xy 360.523282 -111.804704)
			(xy 360.523282 -112.540034) (xy 362.1057 -112.540034) (xy 362.109771 -112.484412) (xy 362.121897 -112.429975)
			(xy 362.14182 -112.377884) (xy 362.169116 -112.329249) (xy 362.203202 -112.285106) (xy 362.243351 -112.246397)
			(xy 362.288709 -112.213946) (xy 362.338309 -112.188445) (xy 362.391093 -112.170438) (xy 362.445936 -112.160308)
			(xy 362.50167 -112.158271) (xy 362.557107 -112.164371) (xy 362.611064 -112.178477) (xy 362.662393 -112.200289)
			(xy 362.709999 -112.229343) (xy 362.752867 -112.265018) (xy 362.790084 -112.306555) (xy 362.820857 -112.353068)
			(xy 362.844529 -112.403565) (xy 362.849823 -112.421162) (xy 364.10722 -112.421162) (xy 364.111291 -112.36554)
			(xy 364.123417 -112.311103) (xy 364.14334 -112.259012) (xy 364.170636 -112.210377) (xy 364.204722 -112.166234)
			(xy 364.244871 -112.127525) (xy 364.290229 -112.095074) (xy 364.339829 -112.069573) (xy 364.392613 -112.051566)
			(xy 364.447456 -112.041436) (xy 364.50319 -112.039399) (xy 364.558627 -112.045499) (xy 364.612584 -112.059605)
			(xy 364.663913 -112.081417) (xy 364.711519 -112.110471) (xy 364.754387 -112.146146) (xy 364.791604 -112.187683)
			(xy 364.822377 -112.234196) (xy 364.846049 -112.284693) (xy 364.862117 -112.3381) (xy 364.870237 -112.393276)
			(xy 364.870746 -112.421162) (xy 364.870237 -112.449048) (xy 364.862117 -112.504224) (xy 364.846049 -112.557631)
			(xy 364.822377 -112.608128) (xy 364.791604 -112.654641) (xy 364.754387 -112.696178) (xy 364.711519 -112.731853)
			(xy 364.663913 -112.760907) (xy 364.612584 -112.782719) (xy 364.558627 -112.796825) (xy 364.50319 -112.802925)
			(xy 364.447456 -112.800888) (xy 364.392613 -112.790758) (xy 364.339829 -112.772751) (xy 364.290229 -112.74725)
			(xy 364.244871 -112.714799) (xy 364.204722 -112.67609) (xy 364.170636 -112.631947) (xy 364.14334 -112.583312)
			(xy 364.123417 -112.531221) (xy 364.111291 -112.476784) (xy 364.10722 -112.421162) (xy 362.849823 -112.421162)
			(xy 362.860597 -112.456972) (xy 362.868717 -112.512148) (xy 362.869226 -112.540034) (xy 362.868717 -112.56792)
			(xy 362.860597 -112.623096) (xy 362.844529 -112.676503) (xy 362.820857 -112.727) (xy 362.790084 -112.773513)
			(xy 362.752867 -112.81505) (xy 362.709999 -112.850725) (xy 362.662393 -112.879779) (xy 362.611064 -112.901591)
			(xy 362.557107 -112.915697) (xy 362.50167 -112.921797) (xy 362.445936 -112.91976) (xy 362.391093 -112.90963)
			(xy 362.338309 -112.891623) (xy 362.288709 -112.866122) (xy 362.243351 -112.833671) (xy 362.203202 -112.794962)
			(xy 362.169116 -112.750819) (xy 362.14182 -112.702184) (xy 362.121897 -112.650093) (xy 362.109771 -112.595656)
			(xy 362.1057 -112.540034) (xy 360.523282 -112.540034) (xy 360.523282 -116.672106) (xy 361.16895 -116.672106)
			(xy 361.169407 -116.644735) (xy 361.177225 -116.590555) (xy 361.192716 -116.538052) (xy 361.21556 -116.488305)
			(xy 361.245287 -116.442339) (xy 361.26293 -116.421408) (xy 361.263184 -116.421154) (xy 361.268752 -116.414055)
			(xy 361.27501 -116.397148) (xy 361.275376 -116.388134) (xy 361.275376 -116.321078) (xy 361.275035 -116.312059)
			(xy 361.268777 -116.295142) (xy 361.263184 -116.288058) (xy 361.26293 -116.288058) (xy 361.26293 -116.287804)
			(xy 361.245295 -116.266867) (xy 361.21557 -116.2209) (xy 361.192724 -116.171154) (xy 361.177227 -116.118653)
			(xy 361.169398 -116.064475) (xy 361.169397 -116.009734) (xy 361.177225 -115.955556) (xy 361.192721 -115.903054)
			(xy 361.215565 -115.853308) (xy 361.24529 -115.807341) (xy 361.26293 -115.786408) (xy 361.263184 -115.786154)
			(xy 361.268752 -115.779055) (xy 361.27501 -115.762148) (xy 361.275376 -115.753134) (xy 361.275376 -115.686078)
			(xy 361.275035 -115.677059) (xy 361.268777 -115.660142) (xy 361.263184 -115.653058) (xy 361.26293 -115.653058)
			(xy 361.26293 -115.652804) (xy 361.245284 -115.631877) (xy 361.215572 -115.585904) (xy 361.192737 -115.536155)
			(xy 361.177248 -115.483653) (xy 361.169422 -115.429476) (xy 361.16895 -115.402106) (xy 361.169483 -115.374857)
			(xy 361.177238 -115.320913) (xy 361.19259 -115.268622) (xy 361.215227 -115.219047) (xy 361.244689 -115.173199)
			(xy 361.280376 -115.13201) (xy 361.32156 -115.096318) (xy 361.367405 -115.06685) (xy 361.416977 -115.044207)
			(xy 361.469266 -115.028848) (xy 361.523209 -115.021087) (xy 361.550458 -115.020598) (xy 361.577827 -115.021089)
			(xy 361.632005 -115.028901) (xy 361.684508 -115.044384) (xy 361.734255 -115.06722) (xy 361.780223 -115.096939)
			(xy 361.801156 -115.114578) (xy 361.80141 -115.114832) (xy 361.808487 -115.120432) (xy 361.825411 -115.12667)
			(xy 361.83443 -115.127024) (xy 361.901486 -115.127024) (xy 361.910502 -115.126655) (xy 361.927418 -115.120415)
			(xy 361.934506 -115.114832) (xy 361.934506 -115.114578) (xy 361.93476 -115.114578) (xy 361.955694 -115.096941)
			(xy 362.001666 -115.067229) (xy 362.051413 -115.044393) (xy 362.103914 -115.028902) (xy 362.158089 -115.021073)
			(xy 362.185458 -115.020598) (xy 362.21271 -115.021094) (xy 362.26666 -115.028846) (xy 362.318958 -115.044197)
			(xy 362.368538 -115.066835) (xy 362.414392 -115.096299) (xy 362.455585 -115.131989) (xy 362.491279 -115.173179)
			(xy 362.520748 -115.21903) (xy 362.543391 -115.268608) (xy 362.558747 -115.320905) (xy 362.566503 -115.374854)
			(xy 362.566966 -115.402106) (xy 362.566512 -115.429477) (xy 362.558692 -115.483657) (xy 362.543201 -115.53616)
			(xy 362.520356 -115.585907) (xy 362.490629 -115.631873) (xy 362.472986 -115.652804) (xy 362.472732 -115.653058)
			(xy 362.467149 -115.660147) (xy 362.460902 -115.677062) (xy 362.46054 -115.686078) (xy 362.46054 -115.753134)
			(xy 362.460872 -115.762154) (xy 362.467136 -115.779071) (xy 362.472732 -115.786154) (xy 362.472986 -115.786154)
			(xy 362.472986 -115.786408) (xy 362.490632 -115.807336) (xy 362.520356 -115.853305) (xy 362.5432 -115.903052)
			(xy 362.558695 -115.955555) (xy 362.566523 -116.009734) (xy 362.566522 -116.064475) (xy 362.558693 -116.118654)
			(xy 362.543197 -116.171156) (xy 362.520351 -116.220903) (xy 362.490627 -116.266871) (xy 362.472986 -116.287804)
			(xy 362.472732 -116.288058) (xy 362.467149 -116.295147) (xy 362.460902 -116.312062) (xy 362.46054 -116.321078)
			(xy 362.46054 -116.388134) (xy 362.460872 -116.397154) (xy 362.467136 -116.414071) (xy 362.472732 -116.421154)
			(xy 362.472986 -116.421154) (xy 362.472986 -116.421408) (xy 362.49064 -116.442328) (xy 362.52035 -116.488304)
			(xy 362.543183 -116.538054) (xy 362.558671 -116.590558) (xy 362.566495 -116.644736) (xy 362.566966 -116.672106)
			(xy 362.566828 -116.680234) (xy 363.451138 -116.680234) (xy 363.455209 -116.624612) (xy 363.467335 -116.570175)
			(xy 363.487258 -116.518084) (xy 363.514554 -116.469449) (xy 363.54864 -116.425306) (xy 363.588789 -116.386597)
			(xy 363.634147 -116.354146) (xy 363.683747 -116.328645) (xy 363.736531 -116.310638) (xy 363.791374 -116.300508)
			(xy 363.847108 -116.298471) (xy 363.902545 -116.304571) (xy 363.956502 -116.318677) (xy 364.007831 -116.340489)
			(xy 364.055437 -116.369543) (xy 364.098305 -116.405218) (xy 364.135522 -116.446755) (xy 364.166295 -116.493268)
			(xy 364.189967 -116.543765) (xy 364.206035 -116.597172) (xy 364.214155 -116.652348) (xy 364.214664 -116.680234)
			(xy 364.214155 -116.70812) (xy 364.206035 -116.763296) (xy 364.189967 -116.816703) (xy 364.166295 -116.8672)
			(xy 364.135522 -116.913713) (xy 364.098305 -116.95525) (xy 364.055437 -116.990925) (xy 364.007831 -117.019979)
			(xy 363.956502 -117.041791) (xy 363.902545 -117.055897) (xy 363.847108 -117.061997) (xy 363.791374 -117.05996)
			(xy 363.736531 -117.04983) (xy 363.683747 -117.031823) (xy 363.634147 -117.006322) (xy 363.588789 -116.973871)
			(xy 363.54864 -116.935162) (xy 363.514554 -116.891019) (xy 363.487258 -116.842384) (xy 363.467335 -116.790293)
			(xy 363.455209 -116.735856) (xy 363.451138 -116.680234) (xy 362.566828 -116.680234) (xy 362.566514 -116.698663)
			(xy 362.559145 -116.751262) (xy 362.54455 -116.802331) (xy 362.5342 -116.826792) (xy 362.529851 -116.83816)
			(xy 362.531199 -116.862434) (xy 362.53674 -116.873274) (xy 362.578142 -116.944394) (xy 362.584859 -116.954477)
			(xy 362.605279 -116.967461) (xy 362.617258 -116.969286) (xy 362.64524 -116.972462) (xy 362.699904 -116.985999)
			(xy 362.751984 -117.007426) (xy 362.800347 -117.036278) (xy 362.843942 -117.071927) (xy 362.881822 -117.113598)
			(xy 362.913164 -117.160386) (xy 362.937286 -117.211274) (xy 362.953663 -117.265155) (xy 362.959105 -117.301772)
			(xy 364.598202 -117.301772) (xy 364.602273 -117.24615) (xy 364.614399 -117.191713) (xy 364.634322 -117.139622)
			(xy 364.661618 -117.090987) (xy 364.695704 -117.046844) (xy 364.735853 -117.008135) (xy 364.781211 -116.975684)
			(xy 364.830811 -116.950183) (xy 364.883595 -116.932176) (xy 364.938438 -116.922046) (xy 364.994172 -116.920009)
			(xy 365.049609 -116.926109) (xy 365.103566 -116.940215) (xy 365.154895 -116.962027) (xy 365.202501 -116.991081)
			(xy 365.245369 -117.026756) (xy 365.282586 -117.068293) (xy 365.313359 -117.114806) (xy 365.337031 -117.165303)
			(xy 365.353099 -117.21871) (xy 365.361219 -117.273886) (xy 365.361728 -117.301772) (xy 365.361219 -117.329658)
			(xy 365.353099 -117.384834) (xy 365.337031 -117.438241) (xy 365.313359 -117.488738) (xy 365.282586 -117.535251)
			(xy 365.245369 -117.576788) (xy 365.202501 -117.612463) (xy 365.154895 -117.641517) (xy 365.103566 -117.663329)
			(xy 365.049609 -117.677435) (xy 364.994172 -117.683535) (xy 364.938438 -117.681498) (xy 364.883595 -117.671368)
			(xy 364.830811 -117.653361) (xy 364.781211 -117.62786) (xy 364.735853 -117.595409) (xy 364.695704 -117.5567)
			(xy 364.661618 -117.512557) (xy 364.634322 -117.463922) (xy 364.614399 -117.411831) (xy 364.602273 -117.357394)
			(xy 364.598202 -117.301772) (xy 362.959105 -117.301772) (xy 362.961941 -117.320858) (xy 362.962444 -117.349016)
			(xy 362.961958 -117.376267) (xy 362.954202 -117.430215) (xy 362.938847 -117.48251) (xy 362.916205 -117.532087)
			(xy 362.886739 -117.577937) (xy 362.851048 -117.619128) (xy 362.809857 -117.654819) (xy 362.764007 -117.684285)
			(xy 362.71443 -117.706927) (xy 362.662135 -117.722282) (xy 362.608187 -117.730038) (xy 362.553685 -117.730038)
			(xy 362.499737 -117.722282) (xy 362.447442 -117.706927) (xy 362.397865 -117.684285) (xy 362.352015 -117.654819)
			(xy 362.310824 -117.619128) (xy 362.275133 -117.577937) (xy 362.245667 -117.532087) (xy 362.223025 -117.48251)
			(xy 362.20767 -117.430215) (xy 362.199914 -117.376267) (xy 362.199428 -117.349016) (xy 362.199888 -117.32246)
			(xy 362.207254 -117.26986) (xy 362.221846 -117.218791) (xy 362.232194 -117.19433) (xy 362.236529 -117.182958)
			(xy 362.235191 -117.158688) (xy 362.229654 -117.147848) (xy 362.188252 -117.076728) (xy 362.181509 -117.066666)
			(xy 362.161107 -117.053675) (xy 362.149136 -117.051836) (xy 362.119662 -117.048454) (xy 362.062193 -117.033737)
			(xy 362.007697 -117.010298) (xy 361.957487 -116.978703) (xy 361.93476 -116.959634) (xy 361.934506 -116.95938)
			(xy 361.927424 -116.953788) (xy 361.910504 -116.947545) (xy 361.901486 -116.947188) (xy 361.83443 -116.947188)
			(xy 361.825415 -116.947562) (xy 361.808498 -116.953798) (xy 361.80141 -116.95938) (xy 361.80141 -116.959634)
			(xy 361.801156 -116.959634) (xy 361.780218 -116.977266) (xy 361.734246 -117.006977) (xy 361.6845 -117.029814)
			(xy 361.632001 -117.045307) (xy 361.577827 -117.053138) (xy 361.550458 -117.053614) (xy 361.523206 -117.053161)
			(xy 361.469257 -117.045399) (xy 361.416962 -117.030039) (xy 361.367385 -117.007393) (xy 361.321536 -116.977923)
			(xy 361.280346 -116.942229) (xy 361.244655 -116.901036) (xy 361.215189 -116.855183) (xy 361.192548 -116.805604)
			(xy 361.177193 -116.753307) (xy 361.169436 -116.699358) (xy 361.16895 -116.672106) (xy 360.523282 -116.672106)
			(xy 360.523282 -116.804186) (xy 360.523535 -116.811599) (xy 360.527794 -116.825799) (xy 360.531664 -116.832126)
			(xy 360.535728 -116.838222) (xy 360.54665 -116.84762) (xy 360.554524 -116.850922) (xy 360.579618 -116.862472)
			(xy 360.62647 -116.891734) (xy 360.668618 -116.927442) (xy 360.705182 -116.968849) (xy 360.735398 -117.015093)
			(xy 360.758636 -117.065207) (xy 360.774412 -117.118146) (xy 360.782395 -117.172806) (xy 360.78287 -117.200426)
			(xy 360.782375 -117.228095) (xy 360.774378 -117.282852) (xy 360.758555 -117.33588) (xy 360.735237 -117.386065)
			(xy 360.704915 -117.432356) (xy 360.668223 -117.473781) (xy 360.625933 -117.509472) (xy 360.578931 -117.538679)
			(xy 360.553762 -117.550184) (xy 360.553508 -117.550438) (xy 360.546904 -117.553615) (xy 360.535676 -117.563022)
			(xy 360.53141 -117.56898) (xy 360.527346 -117.575076) (xy 360.525314 -117.582188) (xy 360.524366 -117.585667)
			(xy 360.523348 -117.592806) (xy 360.523282 -117.596412) (xy 360.523282 -118.318788) (xy 360.523898 -118.330636)
			(xy 360.534488 -118.351834) (xy 360.543602 -118.359428) (xy 362.896912 -118.359428) (xy 362.922999 -118.359915)
			(xy 362.97453 -118.368083) (xy 363.024147 -118.384216) (xy 363.070627 -118.407916) (xy 363.112826 -118.438599)
			(xy 363.131608 -118.45671) (xy 363.685074 -119.010176) (xy 363.694726 -119.017796) (xy 363.709712 -119.026686)
			(xy 363.71022 -119.02694) (xy 363.735787 -119.035387) (xy 363.784436 -119.058465) (xy 363.829358 -119.08815)
			(xy 363.869664 -119.123854) (xy 363.904552 -119.164867) (xy 363.933331 -119.210376) (xy 363.955429 -119.259477)
			(xy 363.970408 -119.311196) (xy 363.97797 -119.364508) (xy 363.978444 -119.39143) (xy 363.977956 -119.418681)
			(xy 363.970196 -119.472627) (xy 363.954839 -119.52492) (xy 363.932197 -119.574496) (xy 363.90273 -119.620345)
			(xy 363.867039 -119.661535) (xy 363.82585 -119.697227) (xy 363.780001 -119.726694) (xy 363.730426 -119.749337)
			(xy 363.678133 -119.764695) (xy 363.624187 -119.772456) (xy 363.596936 -119.772938) (xy 363.570024 -119.772478)
			(xy 363.516733 -119.764914) (xy 363.465036 -119.749932) (xy 363.415958 -119.72783) (xy 363.370477 -119.699046)
			(xy 363.329495 -119.664152) (xy 363.293826 -119.623843) (xy 363.26418 -119.578918) (xy 363.241146 -119.530271)
			(xy 363.2327 -119.504714) (xy 363.23143 -119.500904) (xy 363.22762 -119.493538) (xy 363.220254 -119.48414)
			(xy 362.77423 -119.038116) (xy 362.771379 -119.035409) (xy 362.765002 -119.030815) (xy 362.76153 -119.028972)
			(xy 362.756102 -119.026393) (xy 362.744423 -119.023577) (xy 362.738416 -119.023384) (xy 360.790236 -119.023384)
			(xy 360.785918 -119.02694) (xy 360.777282 -119.037608) (xy 360.765344 -119.058182) (xy 360.758232 -119.070374)
			(xy 360.7562 -119.074184) (xy 360.750612 -119.083836) (xy 360.745949 -119.094194) (xy 360.745157 -119.116867)
			(xy 360.749088 -119.127524) (xy 360.756454 -119.140732) (xy 360.756962 -119.141494) (xy 360.771097 -119.165831)
			(xy 360.793394 -119.217506) (xy 360.808508 -119.271719) (xy 360.816161 -119.327476) (xy 360.816652 -119.355616)
			(xy 360.816652 -119.35587) (xy 360.816209 -119.383366) (xy 360.808956 -119.437876) (xy 360.794574 -119.490953)
			(xy 360.773313 -119.541668) (xy 360.745546 -119.589134) (xy 360.711758 -119.632521) (xy 360.672541 -119.67107)
			(xy 360.628579 -119.704107) (xy 360.580643 -119.731053) (xy 360.555286 -119.741696) (xy 360.551476 -119.74322)
			(xy 360.547783 -119.74514) (xy 360.54102 -119.749992) (xy 360.538014 -119.752872) (xy 360.53158 -119.759911)
			(xy 360.52401 -119.777399) (xy 360.523282 -119.786908) (xy 360.523282 -121.57075) (xy 361.920028 -121.57075)
			(xy 361.920517 -121.54338) (xy 361.928328 -121.489202) (xy 361.943811 -121.436699) (xy 361.966648 -121.386952)
			(xy 361.996369 -121.340984) (xy 362.014008 -121.320052) (xy 362.014262 -121.319798) (xy 362.019863 -121.312722)
			(xy 362.026099 -121.295797) (xy 362.026454 -121.286778) (xy 362.026454 -121.219722) (xy 362.026096 -121.210705)
			(xy 362.01985 -121.193788) (xy 362.014262 -121.186702) (xy 362.014008 -121.186702) (xy 362.014008 -121.186448)
			(xy 361.996379 -121.165508) (xy 361.966666 -121.119537) (xy 361.943827 -121.069792) (xy 361.928334 -121.017293)
			(xy 361.920503 -120.963119) (xy 361.920028 -120.93575) (xy 361.920514 -120.908499) (xy 361.92827 -120.854551)
			(xy 361.943625 -120.802256) (xy 361.966267 -120.752679) (xy 361.995733 -120.706829) (xy 362.031424 -120.665638)
			(xy 362.072615 -120.629947) (xy 362.118465 -120.600481) (xy 362.168042 -120.577839) (xy 362.220337 -120.562484)
			(xy 362.274285 -120.554728) (xy 362.328787 -120.554728) (xy 362.382735 -120.562484) (xy 362.43503 -120.577839)
			(xy 362.484607 -120.600481) (xy 362.530457 -120.629947) (xy 362.571648 -120.665638) (xy 362.607339 -120.706829)
			(xy 362.636805 -120.752679) (xy 362.659447 -120.802256) (xy 362.674802 -120.854551) (xy 362.682558 -120.908499)
			(xy 362.683044 -120.93575) (xy 362.682562 -120.96312) (xy 362.67475 -121.017299) (xy 362.659266 -121.069802)
			(xy 362.636427 -121.119549) (xy 362.606705 -121.165516) (xy 362.589064 -121.186448) (xy 362.58881 -121.186702)
			(xy 362.583218 -121.193785) (xy 362.576974 -121.210704) (xy 362.576618 -121.219722) (xy 362.576618 -121.286778)
			(xy 362.576982 -121.295794) (xy 362.583224 -121.312711) (xy 362.58881 -121.319798) (xy 362.589064 -121.319798)
			(xy 362.589064 -121.320052) (xy 362.606688 -121.340996) (xy 362.636404 -121.386965) (xy 362.659243 -121.436709)
			(xy 362.674737 -121.489208) (xy 362.682569 -121.543382) (xy 362.683044 -121.57075) (xy 362.682558 -121.598001)
			(xy 362.674802 -121.651949) (xy 362.659447 -121.704244) (xy 362.636805 -121.753821) (xy 362.607339 -121.799671)
			(xy 362.571648 -121.840862) (xy 362.530457 -121.876553) (xy 362.484607 -121.906019) (xy 362.43503 -121.928661)
			(xy 362.382735 -121.944016) (xy 362.328787 -121.951772) (xy 362.274285 -121.951772) (xy 362.220337 -121.944016)
			(xy 362.168042 -121.928661) (xy 362.118465 -121.906019) (xy 362.072615 -121.876553) (xy 362.031424 -121.840862)
			(xy 361.995733 -121.799671) (xy 361.966267 -121.753821) (xy 361.943625 -121.704244) (xy 361.92827 -121.651949)
			(xy 361.920514 -121.598001) (xy 361.920028 -121.57075) (xy 360.523282 -121.57075) (xy 360.523282 -122.735086)
			(xy 360.524298 -122.744992) (xy 360.528616 -122.763026) (xy 360.529124 -122.764042) (xy 360.534204 -122.771662)
			(xy 360.560366 -122.80011) (xy 360.560874 -122.800618) (xy 360.585258 -122.827542) (xy 360.588469 -122.830569)
			(xy 360.595748 -122.835559) (xy 360.599736 -122.837448) (xy 360.60761 -122.841004) (xy 360.613452 -122.841512)
			(xy 360.637074 -122.843544) (xy 360.671872 -122.849386) (xy 360.676444 -122.850402) (xy 360.676952 -122.850402)
			(xy 360.683048 -122.851926) (xy 360.684064 -122.851926) (xy 360.684572 -122.85218) (xy 360.6927 -122.854466)
			(xy 360.707178 -122.858784) (xy 360.730038 -122.866912) (xy 360.76255 -122.88139) (xy 360.784784 -122.893012)
			(xy 360.826275 -122.921216) (xy 360.863725 -122.954599) (xy 360.880406 -122.973338) (xy 360.887772 -122.979688)
			(xy 360.891328 -122.981212) (xy 360.899202 -122.984768) (xy 360.902758 -122.985784) (xy 360.910632 -122.987054)
			(xy 360.952796 -122.98807) (xy 360.953304 -122.98807) (xy 360.99115 -122.988324) (xy 361.001056 -122.98426)
			(xy 361.012486 -122.978926) (xy 361.017312 -122.976894) (xy 361.033822 -122.964956) (xy 361.037124 -122.9614)
			(xy 361.055271 -122.942933) (xy 361.095676 -122.910557) (xy 361.140074 -122.88392) (xy 361.187656 -122.863507)
			(xy 361.237554 -122.84969) (xy 361.288858 -122.842721) (xy 361.314746 -122.842274) (xy 361.340573 -122.842695)
			(xy 361.391757 -122.849637) (xy 361.441543 -122.863402) (xy 361.489024 -122.883739) (xy 361.533338 -122.910279)
			(xy 361.55376 -122.926094) (xy 361.554014 -122.926348) (xy 361.560872 -122.931682) (xy 361.568746 -122.934476)
			(xy 361.572925 -122.935887) (xy 361.581609 -122.937421) (xy 361.586018 -122.937524) (xy 361.605576 -122.937524)
			(xy 361.611017 -122.937661) (xy 361.621653 -122.939959) (xy 361.626658 -122.942096) (xy 361.640628 -122.948446)
			(xy 361.646718 -122.950961) (xy 361.659705 -122.953154) (xy 361.666282 -122.952764) (xy 361.675934 -122.950986)
			(xy 361.685332 -122.942604) (xy 361.686094 -122.942096) (xy 361.686348 -122.941842) (xy 361.687618 -122.940572)
			(xy 361.709168 -122.921436) (xy 361.756873 -122.889102) (xy 361.808847 -122.864201) (xy 361.863939 -122.847286)
			(xy 361.920931 -122.838729) (xy 361.949746 -122.83821) (xy 361.95 -122.83821) (xy 361.977224 -122.838693)
			(xy 362.031131 -122.846362) (xy 362.083432 -122.861505) (xy 362.133097 -122.883824) (xy 362.179146 -122.91288)
			(xy 362.20019 -122.930158) (xy 362.20781 -122.936254) (xy 362.218732 -122.937524) (xy 362.240576 -122.937524)
			(xy 362.246017 -122.937661) (xy 362.256653 -122.939959) (xy 362.261658 -122.942096) (xy 362.27766 -122.949462)
			(xy 362.283333 -122.951497) (xy 362.295268 -122.953157) (xy 362.301282 -122.952764) (xy 362.31068 -122.951494)
			(xy 362.312458 -122.95124) (xy 362.325666 -122.94489) (xy 362.331254 -122.939556) (xy 362.33354 -122.937778)
			(xy 362.33481 -122.936508) (xy 362.347172 -122.926032) (xy 362.37337 -122.906959) (xy 362.387134 -122.898408)
			(xy 362.388404 -122.897646) (xy 362.397294 -122.892312) (xy 362.40339 -122.88393) (xy 362.40615 -122.879923)
			(xy 362.410248 -122.8711) (xy 362.411518 -122.866404) (xy 362.415074 -122.85091) (xy 362.415074 -122.850402)
			(xy 362.429806 -122.782838) (xy 362.42752 -122.77217) (xy 362.425488 -122.762264) (xy 362.416852 -122.74931)
			(xy 362.40146 -122.725574) (xy 362.377093 -122.674521) (xy 362.360525 -122.620431) (xy 362.352119 -122.564489)
			(xy 362.351574 -122.536204) (xy 362.351574 -122.535696) (xy 362.351828 -122.529346) (xy 362.351828 -122.527568)
			(xy 362.352875 -122.500709) (xy 362.361581 -122.447667) (xy 362.377647 -122.396372) (xy 362.400755 -122.347841)
			(xy 362.430447 -122.303034) (xy 362.466135 -122.262839) (xy 362.507112 -122.228052) (xy 362.552567 -122.199362)
			(xy 362.601599 -122.177338) (xy 362.653238 -122.162414) (xy 362.70646 -122.154887) (xy 362.733336 -122.154442)
			(xy 362.760586 -122.154908) (xy 362.81453 -122.162669) (xy 362.866821 -122.178029) (xy 362.916393 -122.200674)
			(xy 362.962238 -122.230144) (xy 363.003423 -122.265838) (xy 363.039108 -122.307031) (xy 363.068567 -122.352882)
			(xy 363.091201 -122.40246) (xy 363.106549 -122.454754) (xy 363.114298 -122.5087) (xy 363.114844 -122.53595)
			(xy 363.114358 -122.563966) (xy 363.106189 -122.619398) (xy 363.09002 -122.673046) (xy 363.066196 -122.72376)
			(xy 363.035228 -122.770455) (xy 362.997777 -122.812132) (xy 362.954646 -122.847898) (xy 362.930948 -122.862848)
			(xy 362.929424 -122.863864) (xy 362.92917 -122.864118) (xy 362.9279 -122.86488) (xy 362.919264 -122.870722)
			(xy 362.91393 -122.878088) (xy 362.911724 -122.881386) (xy 362.908281 -122.888533) (xy 362.907072 -122.892312)
			(xy 362.903516 -122.90806) (xy 362.903516 -122.908568) (xy 362.890562 -122.968258) (xy 362.890562 -122.968512)
			(xy 362.889038 -122.974354) (xy 362.890054 -122.984006) (xy 362.890635 -122.988644) (xy 362.893313 -122.997598)
			(xy 362.895388 -123.001786) (xy 362.89742 -123.00585) (xy 362.899198 -123.00839) (xy 362.90123 -123.011184)
			(xy 362.915962 -123.034806) (xy 362.916216 -123.035314) (xy 362.923328 -123.048776) (xy 362.927392 -123.056904)
			(xy 362.937701 -123.078636) (xy 362.953369 -123.124112) (xy 362.958634 -123.147582) (xy 362.962332 -123.166671)
			(xy 362.96628 -123.205355) (xy 362.966508 -123.224798) (xy 362.966508 -123.225306) (xy 362.966008 -123.252567)
			(xy 362.958222 -123.306531) (xy 362.94284 -123.358838) (xy 362.920172 -123.408425) (xy 362.890682 -123.454284)
			(xy 362.854967 -123.49548) (xy 362.813755 -123.531178) (xy 362.767885 -123.560649) (xy 362.718288 -123.583296)
			(xy 362.665974 -123.598656) (xy 362.612007 -123.606419) (xy 362.584746 -123.606814) (xy 362.559163 -123.606405)
			(xy 362.508457 -123.599571) (xy 362.459119 -123.586019) (xy 362.412036 -123.565993) (xy 362.368052 -123.539853)
			(xy 362.347764 -123.524264) (xy 362.342938 -123.520454) (xy 362.337604 -123.517914) (xy 362.331254 -123.514866)
			(xy 362.321094 -123.51258) (xy 362.293916 -123.51258) (xy 362.288475 -123.512442) (xy 362.27784 -123.510143)
			(xy 362.272834 -123.508008) (xy 362.262674 -123.503182) (xy 362.256646 -123.500684) (xy 362.243788 -123.498491)
			(xy 362.237274 -123.498864) (xy 362.23362 -123.4993) (xy 362.226482 -123.501092) (xy 362.22305 -123.50242)
			(xy 362.2167 -123.50496) (xy 362.194995 -123.524921) (xy 362.146661 -123.558695) (xy 362.093757 -123.584735)
			(xy 362.037511 -123.602435) (xy 361.979229 -123.611385) (xy 361.949746 -123.611894) (xy 361.949492 -123.611894)
			(xy 361.922268 -123.61141) (xy 361.868362 -123.603741) (xy 361.816061 -123.588597) (xy 361.766397 -123.566277)
			(xy 361.720348 -123.537221) (xy 361.699302 -123.519946) (xy 361.691682 -123.51385) (xy 361.686094 -123.51258)
			(xy 361.658916 -123.51258) (xy 361.653475 -123.512442) (xy 361.64284 -123.510143) (xy 361.637834 -123.508008)
			(xy 361.626658 -123.50242) (xy 361.617392 -123.498504) (xy 361.59733 -123.497369) (xy 361.578353 -123.503978)
			(xy 361.570524 -123.510294) (xy 361.57027 -123.510294) (xy 361.5491 -123.52856) (xy 361.502455 -123.559392)
			(xy 361.451821 -123.583109) (xy 361.398275 -123.599207) (xy 361.342957 -123.607342) (xy 361.315 -123.60783)
			(xy 361.314492 -123.60783) (xy 361.288411 -123.607394) (xy 361.236732 -123.600317) (xy 361.186494 -123.586281)
			(xy 361.13863 -123.565547) (xy 361.094028 -123.538499) (xy 361.053517 -123.505641) (xy 361.035346 -123.486926)
			(xy 361.032044 -123.48337) (xy 361.015534 -123.471432) (xy 361.009184 -123.468384) (xy 361.001056 -123.464574)
			(xy 360.996058 -123.462388) (xy 360.985425 -123.459958) (xy 360.979974 -123.459748) (xy 360.917236 -123.45924)
			(xy 360.912664 -123.459494) (xy 360.899202 -123.461018) (xy 360.891328 -123.464828) (xy 360.887286 -123.467029)
			(xy 360.880003 -123.472652) (xy 360.87685 -123.476004) (xy 360.876342 -123.476512) (xy 360.87558 -123.477528)
			(xy 360.854888 -123.49972) (xy 360.807736 -123.537903) (xy 360.755135 -123.568142) (xy 360.698411 -123.589673)
			(xy 360.668824 -123.5964) (xy 360.641392 -123.600972) (xy 360.639868 -123.601226) (xy 360.635804 -123.601734)
			(xy 360.633772 -123.601988) (xy 360.628438 -123.60275) (xy 360.626914 -123.60275) (xy 360.624882 -123.603004)
			(xy 360.617516 -123.603512) (xy 360.607356 -123.604274) (xy 360.599482 -123.60783) (xy 360.595794 -123.609681)
			(xy 360.589028 -123.614403) (xy 360.58602 -123.617228) (xy 360.573066 -123.630944) (xy 360.572558 -123.631452)
			(xy 360.536998 -123.669806) (xy 360.536744 -123.67006) (xy 360.529886 -123.677426) (xy 360.526584 -123.686062)
			(xy 360.525822 -123.68784) (xy 360.524552 -123.692412) (xy 360.523282 -123.703588) (xy 360.523282 -125.403356)
			(xy 363.844332 -125.403356) (xy 363.844823 -125.375987) (xy 363.852634 -125.321808) (xy 363.868116 -125.269305)
			(xy 363.890953 -125.219558) (xy 363.920673 -125.17359) (xy 363.938312 -125.152658) (xy 363.938566 -125.152404)
			(xy 363.944165 -125.145326) (xy 363.950402 -125.128402) (xy 363.950758 -125.119384) (xy 363.950758 -125.052328)
			(xy 363.950397 -125.043311) (xy 363.944153 -125.026394) (xy 363.938566 -125.019308) (xy 363.938312 -125.019308)
			(xy 363.938312 -125.019054) (xy 363.920687 -124.998111) (xy 363.890972 -124.952141) (xy 363.868134 -124.902397)
			(xy 363.852639 -124.849898) (xy 363.844808 -124.795724) (xy 363.844332 -124.768356) (xy 363.844818 -124.741105)
			(xy 363.852574 -124.687157) (xy 363.867929 -124.634862) (xy 363.890571 -124.585285) (xy 363.920037 -124.539435)
			(xy 363.955728 -124.498244) (xy 363.996919 -124.462553) (xy 364.042769 -124.433087) (xy 364.092346 -124.410445)
			(xy 364.144641 -124.39509) (xy 364.198589 -124.387334) (xy 364.253091 -124.387334) (xy 364.307039 -124.39509)
			(xy 364.359334 -124.410445) (xy 364.408911 -124.433087) (xy 364.454761 -124.462553) (xy 364.495952 -124.498244)
			(xy 364.531643 -124.539435) (xy 364.561109 -124.585285) (xy 364.583751 -124.634862) (xy 364.599106 -124.687157)
			(xy 364.606862 -124.741105) (xy 364.607348 -124.768356) (xy 364.606869 -124.795726) (xy 364.599056 -124.849905)
			(xy 364.583571 -124.902408) (xy 364.560732 -124.952156) (xy 364.531009 -124.998122) (xy 364.513368 -125.019054)
			(xy 364.513114 -125.019308) (xy 364.507519 -125.026389) (xy 364.501277 -125.04331) (xy 364.500922 -125.052328)
			(xy 364.500922 -125.119384) (xy 364.501282 -125.128401) (xy 364.507527 -125.145318) (xy 364.513114 -125.152404)
			(xy 364.513368 -125.152404) (xy 364.513368 -125.152658) (xy 364.530996 -125.173599) (xy 364.560711 -125.219569)
			(xy 364.583549 -125.269314) (xy 364.599043 -125.321813) (xy 364.606873 -125.375987) (xy 364.607348 -125.403356)
			(xy 364.606862 -125.430607) (xy 364.599106 -125.484555) (xy 364.583751 -125.53685) (xy 364.561109 -125.586427)
			(xy 364.531643 -125.632277) (xy 364.495952 -125.673468) (xy 364.454761 -125.709159) (xy 364.408911 -125.738625)
			(xy 364.359334 -125.761267) (xy 364.307039 -125.776622) (xy 364.253091 -125.784378) (xy 364.198589 -125.784378)
			(xy 364.144641 -125.776622) (xy 364.092346 -125.761267) (xy 364.042769 -125.738625) (xy 363.996919 -125.709159)
			(xy 363.955728 -125.673468) (xy 363.920037 -125.632277) (xy 363.890571 -125.586427) (xy 363.867929 -125.53685)
			(xy 363.852574 -125.484555) (xy 363.844818 -125.430607) (xy 363.844332 -125.403356) (xy 360.523282 -125.403356)
			(xy 360.523282 -125.853698) (xy 364.784894 -125.853698) (xy 364.78536 -125.826328) (xy 364.793178 -125.772149)
			(xy 364.808667 -125.719646) (xy 364.831509 -125.669899) (xy 364.861233 -125.623932) (xy 364.878874 -125.603)
			(xy 364.879128 -125.602746) (xy 364.884705 -125.595653) (xy 364.890956 -125.578741) (xy 364.89132 -125.569726)
			(xy 364.89132 -125.50267) (xy 364.890973 -125.493652) (xy 364.884718 -125.476735) (xy 364.879128 -125.46965)
			(xy 364.878874 -125.46965) (xy 364.878874 -125.469396) (xy 364.861216 -125.44848) (xy 364.831507 -125.402502)
			(xy 364.808676 -125.352751) (xy 364.793189 -125.300247) (xy 364.785366 -125.246068) (xy 364.784894 -125.218698)
			(xy 364.78538 -125.191447) (xy 364.793136 -125.137499) (xy 364.808491 -125.085204) (xy 364.831133 -125.035627)
			(xy 364.860599 -124.989777) (xy 364.89629 -124.948586) (xy 364.937481 -124.912895) (xy 364.983331 -124.883429)
			(xy 365.032908 -124.860787) (xy 365.085203 -124.845432) (xy 365.139151 -124.837676) (xy 365.193653 -124.837676)
			(xy 365.247601 -124.845432) (xy 365.299896 -124.860787) (xy 365.349473 -124.883429) (xy 365.395323 -124.912895)
			(xy 365.436514 -124.948586) (xy 365.472205 -124.989777) (xy 365.501671 -125.035627) (xy 365.524313 -125.085204)
			(xy 365.539668 -125.137499) (xy 365.547424 -125.191447) (xy 365.54791 -125.218698) (xy 365.54744 -125.246068)
			(xy 365.539623 -125.300247) (xy 365.524135 -125.35275) (xy 365.501294 -125.402497) (xy 365.471571 -125.448464)
			(xy 365.45393 -125.469396) (xy 365.453676 -125.46965) (xy 365.448102 -125.476745) (xy 365.441848 -125.493655)
			(xy 365.441484 -125.50267) (xy 365.441484 -125.569726) (xy 365.441832 -125.578744) (xy 365.448086 -125.59566)
			(xy 365.453676 -125.602746) (xy 365.45393 -125.602746) (xy 365.45393 -125.603) (xy 365.471587 -125.623917)
			(xy 365.501295 -125.669895) (xy 365.524127 -125.719646) (xy 365.539614 -125.77215) (xy 365.547438 -125.826328)
			(xy 365.54791 -125.853698) (xy 365.547424 -125.880949) (xy 365.539668 -125.934897) (xy 365.524313 -125.987192)
			(xy 365.501671 -126.036769) (xy 365.472205 -126.082619) (xy 365.436514 -126.12381) (xy 365.395323 -126.159501)
			(xy 365.349473 -126.188967) (xy 365.299896 -126.211609) (xy 365.247601 -126.226964) (xy 365.193653 -126.23472)
			(xy 365.139151 -126.23472) (xy 365.085203 -126.226964) (xy 365.032908 -126.211609) (xy 364.983331 -126.188967)
			(xy 364.937481 -126.159501) (xy 364.89629 -126.12381) (xy 364.860599 -126.082619) (xy 364.831133 -126.036769)
			(xy 364.808491 -125.987192) (xy 364.793136 -125.934897) (xy 364.78538 -125.880949) (xy 364.784894 -125.853698)
			(xy 360.523282 -125.853698) (xy 360.523282 -126.530354) (xy 365.993426 -126.530354) (xy 365.993968 -126.50269)
			(xy 366.001961 -126.447942) (xy 366.017771 -126.39492) (xy 366.041069 -126.344736) (xy 366.071366 -126.298439)
			(xy 366.108028 -126.257001) (xy 366.150286 -126.221287) (xy 366.173512 -126.20625) (xy 366.183163 -126.199581)
			(xy 366.195622 -126.179744) (xy 366.197388 -126.16815) (xy 366.205262 -126.08814) (xy 366.205858 -126.076503)
			(xy 366.197802 -126.054668) (xy 366.189768 -126.04623) (xy 366.189514 -126.045976) (xy 366.170942 -126.027886)
			(xy 366.138362 -125.987557) (xy 366.111547 -125.943184) (xy 366.090993 -125.895587) (xy 366.077078 -125.845645)
			(xy 366.070059 -125.794277) (xy 366.069626 -125.768354) (xy 366.070035 -125.7411) (xy 366.077799 -125.687148)
			(xy 366.093161 -125.63485) (xy 366.11581 -125.58527) (xy 366.145285 -125.539418) (xy 366.180984 -125.498228)
			(xy 366.222182 -125.462537) (xy 366.26804 -125.433072) (xy 366.317625 -125.410433) (xy 366.369926 -125.395082)
			(xy 366.42388 -125.387329) (xy 366.451134 -125.386846) (xy 366.478505 -125.387281) (xy 366.532686 -125.395105)
			(xy 366.58519 -125.4106) (xy 366.634937 -125.433449) (xy 366.680902 -125.463181) (xy 366.701832 -125.480826)
			(xy 366.702086 -125.48108) (xy 366.709166 -125.486676) (xy 366.726088 -125.492915) (xy 366.735106 -125.493272)
			(xy 366.802162 -125.493272) (xy 366.811178 -125.492903) (xy 366.828095 -125.486664) (xy 366.835182 -125.48108)
			(xy 366.835182 -125.480826) (xy 366.835436 -125.480826) (xy 366.856385 -125.463207) (xy 366.902353 -125.433492)
			(xy 366.952096 -125.410651) (xy 367.004593 -125.395156) (xy 367.058766 -125.387322) (xy 367.086134 -125.386846)
			(xy 367.113384 -125.387346) (xy 367.167329 -125.395106) (xy 367.21962 -125.410463) (xy 367.269195 -125.433105)
			(xy 367.315043 -125.46257) (xy 367.356231 -125.49826) (xy 367.391922 -125.539448) (xy 367.421389 -125.585295)
			(xy 367.444033 -125.634868) (xy 367.459391 -125.687159) (xy 367.467153 -125.741104) (xy 367.467642 -125.768354)
			(xy 367.467113 -125.797271) (xy 367.458389 -125.854442) (xy 367.441135 -125.909642) (xy 367.415745 -125.961604)
			(xy 367.382803 -126.009138) (xy 367.343062 -126.051155) (xy 367.320576 -126.069344) (xy 367.311755 -126.076938)
			(xy 367.30158 -126.097849) (xy 367.301018 -126.109476) (xy 367.301018 -126.189232) (xy 367.301547 -126.200865)
			(xy 367.311742 -126.221775) (xy 367.320576 -126.229364) (xy 367.343037 -126.247581) (xy 367.382775 -126.289595)
			(xy 367.415717 -126.337124) (xy 367.44111 -126.38908) (xy 367.45837 -126.444274) (xy 367.467104 -126.501439)
			(xy 367.467642 -126.530354) (xy 367.467102 -126.557604) (xy 367.459352 -126.611551) (xy 367.444004 -126.663845)
			(xy 367.421369 -126.713423) (xy 367.391909 -126.759274) (xy 367.356223 -126.800467) (xy 367.315038 -126.836161)
			(xy 367.269193 -126.865631) (xy 367.21962 -126.888276) (xy 367.167329 -126.903635) (xy 367.113384 -126.911396)
			(xy 367.086134 -126.911862) (xy 367.059818 -126.911451) (xy 367.007687 -126.904206) (xy 366.957042 -126.889877)
			(xy 366.908843 -126.868734) (xy 366.864001 -126.841177) (xy 366.823365 -126.807728) (xy 366.80521 -126.788672)
			(xy 366.797677 -126.781283) (xy 366.778406 -126.772749) (xy 366.767872 -126.772162) (xy 366.693196 -126.772162)
			(xy 366.682646 -126.772687) (xy 366.663352 -126.781226) (xy 366.655858 -126.788672) (xy 366.63771 -126.807736)
			(xy 366.59708 -126.841193) (xy 366.552238 -126.868752) (xy 366.504035 -126.889889) (xy 366.453386 -126.904204)
			(xy 366.401251 -126.911426) (xy 366.374934 -126.911862) (xy 366.34768 -126.911413) (xy 366.293726 -126.903659)
			(xy 366.241425 -126.888305) (xy 366.191842 -126.865663) (xy 366.145987 -126.836195) (xy 366.104792 -126.800499)
			(xy 366.069098 -126.759304) (xy 366.039631 -126.713447) (xy 366.01699 -126.663864) (xy 366.001638 -126.611562)
			(xy 365.993886 -126.557608) (xy 365.993426 -126.530354) (xy 360.523282 -126.530354) (xy 360.523282 -128.290574)
			(xy 360.522845 -128.300638) (xy 360.51511 -128.319221) (xy 360.508296 -128.326642) (xy 357.387781 -131.447157)
			(xy 358.013409 -131.447157) (xy 358.013409 -131.392643) (xy 358.021167 -131.338685) (xy 358.036525 -131.28638)
			(xy 358.059171 -131.236794) (xy 358.088644 -131.190935) (xy 358.124342 -131.149737) (xy 358.165541 -131.114039)
			(xy 358.211401 -131.084567) (xy 358.260988 -131.061923) (xy 358.313293 -131.046565) (xy 358.367251 -131.038808)
			(xy 358.394508 -131.038346) (xy 358.421879 -131.038796) (xy 358.476059 -131.046616) (xy 358.528563 -131.062108)
			(xy 358.57831 -131.084954) (xy 358.624275 -131.114683) (xy 358.645206 -131.132326) (xy 358.64546 -131.13258)
			(xy 358.652547 -131.138165) (xy 358.669464 -131.144411) (xy 358.67848 -131.144772) (xy 358.745536 -131.144772)
			(xy 358.754555 -131.144438) (xy 358.771472 -131.138175) (xy 358.778556 -131.13258) (xy 358.778556 -131.132326)
			(xy 358.77881 -131.132326) (xy 358.799743 -131.114685) (xy 358.845711 -131.084961) (xy 358.895457 -131.062115)
			(xy 358.947959 -131.046619) (xy 359.002137 -131.03879) (xy 359.056879 -131.03879) (xy 359.111057 -131.046619)
			(xy 359.163559 -131.062115) (xy 359.213305 -131.084961) (xy 359.259273 -131.114685) (xy 359.280206 -131.132326)
			(xy 359.28046 -131.13258) (xy 359.287547 -131.138165) (xy 359.304464 -131.144411) (xy 359.31348 -131.144772)
			(xy 359.380536 -131.144772) (xy 359.389555 -131.144438) (xy 359.406472 -131.138175) (xy 359.413556 -131.13258)
			(xy 359.413556 -131.132326) (xy 359.41381 -131.132326) (xy 359.434731 -131.114673) (xy 359.480706 -131.084962)
			(xy 359.530457 -131.062129) (xy 359.58296 -131.046641) (xy 359.637138 -131.038817) (xy 359.664508 -131.038346)
			(xy 359.691756 -131.038925) (xy 359.745696 -131.046681) (xy 359.797983 -131.062035) (xy 359.847553 -131.084674)
			(xy 359.893397 -131.114137) (xy 359.934582 -131.149824) (xy 359.970268 -131.191009) (xy 359.99973 -131.236854)
			(xy 360.022368 -131.286424) (xy 360.037721 -131.338712) (xy 360.045476 -131.392652) (xy 360.045476 -131.447148)
			(xy 360.037721 -131.501088) (xy 360.022368 -131.553376) (xy 359.99973 -131.602946) (xy 359.970268 -131.648791)
			(xy 359.934582 -131.689976) (xy 359.893397 -131.725663) (xy 359.847553 -131.755126) (xy 359.797983 -131.777765)
			(xy 359.745696 -131.793119) (xy 359.691756 -131.800875) (xy 359.664508 -131.801362) (xy 359.637137 -131.800901)
			(xy 359.582958 -131.793083) (xy 359.530454 -131.777593) (xy 359.480708 -131.75475) (xy 359.434741 -131.725024)
			(xy 359.41381 -131.707382) (xy 359.413556 -131.707128) (xy 359.406464 -131.70155) (xy 359.389551 -131.6953)
			(xy 359.380536 -131.694936) (xy 359.31348 -131.694936) (xy 359.304461 -131.695276) (xy 359.287544 -131.701534)
			(xy 359.28046 -131.707128) (xy 359.280206 -131.707382) (xy 359.259273 -131.725023) (xy 359.213305 -131.754747)
			(xy 359.163559 -131.777593) (xy 359.111057 -131.793089) (xy 359.056879 -131.800918) (xy 359.002137 -131.800918)
			(xy 358.947959 -131.793089) (xy 358.895457 -131.777593) (xy 358.845711 -131.754747) (xy 358.799743 -131.725023)
			(xy 358.77881 -131.707382) (xy 358.778556 -131.707128) (xy 358.771464 -131.70155) (xy 358.754551 -131.6953)
			(xy 358.745536 -131.694936) (xy 358.67848 -131.694936) (xy 358.669461 -131.695276) (xy 358.652544 -131.701534)
			(xy 358.64546 -131.707128) (xy 358.64546 -131.707382) (xy 358.645206 -131.707382) (xy 358.62428 -131.725029)
			(xy 358.578306 -131.75474) (xy 358.528557 -131.777575) (xy 358.476055 -131.793064) (xy 358.421878 -131.80089)
			(xy 358.394508 -131.801362) (xy 358.367251 -131.800992) (xy 358.313293 -131.793235) (xy 358.260988 -131.777877)
			(xy 358.211401 -131.755233) (xy 358.165541 -131.725761) (xy 358.124342 -131.690063) (xy 358.088644 -131.648865)
			(xy 358.059171 -131.603006) (xy 358.036525 -131.55342) (xy 358.021167 -131.501115) (xy 358.013409 -131.447157)
			(xy 357.387781 -131.447157) (xy 355.643434 -133.191504) (xy 355.639909 -133.195232) (xy 355.634273 -133.203804)
			(xy 355.632258 -133.208522) (xy 355.628702 -133.217158) (xy 355.628702 -133.443726) (xy 359.422954 -133.443726)
			(xy 359.423421 -133.417412) (xy 359.430654 -133.365283) (xy 359.444972 -133.314639) (xy 359.466104 -133.26644)
			(xy 359.493651 -133.221596) (xy 359.527091 -133.180958) (xy 359.546144 -133.162802) (xy 359.553538 -133.155274)
			(xy 359.562069 -133.135999) (xy 359.562654 -133.125464) (xy 359.562654 -133.050788) (xy 359.562158 -133.040234)
			(xy 359.553601 -133.020938) (xy 359.546144 -133.01345) (xy 359.527061 -132.995323) (xy 359.493608 -132.954686)
			(xy 359.466054 -132.909839) (xy 359.444921 -132.861633) (xy 359.430609 -132.810981) (xy 359.42339 -132.758844)
			(xy 359.422954 -132.732526) (xy 359.42344 -132.705275) (xy 359.431196 -132.651327) (xy 359.446551 -132.599032)
			(xy 359.469193 -132.549455) (xy 359.498659 -132.503605) (xy 359.53435 -132.462414) (xy 359.575541 -132.426723)
			(xy 359.621391 -132.397257) (xy 359.670968 -132.374615) (xy 359.723263 -132.35926) (xy 359.777211 -132.351504)
			(xy 359.831713 -132.351504) (xy 359.885661 -132.35926) (xy 359.937956 -132.374615) (xy 359.987533 -132.397257)
			(xy 360.033383 -132.426723) (xy 360.074574 -132.462414) (xy 360.110265 -132.503605) (xy 360.139731 -132.549455)
			(xy 360.162373 -132.599032) (xy 360.177728 -132.651327) (xy 360.185484 -132.705275) (xy 360.18597 -132.732526)
			(xy 360.185529 -132.758841) (xy 360.17829 -132.810971) (xy 360.163967 -132.861615) (xy 360.142829 -132.909814)
			(xy 360.115278 -132.954657) (xy 360.081834 -132.995295) (xy 360.06278 -133.01345) (xy 360.055351 -133.020948)
			(xy 360.046843 -133.040246) (xy 360.04627 -133.050788) (xy 360.04627 -133.125464) (xy 360.046814 -133.136012)
			(xy 360.05534 -133.155307) (xy 360.06278 -133.162802) (xy 360.081826 -133.180968) (xy 360.115285 -133.221595)
			(xy 360.142845 -133.266433) (xy 360.163986 -133.314632) (xy 360.178305 -133.365278) (xy 360.185531 -133.41741)
			(xy 360.18597 -133.443726) (xy 360.185484 -133.470977) (xy 360.177728 -133.524925) (xy 360.162373 -133.57722)
			(xy 360.139731 -133.626797) (xy 360.110265 -133.672647) (xy 360.074574 -133.713838) (xy 360.033383 -133.749529)
			(xy 359.987533 -133.778995) (xy 359.937956 -133.801637) (xy 359.885661 -133.816992) (xy 359.831713 -133.824748)
			(xy 359.777211 -133.824748) (xy 359.723263 -133.816992) (xy 359.670968 -133.801637) (xy 359.621391 -133.778995)
			(xy 359.575541 -133.749529) (xy 359.53435 -133.713838) (xy 359.498659 -133.672647) (xy 359.469193 -133.626797)
			(xy 359.446551 -133.57722) (xy 359.431196 -133.524925) (xy 359.42344 -133.470977) (xy 359.422954 -133.443726)
			(xy 355.628702 -133.443726) (xy 355.628702 -134.39648) (xy 355.63048 -134.406132) (xy 355.681788 -134.45744)
			(xy 355.682804 -134.458456) (xy 355.695929 -134.471986) (xy 355.71935 -134.501525) (xy 355.72954 -134.517384)
			(xy 355.732588 -134.522464) (xy 355.749098 -134.538974) (xy 355.76665 -134.55719) (xy 355.79638 -134.598115)
			(xy 355.819338 -134.643189) (xy 355.834956 -134.691302) (xy 355.84285 -134.741266) (xy 355.843332 -134.766558)
			(xy 355.843332 -135.142051) (xy 357.66197 -135.142051) (xy 357.66197 -135.087549) (xy 357.669726 -135.033603)
			(xy 357.68508 -134.981309) (xy 357.707719 -134.931733) (xy 357.737184 -134.885883) (xy 357.772873 -134.844693)
			(xy 357.814061 -134.809) (xy 357.859908 -134.779533) (xy 357.909483 -134.756889) (xy 357.961776 -134.741532)
			(xy 358.015721 -134.733772) (xy 358.042972 -134.733284) (xy 358.07189 -134.73379) (xy 358.129063 -134.742517)
			(xy 358.184263 -134.759776) (xy 358.236226 -134.785169) (xy 358.283759 -134.818117) (xy 358.325774 -134.857862)
			(xy 358.343962 -134.88035) (xy 358.351755 -134.889337) (xy 358.37322 -134.899526) (xy 358.38511 -134.899908)
			(xy 358.478582 -134.897876) (xy 358.499918 -134.8867) (xy 358.506776 -134.876794) (xy 358.522175 -134.855885)
			(xy 358.557753 -134.818058) (xy 358.598132 -134.785406) (xy 358.642566 -134.758531) (xy 358.690235 -134.737931)
			(xy 358.740256 -134.723985) (xy 358.791707 -134.716952) (xy 358.817672 -134.71652) (xy 358.845042 -134.716998)
			(xy 358.899221 -134.724812) (xy 358.951724 -134.740298) (xy 359.001471 -134.763137) (xy 359.047438 -134.79286)
			(xy 359.06837 -134.8105) (xy 359.068624 -134.810754) (xy 359.075695 -134.816363) (xy 359.092624 -134.822595)
			(xy 359.101644 -134.822946) (xy 359.1687 -134.822946) (xy 359.177718 -134.822601) (xy 359.194636 -134.816346)
			(xy 359.20172 -134.810754) (xy 359.20172 -134.8105) (xy 359.201974 -134.8105) (xy 359.222907 -134.792859)
			(xy 359.268875 -134.763135) (xy 359.318621 -134.740289) (xy 359.371123 -134.724793) (xy 359.425301 -134.716964)
			(xy 359.480043 -134.716964) (xy 359.534221 -134.724793) (xy 359.586723 -134.740289) (xy 359.636469 -134.763135)
			(xy 359.682437 -134.792859) (xy 359.70337 -134.8105) (xy 359.703624 -134.810754) (xy 359.710695 -134.816363)
			(xy 359.727624 -134.822595) (xy 359.736644 -134.822946) (xy 359.8037 -134.822946) (xy 359.812718 -134.822601)
			(xy 359.829636 -134.816346) (xy 359.83672 -134.810754) (xy 359.837228 -134.8105) (xy 359.849966 -134.79956)
			(xy 359.877055 -134.779716) (xy 359.89133 -134.770876) (xy 359.90022 -134.765542) (xy 359.912412 -134.748524)
			(xy 359.932732 -134.655306) (xy 359.928414 -134.634732) (xy 359.922572 -134.626096) (xy 359.906565 -134.602037)
			(xy 359.881225 -134.550103) (xy 359.864001 -134.494944) (xy 359.855288 -134.437819) (xy 359.854754 -134.408926)
			(xy 359.85524 -134.381675) (xy 359.862996 -134.327727) (xy 359.878351 -134.275432) (xy 359.900993 -134.225855)
			(xy 359.930459 -134.180005) (xy 359.96615 -134.138814) (xy 360.007341 -134.103123) (xy 360.053191 -134.073657)
			(xy 360.102768 -134.051015) (xy 360.155063 -134.03566) (xy 360.209011 -134.027904) (xy 360.263513 -134.027904)
			(xy 360.317461 -134.03566) (xy 360.369756 -134.051015) (xy 360.419333 -134.073657) (xy 360.465183 -134.103123)
			(xy 360.506374 -134.138814) (xy 360.542065 -134.180005) (xy 360.571531 -134.225855) (xy 360.594173 -134.275432)
			(xy 360.609528 -134.327727) (xy 360.617284 -134.381675) (xy 360.61777 -134.408926) (xy 360.617319 -134.437019)
			(xy 360.609086 -134.492599) (xy 360.592789 -134.546371) (xy 360.56878 -134.597169) (xy 360.537578 -134.643895)
			(xy 360.499859 -134.685539) (xy 360.456438 -134.721198) (xy 360.432604 -134.736078) (xy 360.423714 -134.741412)
			(xy 360.411522 -134.75843) (xy 360.391202 -134.851648) (xy 360.39552 -134.872222) (xy 360.401362 -134.880858)
			(xy 360.417342 -134.904935) (xy 360.44269 -134.956861) (xy 360.459922 -135.012015) (xy 360.468643 -135.069137)
			(xy 360.46918 -135.098028) (xy 360.468748 -135.125281) (xy 360.460987 -135.179232) (xy 360.445627 -135.23153)
			(xy 360.422981 -135.281109) (xy 360.393509 -135.326961) (xy 360.357812 -135.368151) (xy 360.316616 -135.403842)
			(xy 360.27076 -135.433307) (xy 360.221177 -135.455947) (xy 360.168878 -135.471299) (xy 360.114925 -135.479052)
			(xy 360.087672 -135.479536) (xy 360.0603 -135.479102) (xy 360.006119 -135.471279) (xy 359.953615 -135.455783)
			(xy 359.903869 -135.432934) (xy 359.857904 -135.403201) (xy 359.836974 -135.385556) (xy 359.83672 -135.385302)
			(xy 359.829632 -135.379718) (xy 359.812716 -135.37347) (xy 359.8037 -135.37311) (xy 359.736644 -135.37311)
			(xy 359.727629 -135.373486) (xy 359.710712 -135.37972) (xy 359.703624 -135.385302) (xy 359.703624 -135.385556)
			(xy 359.70337 -135.385556) (xy 359.682437 -135.403197) (xy 359.636469 -135.432921) (xy 359.586723 -135.455767)
			(xy 359.534221 -135.471263) (xy 359.480043 -135.479092) (xy 359.425301 -135.479092) (xy 359.371123 -135.471263)
			(xy 359.318621 -135.455767) (xy 359.268875 -135.432921) (xy 359.222907 -135.403197) (xy 359.201974 -135.385556)
			(xy 359.20172 -135.385302) (xy 359.194632 -135.379718) (xy 359.177716 -135.37347) (xy 359.1687 -135.37311)
			(xy 359.101644 -135.37311) (xy 359.092629 -135.373486) (xy 359.075712 -135.37972) (xy 359.068624 -135.385302)
			(xy 359.068624 -135.385556) (xy 359.06837 -135.385556) (xy 359.047417 -135.403169) (xy 359.00145 -135.432886)
			(xy 358.951708 -135.455728) (xy 358.899212 -135.471225) (xy 358.84504 -135.479059) (xy 358.817672 -135.479536)
			(xy 358.788756 -135.47899) (xy 358.731585 -135.47027) (xy 358.676386 -135.453019) (xy 358.624423 -135.427633)
			(xy 358.576889 -135.394693) (xy 358.534872 -135.354954) (xy 358.516682 -135.33247) (xy 358.508866 -135.323507)
			(xy 358.487419 -135.313305) (xy 358.475534 -135.312912) (xy 358.382062 -135.314944) (xy 358.360726 -135.32612)
			(xy 358.353868 -135.336026) (xy 358.338447 -135.356919) (xy 358.302873 -135.394745) (xy 358.262497 -135.427398)
			(xy 358.218066 -135.454275) (xy 358.170402 -135.474878) (xy 358.120383 -135.488827) (xy 358.068936 -135.495865)
			(xy 358.042972 -135.4963) (xy 358.015721 -135.495828) (xy 357.961776 -135.488068) (xy 357.909483 -135.472711)
			(xy 357.859908 -135.450067) (xy 357.814061 -135.4206) (xy 357.772873 -135.384907) (xy 357.737184 -135.343717)
			(xy 357.707719 -135.297867) (xy 357.68508 -135.248291) (xy 357.669726 -135.195997) (xy 357.66197 -135.142051)
			(xy 355.843332 -135.142051) (xy 355.843332 -135.207248) (xy 355.84511 -135.220456) (xy 355.846126 -135.223758)
			(xy 355.848119 -135.228818) (xy 355.85388 -135.238039) (xy 355.857556 -135.242046) (xy 355.89972 -135.282686)
			(xy 355.913182 -135.29564) (xy 355.919696 -135.301004) (xy 355.935267 -135.307486) (xy 355.943662 -135.30834)
			(xy 355.957124 -135.308086) (xy 355.966268 -135.308086) (xy 355.993474 -135.308638) (xy 356.047317 -135.316506)
			(xy 356.099496 -135.331945) (xy 356.148952 -135.354641) (xy 356.194682 -135.384133) (xy 356.235757 -135.419824)
			(xy 356.271344 -135.460989) (xy 356.300721 -135.506793) (xy 356.323293 -135.556306) (xy 356.3386 -135.608524)
			(xy 356.346332 -135.662386) (xy 356.34676 -135.689594) (xy 356.346297 -135.716846) (xy 356.33854 -135.770795)
			(xy 356.323184 -135.823091) (xy 356.303183 -135.866886) (xy 356.73995 -135.866886) (xy 356.744021 -135.811264)
			(xy 356.756147 -135.756827) (xy 356.77607 -135.704736) (xy 356.803366 -135.656101) (xy 356.837452 -135.611958)
			(xy 356.877601 -135.573249) (xy 356.922959 -135.540798) (xy 356.972559 -135.515297) (xy 357.025343 -135.49729)
			(xy 357.080186 -135.48716) (xy 357.13592 -135.485123) (xy 357.191357 -135.491223) (xy 357.245314 -135.505329)
			(xy 357.296643 -135.527141) (xy 357.344249 -135.556195) (xy 357.387117 -135.59187) (xy 357.424334 -135.633407)
			(xy 357.455107 -135.67992) (xy 357.478779 -135.730417) (xy 357.494847 -135.783824) (xy 357.502967 -135.839)
			(xy 357.503476 -135.866886) (xy 357.502967 -135.894772) (xy 357.494847 -135.949948) (xy 357.478779 -136.003355)
			(xy 357.455107 -136.053852) (xy 357.424334 -136.100365) (xy 357.387117 -136.141902) (xy 357.344249 -136.177577)
			(xy 357.296643 -136.206631) (xy 357.245314 -136.228443) (xy 357.191357 -136.242549) (xy 357.13592 -136.248649)
			(xy 357.080186 -136.246612) (xy 357.025343 -136.236482) (xy 356.972559 -136.218475) (xy 356.922959 -136.192974)
			(xy 356.877601 -136.160523) (xy 356.837452 -136.121814) (xy 356.803366 -136.077671) (xy 356.77607 -136.029036)
			(xy 356.756147 -135.976945) (xy 356.744021 -135.922508) (xy 356.73995 -135.866886) (xy 356.303183 -135.866886)
			(xy 356.300542 -135.872669) (xy 356.271073 -135.918519) (xy 356.235379 -135.959708) (xy 356.194185 -135.995398)
			(xy 356.148332 -136.024862) (xy 356.098751 -136.047499) (xy 356.046454 -136.062849) (xy 355.992504 -136.0706)
			(xy 355.965252 -136.071102) (xy 355.955854 -136.071102) (xy 355.94036 -136.07034) (xy 355.939852 -136.07034)
			(xy 355.926898 -136.06907) (xy 355.915976 -136.068054) (xy 355.904546 -136.071864) (xy 355.899593 -136.073609)
			(xy 355.890503 -136.078864) (xy 355.886512 -136.082278) (xy 355.830124 -136.132824) (xy 355.822621 -136.140371)
			(xy 355.813973 -136.15979) (xy 355.81336 -136.170416) (xy 355.81336 -136.352788) (xy 355.814122 -136.360408)
			(xy 356.104444 -136.65073) (xy 356.122475 -136.669501) (xy 356.153052 -136.711618) (xy 356.176674 -136.757995)
			(xy 356.192762 -136.807492) (xy 356.200921 -136.858895) (xy 356.201472 -136.884918) (xy 356.201472 -137.44829)
			(xy 356.645208 -137.44829) (xy 356.649279 -137.392668) (xy 356.661405 -137.338231) (xy 356.681328 -137.28614)
			(xy 356.708624 -137.237505) (xy 356.74271 -137.193362) (xy 356.782859 -137.154653) (xy 356.828217 -137.122202)
			(xy 356.877817 -137.096701) (xy 356.930601 -137.078694) (xy 356.985444 -137.068564) (xy 357.041178 -137.066527)
			(xy 357.096615 -137.072627) (xy 357.150572 -137.086733) (xy 357.201901 -137.108545) (xy 357.249507 -137.137599)
			(xy 357.292375 -137.173274) (xy 357.329592 -137.214811) (xy 357.360365 -137.261324) (xy 357.3674 -137.276332)
			(xy 361.347258 -137.276332) (xy 361.347662 -137.250016) (xy 361.354907 -137.197884) (xy 361.369237 -137.147239)
			(xy 361.390382 -137.09904) (xy 361.41794 -137.054198) (xy 361.451391 -137.013562) (xy 361.470448 -136.995408)
			(xy 361.47784 -136.987878) (xy 361.486372 -136.968605) (xy 361.486958 -136.95807) (xy 361.486958 -136.883394)
			(xy 361.486458 -136.872841) (xy 361.477904 -136.853545) (xy 361.470448 -136.846056) (xy 361.451368 -136.827925)
			(xy 361.417915 -136.787289) (xy 361.390361 -136.742443) (xy 361.369227 -136.694238) (xy 361.354914 -136.643586)
			(xy 361.347694 -136.591449) (xy 361.347258 -136.565132) (xy 361.347744 -136.537881) (xy 361.3555 -136.483933)
			(xy 361.370855 -136.431638) (xy 361.393497 -136.382061) (xy 361.422963 -136.336211) (xy 361.458654 -136.29502)
			(xy 361.499845 -136.259329) (xy 361.545695 -136.229863) (xy 361.595272 -136.207221) (xy 361.647567 -136.191866)
			(xy 361.701515 -136.18411) (xy 361.756017 -136.18411) (xy 361.809965 -136.191866) (xy 361.86226 -136.207221)
			(xy 361.911837 -136.229863) (xy 361.957687 -136.259329) (xy 361.998878 -136.29502) (xy 362.034569 -136.336211)
			(xy 362.064035 -136.382061) (xy 362.086677 -136.431638) (xy 362.102032 -136.483933) (xy 362.109788 -136.537881)
			(xy 362.110274 -136.565132) (xy 362.109836 -136.591447) (xy 362.102596 -136.643577) (xy 362.088272 -136.694221)
			(xy 362.067134 -136.74242) (xy 362.039582 -136.787263) (xy 362.006138 -136.827901) (xy 361.987084 -136.846056)
			(xy 361.979697 -136.85359) (xy 361.971165 -136.872861) (xy 361.970574 -136.883394) (xy 361.970574 -136.95807)
			(xy 361.971114 -136.968618) (xy 361.979642 -136.987913) (xy 361.987084 -136.995408) (xy 362.006133 -137.01357)
			(xy 362.039592 -137.054198) (xy 362.067152 -137.099037) (xy 362.088292 -137.147236) (xy 362.10261 -137.197883)
			(xy 362.109835 -137.250016) (xy 362.110274 -137.276332) (xy 362.109788 -137.303583) (xy 362.102032 -137.357531)
			(xy 362.086677 -137.409826) (xy 362.064035 -137.459403) (xy 362.034569 -137.505253) (xy 361.998878 -137.546444)
			(xy 361.957687 -137.582135) (xy 361.911837 -137.611601) (xy 361.86226 -137.634243) (xy 361.809965 -137.649598)
			(xy 361.756017 -137.657354) (xy 361.701515 -137.657354) (xy 361.647567 -137.649598) (xy 361.595272 -137.634243)
			(xy 361.545695 -137.611601) (xy 361.499845 -137.582135) (xy 361.458654 -137.546444) (xy 361.422963 -137.505253)
			(xy 361.393497 -137.459403) (xy 361.370855 -137.409826) (xy 361.3555 -137.357531) (xy 361.347744 -137.303583)
			(xy 361.347258 -137.276332) (xy 357.3674 -137.276332) (xy 357.384037 -137.311821) (xy 357.400105 -137.365228)
			(xy 357.408225 -137.420404) (xy 357.408734 -137.44829) (xy 357.408225 -137.476176) (xy 357.400105 -137.531352)
			(xy 357.384037 -137.584759) (xy 357.360365 -137.635256) (xy 357.329592 -137.681769) (xy 357.292375 -137.723306)
			(xy 357.288328 -137.726674) (xy 362.28782 -137.726674) (xy 362.288266 -137.699303) (xy 362.296088 -137.645123)
			(xy 362.311581 -137.592619) (xy 362.334428 -137.542873) (xy 362.364157 -137.496907) (xy 362.3818 -137.475976)
			(xy 362.382054 -137.475722) (xy 362.387644 -137.468638) (xy 362.393887 -137.451719) (xy 362.394246 -137.442702)
			(xy 362.394246 -137.375646) (xy 362.393879 -137.36663) (xy 362.38764 -137.349712) (xy 362.382054 -137.342626)
			(xy 362.3818 -137.342626) (xy 362.3818 -137.342372) (xy 362.364181 -137.321424) (xy 362.334466 -137.275455)
			(xy 362.311626 -137.225712) (xy 362.296131 -137.173215) (xy 362.288297 -137.119042) (xy 362.28782 -137.091674)
			(xy 362.288306 -137.064423) (xy 362.296062 -137.010475) (xy 362.311417 -136.95818) (xy 362.334059 -136.908603)
			(xy 362.363525 -136.862753) (xy 362.399216 -136.821562) (xy 362.440407 -136.785871) (xy 362.486257 -136.756405)
			(xy 362.535834 -136.733763) (xy 362.588129 -136.718408) (xy 362.642077 -136.710652) (xy 362.696579 -136.710652)
			(xy 362.750527 -136.718408) (xy 362.802822 -136.733763) (xy 362.852399 -136.756405) (xy 362.898249 -136.785871)
			(xy 362.93944 -136.821562) (xy 362.975131 -136.862753) (xy 363.004597 -136.908603) (xy 363.027239 -136.95818)
			(xy 363.042594 -137.010475) (xy 363.05035 -137.064423) (xy 363.050836 -137.091674) (xy 363.05037 -137.119044)
			(xy 363.042555 -137.173224) (xy 363.027066 -137.225728) (xy 363.004224 -137.275475) (xy 362.974498 -137.321441)
			(xy 362.956856 -137.342372) (xy 362.956602 -137.342626) (xy 362.95104 -137.34973) (xy 362.944779 -137.366633)
			(xy 362.94441 -137.375646) (xy 362.94441 -137.442702) (xy 362.944764 -137.451719) (xy 362.951013 -137.468636)
			(xy 362.956602 -137.475722) (xy 362.956856 -137.475722) (xy 362.956856 -137.475976) (xy 362.97449 -137.496912)
			(xy 363.004205 -137.542883) (xy 363.027042 -137.592629) (xy 363.042534 -137.64513) (xy 363.050362 -137.699305)
			(xy 363.050836 -137.726674) (xy 363.05035 -137.753925) (xy 363.042594 -137.807873) (xy 363.027239 -137.860168)
			(xy 363.004597 -137.909745) (xy 362.975131 -137.955595) (xy 362.93944 -137.996786) (xy 362.898249 -138.032477)
			(xy 362.852399 -138.061943) (xy 362.802822 -138.084585) (xy 362.750527 -138.09994) (xy 362.696579 -138.107696)
			(xy 362.642077 -138.107696) (xy 362.588129 -138.09994) (xy 362.535834 -138.084585) (xy 362.486257 -138.061943)
			(xy 362.440407 -138.032477) (xy 362.399216 -137.996786) (xy 362.363525 -137.955595) (xy 362.334059 -137.909745)
			(xy 362.311417 -137.860168) (xy 362.296062 -137.807873) (xy 362.288306 -137.753925) (xy 362.28782 -137.726674)
			(xy 357.288328 -137.726674) (xy 357.249507 -137.758981) (xy 357.201901 -137.788035) (xy 357.150572 -137.809847)
			(xy 357.096615 -137.823953) (xy 357.041178 -137.830053) (xy 356.985444 -137.828016) (xy 356.930601 -137.817886)
			(xy 356.877817 -137.799879) (xy 356.828217 -137.774378) (xy 356.782859 -137.741927) (xy 356.74271 -137.703218)
			(xy 356.708624 -137.659075) (xy 356.681328 -137.61044) (xy 356.661405 -137.558349) (xy 356.649279 -137.503912)
			(xy 356.645208 -137.44829) (xy 356.201472 -137.44829) (xy 356.201472 -138.40333) (xy 363.496352 -138.40333)
			(xy 363.496863 -138.375665) (xy 363.50486 -138.320914) (xy 363.520675 -138.267892) (xy 363.543977 -138.217707)
			(xy 363.574279 -138.171411) (xy 363.610946 -138.129973) (xy 363.65321 -138.094262) (xy 363.676438 -138.079226)
			(xy 363.686103 -138.072575) (xy 363.698554 -138.052724) (xy 363.700314 -138.041126) (xy 363.708188 -137.961116)
			(xy 363.708791 -137.949479) (xy 363.700729 -137.927644) (xy 363.692694 -137.919206) (xy 363.69244 -137.918952)
			(xy 363.673861 -137.900869) (xy 363.641281 -137.860538) (xy 363.614466 -137.816165) (xy 363.593913 -137.768567)
			(xy 363.58 -137.718622) (xy 363.572983 -137.667253) (xy 363.572552 -137.64133) (xy 363.573106 -137.614081)
			(xy 363.580857 -137.560138) (xy 363.596207 -137.507847) (xy 363.618841 -137.458273) (xy 363.648301 -137.412424)
			(xy 363.683985 -137.371235) (xy 363.725168 -137.335543) (xy 363.771011 -137.306075) (xy 363.820582 -137.283431)
			(xy 363.87287 -137.268072) (xy 363.926811 -137.260311) (xy 363.95406 -137.259822) (xy 363.98143 -137.260306)
			(xy 364.035608 -137.268119) (xy 364.088111 -137.283603) (xy 364.137858 -137.306441) (xy 364.183826 -137.336162)
			(xy 364.204758 -137.353802) (xy 364.205012 -137.354056) (xy 364.212086 -137.35966) (xy 364.229013 -137.365895)
			(xy 364.238032 -137.366248) (xy 364.305088 -137.366248) (xy 364.314106 -137.365896) (xy 364.331023 -137.359646)
			(xy 364.338108 -137.354056) (xy 364.338108 -137.353802) (xy 364.338362 -137.353802) (xy 364.359298 -137.336168)
			(xy 364.40527 -137.306455) (xy 364.455016 -137.283618) (xy 364.507516 -137.268126) (xy 364.561691 -137.260297)
			(xy 364.58906 -137.259822) (xy 364.616313 -137.260293) (xy 364.670265 -137.268045) (xy 364.722565 -137.283397)
			(xy 364.772147 -137.306037) (xy 364.818002 -137.335504) (xy 364.859196 -137.371197) (xy 364.89489 -137.41239)
			(xy 364.924358 -137.458244) (xy 364.946999 -137.507826) (xy 364.962353 -137.560125) (xy 364.970107 -137.614077)
			(xy 364.970568 -137.64133) (xy 364.970012 -137.670246) (xy 364.961292 -137.727416) (xy 364.944043 -137.782614)
			(xy 364.918658 -137.834576) (xy 364.885721 -137.882111) (xy 364.845985 -137.924129) (xy 364.823502 -137.94232)
			(xy 364.814696 -137.949929) (xy 364.804512 -137.970828) (xy 364.803944 -137.982452) (xy 364.803944 -138.062208)
			(xy 364.804478 -138.073841) (xy 364.814669 -138.094751) (xy 364.823502 -138.10234) (xy 364.846005 -138.120508)
			(xy 364.885739 -138.162533) (xy 364.918676 -138.210072) (xy 364.944061 -138.262038) (xy 364.961312 -138.31724)
			(xy 364.970036 -138.374413) (xy 364.970568 -138.40333) (xy 364.970173 -138.430585) (xy 364.962411 -138.484541)
			(xy 364.950305 -138.525758) (xy 365.24184 -138.525758) (xy 365.24233 -138.498389) (xy 365.250141 -138.44421)
			(xy 365.265624 -138.391707) (xy 365.28846 -138.34196) (xy 365.318181 -138.295992) (xy 365.33582 -138.27506)
			(xy 365.336074 -138.274806) (xy 365.341673 -138.267728) (xy 365.34791 -138.250804) (xy 365.348266 -138.241786)
			(xy 365.348266 -138.17473) (xy 365.347902 -138.165714) (xy 365.34166 -138.148796) (xy 365.336074 -138.14171)
			(xy 365.33582 -138.14171) (xy 365.33582 -138.141456) (xy 365.318138 -138.120556) (xy 365.288416 -138.074583)
			(xy 365.265573 -138.024831) (xy 365.250081 -137.972324) (xy 365.242256 -137.918141) (xy 365.242261 -137.863396)
			(xy 365.250094 -137.809214) (xy 365.265596 -137.75671) (xy 365.288446 -137.706962) (xy 365.318177 -137.660993)
			(xy 365.33582 -137.64006) (xy 365.336074 -137.639806) (xy 365.341673 -137.632728) (xy 365.34791 -137.615804)
			(xy 365.348266 -137.606786) (xy 365.348266 -137.53973) (xy 365.347902 -137.530714) (xy 365.34166 -137.513796)
			(xy 365.336074 -137.50671) (xy 365.33582 -137.50671) (xy 365.33582 -137.506456) (xy 365.318138 -137.485556)
			(xy 365.288416 -137.439583) (xy 365.265573 -137.389831) (xy 365.250081 -137.337324) (xy 365.242256 -137.283141)
			(xy 365.242261 -137.228396) (xy 365.250094 -137.174214) (xy 365.265596 -137.12171) (xy 365.288446 -137.071962)
			(xy 365.318177 -137.025993) (xy 365.33582 -137.00506) (xy 365.336074 -137.004806) (xy 365.341673 -136.997728)
			(xy 365.34791 -136.980804) (xy 365.348266 -136.971786) (xy 365.348266 -136.90473) (xy 365.347902 -136.895714)
			(xy 365.34166 -136.878796) (xy 365.336074 -136.87171) (xy 365.33582 -136.87171) (xy 365.33582 -136.871456)
			(xy 365.318197 -136.850511) (xy 365.288482 -136.804542) (xy 365.265643 -136.754798) (xy 365.250148 -136.7023)
			(xy 365.242316 -136.648126) (xy 365.24184 -136.620758) (xy 365.242326 -136.593507) (xy 365.250082 -136.539559)
			(xy 365.265437 -136.487264) (xy 365.288079 -136.437687) (xy 365.317545 -136.391837) (xy 365.353236 -136.350646)
			(xy 365.394427 -136.314955) (xy 365.440277 -136.285489) (xy 365.489854 -136.262847) (xy 365.542149 -136.247492)
			(xy 365.596097 -136.239736) (xy 365.650599 -136.239736) (xy 365.704547 -136.247492) (xy 365.756842 -136.262847)
			(xy 365.806419 -136.285489) (xy 365.852269 -136.314955) (xy 365.89346 -136.350646) (xy 365.929151 -136.391837)
			(xy 365.958617 -136.437687) (xy 365.981259 -136.487264) (xy 365.996614 -136.539559) (xy 366.00437 -136.593507)
			(xy 366.004856 -136.620758) (xy 366.004376 -136.648128) (xy 365.996563 -136.702307) (xy 365.981078 -136.75481)
			(xy 365.958239 -136.804557) (xy 365.928517 -136.850524) (xy 365.910876 -136.871456) (xy 365.910622 -136.87171)
			(xy 365.905016 -136.878783) (xy 365.898783 -136.89571) (xy 365.89843 -136.90473) (xy 365.89843 -136.971786)
			(xy 365.898787 -136.980803) (xy 365.905034 -136.99772) (xy 365.910622 -137.004806) (xy 365.910876 -137.004806)
			(xy 365.910876 -137.00506) (xy 365.928475 -137.026026) (xy 365.958202 -137.071988) (xy 365.981049 -137.121729)
			(xy 365.996549 -137.174226) (xy 366.004381 -137.2284) (xy 366.004386 -137.283137) (xy 365.996562 -137.337312)
			(xy 365.981072 -137.389812) (xy 365.958232 -137.439556) (xy 365.928514 -137.485523) (xy 365.910876 -137.506456)
			(xy 365.910622 -137.50671) (xy 365.905016 -137.513783) (xy 365.898783 -137.53071) (xy 365.89843 -137.53973)
			(xy 365.89843 -137.606786) (xy 365.898787 -137.615803) (xy 365.905034 -137.63272) (xy 365.910622 -137.639806)
			(xy 365.910876 -137.639806) (xy 365.910876 -137.64006) (xy 365.928475 -137.661026) (xy 365.958202 -137.706988)
			(xy 365.981049 -137.756729) (xy 365.996549 -137.809226) (xy 366.004381 -137.8634) (xy 366.004386 -137.918137)
			(xy 365.996562 -137.972312) (xy 365.981072 -138.024812) (xy 365.958232 -138.074556) (xy 365.928514 -138.120523)
			(xy 365.910876 -138.141456) (xy 365.910622 -138.14171) (xy 365.905016 -138.148783) (xy 365.898783 -138.16571)
			(xy 365.89843 -138.17473) (xy 365.89843 -138.241786) (xy 365.898787 -138.250803) (xy 365.905034 -138.26772)
			(xy 365.910622 -138.274806) (xy 365.910876 -138.274806) (xy 365.910876 -138.27506) (xy 365.928506 -138.295999)
			(xy 365.95822 -138.34197) (xy 365.981058 -138.391715) (xy 365.996551 -138.444215) (xy 366.004381 -138.498389)
			(xy 366.004856 -138.525758) (xy 366.004277 -138.554944) (xy 365.995383 -138.612636) (xy 365.977812 -138.668301)
			(xy 365.951974 -138.720644) (xy 365.918469 -138.768444) (xy 365.87808 -138.810588) (xy 365.85525 -138.82878)
			(xy 365.846159 -138.836456) (xy 365.835688 -138.857787) (xy 365.835184 -138.869674) (xy 365.835946 -138.950954)
			(xy 365.836649 -138.962668) (xy 365.847243 -138.983581) (xy 365.856266 -138.991086) (xy 365.856774 -138.991594)
			(xy 365.88065 -139.010644) (xy 365.880904 -139.010898) (xy 365.887985 -139.016492) (xy 365.904906 -139.022734)
			(xy 365.913924 -139.02309) (xy 365.98098 -139.02309) (xy 365.989996 -139.022726) (xy 366.006913 -139.016484)
			(xy 366.014 -139.010898) (xy 366.014 -139.010644) (xy 366.014254 -139.010644) (xy 366.035187 -138.993003)
			(xy 366.081155 -138.963279) (xy 366.130901 -138.940433) (xy 366.183403 -138.924937) (xy 366.237581 -138.917108)
			(xy 366.292323 -138.917108) (xy 366.346501 -138.924937) (xy 366.399003 -138.940433) (xy 366.448749 -138.963279)
			(xy 366.494717 -138.993003) (xy 366.51565 -139.010644) (xy 366.515904 -139.010898) (xy 366.522985 -139.016492)
			(xy 366.539906 -139.022734) (xy 366.548924 -139.02309) (xy 366.61598 -139.02309) (xy 366.624996 -139.022726)
			(xy 366.641913 -139.016484) (xy 366.649 -139.010898) (xy 366.649 -139.010644) (xy 366.649254 -139.010644)
			(xy 366.670187 -138.993003) (xy 366.716155 -138.963279) (xy 366.765901 -138.940433) (xy 366.818403 -138.924937)
			(xy 366.872581 -138.917108) (xy 366.927323 -138.917108) (xy 366.981501 -138.924937) (xy 367.034003 -138.940433)
			(xy 367.083749 -138.963279) (xy 367.129717 -138.993003) (xy 367.15065 -139.010644) (xy 367.150904 -139.010898)
			(xy 367.157985 -139.016492) (xy 367.174906 -139.022734) (xy 367.183924 -139.02309) (xy 367.25098 -139.02309)
			(xy 367.259996 -139.022726) (xy 367.276913 -139.016484) (xy 367.284 -139.010898) (xy 367.284 -139.010644)
			(xy 367.284254 -139.010644) (xy 367.305198 -138.99302) (xy 367.351167 -138.963304) (xy 367.400911 -138.940465)
			(xy 367.45341 -138.92497) (xy 367.507584 -138.917139) (xy 367.534952 -138.916664) (xy 367.562205 -138.91718)
			(xy 367.616157 -138.924931) (xy 367.668457 -138.940282) (xy 367.71804 -138.96292) (xy 367.763895 -138.992384)
			(xy 367.805091 -139.028075) (xy 367.840787 -139.069266) (xy 367.870257 -139.115118) (xy 367.892902 -139.164698)
			(xy 367.908259 -139.216996) (xy 367.916017 -139.270947) (xy 367.916017 -139.325453) (xy 367.908259 -139.379404)
			(xy 367.892902 -139.431702) (xy 367.870257 -139.481282) (xy 367.840787 -139.527134) (xy 367.805091 -139.568325)
			(xy 367.763895 -139.604016) (xy 367.71804 -139.63348) (xy 367.668457 -139.656118) (xy 367.616157 -139.671469)
			(xy 367.562205 -139.67922) (xy 367.534952 -139.67968) (xy 367.507583 -139.679188) (xy 367.453404 -139.671377)
			(xy 367.400901 -139.655895) (xy 367.351154 -139.633058) (xy 367.305186 -139.603339) (xy 367.284254 -139.5857)
			(xy 367.284 -139.585446) (xy 367.276922 -139.579847) (xy 367.259999 -139.573609) (xy 367.25098 -139.573254)
			(xy 367.183924 -139.573254) (xy 367.174907 -139.573611) (xy 367.157989 -139.579857) (xy 367.150904 -139.585446)
			(xy 367.150904 -139.5857) (xy 367.15065 -139.5857) (xy 367.129717 -139.603341) (xy 367.083749 -139.633065)
			(xy 367.034003 -139.655911) (xy 366.981501 -139.671407) (xy 366.927323 -139.679236) (xy 366.872581 -139.679236)
			(xy 366.818403 -139.671407) (xy 366.765901 -139.655911) (xy 366.716155 -139.633065) (xy 366.670187 -139.603341)
			(xy 366.649254 -139.5857) (xy 366.649 -139.585446) (xy 366.641922 -139.579847) (xy 366.624999 -139.573609)
			(xy 366.61598 -139.573254) (xy 366.548924 -139.573254) (xy 366.539907 -139.573611) (xy 366.522989 -139.579857)
			(xy 366.515904 -139.585446) (xy 366.515904 -139.5857) (xy 366.51565 -139.5857) (xy 366.494717 -139.603341)
			(xy 366.448749 -139.633065) (xy 366.399003 -139.655911) (xy 366.346501 -139.671407) (xy 366.292323 -139.679236)
			(xy 366.237581 -139.679236) (xy 366.183403 -139.671407) (xy 366.130901 -139.655911) (xy 366.081155 -139.633065)
			(xy 366.035187 -139.603341) (xy 366.014254 -139.5857) (xy 366.014 -139.585446) (xy 366.006922 -139.579847)
			(xy 365.989999 -139.573609) (xy 365.98098 -139.573254) (xy 365.913924 -139.573254) (xy 365.904907 -139.573611)
			(xy 365.887989 -139.579857) (xy 365.880904 -139.585446) (xy 365.880904 -139.5857) (xy 365.88065 -139.5857)
			(xy 365.85971 -139.603329) (xy 365.813739 -139.633042) (xy 365.763994 -139.65588) (xy 365.711495 -139.671374)
			(xy 365.657321 -139.679205) (xy 365.629952 -139.67968) (xy 365.602698 -139.679267) (xy 365.548747 -139.671503)
			(xy 365.496449 -139.65614) (xy 365.446869 -139.633492) (xy 365.401018 -139.604018) (xy 365.359828 -139.568319)
			(xy 365.324137 -139.527121) (xy 365.294672 -139.481264) (xy 365.272033 -139.43168) (xy 365.256681 -139.379379)
			(xy 365.248928 -139.325426) (xy 365.248444 -139.298172) (xy 365.248973 -139.268984) (xy 365.257877 -139.21129)
			(xy 365.275458 -139.155623) (xy 365.301306 -139.103281) (xy 365.334819 -139.055482) (xy 365.375216 -139.013341)
			(xy 365.39805 -138.99515) (xy 365.407128 -138.98746) (xy 365.417605 -138.96614) (xy 365.418116 -138.954256)
			(xy 365.417354 -138.872976) (xy 365.416635 -138.861264) (xy 365.406052 -138.840351) (xy 365.397034 -138.832844)
			(xy 365.397034 -138.83259) (xy 365.396526 -138.83259) (xy 365.372936 -138.814499) (xy 365.331183 -138.772183)
			(xy 365.296507 -138.723897) (xy 365.269751 -138.670812) (xy 365.251562 -138.614216) (xy 365.242384 -138.555482)
			(xy 365.24184 -138.525758) (xy 364.950305 -138.525758) (xy 364.947049 -138.536843) (xy 364.9244 -138.586426)
			(xy 364.894925 -138.63228) (xy 364.859224 -138.673474) (xy 364.818024 -138.709167) (xy 364.772164 -138.738634)
			(xy 364.722577 -138.761273) (xy 364.670272 -138.776626) (xy 364.616316 -138.784378) (xy 364.58906 -138.784838)
			(xy 364.562744 -138.784417) (xy 364.510613 -138.777175) (xy 364.459969 -138.762849) (xy 364.411769 -138.741708)
			(xy 364.366927 -138.714152) (xy 364.32629 -138.680704) (xy 364.308136 -138.661648) (xy 364.300596 -138.654267)
			(xy 364.28133 -138.645729) (xy 364.270798 -138.645138) (xy 364.196122 -138.645138) (xy 364.18557 -138.645654)
			(xy 364.166274 -138.654197) (xy 364.158784 -138.661648) (xy 364.140639 -138.680713) (xy 364.100006 -138.714168)
			(xy 364.055163 -138.741724) (xy 364.00696 -138.762861) (xy 363.956312 -138.777176) (xy 363.904177 -138.7844)
			(xy 363.87786 -138.784838) (xy 363.850609 -138.784359) (xy 363.796663 -138.776598) (xy 363.74437 -138.76124)
			(xy 363.694794 -138.738596) (xy 363.648946 -138.709128) (xy 363.607757 -138.673436) (xy 363.572066 -138.632246)
			(xy 363.542599 -138.586397) (xy 363.519957 -138.536821) (xy 363.5046 -138.484527) (xy 363.49684 -138.430581)
			(xy 363.496352 -138.40333) (xy 356.201472 -138.40333) (xy 356.201472 -138.824462) (xy 356.661972 -138.824462)
			(xy 356.666043 -138.76884) (xy 356.678169 -138.714403) (xy 356.698092 -138.662312) (xy 356.725388 -138.613677)
			(xy 356.759474 -138.569534) (xy 356.799623 -138.530825) (xy 356.844981 -138.498374) (xy 356.894581 -138.472873)
			(xy 356.947365 -138.454866) (xy 357.002208 -138.444736) (xy 357.057942 -138.442699) (xy 357.113379 -138.448799)
			(xy 357.167336 -138.462905) (xy 357.218665 -138.484717) (xy 357.266271 -138.513771) (xy 357.309139 -138.549446)
			(xy 357.346356 -138.590983) (xy 357.377129 -138.637496) (xy 357.400801 -138.687993) (xy 357.416869 -138.7414)
			(xy 357.424989 -138.796576) (xy 357.425498 -138.824462) (xy 357.424989 -138.852348) (xy 357.416869 -138.907524)
			(xy 357.400801 -138.960931) (xy 357.377129 -139.011428) (xy 357.346356 -139.057941) (xy 357.309139 -139.099478)
			(xy 357.266271 -139.135153) (xy 357.218665 -139.164207) (xy 357.167336 -139.186019) (xy 357.113379 -139.200125)
			(xy 357.057942 -139.206225) (xy 357.002208 -139.204188) (xy 356.947365 -139.194058) (xy 356.894581 -139.176051)
			(xy 356.844981 -139.15055) (xy 356.799623 -139.118099) (xy 356.759474 -139.07939) (xy 356.725388 -139.035247)
			(xy 356.698092 -138.986612) (xy 356.678169 -138.934521) (xy 356.666043 -138.880084) (xy 356.661972 -138.824462)
			(xy 356.201472 -138.824462) (xy 356.201472 -140.392404) (xy 356.667814 -140.392404) (xy 356.671885 -140.336782)
			(xy 356.684011 -140.282345) (xy 356.703934 -140.230254) (xy 356.73123 -140.181619) (xy 356.765316 -140.137476)
			(xy 356.805465 -140.098767) (xy 356.850823 -140.066316) (xy 356.900423 -140.040815) (xy 356.953207 -140.022808)
			(xy 357.00805 -140.012678) (xy 357.063784 -140.010641) (xy 357.119221 -140.016741) (xy 357.173178 -140.030847)
			(xy 357.224507 -140.052659) (xy 357.272113 -140.081713) (xy 357.314981 -140.117388) (xy 357.352198 -140.158925)
			(xy 357.382971 -140.205438) (xy 357.406643 -140.255935) (xy 357.422711 -140.309342) (xy 357.430831 -140.364518)
			(xy 357.43134 -140.392404) (xy 357.430831 -140.42029) (xy 357.422711 -140.475466) (xy 357.406643 -140.528873)
			(xy 357.382971 -140.57937) (xy 357.352198 -140.625883) (xy 357.314981 -140.66742) (xy 357.272113 -140.703095)
			(xy 357.224507 -140.732149) (xy 357.173178 -140.753961) (xy 357.119221 -140.768067) (xy 357.063784 -140.774167)
			(xy 357.00805 -140.77213) (xy 356.953207 -140.762) (xy 356.900423 -140.743993) (xy 356.850823 -140.718492)
			(xy 356.805465 -140.686041) (xy 356.765316 -140.647332) (xy 356.73123 -140.603189) (xy 356.703934 -140.554554)
			(xy 356.684011 -140.502463) (xy 356.671885 -140.448026) (xy 356.667814 -140.392404) (xy 356.201472 -140.392404)
			(xy 356.201472 -141.046551) (xy 359.055154 -141.046551) (xy 359.055154 -140.992049) (xy 359.06291 -140.938101)
			(xy 359.078264 -140.885806) (xy 359.100904 -140.836228) (xy 359.130368 -140.790377) (xy 359.166058 -140.749185)
			(xy 359.207246 -140.713491) (xy 359.253095 -140.684022) (xy 359.30267 -140.661377) (xy 359.354964 -140.646018)
			(xy 359.408911 -140.638256) (xy 359.436162 -140.637768) (xy 359.462477 -140.638204) (xy 359.514606 -140.645447)
			(xy 359.565249 -140.659773) (xy 359.613448 -140.680911) (xy 359.658291 -140.708462) (xy 359.69893 -140.741905)
			(xy 359.717086 -140.760958) (xy 359.724617 -140.768349) (xy 359.74389 -140.776881) (xy 359.754424 -140.777468)
			(xy 359.8291 -140.777468) (xy 359.839653 -140.776962) (xy 359.858948 -140.768412) (xy 359.866438 -140.760958)
			(xy 359.884574 -140.741883) (xy 359.925209 -140.708429) (xy 359.970053 -140.680874) (xy 360.018258 -140.659739)
			(xy 360.068908 -140.645426) (xy 360.121045 -140.638205) (xy 360.147362 -140.637768) (xy 360.174615 -140.638277)
			(xy 360.228567 -140.646029) (xy 360.280866 -140.661381) (xy 360.330447 -140.684019) (xy 360.376302 -140.713485)
			(xy 360.417497 -140.749176) (xy 360.453193 -140.790367) (xy 360.482662 -140.836219) (xy 360.505306 -140.885799)
			(xy 360.520663 -140.938096) (xy 360.528421 -140.992047) (xy 360.528421 -141.046553) (xy 360.520663 -141.100504)
			(xy 360.505306 -141.152801) (xy 360.482662 -141.202381) (xy 360.453193 -141.248233) (xy 360.417497 -141.289424)
			(xy 360.376302 -141.325115) (xy 360.330447 -141.354581) (xy 360.280866 -141.377219) (xy 360.228567 -141.392571)
			(xy 360.174615 -141.400323) (xy 360.147362 -141.400784) (xy 360.121047 -141.400347) (xy 360.068917 -141.393107)
			(xy 360.018273 -141.378782) (xy 359.970074 -141.357644) (xy 359.925232 -141.330092) (xy 359.884594 -141.296648)
			(xy 359.866438 -141.277594) (xy 359.858905 -141.270206) (xy 359.839634 -141.261674) (xy 359.8291 -141.261084)
			(xy 359.754424 -141.261084) (xy 359.743875 -141.261618) (xy 359.72458 -141.27015) (xy 359.717086 -141.277594)
			(xy 359.698929 -141.296648) (xy 359.6583 -141.330106) (xy 359.61346 -141.357665) (xy 359.565259 -141.378804)
			(xy 359.514612 -141.393121) (xy 359.462478 -141.400346) (xy 359.436162 -141.400784) (xy 359.408911 -141.400344)
			(xy 359.354964 -141.392582) (xy 359.30267 -141.377223) (xy 359.253095 -141.354578) (xy 359.207246 -141.325109)
			(xy 359.166058 -141.289415) (xy 359.130368 -141.248223) (xy 359.100904 -141.202372) (xy 359.078264 -141.152794)
			(xy 359.06291 -141.100499) (xy 359.055154 -141.046551) (xy 356.201472 -141.046551) (xy 356.201472 -143.078551)
			(xy 359.055154 -143.078551) (xy 359.055154 -143.024049) (xy 359.06291 -142.970101) (xy 359.078264 -142.917806)
			(xy 359.100904 -142.868228) (xy 359.130368 -142.822377) (xy 359.166058 -142.781185) (xy 359.207246 -142.745491)
			(xy 359.253095 -142.716022) (xy 359.30267 -142.693377) (xy 359.354964 -142.678018) (xy 359.408911 -142.670256)
			(xy 359.436162 -142.669768) (xy 359.462477 -142.670204) (xy 359.514606 -142.677447) (xy 359.565249 -142.691773)
			(xy 359.613448 -142.712911) (xy 359.658291 -142.740462) (xy 359.69893 -142.773905) (xy 359.717086 -142.792958)
			(xy 359.724617 -142.800349) (xy 359.74389 -142.808881) (xy 359.754424 -142.809468) (xy 359.8291 -142.809468)
			(xy 359.839653 -142.808962) (xy 359.858948 -142.800412) (xy 359.866438 -142.792958) (xy 359.884574 -142.773883)
			(xy 359.925209 -142.740429) (xy 359.970053 -142.712874) (xy 360.018258 -142.691739) (xy 360.068908 -142.677426)
			(xy 360.121045 -142.670205) (xy 360.147362 -142.669768) (xy 360.174615 -142.670277) (xy 360.228567 -142.678029)
			(xy 360.280866 -142.693381) (xy 360.330447 -142.716019) (xy 360.376302 -142.745485) (xy 360.417497 -142.781176)
			(xy 360.453193 -142.822367) (xy 360.482662 -142.868219) (xy 360.505306 -142.917799) (xy 360.520663 -142.970096)
			(xy 360.528421 -143.024047) (xy 360.528421 -143.078553) (xy 360.520663 -143.132504) (xy 360.505306 -143.184801)
			(xy 360.482662 -143.234381) (xy 360.453193 -143.280233) (xy 360.417497 -143.321424) (xy 360.376302 -143.357115)
			(xy 360.330447 -143.386581) (xy 360.280866 -143.409219) (xy 360.228567 -143.424571) (xy 360.174615 -143.432323)
			(xy 360.147362 -143.432784) (xy 360.121047 -143.432347) (xy 360.068917 -143.425107) (xy 360.018273 -143.410782)
			(xy 359.970074 -143.389644) (xy 359.925232 -143.362092) (xy 359.884594 -143.328648) (xy 359.866438 -143.309594)
			(xy 359.858905 -143.302206) (xy 359.839634 -143.293674) (xy 359.8291 -143.293084) (xy 359.754424 -143.293084)
			(xy 359.743875 -143.293618) (xy 359.72458 -143.30215) (xy 359.717086 -143.309594) (xy 359.698929 -143.328648)
			(xy 359.6583 -143.362106) (xy 359.61346 -143.389665) (xy 359.565259 -143.410804) (xy 359.514612 -143.425121)
			(xy 359.462478 -143.432346) (xy 359.436162 -143.432784) (xy 359.408911 -143.432344) (xy 359.354964 -143.424582)
			(xy 359.30267 -143.409223) (xy 359.253095 -143.386578) (xy 359.207246 -143.357109) (xy 359.166058 -143.321415)
			(xy 359.130368 -143.280223) (xy 359.100904 -143.234372) (xy 359.078264 -143.184794) (xy 359.06291 -143.132499)
			(xy 359.055154 -143.078551) (xy 356.201472 -143.078551) (xy 356.201472 -143.966438) (xy 367.764314 -143.966438)
			(xy 367.764725 -143.940462) (xy 367.771775 -143.88899) (xy 367.785751 -143.838952) (xy 367.806392 -143.791277)
			(xy 367.833317 -143.746846) (xy 367.866026 -143.706483) (xy 367.903914 -143.670936) (xy 367.924842 -143.655542)
			(xy 367.934333 -143.64791) (xy 367.945478 -143.626298) (xy 367.946178 -143.61414) (xy 367.946178 -143.531336)
			(xy 367.945487 -143.519174) (xy 367.934347 -143.497553) (xy 367.924842 -143.489934) (xy 367.903923 -143.474532)
			(xy 367.866046 -143.438979) (xy 367.833346 -143.398614) (xy 367.806428 -143.354184) (xy 367.785789 -143.306512)
			(xy 367.771812 -143.256479) (xy 367.764756 -143.205012) (xy 367.764314 -143.179038) (xy 367.764823 -143.150299)
			(xy 367.773453 -143.093472) (xy 367.790508 -143.038582) (xy 367.815602 -142.98687) (xy 367.848168 -142.939508)
			(xy 367.867438 -142.91818) (xy 367.874042 -142.911322) (xy 367.881154 -142.893288) (xy 367.881154 -142.804388)
			(xy 367.874042 -142.786354) (xy 367.867438 -142.779496) (xy 367.848204 -142.758137) (xy 367.815637 -142.71078)
			(xy 367.790542 -142.659074) (xy 367.773488 -142.604188) (xy 367.764862 -142.547365) (xy 367.764858 -142.489891)
			(xy 367.773476 -142.433066) (xy 367.790522 -142.378178) (xy 367.815609 -142.326468) (xy 367.848169 -142.279106)
			(xy 367.867438 -142.25778) (xy 367.874042 -142.250922) (xy 367.881154 -142.232888) (xy 367.881154 -142.143988)
			(xy 367.874042 -142.125954) (xy 367.867438 -142.119096) (xy 367.848204 -142.097737) (xy 367.815637 -142.05038)
			(xy 367.790542 -141.998674) (xy 367.773488 -141.943788) (xy 367.764862 -141.886965) (xy 367.764858 -141.829491)
			(xy 367.773476 -141.772666) (xy 367.790522 -141.717778) (xy 367.815609 -141.666068) (xy 367.848169 -141.618706)
			(xy 367.867438 -141.59738) (xy 367.874042 -141.590522) (xy 367.881154 -141.572488) (xy 367.881154 -141.483588)
			(xy 367.874042 -141.465554) (xy 367.867438 -141.458696) (xy 367.848204 -141.437337) (xy 367.815637 -141.38998)
			(xy 367.790542 -141.338274) (xy 367.773488 -141.283388) (xy 367.764862 -141.226565) (xy 367.764858 -141.169091)
			(xy 367.773476 -141.112266) (xy 367.790522 -141.057378) (xy 367.815609 -141.005668) (xy 367.848169 -140.958306)
			(xy 367.867438 -140.93698) (xy 367.874042 -140.930122) (xy 367.881154 -140.912088) (xy 367.881154 -140.823188)
			(xy 367.874042 -140.805154) (xy 367.867438 -140.798296) (xy 367.848185 -140.776953) (xy 367.815617 -140.729596)
			(xy 367.790521 -140.677888) (xy 367.773466 -140.623001) (xy 367.764838 -140.566176) (xy 367.764314 -140.537438)
			(xy 367.7648 -140.510187) (xy 367.772556 -140.456239) (xy 367.787911 -140.403944) (xy 367.810553 -140.354367)
			(xy 367.840019 -140.308517) (xy 367.87571 -140.267326) (xy 367.916901 -140.231635) (xy 367.962751 -140.202169)
			(xy 368.012328 -140.179527) (xy 368.064623 -140.164172) (xy 368.118571 -140.156416) (xy 368.173073 -140.156416)
			(xy 368.227021 -140.164172) (xy 368.279316 -140.179527) (xy 368.328893 -140.202169) (xy 368.374743 -140.231635)
			(xy 368.415934 -140.267326) (xy 368.451625 -140.308517) (xy 368.481091 -140.354367) (xy 368.503733 -140.403944)
			(xy 368.519088 -140.456239) (xy 368.526844 -140.510187) (xy 368.52733 -140.537438) (xy 368.526821 -140.566177)
			(xy 368.518194 -140.623005) (xy 368.50114 -140.677896) (xy 368.476045 -140.729607) (xy 368.443478 -140.776969)
			(xy 368.424206 -140.798296) (xy 368.417602 -140.805154) (xy 368.41049 -140.823188) (xy 368.41049 -140.912088)
			(xy 368.417602 -140.930122) (xy 368.424206 -140.93698) (xy 368.443513 -140.958275) (xy 368.476075 -141.005644)
			(xy 368.501162 -141.057361) (xy 368.518208 -141.112256) (xy 368.526826 -141.169087) (xy 368.526822 -141.226568)
			(xy 368.518195 -141.283398) (xy 368.501142 -141.338291) (xy 368.476047 -141.390004) (xy 368.443478 -141.437368)
			(xy 368.424206 -141.458696) (xy 368.417602 -141.465554) (xy 368.41049 -141.483588) (xy 368.41049 -141.572488)
			(xy 368.417602 -141.590522) (xy 368.424206 -141.59738) (xy 368.443513 -141.618675) (xy 368.476075 -141.666044)
			(xy 368.501162 -141.717761) (xy 368.518208 -141.772656) (xy 368.526826 -141.829487) (xy 368.526822 -141.886968)
			(xy 368.518195 -141.943798) (xy 368.501142 -141.998691) (xy 368.476047 -142.050404) (xy 368.443478 -142.097768)
			(xy 368.424206 -142.119096) (xy 368.417602 -142.125954) (xy 368.41049 -142.143988) (xy 368.41049 -142.232888)
			(xy 368.417602 -142.250922) (xy 368.424206 -142.25778) (xy 368.443513 -142.279075) (xy 368.476075 -142.326444)
			(xy 368.501162 -142.378161) (xy 368.518208 -142.433056) (xy 368.526826 -142.489887) (xy 368.526822 -142.547368)
			(xy 368.518195 -142.604198) (xy 368.501142 -142.659091) (xy 368.476047 -142.710804) (xy 368.443478 -142.758168)
			(xy 368.424206 -142.779496) (xy 368.417602 -142.786354) (xy 368.41049 -142.804388) (xy 368.41049 -142.893288)
			(xy 368.417602 -142.911322) (xy 368.424206 -142.91818) (xy 368.443485 -142.9395) (xy 368.476052 -142.986863)
			(xy 368.501144 -143.038576) (xy 368.518192 -143.093469) (xy 368.526811 -143.150298) (xy 368.52733 -143.179038)
			(xy 368.526925 -143.205015) (xy 368.519876 -143.256488) (xy 368.505902 -143.306526) (xy 368.48526 -143.354203)
			(xy 368.458334 -143.398634) (xy 368.425622 -143.438996) (xy 368.387731 -143.474541) (xy 368.366802 -143.489934)
			(xy 368.35733 -143.497587) (xy 368.346173 -143.519183) (xy 368.345466 -143.531336) (xy 368.345466 -143.61414)
			(xy 368.346155 -143.626303) (xy 368.357295 -143.647925) (xy 368.366802 -143.655542) (xy 368.38772 -143.670946)
			(xy 368.425594 -143.7065) (xy 368.458293 -143.746865) (xy 368.485211 -143.791295) (xy 368.50585 -143.838967)
			(xy 368.519828 -143.888998) (xy 368.526887 -143.940464) (xy 368.52733 -143.966438) (xy 368.526844 -143.993689)
			(xy 368.519088 -144.047637) (xy 368.503733 -144.099932) (xy 368.481091 -144.149509) (xy 368.451625 -144.195359)
			(xy 368.415934 -144.23655) (xy 368.374743 -144.272241) (xy 368.328893 -144.301707) (xy 368.279316 -144.324349)
			(xy 368.227021 -144.339704) (xy 368.173073 -144.34746) (xy 368.118571 -144.34746) (xy 368.064623 -144.339704)
			(xy 368.012328 -144.324349) (xy 367.962751 -144.301707) (xy 367.916901 -144.272241) (xy 367.87571 -144.23655)
			(xy 367.840019 -144.195359) (xy 367.810553 -144.149509) (xy 367.787911 -144.099932) (xy 367.772556 -144.047637)
			(xy 367.7648 -143.993689) (xy 367.764314 -143.966438) (xy 356.201472 -143.966438) (xy 356.201472 -144.40281)
			(xy 356.20094 -144.428832) (xy 356.192766 -144.480231) (xy 356.176665 -144.529723) (xy 356.153035 -144.576094)
			(xy 356.122453 -144.618206) (xy 356.104444 -144.636998) (xy 355.630891 -145.110551) (xy 359.055154 -145.110551)
			(xy 359.055154 -145.056049) (xy 359.06291 -145.002101) (xy 359.078264 -144.949806) (xy 359.100904 -144.900228)
			(xy 359.130368 -144.854377) (xy 359.166058 -144.813185) (xy 359.207246 -144.777491) (xy 359.253095 -144.748022)
			(xy 359.30267 -144.725377) (xy 359.354964 -144.710018) (xy 359.408911 -144.702256) (xy 359.436162 -144.701768)
			(xy 359.462477 -144.702204) (xy 359.514606 -144.709447) (xy 359.565249 -144.723773) (xy 359.613448 -144.744911)
			(xy 359.658291 -144.772462) (xy 359.69893 -144.805905) (xy 359.717086 -144.824958) (xy 359.724617 -144.832349)
			(xy 359.74389 -144.840881) (xy 359.754424 -144.841468) (xy 359.8291 -144.841468) (xy 359.839653 -144.840962)
			(xy 359.858948 -144.832412) (xy 359.866438 -144.824958) (xy 359.884574 -144.805883) (xy 359.925209 -144.772429)
			(xy 359.970053 -144.744874) (xy 360.018258 -144.723739) (xy 360.068908 -144.709426) (xy 360.121045 -144.702205)
			(xy 360.147362 -144.701768) (xy 360.174615 -144.702277) (xy 360.228567 -144.710029) (xy 360.280866 -144.725381)
			(xy 360.330447 -144.748019) (xy 360.376302 -144.777485) (xy 360.417497 -144.813176) (xy 360.453193 -144.854367)
			(xy 360.482662 -144.900219) (xy 360.505306 -144.949799) (xy 360.506611 -144.954244) (xy 366.239044 -144.954244)
			(xy 366.239619 -144.926996) (xy 366.247368 -144.873054) (xy 366.262715 -144.820764) (xy 366.285348 -144.77119)
			(xy 366.314805 -144.725342) (xy 366.350487 -144.684152) (xy 366.391668 -144.64846) (xy 366.437509 -144.618992)
			(xy 366.487078 -144.596348) (xy 366.539364 -144.580988) (xy 366.593304 -144.573226) (xy 366.620552 -144.572736)
			(xy 366.649326 -144.573259) (xy 366.706221 -144.581909) (xy 366.761172 -144.599005) (xy 366.812932 -144.624159)
			(xy 366.860328 -144.656801) (xy 366.881664 -144.676114) (xy 366.889538 -144.68348) (xy 366.90935 -144.690592)
			(xy 367.005616 -144.683226) (xy 367.024412 -144.67332) (xy 367.031016 -144.664938) (xy 367.049197 -144.642716)
			(xy 367.091141 -144.603508) (xy 367.138486 -144.571026) (xy 367.190162 -144.546004) (xy 367.245004 -144.529006)
			(xy 367.301774 -144.520416) (xy 367.330482 -144.519904) (xy 367.357735 -144.520372) (xy 367.411686 -144.528127)
			(xy 367.463985 -144.543481) (xy 367.513566 -144.566123) (xy 367.559419 -144.59559) (xy 367.600613 -144.631283)
			(xy 367.636307 -144.672476) (xy 367.665775 -144.718329) (xy 367.688417 -144.76791) (xy 367.703772 -144.820208)
			(xy 367.711527 -144.874159) (xy 367.71199 -144.901412) (xy 367.711543 -144.928315) (xy 367.703969 -144.981586)
			(xy 367.688988 -145.033265) (xy 367.666895 -145.082327) (xy 367.63813 -145.127799) (xy 367.603263 -145.16878)
			(xy 367.562985 -145.204457) (xy 367.540794 -145.219674) (xy 367.529872 -145.226786) (xy 367.517934 -145.249646)
			(xy 367.519966 -145.361914) (xy 367.53292 -145.384266) (xy 367.544096 -145.391124) (xy 367.567696 -145.406048)
			(xy 367.610649 -145.441726) (xy 367.647942 -145.483283) (xy 367.67878 -145.529833) (xy 367.702504 -145.58038)
			(xy 367.718606 -145.633846) (xy 367.726744 -145.689087) (xy 367.72723 -145.717006) (xy 367.726776 -145.744)
			(xy 367.719169 -145.797448) (xy 367.704107 -145.849292) (xy 367.681891 -145.898496) (xy 367.652965 -145.94408)
			(xy 367.63579 -145.96491) (xy 367.628678 -145.973038) (xy 367.622582 -145.993612) (xy 367.633504 -146.078956)
			(xy 367.635295 -146.089496) (xy 367.646338 -146.107781) (xy 367.65484 -146.114262) (xy 367.676045 -146.12965)
			(xy 367.714499 -146.165231) (xy 367.74772 -146.205741) (xy 367.775082 -146.250419) (xy 367.79607 -146.298421)
			(xy 367.810288 -146.348845) (xy 367.817469 -146.400741) (xy 367.817908 -146.426936) (xy 367.817422 -146.454187)
			(xy 367.809666 -146.508135) (xy 367.794311 -146.56043) (xy 367.771669 -146.610007) (xy 367.742203 -146.655857)
			(xy 367.706512 -146.697048) (xy 367.665321 -146.732739) (xy 367.619471 -146.762205) (xy 367.569894 -146.784847)
			(xy 367.517599 -146.800202) (xy 367.463651 -146.807958) (xy 367.409149 -146.807958) (xy 367.355201 -146.800202)
			(xy 367.302906 -146.784847) (xy 367.253329 -146.762205) (xy 367.207479 -146.732739) (xy 367.166288 -146.697048)
			(xy 367.130597 -146.655857) (xy 367.101131 -146.610007) (xy 367.078489 -146.56043) (xy 367.063134 -146.508135)
			(xy 367.055378 -146.454187) (xy 367.054892 -146.426936) (xy 367.055365 -146.399943) (xy 367.062967 -146.346495)
			(xy 367.078024 -146.294651) (xy 367.100235 -146.245447) (xy 367.129158 -146.199862) (xy 367.146332 -146.179032)
			(xy 367.153444 -146.170904) (xy 367.15954 -146.15033) (xy 367.148618 -146.064986) (xy 367.146848 -146.054441)
			(xy 367.135789 -146.036159) (xy 367.127282 -146.02968) (xy 367.102981 -146.012068) (xy 367.059722 -145.970472)
			(xy 367.041176 -145.946876) (xy 367.035334 -145.939002) (xy 367.017808 -145.928588) (xy 366.927384 -145.91538)
			(xy 366.90808 -145.920206) (xy 366.900206 -145.926048) (xy 366.899952 -145.926048) (xy 366.87521 -145.943554)
			(xy 366.821357 -145.971357) (xy 366.763784 -145.990292) (xy 366.703941 -145.999884) (xy 366.673638 -146.00047)
			(xy 366.646384 -146.000009) (xy 366.592431 -145.992256) (xy 366.540131 -145.976903) (xy 366.490549 -145.954262)
			(xy 366.444693 -145.924795) (xy 366.403499 -145.889101) (xy 366.367805 -145.847907) (xy 366.338338 -145.802051)
			(xy 366.315697 -145.752469) (xy 366.300344 -145.700169) (xy 366.292591 -145.646216) (xy 366.29213 -145.618962)
			(xy 366.292566 -145.592928) (xy 366.299657 -145.541345) (xy 366.31369 -145.491203) (xy 366.334403 -145.443433)
			(xy 366.361413 -145.398918) (xy 366.377474 -145.378424) (xy 366.383214 -145.370666) (xy 366.388956 -145.352256)
			(xy 366.38865 -145.34261) (xy 366.3823 -145.262854) (xy 366.373664 -145.245074) (xy 366.366298 -145.238724)
			(xy 366.346658 -145.220536) (xy 366.312132 -145.179632) (xy 366.28366 -145.134305) (xy 366.261801 -145.085445)
			(xy 366.246983 -145.034009) (xy 366.239498 -144.981008) (xy 366.239044 -144.954244) (xy 360.506611 -144.954244)
			(xy 360.520663 -145.002096) (xy 360.528421 -145.056047) (xy 360.528421 -145.110553) (xy 360.520663 -145.164504)
			(xy 360.505306 -145.216801) (xy 360.482662 -145.266381) (xy 360.453193 -145.312233) (xy 360.417497 -145.353424)
			(xy 360.376302 -145.389115) (xy 360.330447 -145.418581) (xy 360.280866 -145.441219) (xy 360.228567 -145.456571)
			(xy 360.174615 -145.464323) (xy 360.147362 -145.464784) (xy 360.121047 -145.464347) (xy 360.068917 -145.457107)
			(xy 360.018273 -145.442782) (xy 359.970074 -145.421644) (xy 359.925232 -145.394092) (xy 359.884594 -145.360648)
			(xy 359.866438 -145.341594) (xy 359.858905 -145.334206) (xy 359.839634 -145.325674) (xy 359.8291 -145.325084)
			(xy 359.754424 -145.325084) (xy 359.743875 -145.325618) (xy 359.72458 -145.33415) (xy 359.717086 -145.341594)
			(xy 359.698929 -145.360648) (xy 359.6583 -145.394106) (xy 359.61346 -145.421665) (xy 359.565259 -145.442804)
			(xy 359.514612 -145.457121) (xy 359.462478 -145.464346) (xy 359.436162 -145.464784) (xy 359.408911 -145.464344)
			(xy 359.354964 -145.456582) (xy 359.30267 -145.441223) (xy 359.253095 -145.418578) (xy 359.207246 -145.389109)
			(xy 359.166058 -145.353415) (xy 359.130368 -145.312223) (xy 359.100904 -145.266372) (xy 359.078264 -145.216794)
			(xy 359.06291 -145.164499) (xy 359.055154 -145.110551) (xy 355.630891 -145.110551) (xy 355.62921 -145.112232)
			(xy 355.628702 -145.118836) (xy 355.628702 -146.91487) (xy 367.916204 -146.91487) (xy 367.920275 -146.859248)
			(xy 367.932401 -146.804811) (xy 367.952324 -146.75272) (xy 367.97962 -146.704085) (xy 368.013706 -146.659942)
			(xy 368.053855 -146.621233) (xy 368.099213 -146.588782) (xy 368.148813 -146.563281) (xy 368.201597 -146.545274)
			(xy 368.25644 -146.535144) (xy 368.312174 -146.533107) (xy 368.367611 -146.539207) (xy 368.421568 -146.553313)
			(xy 368.472897 -146.575125) (xy 368.520503 -146.604179) (xy 368.563371 -146.639854) (xy 368.600588 -146.681391)
			(xy 368.631361 -146.727904) (xy 368.655033 -146.778401) (xy 368.671101 -146.831808) (xy 368.679221 -146.886984)
			(xy 368.67973 -146.91487) (xy 368.679221 -146.942756) (xy 368.671101 -146.997932) (xy 368.655033 -147.051339)
			(xy 368.649827 -147.062444) (xy 369.294408 -147.062444) (xy 369.298479 -147.006822) (xy 369.310605 -146.952385)
			(xy 369.330528 -146.900294) (xy 369.357824 -146.851659) (xy 369.39191 -146.807516) (xy 369.432059 -146.768807)
			(xy 369.477417 -146.736356) (xy 369.527017 -146.710855) (xy 369.579801 -146.692848) (xy 369.634644 -146.682718)
			(xy 369.690378 -146.680681) (xy 369.745815 -146.686781) (xy 369.799772 -146.700887) (xy 369.851101 -146.722699)
			(xy 369.898707 -146.751753) (xy 369.941575 -146.787428) (xy 369.978792 -146.828965) (xy 370.009565 -146.875478)
			(xy 370.033237 -146.925975) (xy 370.049305 -146.979382) (xy 370.057425 -147.034558) (xy 370.057934 -147.062444)
			(xy 370.057425 -147.09033) (xy 370.049305 -147.145506) (xy 370.033237 -147.198913) (xy 370.009565 -147.24941)
			(xy 369.978792 -147.295923) (xy 369.941575 -147.33746) (xy 369.898707 -147.373135) (xy 369.851101 -147.402189)
			(xy 369.799772 -147.424001) (xy 369.745815 -147.438107) (xy 369.690378 -147.444207) (xy 369.634644 -147.44217)
			(xy 369.579801 -147.43204) (xy 369.527017 -147.414033) (xy 369.477417 -147.388532) (xy 369.432059 -147.356081)
			(xy 369.39191 -147.317372) (xy 369.357824 -147.273229) (xy 369.330528 -147.224594) (xy 369.310605 -147.172503)
			(xy 369.298479 -147.118066) (xy 369.294408 -147.062444) (xy 368.649827 -147.062444) (xy 368.631361 -147.101836)
			(xy 368.600588 -147.148349) (xy 368.563371 -147.189886) (xy 368.520503 -147.225561) (xy 368.472897 -147.254615)
			(xy 368.421568 -147.276427) (xy 368.367611 -147.290533) (xy 368.312174 -147.296633) (xy 368.25644 -147.294596)
			(xy 368.201597 -147.284466) (xy 368.148813 -147.266459) (xy 368.099213 -147.240958) (xy 368.053855 -147.208507)
			(xy 368.013706 -147.169798) (xy 367.97962 -147.125655) (xy 367.952324 -147.07702) (xy 367.932401 -147.024929)
			(xy 367.920275 -146.970492) (xy 367.916204 -146.91487) (xy 355.628702 -146.91487) (xy 355.628702 -147.657656)
			(xy 359.450543 -147.657656) (xy 359.450543 -147.603144) (xy 359.458301 -147.549188) (xy 359.47366 -147.496885)
			(xy 359.496306 -147.447301) (xy 359.525779 -147.401445) (xy 359.561478 -147.360249) (xy 359.602677 -147.324555)
			(xy 359.648536 -147.295087) (xy 359.698123 -147.272446) (xy 359.750427 -147.257093) (xy 359.804384 -147.24934)
			(xy 359.83164 -147.24888) (xy 359.857955 -147.249327) (xy 359.910084 -147.256567) (xy 359.960727 -147.270891)
			(xy 360.008925 -147.292027) (xy 360.053768 -147.319576) (xy 360.094408 -147.353017) (xy 360.112564 -147.37207)
			(xy 360.120101 -147.379453) (xy 360.139369 -147.387989) (xy 360.149902 -147.38858) (xy 360.224578 -147.38858)
			(xy 360.235129 -147.388058) (xy 360.254424 -147.379519) (xy 360.261916 -147.37207) (xy 360.281736 -147.351282)
			(xy 360.326508 -147.315307) (xy 360.376166 -147.286447) (xy 360.429588 -147.265354) (xy 360.485567 -147.252505)
			(xy 360.54284 -147.24819) (xy 360.600113 -147.252505) (xy 360.656092 -147.265354) (xy 360.709514 -147.286447)
			(xy 360.759172 -147.315307) (xy 360.803944 -147.351282) (xy 360.823764 -147.37207) (xy 360.831301 -147.379453)
			(xy 360.850569 -147.387989) (xy 360.861102 -147.38858) (xy 360.935778 -147.38858) (xy 360.946329 -147.388058)
			(xy 360.965624 -147.379519) (xy 360.973116 -147.37207) (xy 360.991265 -147.353008) (xy 361.031897 -147.319553)
			(xy 361.076739 -147.291995) (xy 361.124941 -147.270858) (xy 361.175589 -147.256542) (xy 361.227724 -147.249318)
			(xy 361.25404 -147.24888) (xy 361.281288 -147.249393) (xy 361.33523 -147.257154) (xy 361.387518 -147.272512)
			(xy 361.437089 -147.295155) (xy 361.482933 -147.324621) (xy 361.524117 -147.360311) (xy 361.559803 -147.401499)
			(xy 361.589265 -147.447346) (xy 361.611902 -147.496919) (xy 361.627255 -147.549209) (xy 361.63501 -147.603151)
			(xy 361.63501 -147.657649) (xy 361.627255 -147.711591) (xy 361.611902 -147.763881) (xy 361.589265 -147.813454)
			(xy 361.559803 -147.859301) (xy 361.524117 -147.900489) (xy 361.482933 -147.936179) (xy 361.437089 -147.965645)
			(xy 361.387518 -147.988288) (xy 361.33523 -148.003646) (xy 361.281288 -148.011407) (xy 361.25404 -148.011896)
			(xy 361.227725 -148.01147) (xy 361.175594 -148.004227) (xy 361.124951 -147.9899) (xy 361.076752 -147.968759)
			(xy 361.031909 -147.941206) (xy 360.991271 -147.907761) (xy 360.973116 -147.888706) (xy 360.965589 -147.88131)
			(xy 360.946313 -147.872782) (xy 360.935778 -147.872196) (xy 360.861102 -147.872196) (xy 360.850551 -147.872714)
			(xy 360.831256 -147.881257) (xy 360.823764 -147.888706) (xy 360.803944 -147.909494) (xy 360.759172 -147.945469)
			(xy 360.709514 -147.974329) (xy 360.656092 -147.995422) (xy 360.600113 -148.008271) (xy 360.54284 -148.012586)
			(xy 360.485567 -148.008271) (xy 360.429588 -147.995422) (xy 360.376166 -147.974329) (xy 360.326508 -147.945469)
			(xy 360.281736 -147.909494) (xy 360.261916 -147.888706) (xy 360.254389 -147.88131) (xy 360.235113 -147.872782)
			(xy 360.224578 -147.872196) (xy 360.149902 -147.872196) (xy 360.139351 -147.872714) (xy 360.120056 -147.881257)
			(xy 360.112564 -147.888706) (xy 360.09442 -147.907773) (xy 360.053788 -147.941229) (xy 360.008945 -147.968786)
			(xy 359.960742 -147.989923) (xy 359.910092 -148.004237) (xy 359.857957 -148.011459) (xy 359.83164 -148.011896)
			(xy 359.804384 -148.01146) (xy 359.750427 -148.003707) (xy 359.698123 -147.988354) (xy 359.648536 -147.965713)
			(xy 359.602677 -147.936245) (xy 359.561478 -147.900551) (xy 359.525779 -147.859355) (xy 359.496306 -147.813499)
			(xy 359.47366 -147.763915) (xy 359.458301 -147.711612) (xy 359.450543 -147.657656) (xy 355.628702 -147.657656)
			(xy 355.628702 -148.017738) (xy 364.277654 -148.017738) (xy 364.281725 -147.962116) (xy 364.293851 -147.907679)
			(xy 364.313774 -147.855588) (xy 364.34107 -147.806953) (xy 364.375156 -147.76281) (xy 364.415305 -147.724101)
			(xy 364.460663 -147.69165) (xy 364.510263 -147.666149) (xy 364.563047 -147.648142) (xy 364.61789 -147.638012)
			(xy 364.673624 -147.635975) (xy 364.729061 -147.642075) (xy 364.783018 -147.656181) (xy 364.834347 -147.677993)
			(xy 364.881953 -147.707047) (xy 364.923216 -147.741386) (xy 370.18163 -147.741386) (xy 370.185701 -147.685764)
			(xy 370.197827 -147.631327) (xy 370.21775 -147.579236) (xy 370.245046 -147.530601) (xy 370.279132 -147.486458)
			(xy 370.319281 -147.447749) (xy 370.364639 -147.415298) (xy 370.414239 -147.389797) (xy 370.467023 -147.37179)
			(xy 370.521866 -147.36166) (xy 370.5776 -147.359623) (xy 370.633037 -147.365723) (xy 370.686994 -147.379829)
			(xy 370.738323 -147.401641) (xy 370.785929 -147.430695) (xy 370.828797 -147.46637) (xy 370.866014 -147.507907)
			(xy 370.896787 -147.55442) (xy 370.920459 -147.604917) (xy 370.936527 -147.658324) (xy 370.944647 -147.7135)
			(xy 370.945156 -147.741386) (xy 370.944647 -147.769272) (xy 370.936527 -147.824448) (xy 370.920459 -147.877855)
			(xy 370.896787 -147.928352) (xy 370.866014 -147.974865) (xy 370.828797 -148.016402) (xy 370.785929 -148.052077)
			(xy 370.738323 -148.081131) (xy 370.686994 -148.102943) (xy 370.633037 -148.117049) (xy 370.5776 -148.123149)
			(xy 370.521866 -148.121112) (xy 370.467023 -148.110982) (xy 370.414239 -148.092975) (xy 370.364639 -148.067474)
			(xy 370.319281 -148.035023) (xy 370.279132 -147.996314) (xy 370.245046 -147.952171) (xy 370.21775 -147.903536)
			(xy 370.197827 -147.851445) (xy 370.185701 -147.797008) (xy 370.18163 -147.741386) (xy 364.923216 -147.741386)
			(xy 364.924821 -147.742722) (xy 364.962038 -147.784259) (xy 364.992811 -147.830772) (xy 365.016483 -147.881269)
			(xy 365.032551 -147.934676) (xy 365.040671 -147.989852) (xy 365.04118 -148.017738) (xy 365.040671 -148.045624)
			(xy 365.032551 -148.1008) (xy 365.016483 -148.154207) (xy 364.992811 -148.204704) (xy 364.962038 -148.251217)
			(xy 364.924821 -148.292754) (xy 364.881953 -148.328429) (xy 364.834347 -148.357483) (xy 364.783018 -148.379295)
			(xy 364.729061 -148.393401) (xy 364.673624 -148.399501) (xy 364.61789 -148.397464) (xy 364.563047 -148.387334)
			(xy 364.510263 -148.369327) (xy 364.460663 -148.343826) (xy 364.415305 -148.311375) (xy 364.375156 -148.272666)
			(xy 364.34107 -148.228523) (xy 364.313774 -148.179888) (xy 364.293851 -148.127797) (xy 364.281725 -148.07336)
			(xy 364.277654 -148.017738) (xy 355.628702 -148.017738) (xy 355.628702 -150.195854) (xy 359.450565 -150.195854)
			(xy 359.450565 -150.141346) (xy 359.458323 -150.087393) (xy 359.473681 -150.035093) (xy 359.496326 -149.985512)
			(xy 359.525797 -149.939658) (xy 359.561494 -149.898465) (xy 359.60269 -149.862773) (xy 359.648547 -149.833307)
			(xy 359.698131 -149.810667) (xy 359.750432 -149.795315) (xy 359.804386 -149.787563) (xy 359.83164 -149.787102)
			(xy 359.857955 -149.787542) (xy 359.910085 -149.794782) (xy 359.960728 -149.809107) (xy 360.008927 -149.830244)
			(xy 360.05377 -149.857795) (xy 360.094408 -149.891238) (xy 360.112564 -149.910292) (xy 360.120098 -149.917679)
			(xy 360.139369 -149.926212) (xy 360.149902 -149.926802) (xy 360.224578 -149.926802) (xy 360.235128 -149.926274)
			(xy 360.254423 -149.917738) (xy 360.261916 -149.910292) (xy 360.281736 -149.889504) (xy 360.326508 -149.853529)
			(xy 360.376166 -149.824669) (xy 360.429588 -149.803576) (xy 360.485567 -149.790727) (xy 360.54284 -149.786412)
			(xy 360.600113 -149.790727) (xy 360.656092 -149.803576) (xy 360.709514 -149.824669) (xy 360.759172 -149.853529)
			(xy 360.803944 -149.889504) (xy 360.823764 -149.910292) (xy 360.831298 -149.917679) (xy 360.850569 -149.926212)
			(xy 360.861102 -149.926802) (xy 360.935778 -149.926802) (xy 360.946328 -149.926274) (xy 360.965623 -149.917738)
			(xy 360.973116 -149.910292) (xy 360.991269 -149.891234) (xy 361.0319 -149.857778) (xy 361.07674 -149.830219)
			(xy 361.124942 -149.809081) (xy 361.175589 -149.794764) (xy 361.227724 -149.78754) (xy 361.25404 -149.787102)
			(xy 361.28129 -149.787571) (xy 361.335235 -149.795332) (xy 361.387526 -149.810691) (xy 361.4371 -149.833335)
			(xy 361.482946 -149.862803) (xy 361.524133 -149.898495) (xy 361.559821 -149.939686) (xy 361.589284 -149.985535)
			(xy 361.611923 -150.035111) (xy 361.627277 -150.087404) (xy 361.6311 -150.114) (xy 363.091982 -150.114)
			(xy 363.096053 -150.058378) (xy 363.108179 -150.003941) (xy 363.128102 -149.95185) (xy 363.155398 -149.903215)
			(xy 363.189484 -149.859072) (xy 363.229633 -149.820363) (xy 363.274991 -149.787912) (xy 363.324591 -149.762411)
			(xy 363.377375 -149.744404) (xy 363.432218 -149.734274) (xy 363.487952 -149.732237) (xy 363.543389 -149.738337)
			(xy 363.597346 -149.752443) (xy 363.648675 -149.774255) (xy 363.696281 -149.803309) (xy 363.739149 -149.838984)
			(xy 363.776366 -149.880521) (xy 363.807139 -149.927034) (xy 363.830811 -149.977531) (xy 363.846879 -150.030938)
			(xy 363.851664 -150.063454) (xy 364.138208 -150.063454) (xy 364.142279 -150.007832) (xy 364.154405 -149.953395)
			(xy 364.174328 -149.901304) (xy 364.201624 -149.852669) (xy 364.23571 -149.808526) (xy 364.275859 -149.769817)
			(xy 364.321217 -149.737366) (xy 364.370817 -149.711865) (xy 364.423601 -149.693858) (xy 364.478444 -149.683728)
			(xy 364.534178 -149.681691) (xy 364.589615 -149.687791) (xy 364.643572 -149.701897) (xy 364.694901 -149.723709)
			(xy 364.742507 -149.752763) (xy 364.785375 -149.788438) (xy 364.822592 -149.829975) (xy 364.853365 -149.876488)
			(xy 364.877037 -149.926985) (xy 364.893105 -149.980392) (xy 364.901225 -150.035568) (xy 364.901734 -150.063454)
			(xy 364.901225 -150.09134) (xy 364.893105 -150.146516) (xy 364.877037 -150.199923) (xy 364.853365 -150.25042)
			(xy 364.822592 -150.296933) (xy 364.785375 -150.33847) (xy 364.742507 -150.374145) (xy 364.694901 -150.403199)
			(xy 364.643572 -150.425011) (xy 364.589615 -150.439117) (xy 364.534178 -150.445217) (xy 364.478444 -150.44318)
			(xy 364.423601 -150.43305) (xy 364.370817 -150.415043) (xy 364.321217 -150.389542) (xy 364.275859 -150.357091)
			(xy 364.23571 -150.318382) (xy 364.201624 -150.274239) (xy 364.174328 -150.225604) (xy 364.154405 -150.173513)
			(xy 364.142279 -150.119076) (xy 364.138208 -150.063454) (xy 363.851664 -150.063454) (xy 363.854999 -150.086114)
			(xy 363.855508 -150.114) (xy 363.854999 -150.141886) (xy 363.846879 -150.197062) (xy 363.830811 -150.250469)
			(xy 363.807139 -150.300966) (xy 363.776366 -150.347479) (xy 363.739149 -150.389016) (xy 363.696281 -150.424691)
			(xy 363.648675 -150.453745) (xy 363.597346 -150.475557) (xy 363.543389 -150.489663) (xy 363.487952 -150.495763)
			(xy 363.432218 -150.493726) (xy 363.377375 -150.483596) (xy 363.324591 -150.465589) (xy 363.274991 -150.440088)
			(xy 363.229633 -150.407637) (xy 363.189484 -150.368928) (xy 363.155398 -150.324785) (xy 363.128102 -150.27615)
			(xy 363.108179 -150.224059) (xy 363.096053 -150.169622) (xy 363.091982 -150.114) (xy 361.6311 -150.114)
			(xy 361.635032 -150.14135) (xy 361.635032 -150.19585) (xy 361.627277 -150.249796) (xy 361.611923 -150.302089)
			(xy 361.589284 -150.351665) (xy 361.559821 -150.397514) (xy 361.524133 -150.438705) (xy 361.482946 -150.474397)
			(xy 361.4371 -150.503865) (xy 361.387526 -150.526509) (xy 361.335235 -150.541868) (xy 361.28129 -150.549629)
			(xy 361.25404 -150.550118) (xy 361.227725 -150.549685) (xy 361.175595 -150.542442) (xy 361.124952 -150.528116)
			(xy 361.076753 -150.506977) (xy 361.031911 -150.479425) (xy 360.991272 -150.445982) (xy 360.973116 -150.426928)
			(xy 360.965587 -150.419535) (xy 360.946313 -150.411005) (xy 360.935778 -150.410418) (xy 360.861102 -150.410418)
			(xy 360.85055 -150.410929) (xy 360.831255 -150.419477) (xy 360.823764 -150.426928) (xy 360.803944 -150.447716)
			(xy 360.759172 -150.483691) (xy 360.709514 -150.512551) (xy 360.656092 -150.533644) (xy 360.600113 -150.546493)
			(xy 360.54284 -150.550808) (xy 360.485567 -150.546493) (xy 360.429588 -150.533644) (xy 360.376166 -150.512551)
			(xy 360.326508 -150.483691) (xy 360.281736 -150.447716) (xy 360.261916 -150.426928) (xy 360.254387 -150.419535)
			(xy 360.235113 -150.411005) (xy 360.224578 -150.410418) (xy 360.149902 -150.410418) (xy 360.13935 -150.410929)
			(xy 360.120055 -150.419477) (xy 360.112564 -150.426928) (xy 360.094424 -150.445999) (xy 360.053791 -150.479454)
			(xy 360.008947 -150.50701) (xy 359.960743 -150.528146) (xy 359.910093 -150.54246) (xy 359.857957 -150.549681)
			(xy 359.83164 -150.550118) (xy 359.804386 -150.549637) (xy 359.750432 -150.541885) (xy 359.698131 -150.526533)
			(xy 359.648547 -150.503893) (xy 359.60269 -150.474427) (xy 359.561494 -150.438735) (xy 359.525797 -150.397542)
			(xy 359.496326 -150.351688) (xy 359.473681 -150.302107) (xy 359.458323 -150.249807) (xy 359.450565 -150.195854)
			(xy 355.628702 -150.195854) (xy 355.628702 -151.67102) (xy 364.093758 -151.67102) (xy 364.097829 -151.615398)
			(xy 364.109955 -151.560961) (xy 364.129878 -151.50887) (xy 364.157174 -151.460235) (xy 364.19126 -151.416092)
			(xy 364.231409 -151.377383) (xy 364.276767 -151.344932) (xy 364.326367 -151.319431) (xy 364.379151 -151.301424)
			(xy 364.433994 -151.291294) (xy 364.489728 -151.289257) (xy 364.545165 -151.295357) (xy 364.599122 -151.309463)
			(xy 364.650451 -151.331275) (xy 364.698057 -151.360329) (xy 364.740925 -151.396004) (xy 364.778142 -151.437541)
			(xy 364.808915 -151.484054) (xy 364.832587 -151.534551) (xy 364.848655 -151.587958) (xy 364.856775 -151.643134)
			(xy 364.857284 -151.67102) (xy 364.856811 -151.696928) (xy 365.109758 -151.696928) (xy 365.113829 -151.641306)
			(xy 365.125955 -151.586869) (xy 365.145878 -151.534778) (xy 365.173174 -151.486143) (xy 365.20726 -151.442)
			(xy 365.247409 -151.403291) (xy 365.292767 -151.37084) (xy 365.342367 -151.345339) (xy 365.395151 -151.327332)
			(xy 365.449994 -151.317202) (xy 365.505728 -151.315165) (xy 365.561165 -151.321265) (xy 365.615122 -151.335371)
			(xy 365.666451 -151.357183) (xy 365.714057 -151.386237) (xy 365.738533 -151.406606) (xy 366.336832 -151.406606)
			(xy 366.340903 -151.350984) (xy 366.353029 -151.296547) (xy 366.372952 -151.244456) (xy 366.400248 -151.195821)
			(xy 366.434334 -151.151678) (xy 366.474483 -151.112969) (xy 366.519841 -151.080518) (xy 366.569441 -151.055017)
			(xy 366.622225 -151.03701) (xy 366.677068 -151.02688) (xy 366.732802 -151.024843) (xy 366.788239 -151.030943)
			(xy 366.842196 -151.045049) (xy 366.893525 -151.066861) (xy 366.941131 -151.095915) (xy 366.983999 -151.13159)
			(xy 367.021216 -151.173127) (xy 367.051989 -151.21964) (xy 367.075661 -151.270137) (xy 367.091729 -151.323544)
			(xy 367.099849 -151.37872) (xy 367.100358 -151.406606) (xy 367.099849 -151.434492) (xy 367.091729 -151.489668)
			(xy 367.075661 -151.543075) (xy 367.057119 -151.582628) (xy 367.662458 -151.582628) (xy 367.666529 -151.527006)
			(xy 367.678655 -151.472569) (xy 367.698578 -151.420478) (xy 367.725874 -151.371843) (xy 367.75996 -151.3277)
			(xy 367.800109 -151.288991) (xy 367.845467 -151.25654) (xy 367.895067 -151.231039) (xy 367.947851 -151.213032)
			(xy 368.002694 -151.202902) (xy 368.058428 -151.200865) (xy 368.113865 -151.206965) (xy 368.167822 -151.221071)
			(xy 368.219151 -151.242883) (xy 368.266757 -151.271937) (xy 368.309625 -151.307612) (xy 368.346842 -151.349149)
			(xy 368.377615 -151.395662) (xy 368.401287 -151.446159) (xy 368.417355 -151.499566) (xy 368.425475 -151.554742)
			(xy 368.425738 -151.569166) (xy 369.173758 -151.569166) (xy 369.177829 -151.513544) (xy 369.189955 -151.459107)
			(xy 369.209878 -151.407016) (xy 369.237174 -151.358381) (xy 369.27126 -151.314238) (xy 369.311409 -151.275529)
			(xy 369.356767 -151.243078) (xy 369.406367 -151.217577) (xy 369.459151 -151.19957) (xy 369.513994 -151.18944)
			(xy 369.569728 -151.187403) (xy 369.625165 -151.193503) (xy 369.679122 -151.207609) (xy 369.730451 -151.229421)
			(xy 369.778057 -151.258475) (xy 369.820925 -151.29415) (xy 369.858142 -151.335687) (xy 369.888915 -151.3822)
			(xy 369.912587 -151.432697) (xy 369.928655 -151.486104) (xy 369.936775 -151.54128) (xy 369.937284 -151.569166)
			(xy 369.936775 -151.597052) (xy 369.928655 -151.652228) (xy 369.912587 -151.705635) (xy 369.888915 -151.756132)
			(xy 369.858142 -151.802645) (xy 369.820925 -151.844182) (xy 369.778057 -151.879857) (xy 369.730451 -151.908911)
			(xy 369.679122 -151.930723) (xy 369.625165 -151.944829) (xy 369.569728 -151.950929) (xy 369.513994 -151.948892)
			(xy 369.459151 -151.938762) (xy 369.406367 -151.920755) (xy 369.356767 -151.895254) (xy 369.311409 -151.862803)
			(xy 369.27126 -151.824094) (xy 369.237174 -151.779951) (xy 369.209878 -151.731316) (xy 369.189955 -151.679225)
			(xy 369.177829 -151.624788) (xy 369.173758 -151.569166) (xy 368.425738 -151.569166) (xy 368.425984 -151.582628)
			(xy 368.425475 -151.610514) (xy 368.417355 -151.66569) (xy 368.401287 -151.719097) (xy 368.377615 -151.769594)
			(xy 368.346842 -151.816107) (xy 368.309625 -151.857644) (xy 368.266757 -151.893319) (xy 368.219151 -151.922373)
			(xy 368.167822 -151.944185) (xy 368.113865 -151.958291) (xy 368.058428 -151.964391) (xy 368.002694 -151.962354)
			(xy 367.947851 -151.952224) (xy 367.895067 -151.934217) (xy 367.845467 -151.908716) (xy 367.800109 -151.876265)
			(xy 367.75996 -151.837556) (xy 367.725874 -151.793413) (xy 367.698578 -151.744778) (xy 367.678655 -151.692687)
			(xy 367.666529 -151.63825) (xy 367.662458 -151.582628) (xy 367.057119 -151.582628) (xy 367.051989 -151.593572)
			(xy 367.021216 -151.640085) (xy 366.983999 -151.681622) (xy 366.941131 -151.717297) (xy 366.893525 -151.746351)
			(xy 366.842196 -151.768163) (xy 366.788239 -151.782269) (xy 366.732802 -151.788369) (xy 366.677068 -151.786332)
			(xy 366.622225 -151.776202) (xy 366.569441 -151.758195) (xy 366.519841 -151.732694) (xy 366.474483 -151.700243)
			(xy 366.434334 -151.661534) (xy 366.400248 -151.617391) (xy 366.372952 -151.568756) (xy 366.353029 -151.516665)
			(xy 366.340903 -151.462228) (xy 366.336832 -151.406606) (xy 365.738533 -151.406606) (xy 365.756925 -151.421912)
			(xy 365.794142 -151.463449) (xy 365.824915 -151.509962) (xy 365.848587 -151.560459) (xy 365.864655 -151.613866)
			(xy 365.872775 -151.669042) (xy 365.873284 -151.696928) (xy 365.872775 -151.724814) (xy 365.864655 -151.77999)
			(xy 365.848587 -151.833397) (xy 365.824915 -151.883894) (xy 365.794142 -151.930407) (xy 365.756925 -151.971944)
			(xy 365.714057 -152.007619) (xy 365.666451 -152.036673) (xy 365.615122 -152.058485) (xy 365.561165 -152.072591)
			(xy 365.505728 -152.078691) (xy 365.449994 -152.076654) (xy 365.395151 -152.066524) (xy 365.342367 -152.048517)
			(xy 365.292767 -152.023016) (xy 365.247409 -151.990565) (xy 365.20726 -151.951856) (xy 365.173174 -151.907713)
			(xy 365.145878 -151.859078) (xy 365.125955 -151.806987) (xy 365.113829 -151.75255) (xy 365.109758 -151.696928)
			(xy 364.856811 -151.696928) (xy 364.856775 -151.698906) (xy 364.848655 -151.754082) (xy 364.832587 -151.807489)
			(xy 364.808915 -151.857986) (xy 364.778142 -151.904499) (xy 364.740925 -151.946036) (xy 364.698057 -151.981711)
			(xy 364.650451 -152.010765) (xy 364.599122 -152.032577) (xy 364.545165 -152.046683) (xy 364.489728 -152.052783)
			(xy 364.433994 -152.050746) (xy 364.379151 -152.040616) (xy 364.326367 -152.022609) (xy 364.276767 -151.997108)
			(xy 364.231409 -151.964657) (xy 364.19126 -151.925948) (xy 364.157174 -151.881805) (xy 364.129878 -151.83317)
			(xy 364.109955 -151.781079) (xy 364.097829 -151.726642) (xy 364.093758 -151.67102) (xy 355.628702 -151.67102)
			(xy 355.628702 -153.782522) (xy 363.077758 -153.782522) (xy 363.081829 -153.7269) (xy 363.093955 -153.672463)
			(xy 363.113878 -153.620372) (xy 363.141174 -153.571737) (xy 363.17526 -153.527594) (xy 363.215409 -153.488885)
			(xy 363.260767 -153.456434) (xy 363.310367 -153.430933) (xy 363.363151 -153.412926) (xy 363.417994 -153.402796)
			(xy 363.473728 -153.400759) (xy 363.529165 -153.406859) (xy 363.583122 -153.420965) (xy 363.634451 -153.442777)
			(xy 363.682057 -153.471831) (xy 363.724925 -153.507506) (xy 363.762142 -153.549043) (xy 363.792915 -153.595556)
			(xy 363.816587 -153.646053) (xy 363.832655 -153.69946) (xy 363.840775 -153.754636) (xy 363.841284 -153.782522)
			(xy 364.093758 -153.782522) (xy 364.097829 -153.7269) (xy 364.109955 -153.672463) (xy 364.129878 -153.620372)
			(xy 364.157174 -153.571737) (xy 364.19126 -153.527594) (xy 364.231409 -153.488885) (xy 364.276767 -153.456434)
			(xy 364.326367 -153.430933) (xy 364.379151 -153.412926) (xy 364.433994 -153.402796) (xy 364.489728 -153.400759)
			(xy 364.545165 -153.406859) (xy 364.599122 -153.420965) (xy 364.650451 -153.442777) (xy 364.698057 -153.471831)
			(xy 364.740925 -153.507506) (xy 364.778142 -153.549043) (xy 364.808915 -153.595556) (xy 364.832587 -153.646053)
			(xy 364.848655 -153.69946) (xy 364.856775 -153.754636) (xy 364.857284 -153.782522) (xy 364.856775 -153.810408)
			(xy 364.853627 -153.831798) (xy 365.109758 -153.831798) (xy 365.113829 -153.776176) (xy 365.125955 -153.721739)
			(xy 365.145878 -153.669648) (xy 365.173174 -153.621013) (xy 365.20726 -153.57687) (xy 365.247409 -153.538161)
			(xy 365.292767 -153.50571) (xy 365.342367 -153.480209) (xy 365.395151 -153.462202) (xy 365.449994 -153.452072)
			(xy 365.505728 -153.450035) (xy 365.561165 -153.456135) (xy 365.615122 -153.470241) (xy 365.666451 -153.492053)
			(xy 365.714057 -153.521107) (xy 365.756925 -153.556782) (xy 365.794142 -153.598319) (xy 365.824915 -153.644832)
			(xy 365.848587 -153.695329) (xy 365.864655 -153.748736) (xy 365.869627 -153.782522) (xy 368.157758 -153.782522)
			(xy 368.161829 -153.7269) (xy 368.173955 -153.672463) (xy 368.193878 -153.620372) (xy 368.221174 -153.571737)
			(xy 368.25526 -153.527594) (xy 368.295409 -153.488885) (xy 368.340767 -153.456434) (xy 368.390367 -153.430933)
			(xy 368.443151 -153.412926) (xy 368.497994 -153.402796) (xy 368.553728 -153.400759) (xy 368.609165 -153.406859)
			(xy 368.663122 -153.420965) (xy 368.714451 -153.442777) (xy 368.762057 -153.471831) (xy 368.804925 -153.507506)
			(xy 368.842142 -153.549043) (xy 368.872915 -153.595556) (xy 368.896587 -153.646053) (xy 368.912655 -153.69946)
			(xy 368.920775 -153.754636) (xy 368.921284 -153.782522) (xy 370.189758 -153.782522) (xy 370.193829 -153.7269)
			(xy 370.205955 -153.672463) (xy 370.225878 -153.620372) (xy 370.253174 -153.571737) (xy 370.28726 -153.527594)
			(xy 370.327409 -153.488885) (xy 370.372767 -153.456434) (xy 370.422367 -153.430933) (xy 370.475151 -153.412926)
			(xy 370.529994 -153.402796) (xy 370.585728 -153.400759) (xy 370.641165 -153.406859) (xy 370.695122 -153.420965)
			(xy 370.746451 -153.442777) (xy 370.794057 -153.471831) (xy 370.836925 -153.507506) (xy 370.874142 -153.549043)
			(xy 370.904915 -153.595556) (xy 370.928587 -153.646053) (xy 370.944655 -153.69946) (xy 370.952775 -153.754636)
			(xy 370.953284 -153.782522) (xy 370.952775 -153.810408) (xy 370.944655 -153.865584) (xy 370.928587 -153.918991)
			(xy 370.904915 -153.969488) (xy 370.874142 -154.016001) (xy 370.836925 -154.057538) (xy 370.794057 -154.093213)
			(xy 370.746451 -154.122267) (xy 370.695122 -154.144079) (xy 370.641165 -154.158185) (xy 370.585728 -154.164285)
			(xy 370.529994 -154.162248) (xy 370.475151 -154.152118) (xy 370.422367 -154.134111) (xy 370.372767 -154.10861)
			(xy 370.327409 -154.076159) (xy 370.28726 -154.03745) (xy 370.253174 -153.993307) (xy 370.225878 -153.944672)
			(xy 370.205955 -153.892581) (xy 370.193829 -153.838144) (xy 370.189758 -153.782522) (xy 368.921284 -153.782522)
			(xy 368.920775 -153.810408) (xy 368.912655 -153.865584) (xy 368.896587 -153.918991) (xy 368.872915 -153.969488)
			(xy 368.842142 -154.016001) (xy 368.804925 -154.057538) (xy 368.762057 -154.093213) (xy 368.714451 -154.122267)
			(xy 368.663122 -154.144079) (xy 368.609165 -154.158185) (xy 368.553728 -154.164285) (xy 368.497994 -154.162248)
			(xy 368.443151 -154.152118) (xy 368.390367 -154.134111) (xy 368.340767 -154.10861) (xy 368.295409 -154.076159)
			(xy 368.25526 -154.03745) (xy 368.221174 -153.993307) (xy 368.193878 -153.944672) (xy 368.173955 -153.892581)
			(xy 368.161829 -153.838144) (xy 368.157758 -153.782522) (xy 365.869627 -153.782522) (xy 365.872775 -153.803912)
			(xy 365.873284 -153.831798) (xy 365.872775 -153.859684) (xy 365.864655 -153.91486) (xy 365.848587 -153.968267)
			(xy 365.824915 -154.018764) (xy 365.794142 -154.065277) (xy 365.756925 -154.106814) (xy 365.714057 -154.142489)
			(xy 365.666451 -154.171543) (xy 365.615122 -154.193355) (xy 365.561165 -154.207461) (xy 365.505728 -154.213561)
			(xy 365.449994 -154.211524) (xy 365.395151 -154.201394) (xy 365.342367 -154.183387) (xy 365.292767 -154.157886)
			(xy 365.247409 -154.125435) (xy 365.20726 -154.086726) (xy 365.173174 -154.042583) (xy 365.145878 -153.993948)
			(xy 365.125955 -153.941857) (xy 365.113829 -153.88742) (xy 365.109758 -153.831798) (xy 364.853627 -153.831798)
			(xy 364.848655 -153.865584) (xy 364.832587 -153.918991) (xy 364.808915 -153.969488) (xy 364.778142 -154.016001)
			(xy 364.740925 -154.057538) (xy 364.698057 -154.093213) (xy 364.650451 -154.122267) (xy 364.599122 -154.144079)
			(xy 364.545165 -154.158185) (xy 364.489728 -154.164285) (xy 364.433994 -154.162248) (xy 364.379151 -154.152118)
			(xy 364.326367 -154.134111) (xy 364.276767 -154.10861) (xy 364.231409 -154.076159) (xy 364.19126 -154.03745)
			(xy 364.157174 -153.993307) (xy 364.129878 -153.944672) (xy 364.109955 -153.892581) (xy 364.097829 -153.838144)
			(xy 364.093758 -153.782522) (xy 363.841284 -153.782522) (xy 363.840775 -153.810408) (xy 363.832655 -153.865584)
			(xy 363.816587 -153.918991) (xy 363.792915 -153.969488) (xy 363.762142 -154.016001) (xy 363.724925 -154.057538)
			(xy 363.682057 -154.093213) (xy 363.634451 -154.122267) (xy 363.583122 -154.144079) (xy 363.529165 -154.158185)
			(xy 363.473728 -154.164285) (xy 363.417994 -154.162248) (xy 363.363151 -154.152118) (xy 363.310367 -154.134111)
			(xy 363.260767 -154.10861) (xy 363.215409 -154.076159) (xy 363.17526 -154.03745) (xy 363.141174 -153.993307)
			(xy 363.113878 -153.944672) (xy 363.093955 -153.892581) (xy 363.081829 -153.838144) (xy 363.077758 -153.782522)
			(xy 355.628702 -153.782522) (xy 355.628702 -154.780488) (xy 355.629464 -154.788616) (xy 355.629464 -154.789124)
			(xy 355.631062 -154.796644) (xy 355.638034 -154.810337) (xy 355.64318 -154.816048) (xy 355.647752 -154.82062)
			(xy 355.648514 -154.821382) (xy 355.649276 -154.822144) (xy 355.652324 -154.824684) (xy 355.652832 -154.825192)
			(xy 355.655118 -154.826716) (xy 355.655626 -154.82697) (xy 355.656642 -154.827732) (xy 355.664262 -154.832558)
			(xy 355.66477 -154.833066) (xy 355.718618 -154.865324) (xy 355.724625 -154.868705) (xy 355.737891 -154.872427)
			(xy 355.74478 -154.87269) (xy 355.770434 -154.87269) (xy 355.780086 -154.870658) (xy 355.784912 -154.868372)
			(xy 355.786436 -154.86761) (xy 355.81219 -154.855907) (xy 355.86629 -154.839383) (xy 355.922236 -154.83103)
			(xy 355.95052 -154.830526) (xy 355.959156 -154.830526) (xy 355.986038 -154.831541) (xy 356.039131 -154.840194)
			(xy 356.090482 -154.85622) (xy 356.139072 -154.879302) (xy 356.183937 -154.908981) (xy 356.224188 -154.94467)
			(xy 356.259025 -154.985659) (xy 356.287758 -155.031136) (xy 356.309364 -155.079192) (xy 358.16997 -155.079192)
			(xy 358.174041 -155.02357) (xy 358.186167 -154.969133) (xy 358.20609 -154.917042) (xy 358.233386 -154.868407)
			(xy 358.267472 -154.824264) (xy 358.307621 -154.785555) (xy 358.352979 -154.753104) (xy 358.402579 -154.727603)
			(xy 358.455363 -154.709596) (xy 358.510206 -154.699466) (xy 358.56594 -154.697429) (xy 358.621377 -154.703529)
			(xy 358.675334 -154.717635) (xy 358.726663 -154.739447) (xy 358.774269 -154.768501) (xy 358.817137 -154.804176)
			(xy 358.854354 -154.845713) (xy 358.885127 -154.892226) (xy 358.908799 -154.942723) (xy 358.924867 -154.99613)
			(xy 358.932987 -155.051306) (xy 358.933496 -155.079192) (xy 358.933431 -155.082748) (xy 359.49382 -155.082748)
			(xy 359.494246 -155.056433) (xy 359.501489 -155.004302) (xy 359.515815 -154.953658) (xy 359.536956 -154.905459)
			(xy 359.564509 -154.860617) (xy 359.597955 -154.819979) (xy 359.61701 -154.801824) (xy 359.624405 -154.794297)
			(xy 359.632933 -154.775021) (xy 359.63352 -154.764486) (xy 359.63352 -154.68981) (xy 359.632993 -154.67926)
			(xy 359.624456 -154.659965) (xy 359.61701 -154.652472) (xy 359.59795 -154.634321) (xy 359.564493 -154.593691)
			(xy 359.536934 -154.548849) (xy 359.515796 -154.500648) (xy 359.50148 -154.449999) (xy 359.494257 -154.397864)
			(xy 359.49382 -154.371548) (xy 359.4943 -154.344295) (xy 359.502051 -154.290343) (xy 359.517403 -154.238044)
			(xy 359.540042 -154.188462) (xy 359.569507 -154.142607) (xy 359.605199 -154.101414) (xy 359.646391 -154.065719)
			(xy 359.692245 -154.036251) (xy 359.741825 -154.01361) (xy 359.794124 -153.998255) (xy 359.848075 -153.990501)
			(xy 359.875328 -153.99004) (xy 359.901643 -153.990476) (xy 359.953774 -153.997715) (xy 360.004417 -154.01204)
			(xy 360.052617 -154.033178) (xy 360.097459 -154.06073) (xy 360.138097 -154.094175) (xy 360.156252 -154.11323)
			(xy 360.163762 -154.120646) (xy 360.18305 -154.129165) (xy 360.19359 -154.12974) (xy 360.268266 -154.12974)
			(xy 360.278813 -154.129194) (xy 360.298108 -154.12067) (xy 360.305604 -154.11323) (xy 360.325424 -154.092442)
			(xy 360.370196 -154.056467) (xy 360.419854 -154.027607) (xy 360.473276 -154.006514) (xy 360.529255 -153.993665)
			(xy 360.586528 -153.98935) (xy 360.643801 -153.993665) (xy 360.69978 -154.006514) (xy 360.753202 -154.027607)
			(xy 360.80286 -154.056467) (xy 360.847632 -154.092442) (xy 360.867452 -154.11323) (xy 360.874962 -154.120646)
			(xy 360.89425 -154.129165) (xy 360.90479 -154.12974) (xy 360.979466 -154.12974) (xy 360.990013 -154.129194)
			(xy 361.009308 -154.12067) (xy 361.016804 -154.11323) (xy 361.036624 -154.092442) (xy 361.081396 -154.056467)
			(xy 361.131054 -154.027607) (xy 361.184476 -154.006514) (xy 361.240455 -153.993665) (xy 361.297728 -153.98935)
			(xy 361.355001 -153.993665) (xy 361.41098 -154.006514) (xy 361.464402 -154.027607) (xy 361.51406 -154.056467)
			(xy 361.558832 -154.092442) (xy 361.578652 -154.11323) (xy 361.586162 -154.120646) (xy 361.60545 -154.129165)
			(xy 361.61599 -154.12974) (xy 361.690666 -154.12974) (xy 361.701213 -154.129194) (xy 361.720508 -154.12067)
			(xy 361.728004 -154.11323) (xy 361.746171 -154.094185) (xy 361.786797 -154.060726) (xy 361.831635 -154.033165)
			(xy 361.879834 -154.012024) (xy 361.93048 -153.997705) (xy 361.982612 -153.990479) (xy 362.008928 -153.99004)
			(xy 362.036184 -153.990429) (xy 362.09014 -153.998191) (xy 362.142442 -154.013553) (xy 362.192026 -154.036202)
			(xy 362.237881 -154.065678) (xy 362.279075 -154.101379) (xy 362.314768 -154.14258) (xy 362.344234 -154.188441)
			(xy 362.366874 -154.238029) (xy 362.382225 -154.290334) (xy 362.389976 -154.344292) (xy 362.390436 -154.371548)
			(xy 362.389989 -154.397863) (xy 362.382748 -154.449991) (xy 362.368424 -154.500634) (xy 362.347288 -154.548833)
			(xy 362.319739 -154.593676) (xy 362.286298 -154.634315) (xy 362.267246 -154.652472) (xy 362.259862 -154.660008)
			(xy 362.251326 -154.679277) (xy 362.250736 -154.68981) (xy 362.250736 -154.764486) (xy 362.251248 -154.775038)
			(xy 362.259794 -154.794334) (xy 362.267246 -154.801824) (xy 362.286315 -154.819966) (xy 362.319769 -154.8606)
			(xy 362.347325 -154.905443) (xy 362.368461 -154.953646) (xy 362.382776 -155.004296) (xy 362.389998 -155.056431)
			(xy 362.390436 -155.082748) (xy 362.389967 -155.109999) (xy 362.382205 -155.163946) (xy 362.366845 -155.216239)
			(xy 362.3442 -155.265815) (xy 362.314731 -155.311664) (xy 362.279038 -155.352853) (xy 362.237848 -155.388543)
			(xy 362.191997 -155.41801) (xy 362.142421 -155.440652) (xy 362.090126 -155.456009) (xy 362.036179 -155.463768)
			(xy 362.008928 -155.464256) (xy 361.982612 -155.463851) (xy 361.93048 -155.456605) (xy 361.879836 -155.442275)
			(xy 361.831636 -155.421131) (xy 361.786795 -155.393573) (xy 361.746158 -155.360123) (xy 361.728004 -155.341066)
			(xy 361.720474 -155.333674) (xy 361.701201 -155.325142) (xy 361.690666 -155.324556) (xy 361.61599 -155.324556)
			(xy 361.60544 -155.325079) (xy 361.586146 -155.33362) (xy 361.578652 -155.341066) (xy 361.558832 -155.361854)
			(xy 361.51406 -155.397829) (xy 361.464402 -155.426689) (xy 361.41098 -155.447782) (xy 361.355001 -155.460631)
			(xy 361.297728 -155.464946) (xy 361.240455 -155.460631) (xy 361.184476 -155.447782) (xy 361.131054 -155.426689)
			(xy 361.081396 -155.397829) (xy 361.036624 -155.361854) (xy 361.016804 -155.341066) (xy 361.009274 -155.333674)
			(xy 360.990001 -155.325142) (xy 360.979466 -155.324556) (xy 360.90479 -155.324556) (xy 360.89424 -155.325079)
			(xy 360.874946 -155.33362) (xy 360.867452 -155.341066) (xy 360.847632 -155.361854) (xy 360.80286 -155.397829)
			(xy 360.753202 -155.426689) (xy 360.69978 -155.447782) (xy 360.643801 -155.460631) (xy 360.586528 -155.464946)
			(xy 360.529255 -155.460631) (xy 360.473276 -155.447782) (xy 360.419854 -155.426689) (xy 360.370196 -155.397829)
			(xy 360.325424 -155.361854) (xy 360.305604 -155.341066) (xy 360.298074 -155.333674) (xy 360.278801 -155.325142)
			(xy 360.268266 -155.324556) (xy 360.19359 -155.324556) (xy 360.18304 -155.325079) (xy 360.163746 -155.33362)
			(xy 360.156252 -155.341066) (xy 360.138126 -155.36015) (xy 360.097488 -155.393602) (xy 360.052641 -155.421156)
			(xy 360.004435 -155.442289) (xy 359.953783 -155.456601) (xy 359.901646 -155.46382) (xy 359.875328 -155.464256)
			(xy 359.84808 -155.463696) (xy 359.794137 -155.455944) (xy 359.741847 -155.440595) (xy 359.692273 -155.417961)
			(xy 359.646425 -155.388502) (xy 359.605235 -155.352818) (xy 359.569544 -155.311636) (xy 359.540076 -155.265794)
			(xy 359.517431 -155.216225) (xy 359.502072 -155.163937) (xy 359.49431 -155.109996) (xy 359.49382 -155.082748)
			(xy 358.933431 -155.082748) (xy 358.932987 -155.107078) (xy 358.924867 -155.162254) (xy 358.908799 -155.215661)
			(xy 358.885127 -155.266158) (xy 358.854354 -155.312671) (xy 358.817137 -155.354208) (xy 358.774269 -155.389883)
			(xy 358.726663 -155.418937) (xy 358.675334 -155.440749) (xy 358.621377 -155.454855) (xy 358.56594 -155.460955)
			(xy 358.510206 -155.458918) (xy 358.455363 -155.448788) (xy 358.402579 -155.430781) (xy 358.352979 -155.40528)
			(xy 358.307621 -155.372829) (xy 358.267472 -155.33412) (xy 358.233386 -155.289977) (xy 358.20609 -155.241342)
			(xy 358.186167 -155.189251) (xy 358.174041 -155.134814) (xy 358.16997 -155.079192) (xy 356.309364 -155.079192)
			(xy 356.309817 -155.080199) (xy 356.324764 -155.131874) (xy 356.332303 -155.185137) (xy 356.33279 -155.212034)
			(xy 356.332312 -155.239133) (xy 356.324636 -155.292786) (xy 356.309445 -155.344812) (xy 356.287042 -155.394164)
			(xy 356.25788 -155.439848) (xy 356.222546 -155.480946) (xy 356.181751 -155.516629) (xy 356.136317 -155.546178)
			(xy 356.087157 -155.569) (xy 356.035263 -155.584635) (xy 355.981678 -155.592767) (xy 355.954584 -155.593542)
			(xy 355.946964 -155.593542) (xy 355.919459 -155.592769) (xy 355.865093 -155.584285) (xy 355.812511 -155.568077)
			(xy 355.787452 -155.556712) (xy 355.786944 -155.556458) (xy 355.782118 -155.554172) (xy 355.777038 -155.551632)
			(xy 355.774498 -155.550616) (xy 355.769926 -155.548838) (xy 355.758468 -155.545379) (xy 355.734745 -155.548302)
			(xy 355.72446 -155.554426) (xy 355.66477 -155.591002) (xy 355.664262 -155.59151) (xy 355.656642 -155.596336)
			(xy 355.655626 -155.596844) (xy 355.655118 -155.597352) (xy 355.652832 -155.598876) (xy 355.652324 -155.599384)
			(xy 355.647752 -155.603448) (xy 355.645212 -155.605988) (xy 355.644196 -155.607258) (xy 355.642164 -155.609544)
			(xy 355.639116 -155.612846) (xy 355.634363 -155.619629) (xy 355.62905 -155.635305) (xy 355.628702 -155.64358)
			(xy 355.628702 -156.69387) (xy 357.187498 -156.69387) (xy 357.191569 -156.638248) (xy 357.203695 -156.583811)
			(xy 357.223618 -156.53172) (xy 357.250914 -156.483085) (xy 357.285 -156.438942) (xy 357.325149 -156.400233)
			(xy 357.370507 -156.367782) (xy 357.420107 -156.342281) (xy 357.472891 -156.324274) (xy 357.527734 -156.314144)
			(xy 357.583468 -156.312107) (xy 357.638905 -156.318207) (xy 357.692862 -156.332313) (xy 357.744191 -156.354125)
			(xy 357.791797 -156.383179) (xy 357.834665 -156.418854) (xy 357.871882 -156.460391) (xy 357.902655 -156.506904)
			(xy 357.926327 -156.557401) (xy 357.942395 -156.610808) (xy 357.950515 -156.665984) (xy 357.951024 -156.69387)
			(xy 357.950515 -156.721756) (xy 357.942395 -156.776932) (xy 357.926327 -156.830339) (xy 357.902655 -156.880836)
			(xy 357.871882 -156.927349) (xy 357.834665 -156.968886) (xy 357.791797 -157.004561) (xy 357.744191 -157.033615)
			(xy 357.692862 -157.055427) (xy 357.638905 -157.069533) (xy 357.583468 -157.075633) (xy 357.527734 -157.073596)
			(xy 357.472891 -157.063466) (xy 357.420107 -157.045459) (xy 357.370507 -157.019958) (xy 357.325149 -156.987507)
			(xy 357.285 -156.948798) (xy 357.250914 -156.904655) (xy 357.223618 -156.85602) (xy 357.203695 -156.803929)
			(xy 357.191569 -156.749492) (xy 357.187498 -156.69387) (xy 355.628702 -156.69387) (xy 355.628702 -156.84881)
			(xy 355.62921 -156.855922) (xy 356.421182 -157.647894) (xy 359.313988 -157.647894) (xy 359.314524 -157.621251)
			(xy 359.323048 -157.568653) (xy 359.339905 -157.518105) (xy 359.364658 -157.470919) (xy 359.396665 -157.428318)
			(xy 359.435096 -157.391409) (xy 359.456736 -157.37586) (xy 359.468026 -157.367502) (xy 359.485877 -157.345826)
			(xy 359.497157 -157.320111) (xy 359.501013 -157.292297) (xy 359.497155 -157.264483) (xy 359.485874 -157.238768)
			(xy 359.468021 -157.217094) (xy 359.456736 -157.208728) (xy 359.435134 -157.193132) (xy 359.396719 -157.156218)
			(xy 359.364719 -157.113623) (xy 359.339961 -157.066449) (xy 359.323086 -157.015916) (xy 359.31453 -156.963332)
			(xy 359.313988 -156.936694) (xy 359.314498 -156.910707) (xy 359.322628 -156.859372) (xy 359.338689 -156.809942)
			(xy 359.362285 -156.763632) (xy 359.392835 -156.721584) (xy 359.429586 -156.684833) (xy 359.471634 -156.654283)
			(xy 359.517944 -156.630687) (xy 359.567374 -156.614626) (xy 359.618709 -156.606496) (xy 359.670683 -156.606496)
			(xy 359.722018 -156.614626) (xy 359.771448 -156.630687) (xy 359.817758 -156.654283) (xy 359.859806 -156.684833)
			(xy 359.896557 -156.721584) (xy 359.927107 -156.763632) (xy 359.950703 -156.809942) (xy 359.966764 -156.859372)
			(xy 359.974894 -156.910707) (xy 359.975404 -156.936694) (xy 359.974862 -156.963336) (xy 359.96634 -157.015935)
			(xy 359.949485 -157.066483) (xy 359.924733 -157.113669) (xy 359.892726 -157.15627) (xy 359.854296 -157.193179)
			(xy 359.832656 -157.208728) (xy 359.821379 -157.217101) (xy 359.803529 -157.238774) (xy 359.79225 -157.264486)
			(xy 359.788392 -157.292297) (xy 359.792248 -157.320108) (xy 359.803525 -157.34582) (xy 359.821374 -157.367494)
			(xy 359.832656 -157.37586) (xy 359.854251 -157.391466) (xy 359.892666 -157.428378) (xy 359.924667 -157.47097)
			(xy 359.949427 -157.518142) (xy 359.966303 -157.568674) (xy 359.974861 -157.621257) (xy 359.975404 -157.647894)
			(xy 360.21391 -157.647894) (xy 360.214437 -157.621251) (xy 360.222961 -157.568652) (xy 360.239819 -157.518103)
			(xy 360.264574 -157.470917) (xy 360.296583 -157.428317) (xy 360.335017 -157.391408) (xy 360.356658 -157.37586)
			(xy 360.367946 -157.3675) (xy 360.385793 -157.345824) (xy 360.39707 -157.320109) (xy 360.400926 -157.292297)
			(xy 360.397068 -157.264484) (xy 360.38579 -157.23877) (xy 360.367941 -157.217095) (xy 360.356658 -157.208728)
			(xy 360.335061 -157.193125) (xy 360.296645 -157.156214) (xy 360.264643 -157.11362) (xy 360.239884 -157.066447)
			(xy 360.223009 -157.015915) (xy 360.214452 -156.963332) (xy 360.21391 -156.936694) (xy 360.21442 -156.910707)
			(xy 360.22255 -156.859372) (xy 360.238611 -156.809942) (xy 360.262207 -156.763632) (xy 360.292757 -156.721584)
			(xy 360.329508 -156.684833) (xy 360.371556 -156.654283) (xy 360.417866 -156.630687) (xy 360.467296 -156.614626)
			(xy 360.518631 -156.606496) (xy 360.570605 -156.606496) (xy 360.62194 -156.614626) (xy 360.67137 -156.630687)
			(xy 360.71768 -156.654283) (xy 360.759728 -156.684833) (xy 360.796479 -156.721584) (xy 360.827029 -156.763632)
			(xy 360.850625 -156.809942) (xy 360.866686 -156.859372) (xy 360.874816 -156.910707) (xy 360.875326 -156.936694)
			(xy 360.874817 -156.963338) (xy 360.866294 -157.01594) (xy 360.849434 -157.06649) (xy 360.824675 -157.113677)
			(xy 360.792661 -157.156276) (xy 360.754222 -157.193182) (xy 360.732578 -157.208728) (xy 360.721299 -157.2171)
			(xy 360.703445 -157.238772) (xy 360.692163 -157.264484) (xy 360.688305 -157.292297) (xy 360.692161 -157.320109)
			(xy 360.703441 -157.345823) (xy 360.721294 -157.367495) (xy 360.732578 -157.37586) (xy 360.754178 -157.391459)
			(xy 360.792592 -157.428373) (xy 360.824592 -157.470967) (xy 360.84935 -157.518141) (xy 360.866226 -157.568673)
			(xy 360.874783 -157.621256) (xy 360.875326 -157.647894) (xy 361.113832 -157.647894) (xy 361.11435 -157.62125)
			(xy 361.122874 -157.56865) (xy 361.139734 -157.518101) (xy 361.16449 -157.470914) (xy 361.196502 -157.428315)
			(xy 361.234937 -157.391407) (xy 361.25658 -157.37586) (xy 361.267875 -157.367505) (xy 361.285736 -157.345832)
			(xy 361.297022 -157.320115) (xy 361.300881 -157.292297) (xy 361.29702 -157.264479) (xy 361.285732 -157.238762)
			(xy 361.26787 -157.217091) (xy 361.25658 -157.208728) (xy 361.234987 -157.193119) (xy 361.19657 -157.156209)
			(xy 361.164567 -157.113617) (xy 361.139808 -157.066446) (xy 361.122931 -157.015915) (xy 361.114374 -156.963331)
			(xy 361.113832 -156.936694) (xy 361.114342 -156.910707) (xy 361.122472 -156.859372) (xy 361.138533 -156.809942)
			(xy 361.162129 -156.763632) (xy 361.192679 -156.721584) (xy 361.22943 -156.684833) (xy 361.271478 -156.654283)
			(xy 361.317788 -156.630687) (xy 361.367218 -156.614626) (xy 361.418553 -156.606496) (xy 361.470527 -156.606496)
			(xy 361.521862 -156.614626) (xy 361.571292 -156.630687) (xy 361.617602 -156.654283) (xy 361.65965 -156.684833)
			(xy 361.696401 -156.721584) (xy 361.726951 -156.763632) (xy 361.750547 -156.809942) (xy 361.766608 -156.859372)
			(xy 361.774738 -156.910707) (xy 361.775248 -156.936694) (xy 361.77473 -156.963338) (xy 361.766207 -157.015938)
			(xy 361.749348 -157.066488) (xy 361.724592 -157.113675) (xy 361.69258 -157.156274) (xy 361.654143 -157.193181)
			(xy 361.6325 -157.208728) (xy 361.621219 -157.217099) (xy 361.603362 -157.23877) (xy 361.592077 -157.264483)
			(xy 361.588218 -157.292297) (xy 361.592075 -157.320111) (xy 361.603358 -157.345825) (xy 361.621214 -157.367496)
			(xy 361.6325 -157.37586) (xy 361.654083 -157.391483) (xy 361.692501 -157.428389) (xy 361.724506 -157.470977)
			(xy 361.749267 -157.518147) (xy 361.766146 -157.568676) (xy 361.774705 -157.621257) (xy 361.775248 -157.647894)
			(xy 362.014008 -157.647894) (xy 362.014536 -157.621251) (xy 362.02306 -157.568652) (xy 362.039918 -157.518103)
			(xy 362.064672 -157.470917) (xy 362.096682 -157.428317) (xy 362.135115 -157.391408) (xy 362.156756 -157.37586)
			(xy 362.168044 -157.367501) (xy 362.185892 -157.345824) (xy 362.197169 -157.320109) (xy 362.201024 -157.292297)
			(xy 362.197167 -157.264484) (xy 362.185888 -157.23877) (xy 362.168039 -157.217095) (xy 362.156756 -157.208728)
			(xy 362.135158 -157.193126) (xy 362.096742 -157.156214) (xy 362.064741 -157.113621) (xy 362.039982 -157.066448)
			(xy 362.023107 -157.015916) (xy 362.01455 -156.963332) (xy 362.014008 -156.936694) (xy 362.014518 -156.910707)
			(xy 362.022648 -156.859372) (xy 362.038709 -156.809942) (xy 362.062305 -156.763632) (xy 362.092855 -156.721584)
			(xy 362.129606 -156.684833) (xy 362.171654 -156.654283) (xy 362.217964 -156.630687) (xy 362.267394 -156.614626)
			(xy 362.318729 -156.606496) (xy 362.370703 -156.606496) (xy 362.422038 -156.614626) (xy 362.471468 -156.630687)
			(xy 362.517778 -156.654283) (xy 362.559826 -156.684833) (xy 362.596577 -156.721584) (xy 362.627127 -156.763632)
			(xy 362.650723 -156.809942) (xy 362.666784 -156.859372) (xy 362.674914 -156.910707) (xy 362.675424 -156.936694)
			(xy 362.674916 -156.963338) (xy 362.666392 -157.01594) (xy 362.649532 -157.06649) (xy 362.624774 -157.113677)
			(xy 362.59276 -157.156276) (xy 362.55432 -157.193182) (xy 362.532676 -157.208728) (xy 362.521397 -157.2171)
			(xy 362.503544 -157.238772) (xy 362.492262 -157.264484) (xy 362.488404 -157.292297) (xy 362.49226 -157.320109)
			(xy 362.50354 -157.345822) (xy 362.521392 -157.367495) (xy 362.532676 -157.37586) (xy 362.554275 -157.39146)
			(xy 362.592689 -157.428374) (xy 362.624689 -157.470968) (xy 362.649448 -157.518141) (xy 362.666324 -157.568673)
			(xy 362.674881 -157.621256) (xy 362.675383 -157.645862) (xy 363.629448 -157.645862) (xy 363.629875 -157.619546)
			(xy 363.637116 -157.567416) (xy 363.651442 -157.516771) (xy 363.672582 -157.468572) (xy 363.700136 -157.42373)
			(xy 363.733582 -157.383093) (xy 363.752638 -157.364938) (xy 363.760016 -157.357396) (xy 363.768556 -157.338132)
			(xy 363.769148 -157.3276) (xy 363.769148 -157.252924) (xy 363.768605 -157.242376) (xy 363.760078 -157.223082)
			(xy 363.752638 -157.215586) (xy 363.733571 -157.197442) (xy 363.700117 -157.156809) (xy 363.672561 -157.111965)
			(xy 363.651425 -157.063763) (xy 363.63711 -157.013114) (xy 363.629886 -156.960979) (xy 363.629448 -156.934662)
			(xy 363.629934 -156.907411) (xy 363.63769 -156.853463) (xy 363.653045 -156.801168) (xy 363.675687 -156.751591)
			(xy 363.705153 -156.705741) (xy 363.740844 -156.66455) (xy 363.782035 -156.628859) (xy 363.827885 -156.599393)
			(xy 363.877462 -156.576751) (xy 363.929757 -156.561396) (xy 363.983705 -156.55364) (xy 364.038207 -156.55364)
			(xy 364.092155 -156.561396) (xy 364.14445 -156.576751) (xy 364.194027 -156.599393) (xy 364.239877 -156.628859)
			(xy 364.258622 -156.645101) (xy 365.614017 -156.645101) (xy 365.618332 -156.587828) (xy 365.631182 -156.531849)
			(xy 365.652276 -156.478427) (xy 365.681137 -156.428769) (xy 365.717113 -156.383997) (xy 365.737902 -156.364178)
			(xy 365.745315 -156.356667) (xy 365.753833 -156.337379) (xy 365.754412 -156.32684) (xy 365.754412 -156.252164)
			(xy 365.753858 -156.241617) (xy 365.74534 -156.222322) (xy 365.737902 -156.214826) (xy 365.718866 -156.19665)
			(xy 365.685407 -156.156025) (xy 365.657846 -156.111189) (xy 365.636704 -156.062992) (xy 365.622382 -156.012348)
			(xy 365.615153 -155.960217) (xy 365.614712 -155.933902) (xy 365.615198 -155.906651) (xy 365.622954 -155.852703)
			(xy 365.638309 -155.800408) (xy 365.660951 -155.750831) (xy 365.690417 -155.704981) (xy 365.726108 -155.66379)
			(xy 365.767299 -155.628099) (xy 365.813149 -155.598633) (xy 365.862726 -155.575991) (xy 365.915021 -155.560636)
			(xy 365.968969 -155.55288) (xy 366.023471 -155.55288) (xy 366.077419 -155.560636) (xy 366.129714 -155.575991)
			(xy 366.179291 -155.598633) (xy 366.225141 -155.628099) (xy 366.266332 -155.66379) (xy 366.302023 -155.704981)
			(xy 366.331489 -155.750831) (xy 366.354131 -155.800408) (xy 366.369486 -155.852703) (xy 366.377242 -155.906651)
			(xy 366.377728 -155.933902) (xy 366.377253 -155.960216) (xy 366.370018 -156.012343) (xy 366.3557 -156.062986)
			(xy 366.334569 -156.111184) (xy 366.307025 -156.156028) (xy 366.273588 -156.196669) (xy 366.254538 -156.214826)
			(xy 366.247129 -156.222341) (xy 366.238608 -156.241626) (xy 366.238028 -156.252164) (xy 366.238028 -156.32684)
			(xy 366.238568 -156.337389) (xy 366.247095 -156.356685) (xy 366.254538 -156.364178) (xy 366.275327 -156.383996)
			(xy 366.3113 -156.42877) (xy 366.340158 -156.478428) (xy 366.36125 -156.53185) (xy 366.374098 -156.587829)
			(xy 366.378413 -156.645101) (xy 366.374098 -156.702374) (xy 366.372962 -156.707322) (xy 368.679825 -156.707322)
			(xy 368.684137 -156.650052) (xy 368.696983 -156.594076) (xy 368.718071 -156.540656) (xy 368.746926 -156.491)
			(xy 368.782897 -156.446228) (xy 368.803682 -156.426408) (xy 368.811079 -156.418883) (xy 368.819607 -156.399606)
			(xy 368.820192 -156.38907) (xy 368.820192 -156.314394) (xy 368.819682 -156.303842) (xy 368.811133 -156.284547)
			(xy 368.803682 -156.277056) (xy 368.784609 -156.258918) (xy 368.751154 -156.218284) (xy 368.723598 -156.17344)
			(xy 368.702462 -156.125236) (xy 368.688149 -156.074586) (xy 368.680928 -156.022449) (xy 368.680492 -155.996132)
			(xy 368.680978 -155.968881) (xy 368.688734 -155.914933) (xy 368.704089 -155.862638) (xy 368.726731 -155.813061)
			(xy 368.756197 -155.767211) (xy 368.791888 -155.72602) (xy 368.833079 -155.690329) (xy 368.878929 -155.660863)
			(xy 368.928506 -155.638221) (xy 368.980801 -155.622866) (xy 369.034749 -155.61511) (xy 369.089251 -155.61511)
			(xy 369.143199 -155.622866) (xy 369.195494 -155.638221) (xy 369.245071 -155.660863) (xy 369.290921 -155.690329)
			(xy 369.332112 -155.72602) (xy 369.367803 -155.767211) (xy 369.397269 -155.813061) (xy 369.419911 -155.862638)
			(xy 369.435266 -155.914933) (xy 369.443022 -155.968881) (xy 369.443508 -155.996132) (xy 369.443059 -156.022447)
			(xy 369.43582 -156.074576) (xy 369.421497 -156.125219) (xy 369.400361 -156.173418) (xy 369.372812 -156.218261)
			(xy 369.339371 -156.2589) (xy 369.320318 -156.277056) (xy 369.312936 -156.284594) (xy 369.3044 -156.303862)
			(xy 369.303808 -156.314394) (xy 369.303808 -156.38907) (xy 369.304337 -156.39962) (xy 369.312872 -156.418915)
			(xy 369.320318 -156.426408) (xy 369.341138 -156.446196) (xy 369.377113 -156.490973) (xy 369.405971 -156.540635)
			(xy 369.427062 -156.594062) (xy 369.439909 -156.650045) (xy 369.444222 -156.707322) (xy 369.439903 -156.764598)
			(xy 369.427049 -156.82058) (xy 369.405952 -156.874004) (xy 369.377088 -156.923663) (xy 369.341108 -156.968436)
			(xy 369.320318 -156.988256) (xy 369.312936 -156.995794) (xy 369.3044 -157.015062) (xy 369.303808 -157.025594)
			(xy 369.303808 -157.10027) (xy 369.304337 -157.11082) (xy 369.312872 -157.130115) (xy 369.320318 -157.137608)
			(xy 369.339374 -157.155763) (xy 369.37283 -157.196393) (xy 369.400389 -157.241234) (xy 369.421527 -157.289435)
			(xy 369.435844 -157.340082) (xy 369.443069 -157.392216) (xy 369.443508 -157.418532) (xy 369.443022 -157.445783)
			(xy 369.435266 -157.499731) (xy 369.419911 -157.552026) (xy 369.397269 -157.601603) (xy 369.367803 -157.647453)
			(xy 369.332112 -157.688644) (xy 369.290921 -157.724335) (xy 369.245071 -157.753801) (xy 369.195494 -157.776443)
			(xy 369.143199 -157.791798) (xy 369.089251 -157.799554) (xy 369.034749 -157.799554) (xy 368.980801 -157.791798)
			(xy 368.928506 -157.776443) (xy 368.878929 -157.753801) (xy 368.833079 -157.724335) (xy 368.791888 -157.688644)
			(xy 368.756197 -157.647453) (xy 368.726731 -157.601603) (xy 368.704089 -157.552026) (xy 368.688734 -157.499731)
			(xy 368.680978 -157.445783) (xy 368.680492 -157.418532) (xy 368.680917 -157.392217) (xy 368.688161 -157.340086)
			(xy 368.702488 -157.289443) (xy 368.723629 -157.241244) (xy 368.751182 -157.196402) (xy 368.784627 -157.155764)
			(xy 368.803682 -157.137608) (xy 368.811079 -157.130083) (xy 368.819607 -157.110806) (xy 368.820192 -157.10027)
			(xy 368.820192 -157.025594) (xy 368.819682 -157.015042) (xy 368.811133 -156.995747) (xy 368.803682 -156.988256)
			(xy 368.782926 -156.968404) (xy 368.746951 -156.923636) (xy 368.71809 -156.873983) (xy 368.696996 -156.820566)
			(xy 368.684144 -156.764591) (xy 368.679825 -156.707322) (xy 366.372962 -156.707322) (xy 366.361249 -156.758353)
			(xy 366.340157 -156.811774) (xy 366.311299 -156.861432) (xy 366.275325 -156.906205) (xy 366.254538 -156.926026)
			(xy 366.247129 -156.933541) (xy 366.238608 -156.952826) (xy 366.238028 -156.963364) (xy 366.238028 -157.03804)
			(xy 366.238568 -157.048589) (xy 366.247095 -157.067885) (xy 366.254538 -157.075378) (xy 366.273583 -157.093544)
			(xy 366.30704 -157.134172) (xy 366.334599 -157.179011) (xy 366.355739 -157.227209) (xy 366.370059 -157.277854)
			(xy 366.377287 -157.329987) (xy 366.377728 -157.356302) (xy 366.377242 -157.383553) (xy 366.369486 -157.437501)
			(xy 366.354131 -157.489796) (xy 366.331489 -157.539373) (xy 366.302023 -157.585223) (xy 366.266332 -157.626414)
			(xy 366.225141 -157.662105) (xy 366.179291 -157.691571) (xy 366.129714 -157.714213) (xy 366.077419 -157.729568)
			(xy 366.023471 -157.737324) (xy 365.968969 -157.737324) (xy 365.915021 -157.729568) (xy 365.862726 -157.714213)
			(xy 365.813149 -157.691571) (xy 365.767299 -157.662105) (xy 365.726108 -157.626414) (xy 365.690417 -157.585223)
			(xy 365.660951 -157.539373) (xy 365.638309 -157.489796) (xy 365.622954 -157.437501) (xy 365.615198 -157.383553)
			(xy 365.614712 -157.356302) (xy 365.615177 -157.329988) (xy 365.622412 -157.277859) (xy 365.636731 -157.227216)
			(xy 365.657864 -157.179017) (xy 365.685411 -157.134174) (xy 365.71885 -157.093534) (xy 365.737902 -157.075378)
			(xy 365.745315 -157.067867) (xy 365.753833 -157.048579) (xy 365.754412 -157.03804) (xy 365.754412 -156.963364)
			(xy 365.753858 -156.952817) (xy 365.74534 -156.933522) (xy 365.737902 -156.926026) (xy 365.717115 -156.906205)
			(xy 365.681138 -156.861433) (xy 365.652277 -156.811776) (xy 365.631183 -156.758354) (xy 365.618333 -156.702374)
			(xy 365.614017 -156.645101) (xy 364.258622 -156.645101) (xy 364.281068 -156.66455) (xy 364.316759 -156.705741)
			(xy 364.346225 -156.751591) (xy 364.368867 -156.801168) (xy 364.384222 -156.853463) (xy 364.391978 -156.907411)
			(xy 364.392464 -156.934662) (xy 364.392049 -156.960978) (xy 364.384805 -157.013109) (xy 364.370477 -157.063753)
			(xy 364.349334 -157.111952) (xy 364.321778 -157.156794) (xy 364.28833 -157.197431) (xy 364.269274 -157.215586)
			(xy 364.261887 -157.223121) (xy 364.253352 -157.24239) (xy 364.252764 -157.252924) (xy 364.252764 -157.3276)
			(xy 364.25329 -157.33815) (xy 364.261829 -157.357444) (xy 364.269274 -157.364938) (xy 364.288336 -157.383087)
			(xy 364.321794 -157.423718) (xy 364.349352 -157.468559) (xy 364.37049 -157.516761) (xy 364.384805 -157.56741)
			(xy 364.392027 -157.619545) (xy 364.392464 -157.645862) (xy 364.391978 -157.673113) (xy 364.384222 -157.727061)
			(xy 364.368867 -157.779356) (xy 364.346225 -157.828933) (xy 364.316759 -157.874783) (xy 364.281068 -157.915974)
			(xy 364.239877 -157.951665) (xy 364.194027 -157.981131) (xy 364.14445 -158.003773) (xy 364.092155 -158.019128)
			(xy 364.038207 -158.026884) (xy 363.983705 -158.026884) (xy 363.929757 -158.019128) (xy 363.877462 -158.003773)
			(xy 363.827885 -157.981131) (xy 363.782035 -157.951665) (xy 363.740844 -157.915974) (xy 363.705153 -157.874783)
			(xy 363.675687 -157.828933) (xy 363.653045 -157.779356) (xy 363.63769 -157.727061) (xy 363.629934 -157.673113)
			(xy 363.629448 -157.645862) (xy 362.675383 -157.645862) (xy 362.675424 -157.647894) (xy 362.674914 -157.673881)
			(xy 362.666784 -157.725216) (xy 362.650723 -157.774646) (xy 362.627127 -157.820956) (xy 362.596577 -157.863004)
			(xy 362.559826 -157.899755) (xy 362.517778 -157.930305) (xy 362.471468 -157.953901) (xy 362.422038 -157.969962)
			(xy 362.370703 -157.978092) (xy 362.318729 -157.978092) (xy 362.267394 -157.969962) (xy 362.217964 -157.953901)
			(xy 362.171654 -157.930305) (xy 362.129606 -157.899755) (xy 362.092855 -157.863004) (xy 362.062305 -157.820956)
			(xy 362.038709 -157.774646) (xy 362.022648 -157.725216) (xy 362.014518 -157.673881) (xy 362.014008 -157.647894)
			(xy 361.775248 -157.647894) (xy 361.774738 -157.673881) (xy 361.766608 -157.725216) (xy 361.750547 -157.774646)
			(xy 361.726951 -157.820956) (xy 361.696401 -157.863004) (xy 361.65965 -157.899755) (xy 361.617602 -157.930305)
			(xy 361.571292 -157.953901) (xy 361.521862 -157.969962) (xy 361.470527 -157.978092) (xy 361.418553 -157.978092)
			(xy 361.367218 -157.969962) (xy 361.317788 -157.953901) (xy 361.271478 -157.930305) (xy 361.22943 -157.899755)
			(xy 361.192679 -157.863004) (xy 361.162129 -157.820956) (xy 361.138533 -157.774646) (xy 361.122472 -157.725216)
			(xy 361.114342 -157.673881) (xy 361.113832 -157.647894) (xy 360.875326 -157.647894) (xy 360.874816 -157.673881)
			(xy 360.866686 -157.725216) (xy 360.850625 -157.774646) (xy 360.827029 -157.820956) (xy 360.796479 -157.863004)
			(xy 360.759728 -157.899755) (xy 360.71768 -157.930305) (xy 360.67137 -157.953901) (xy 360.62194 -157.969962)
			(xy 360.570605 -157.978092) (xy 360.518631 -157.978092) (xy 360.467296 -157.969962) (xy 360.417866 -157.953901)
			(xy 360.371556 -157.930305) (xy 360.329508 -157.899755) (xy 360.292757 -157.863004) (xy 360.262207 -157.820956)
			(xy 360.238611 -157.774646) (xy 360.22255 -157.725216) (xy 360.21442 -157.673881) (xy 360.21391 -157.647894)
			(xy 359.975404 -157.647894) (xy 359.974894 -157.673881) (xy 359.966764 -157.725216) (xy 359.950703 -157.774646)
			(xy 359.927107 -157.820956) (xy 359.896557 -157.863004) (xy 359.859806 -157.899755) (xy 359.817758 -157.930305)
			(xy 359.771448 -157.953901) (xy 359.722018 -157.969962) (xy 359.670683 -157.978092) (xy 359.618709 -157.978092)
			(xy 359.567374 -157.969962) (xy 359.517944 -157.953901) (xy 359.471634 -157.930305) (xy 359.429586 -157.899755)
			(xy 359.392835 -157.863004) (xy 359.362285 -157.820956) (xy 359.338689 -157.774646) (xy 359.322628 -157.725216)
			(xy 359.314498 -157.673881) (xy 359.313988 -157.647894) (xy 356.421182 -157.647894) (xy 356.714552 -157.941264)
			(xy 356.732586 -157.960034) (xy 356.763171 -158.002149) (xy 356.786802 -158.048525) (xy 356.790661 -158.06039)
			(xy 357.139746 -158.06039) (xy 357.143817 -158.004768) (xy 357.155943 -157.950331) (xy 357.175866 -157.89824)
			(xy 357.203162 -157.849605) (xy 357.237248 -157.805462) (xy 357.277397 -157.766753) (xy 357.322755 -157.734302)
			(xy 357.372355 -157.708801) (xy 357.425139 -157.690794) (xy 357.479982 -157.680664) (xy 357.535716 -157.678627)
			(xy 357.591153 -157.684727) (xy 357.64511 -157.698833) (xy 357.696439 -157.720645) (xy 357.744045 -157.749699)
			(xy 357.786913 -157.785374) (xy 357.82413 -157.826911) (xy 357.854903 -157.873424) (xy 357.878575 -157.923921)
			(xy 357.894643 -157.977328) (xy 357.902763 -158.032504) (xy 357.903272 -158.06039) (xy 357.902763 -158.088276)
			(xy 357.894643 -158.143452) (xy 357.878575 -158.196859) (xy 357.854903 -158.247356) (xy 357.82413 -158.293869)
			(xy 357.786913 -158.335406) (xy 357.744045 -158.371081) (xy 357.696439 -158.400135) (xy 357.64511 -158.421947)
			(xy 357.591153 -158.436053) (xy 357.535716 -158.442153) (xy 357.479982 -158.440116) (xy 357.425139 -158.429986)
			(xy 357.372355 -158.411979) (xy 357.322755 -158.386478) (xy 357.277397 -158.354027) (xy 357.237248 -158.315318)
			(xy 357.203162 -158.271175) (xy 357.175866 -158.22254) (xy 357.155943 -158.170449) (xy 357.143817 -158.116012)
			(xy 357.139746 -158.06039) (xy 356.790661 -158.06039) (xy 356.802899 -158.098023) (xy 356.811068 -158.149428)
			(xy 356.81158 -158.175452) (xy 356.81158 -158.753302) (xy 364.816642 -158.753302) (xy 364.820713 -158.69768)
			(xy 364.832839 -158.643243) (xy 364.852762 -158.591152) (xy 364.880058 -158.542517) (xy 364.914144 -158.498374)
			(xy 364.954293 -158.459665) (xy 364.999651 -158.427214) (xy 365.049251 -158.401713) (xy 365.102035 -158.383706)
			(xy 365.156878 -158.373576) (xy 365.212612 -158.371539) (xy 365.268049 -158.377639) (xy 365.322006 -158.391745)
			(xy 365.373335 -158.413557) (xy 365.420941 -158.442611) (xy 365.463809 -158.478286) (xy 365.501026 -158.519823)
			(xy 365.531799 -158.566336) (xy 365.555471 -158.616833) (xy 365.571539 -158.67024) (xy 365.579659 -158.725416)
			(xy 365.580168 -158.753302) (xy 365.579659 -158.781188) (xy 365.571539 -158.836364) (xy 365.555471 -158.889771)
			(xy 365.531799 -158.940268) (xy 365.501026 -158.986781) (xy 365.463809 -159.028318) (xy 365.420941 -159.063993)
			(xy 365.373335 -159.093047) (xy 365.322006 -159.114859) (xy 365.268049 -159.128965) (xy 365.212612 -159.135065)
			(xy 365.156878 -159.133028) (xy 365.102035 -159.122898) (xy 365.049251 -159.104891) (xy 364.999651 -159.07939)
			(xy 364.954293 -159.046939) (xy 364.914144 -159.00823) (xy 364.880058 -158.964087) (xy 364.852762 -158.915452)
			(xy 364.832839 -158.863361) (xy 364.820713 -158.808924) (xy 364.816642 -158.753302) (xy 356.81158 -158.753302)
			(xy 356.81158 -159.439102) (xy 357.208072 -159.439102) (xy 357.212143 -159.38348) (xy 357.224269 -159.329043)
			(xy 357.244192 -159.276952) (xy 357.271488 -159.228317) (xy 357.305574 -159.184174) (xy 357.345723 -159.145465)
			(xy 357.391081 -159.113014) (xy 357.440681 -159.087513) (xy 357.493465 -159.069506) (xy 357.548308 -159.059376)
			(xy 357.604042 -159.057339) (xy 357.659479 -159.063439) (xy 357.713436 -159.077545) (xy 357.764765 -159.099357)
			(xy 357.812371 -159.128411) (xy 357.855239 -159.164086) (xy 357.892456 -159.205623) (xy 357.923229 -159.252136)
			(xy 357.946901 -159.302633) (xy 357.962969 -159.35604) (xy 357.971089 -159.411216) (xy 357.971598 -159.439102)
			(xy 357.971089 -159.466988) (xy 357.962969 -159.522164) (xy 357.960066 -159.531812) (xy 360.41279 -159.531812)
			(xy 360.416861 -159.47619) (xy 360.428987 -159.421753) (xy 360.44891 -159.369662) (xy 360.476206 -159.321027)
			(xy 360.510292 -159.276884) (xy 360.550441 -159.238175) (xy 360.595799 -159.205724) (xy 360.645399 -159.180223)
			(xy 360.698183 -159.162216) (xy 360.753026 -159.152086) (xy 360.80876 -159.150049) (xy 360.864197 -159.156149)
			(xy 360.918154 -159.170255) (xy 360.969483 -159.192067) (xy 361.017089 -159.221121) (xy 361.059957 -159.256796)
			(xy 361.097174 -159.298333) (xy 361.127947 -159.344846) (xy 361.151619 -159.395343) (xy 361.167687 -159.44875)
			(xy 361.171463 -159.474408) (xy 362.882432 -159.474408) (xy 362.886503 -159.418786) (xy 362.898629 -159.364349)
			(xy 362.918552 -159.312258) (xy 362.945848 -159.263623) (xy 362.979934 -159.21948) (xy 363.020083 -159.180771)
			(xy 363.065441 -159.14832) (xy 363.115041 -159.122819) (xy 363.167825 -159.104812) (xy 363.222668 -159.094682)
			(xy 363.278402 -159.092645) (xy 363.333839 -159.098745) (xy 363.387796 -159.112851) (xy 363.439125 -159.134663)
			(xy 363.486731 -159.163717) (xy 363.529599 -159.199392) (xy 363.566816 -159.240929) (xy 363.597589 -159.287442)
			(xy 363.621261 -159.337939) (xy 363.637329 -159.391346) (xy 363.645449 -159.446522) (xy 363.645958 -159.474408)
			(xy 363.645449 -159.502294) (xy 363.637329 -159.55747) (xy 363.621261 -159.610877) (xy 363.597589 -159.661374)
			(xy 363.566816 -159.707887) (xy 363.529599 -159.749424) (xy 363.486731 -159.785099) (xy 363.439125 -159.814153)
			(xy 363.387796 -159.835965) (xy 363.333839 -159.850071) (xy 363.278402 -159.856171) (xy 363.222668 -159.854134)
			(xy 363.167825 -159.844004) (xy 363.115041 -159.825997) (xy 363.065441 -159.800496) (xy 363.020083 -159.768045)
			(xy 362.979934 -159.729336) (xy 362.945848 -159.685193) (xy 362.918552 -159.636558) (xy 362.898629 -159.584467)
			(xy 362.886503 -159.53003) (xy 362.882432 -159.474408) (xy 361.171463 -159.474408) (xy 361.175807 -159.503926)
			(xy 361.176316 -159.531812) (xy 361.175807 -159.559698) (xy 361.167687 -159.614874) (xy 361.151619 -159.668281)
			(xy 361.127947 -159.718778) (xy 361.097174 -159.765291) (xy 361.059957 -159.806828) (xy 361.017089 -159.842503)
			(xy 360.969483 -159.871557) (xy 360.918154 -159.893369) (xy 360.864197 -159.907475) (xy 360.80876 -159.913575)
			(xy 360.753026 -159.911538) (xy 360.698183 -159.901408) (xy 360.645399 -159.883401) (xy 360.595799 -159.8579)
			(xy 360.550441 -159.825449) (xy 360.510292 -159.78674) (xy 360.476206 -159.742597) (xy 360.44891 -159.693962)
			(xy 360.428987 -159.641871) (xy 360.416861 -159.587434) (xy 360.41279 -159.531812) (xy 357.960066 -159.531812)
			(xy 357.946901 -159.575571) (xy 357.923229 -159.626068) (xy 357.892456 -159.672581) (xy 357.855239 -159.714118)
			(xy 357.812371 -159.749793) (xy 357.764765 -159.778847) (xy 357.713436 -159.800659) (xy 357.659479 -159.814765)
			(xy 357.604042 -159.820865) (xy 357.548308 -159.818828) (xy 357.493465 -159.808698) (xy 357.440681 -159.790691)
			(xy 357.391081 -159.76519) (xy 357.345723 -159.732739) (xy 357.305574 -159.69403) (xy 357.271488 -159.649887)
			(xy 357.244192 -159.601252) (xy 357.224269 -159.549161) (xy 357.212143 -159.494724) (xy 357.208072 -159.439102)
			(xy 356.81158 -159.439102) (xy 356.81158 -159.862012) (xy 356.815898 -159.867092) (xy 357.522526 -160.57372)
			(xy 357.52673 -160.577753) (xy 357.536611 -160.583918) (xy 357.542084 -160.585912) (xy 357.553006 -160.589722)
			(xy 357.558086 -160.58896) (xy 357.562912 -160.588198) (xy 357.576928 -160.586261) (xy 357.605151 -160.584224)
			(xy 357.6193 -160.584134) (xy 357.619808 -160.584134) (xy 357.647077 -160.584621) (xy 357.70106 -160.592384)
			(xy 357.753389 -160.60775) (xy 357.802998 -160.630406) (xy 357.848878 -160.659892) (xy 357.890095 -160.695607)
			(xy 357.92581 -160.736825) (xy 357.955296 -160.782705) (xy 357.977952 -160.832315) (xy 357.993317 -160.884644)
			(xy 358.001079 -160.938627) (xy 358.00157 -160.965896) (xy 358.00157 -160.966404) (xy 358.001466 -160.980552)
			(xy 357.99943 -161.008775) (xy 357.997506 -161.022792) (xy 357.996744 -161.027618) (xy 357.995982 -161.032698)
			(xy 357.999792 -161.04362) (xy 358.001849 -161.049063) (xy 358.008001 -161.058937) (xy 358.011984 -161.063178)
			(xy 358.296972 -161.348166) (xy 358.29748 -161.348674) (xy 358.30256 -161.352992) (xy 358.660446 -161.352992)
			(xy 358.666159 -161.348962) (xy 358.675304 -161.338393) (xy 358.67848 -161.332164) (xy 358.69118 -161.305494)
			(xy 358.69118 -161.304986) (xy 358.706166 -161.274252) (xy 358.708513 -161.26903) (xy 358.711083 -161.257876)
			(xy 358.711246 -161.252154) (xy 358.711246 -161.216848) (xy 358.711095 -161.21098) (xy 358.708399 -161.199559)
			(xy 358.705912 -161.194242) (xy 358.703372 -161.189162) (xy 358.701086 -161.18586) (xy 358.700832 -161.185606)
			(xy 358.684278 -161.161398) (xy 358.658008 -161.108968) (xy 358.64007 -161.053135) (xy 358.630885 -160.995215)
			(xy 358.63022 -160.965896) (xy 358.63022 -160.963356) (xy 358.631998 -160.92678) (xy 358.632252 -160.92424)
			(xy 358.63276 -160.918652) (xy 358.636557 -160.891196) (xy 358.651054 -160.8377) (xy 358.673133 -160.786861)
			(xy 358.70233 -160.739749) (xy 358.738031 -160.697352) (xy 358.779487 -160.660562) (xy 358.825825 -160.630152)
			(xy 358.876073 -160.60676) (xy 358.929175 -160.590879) (xy 358.984015 -160.582841) (xy 359.011728 -160.582356)
			(xy 359.039466 -160.582856) (xy 359.094358 -160.590892) (xy 359.147507 -160.606791) (xy 359.197795 -160.630218)
			(xy 359.244161 -160.660678) (xy 359.285628 -160.697531) (xy 359.321322 -160.74) (xy 359.350492 -160.787189)
			(xy 359.372522 -160.838104) (xy 359.386947 -160.891672) (xy 359.390696 -160.91916) (xy 359.39222 -160.932876)
			(xy 359.39349 -160.963864) (xy 359.393398 -160.968944) (xy 359.901488 -160.968944) (xy 359.905559 -160.913322)
			(xy 359.917685 -160.858885) (xy 359.937608 -160.806794) (xy 359.964904 -160.758159) (xy 359.99899 -160.714016)
			(xy 360.039139 -160.675307) (xy 360.084497 -160.642856) (xy 360.134097 -160.617355) (xy 360.186881 -160.599348)
			(xy 360.241724 -160.589218) (xy 360.297458 -160.587181) (xy 360.352895 -160.593281) (xy 360.406852 -160.607387)
			(xy 360.458181 -160.629199) (xy 360.505787 -160.658253) (xy 360.548655 -160.693928) (xy 360.585872 -160.735465)
			(xy 360.616645 -160.781978) (xy 360.640317 -160.832475) (xy 360.656385 -160.885882) (xy 360.658778 -160.902142)
			(xy 361.68279 -160.902142) (xy 361.686861 -160.84652) (xy 361.698987 -160.792083) (xy 361.71891 -160.739992)
			(xy 361.746206 -160.691357) (xy 361.780292 -160.647214) (xy 361.820441 -160.608505) (xy 361.865799 -160.576054)
			(xy 361.915399 -160.550553) (xy 361.968183 -160.532546) (xy 362.023026 -160.522416) (xy 362.07876 -160.520379)
			(xy 362.134197 -160.526479) (xy 362.188154 -160.540585) (xy 362.239483 -160.562397) (xy 362.287089 -160.591451)
			(xy 362.329957 -160.627126) (xy 362.367174 -160.668663) (xy 362.397947 -160.715176) (xy 362.421619 -160.765673)
			(xy 362.437687 -160.81908) (xy 362.445807 -160.874256) (xy 362.446316 -160.902142) (xy 362.445807 -160.930028)
			(xy 362.437687 -160.985204) (xy 362.421619 -161.038611) (xy 362.397947 -161.089108) (xy 362.367174 -161.135621)
			(xy 362.329957 -161.177158) (xy 362.287089 -161.212833) (xy 362.239483 -161.241887) (xy 362.188154 -161.263699)
			(xy 362.134197 -161.277805) (xy 362.07876 -161.283905) (xy 362.023026 -161.281868) (xy 361.968183 -161.271738)
			(xy 361.915399 -161.253731) (xy 361.865799 -161.22823) (xy 361.820441 -161.195779) (xy 361.780292 -161.15707)
			(xy 361.746206 -161.112927) (xy 361.71891 -161.064292) (xy 361.698987 -161.012201) (xy 361.686861 -160.957764)
			(xy 361.68279 -160.902142) (xy 360.658778 -160.902142) (xy 360.664505 -160.941058) (xy 360.665014 -160.968944)
			(xy 360.664505 -160.99683) (xy 360.656385 -161.052006) (xy 360.640317 -161.105413) (xy 360.616645 -161.15591)
			(xy 360.585872 -161.202423) (xy 360.548655 -161.24396) (xy 360.505787 -161.279635) (xy 360.458181 -161.308689)
			(xy 360.406852 -161.330501) (xy 360.352895 -161.344607) (xy 360.297458 -161.350707) (xy 360.241724 -161.34867)
			(xy 360.186881 -161.33854) (xy 360.134097 -161.320533) (xy 360.084497 -161.295032) (xy 360.039139 -161.262581)
			(xy 359.99899 -161.223872) (xy 359.964904 -161.179729) (xy 359.937608 -161.131094) (xy 359.917685 -161.079003)
			(xy 359.905559 -161.024566) (xy 359.901488 -160.968944) (xy 359.393398 -160.968944) (xy 359.392988 -160.991694)
			(xy 359.384907 -161.046763) (xy 359.368912 -161.100074) (xy 359.345341 -161.150496) (xy 359.314695 -161.196958)
			(xy 359.277624 -161.238475) (xy 359.234915 -161.274166) (xy 359.187473 -161.303274) (xy 359.136307 -161.325181)
			(xy 359.0825 -161.339421) (xy 359.054908 -161.343086) (xy 359.045256 -161.344102) (xy 359.010458 -161.362136)
			(xy 359.003854 -161.368994) (xy 358.998551 -161.374649) (xy 358.991315 -161.388351) (xy 358.98963 -161.395918)
			(xy 359.007918 -161.431224) (xy 359.014776 -161.43732) (xy 359.027984 -161.449766) (xy 359.229152 -161.650934)
			(xy 359.236264 -161.651442) (xy 359.243122 -161.651442) (xy 359.252266 -161.655252) (xy 359.256829 -161.657261)
			(xy 359.265141 -161.662762) (xy 359.268776 -161.666174) (xy 360.380788 -162.778186) (xy 360.381296 -162.778694)
			(xy 360.386376 -162.783012) (xy 364.543086 -162.783012) (xy 364.546896 -162.78098) (xy 364.575387 -162.765982)
			(xy 364.636149 -162.744703) (xy 364.699618 -162.733902) (xy 364.731808 -162.733228) (xy 364.759543 -162.733733)
			(xy 364.814428 -162.741779) (xy 364.867569 -162.757684) (xy 364.917848 -162.781115) (xy 364.964206 -162.811578)
			(xy 365.005666 -162.84843) (xy 365.041354 -162.890896) (xy 365.070519 -162.938081) (xy 365.092547 -162.988991)
			(xy 365.106972 -163.042553) (xy 365.110776 -163.070032) (xy 365.1123 -163.084256) (xy 365.11357 -163.115244)
			(xy 365.11357 -163.115498) (xy 365.112931 -163.145683) (xy 365.103311 -163.205285) (xy 365.084452 -163.262637)
			(xy 365.071152 -163.289742) (xy 365.062267 -163.306483) (xy 365.04165 -163.338289) (xy 365.030004 -163.353242)
			(xy 365.024162 -163.360608) (xy 365.021368 -163.369244) (xy 365.02086 -163.370768) (xy 365.018828 -163.383214)
			(xy 365.01959 -163.405312) (xy 365.020098 -163.416996) (xy 365.020899 -163.426371) (xy 365.028481 -163.443577)
			(xy 365.03483 -163.450524) (xy 365.776256 -164.19195) (xy 365.783099 -164.199349) (xy 365.790822 -164.217948)
			(xy 365.791242 -164.228018) (xy 365.791242 -164.587682) (xy 365.792004 -164.59581) (xy 365.792004 -164.596318)
			(xy 365.793603 -164.603837) (xy 365.800577 -164.617528) (xy 365.80572 -164.623242) (xy 367.757696 -166.574978)
			(xy 370.832378 -166.574978) (xy 370.836449 -166.519356) (xy 370.848575 -166.464919) (xy 370.868498 -166.412828)
			(xy 370.895794 -166.364193) (xy 370.92988 -166.32005) (xy 370.970029 -166.281341) (xy 371.015387 -166.24889)
			(xy 371.064987 -166.223389) (xy 371.117771 -166.205382) (xy 371.172614 -166.195252) (xy 371.228348 -166.193215)
			(xy 371.283785 -166.199315) (xy 371.337742 -166.213421) (xy 371.389071 -166.235233) (xy 371.436677 -166.264287)
			(xy 371.479545 -166.299962) (xy 371.516762 -166.341499) (xy 371.547535 -166.388012) (xy 371.571207 -166.438509)
			(xy 371.587275 -166.491916) (xy 371.595395 -166.547092) (xy 371.595904 -166.574978) (xy 371.595395 -166.602864)
			(xy 371.587275 -166.65804) (xy 371.571207 -166.711447) (xy 371.547535 -166.761944) (xy 371.516762 -166.808457)
			(xy 371.479545 -166.849994) (xy 371.436677 -166.885669) (xy 371.389071 -166.914723) (xy 371.337742 -166.936535)
			(xy 371.283785 -166.950641) (xy 371.228348 -166.956741) (xy 371.172614 -166.954704) (xy 371.117771 -166.944574)
			(xy 371.064987 -166.926567) (xy 371.015387 -166.901066) (xy 370.970029 -166.868615) (xy 370.92988 -166.829906)
			(xy 370.895794 -166.785763) (xy 370.868498 -166.737128) (xy 370.848575 -166.685037) (xy 370.836449 -166.6306)
			(xy 370.832378 -166.574978) (xy 367.757696 -166.574978) (xy 367.87328 -166.690548) (xy 370.013738 -168.831006)
			(xy 370.019418 -168.836197) (xy 370.033125 -168.84317) (xy 370.040662 -168.844722) (xy 370.04117 -168.844722)
			(xy 370.049298 -168.845484) (xy 373.025416 -168.845484) (xy 373.050706 -168.84598) (xy 373.100663 -168.853891)
			(xy 373.148769 -168.869514) (xy 373.19384 -168.892467) (xy 373.234769 -168.922184) (xy 373.253 -168.939718)
			(xy 373.259604 -168.946576) (xy 373.260112 -168.947084) (xy 373.262964 -168.949789) (xy 373.269344 -168.954379)
			(xy 373.272812 -168.956228) (xy 373.278239 -168.958813) (xy 373.289918 -168.961642) (xy 373.295926 -168.961816)
			(xy 375.340626 -168.961816) (xy 375.354841 -168.9613) (xy 375.382148 -168.953383) (xy 375.40622 -168.938251)
			(xy 375.425193 -168.917075) (xy 375.437601 -168.891492) (xy 375.442484 -168.863482) (xy 375.441464 -168.849294)
			(xy 375.44121 -168.8465) (xy 372.250208 -151.996648) (xy 371.00637 -145.429478) (xy 370.997226 -145.372074)
			(xy 370.914168 -144.728692) (xy 369.431316 -133.454648) (xy 368.569494 -126.903734) (xy 368.567328 -126.894247)
			(xy 368.556972 -126.877792) (xy 368.541227 -126.866384) (xy 368.531902 -126.863602) (xy 368.512852 -126.858776)
			(xy 368.48796 -126.852426) (xy 368.48034 -126.853188) (xy 368.479578 -126.853188) (xy 368.467386 -126.854204)
			(xy 368.462052 -126.856998) (xy 368.459258 -126.858522) (xy 368.459004 -126.858522) (xy 368.44351 -126.86665)
			(xy 368.4404 -126.868377) (xy 368.434665 -126.872588) (xy 368.43208 -126.875032) (xy 368.428778 -126.878334)
			(xy 368.42827 -126.879096) (xy 368.426492 -126.881382) (xy 368.408292 -126.9047) (xy 368.365919 -126.945969)
			(xy 368.317703 -126.98023) (xy 368.26479 -127.006666) (xy 368.208441 -127.024649) (xy 368.149997 -127.033751)
			(xy 368.120422 -127.03429) (xy 368.092685 -127.033787) (xy 368.037797 -127.025745) (xy 367.984651 -127.009842)
			(xy 367.934366 -126.986414) (xy 367.888004 -126.955952) (xy 367.846539 -126.9191) (xy 367.810845 -126.876634)
			(xy 367.781676 -126.829448) (xy 367.759644 -126.778536) (xy 367.745214 -126.724972) (xy 367.741454 -126.697486)
			(xy 367.739676 -126.682246) (xy 367.73866 -126.652782) (xy 367.739049 -126.62715) (xy 367.745857 -126.57634)
			(xy 367.759401 -126.526899) (xy 367.77944 -126.479714) (xy 367.805611 -126.435634) (xy 367.82121 -126.415292)
			(xy 367.823496 -126.412752) (xy 367.825528 -126.409958) (xy 367.82883 -126.402338) (xy 367.829846 -126.399798)
			(xy 367.831237 -126.39568) (xy 367.832776 -126.387125) (xy 367.832894 -126.38278) (xy 367.832894 -126.361952)
			(xy 367.833039 -126.356513) (xy 367.835349 -126.345883) (xy 367.837466 -126.34087) (xy 367.842292 -126.33071)
			(xy 367.845594 -126.320296) (xy 367.845594 -126.299468) (xy 367.843308 -126.291594) (xy 367.835688 -126.271782)
			(xy 367.829846 -126.265178) (xy 367.817054 -126.249872) (xy 367.794401 -126.217038) (xy 367.784634 -126.199646)
			(xy 367.780062 -126.190756) (xy 367.778792 -126.188216) (xy 367.777014 -126.18466) (xy 367.764903 -126.158527)
			(xy 367.747807 -126.103526) (xy 367.739169 -126.046581) (xy 367.73866 -126.017782) (xy 367.739049 -125.99215)
			(xy 367.745857 -125.94134) (xy 367.759401 -125.891899) (xy 367.77944 -125.844714) (xy 367.805611 -125.800634)
			(xy 367.82121 -125.780292) (xy 367.823496 -125.777752) (xy 367.825528 -125.774958) (xy 367.82883 -125.767338)
			(xy 367.829846 -125.764798) (xy 367.831237 -125.76068) (xy 367.832776 -125.752125) (xy 367.832894 -125.74778)
			(xy 367.832894 -125.726952) (xy 367.833039 -125.721513) (xy 367.835349 -125.710883) (xy 367.837466 -125.70587)
			(xy 367.842292 -125.69571) (xy 367.845594 -125.685296) (xy 367.845594 -125.664468) (xy 367.843308 -125.656594)
			(xy 367.835688 -125.636782) (xy 367.829846 -125.630178) (xy 367.817054 -125.614872) (xy 367.794401 -125.582038)
			(xy 367.784634 -125.564646) (xy 367.780062 -125.555756) (xy 367.778792 -125.553216) (xy 367.777014 -125.54966)
			(xy 367.764903 -125.523527) (xy 367.747807 -125.468526) (xy 367.739169 -125.411581) (xy 367.73866 -125.382782)
			(xy 367.739049 -125.35715) (xy 367.745857 -125.30634) (xy 367.759401 -125.256899) (xy 367.77944 -125.209714)
			(xy 367.805611 -125.165634) (xy 367.82121 -125.145292) (xy 367.823496 -125.142752) (xy 367.825528 -125.139958)
			(xy 367.82883 -125.132338) (xy 367.829846 -125.129798) (xy 367.831237 -125.12568) (xy 367.832776 -125.117125)
			(xy 367.832894 -125.11278) (xy 367.832894 -125.091952) (xy 367.833039 -125.086513) (xy 367.835349 -125.075883)
			(xy 367.837466 -125.07087) (xy 367.843816 -125.0569) (xy 367.847484 -125.047735) (xy 367.848296 -125.028028)
			(xy 367.84164 -125.009462) (xy 367.835434 -125.001782) (xy 367.82629 -124.991368) (xy 367.809861 -124.97075)
			(xy 367.782226 -124.925854) (xy 367.761021 -124.877587) (xy 367.746649 -124.826865) (xy 367.73938 -124.774649)
			(xy 367.738914 -124.74829) (xy 367.738914 -124.747782) (xy 367.739379 -124.720531) (xy 367.747138 -124.666583)
			(xy 367.762496 -124.614288) (xy 367.785139 -124.564712) (xy 367.814608 -124.518863) (xy 367.850302 -124.477674)
			(xy 367.891495 -124.441984) (xy 367.937347 -124.41252) (xy 367.986926 -124.389882) (xy 368.039222 -124.374529)
			(xy 368.093171 -124.366776) (xy 368.120422 -124.366274) (xy 368.158268 -124.368052) (xy 368.16538 -124.368814)
			(xy 368.177064 -124.366528) (xy 368.184223 -124.364931) (xy 368.197261 -124.358221) (xy 368.202718 -124.35332)
			(xy 368.213386 -124.342144) (xy 368.220414 -124.33414) (xy 368.227785 -124.314184) (xy 368.22761 -124.303536)
			(xy 368.099594 -123.326906) (xy 368.098163 -123.318801) (xy 368.090907 -123.304039) (xy 368.08537 -123.29795)
			(xy 368.079782 -123.292362) (xy 368.065558 -123.284742) (xy 368.05743 -123.283472) (xy 368.031059 -123.278581)
			(xy 367.97993 -123.26238) (xy 367.931571 -123.239183) (xy 367.886933 -123.209448) (xy 367.846896 -123.173759)
			(xy 367.812248 -123.132819) (xy 367.783669 -123.087432) (xy 367.761722 -123.038494) (xy 367.746839 -122.986965)
			(xy 367.739314 -122.933861) (xy 367.738914 -122.907044) (xy 367.739477 -122.876955) (xy 367.748921 -122.817521)
			(xy 367.767581 -122.760309) (xy 367.794995 -122.706737) (xy 367.830481 -122.658134) (xy 367.851436 -122.636534)
			(xy 367.854992 -122.632978) (xy 367.864136 -122.619262) (xy 367.86439 -122.619008) (xy 367.866422 -122.615706)
			(xy 367.868708 -122.611642) (xy 367.873026 -122.601228) (xy 367.87582 -122.594116) (xy 367.877852 -122.586496)
			(xy 367.878614 -122.57786) (xy 367.878614 -122.525282) (xy 367.878493 -122.520593) (xy 367.876703 -122.511387)
			(xy 367.875058 -122.506994) (xy 367.8682 -122.490738) (xy 367.86566 -122.485404) (xy 367.854992 -122.46991)
			(xy 367.85169 -122.466862) (xy 367.833793 -122.448531) (xy 367.80257 -122.407914) (xy 367.777062 -122.363485)
			(xy 367.757727 -122.316043) (xy 367.744914 -122.26644) (xy 367.741454 -122.241056) (xy 367.739676 -122.225308)
			(xy 367.73866 -122.195844) (xy 367.739051 -122.170213) (xy 367.745864 -122.119406) (xy 367.759413 -122.069967)
			(xy 367.779454 -122.022785) (xy 367.805628 -121.978709) (xy 367.82121 -121.958354) (xy 367.823496 -121.955814)
			(xy 367.825528 -121.95302) (xy 367.82883 -121.9454) (xy 367.829846 -121.94286) (xy 367.831234 -121.938741)
			(xy 367.832767 -121.930187) (xy 367.832894 -121.925842) (xy 367.832894 -121.905014) (xy 367.833032 -121.899573)
			(xy 367.835331 -121.888938) (xy 367.837466 -121.883932) (xy 367.842292 -121.873772) (xy 367.845594 -121.863358)
			(xy 367.845594 -121.84253) (xy 367.843308 -121.834656) (xy 367.835688 -121.814844) (xy 367.829846 -121.80824)
			(xy 367.817052 -121.792936) (xy 367.794394 -121.760104) (xy 367.784634 -121.742708) (xy 367.780062 -121.733818)
			(xy 367.778792 -121.731278) (xy 367.777014 -121.727722) (xy 367.764905 -121.701588) (xy 367.747815 -121.646587)
			(xy 367.739183 -121.589642) (xy 367.73866 -121.560844) (xy 367.739079 -121.535367) (xy 367.745847 -121.484863)
			(xy 367.759268 -121.435707) (xy 367.779104 -121.388772) (xy 367.805003 -121.34489) (xy 367.820448 -121.324624)
			(xy 367.825782 -121.317766) (xy 367.82883 -121.3104) (xy 367.829846 -121.30786) (xy 367.832386 -121.2977)
			(xy 367.827052 -121.257314) (xy 367.81486 -121.165112) (xy 367.811812 -121.153428) (xy 367.80978 -121.14784)
			(xy 367.806224 -121.14276) (xy 367.800414 -121.134258) (xy 367.789613 -121.116722) (xy 367.784634 -121.107708)
			(xy 367.780062 -121.098818) (xy 367.767099 -121.071935) (xy 367.748756 -121.015144) (xy 367.739467 -120.956192)
			(xy 367.738914 -120.926352) (xy 367.738914 -120.925844) (xy 367.739586 -120.893186) (xy 367.750704 -120.828824)
			(xy 367.761012 -120.797828) (xy 367.763044 -120.791986) (xy 367.764314 -120.780556) (xy 367.717578 -120.425718)
			(xy 367.68659 -120.189244) (xy 367.684812 -120.181116) (xy 366.902238 -117.599714) (xy 366.899396 -117.591552)
			(xy 366.889129 -117.577665) (xy 366.882172 -117.572536) (xy 366.878874 -117.57033) (xy 366.871728 -117.566885)
			(xy 366.867948 -117.565678) (xy 366.827816 -117.55374) (xy 366.824275 -117.552777) (xy 366.817007 -117.55176)
			(xy 366.813338 -117.551708) (xy 366.749076 -117.551708) (xy 366.733074 -117.557042) (xy 366.728756 -117.560598)
			(xy 366.706415 -117.577353) (xy 366.657834 -117.604888) (xy 366.605761 -117.625057) (xy 366.578642 -117.631718)
			(xy 366.55965 -117.635788) (xy 366.521093 -117.640492) (xy 366.50168 -117.641116) (xy 366.492536 -117.641116)
			(xy 366.488218 -117.641116) (xy 366.4839 -117.641116) (xy 366.476026 -117.640862) (xy 366.470184 -117.640862)
			(xy 366.456875 -117.639834) (xy 366.430434 -117.636151) (xy 366.417352 -117.633496) (xy 366.402861 -117.63035)
			(xy 366.374379 -117.622089) (xy 366.360456 -117.616986) (xy 366.332492 -117.605952) (xy 366.280173 -117.576349)
			(xy 366.256316 -117.558058) (xy 366.249458 -117.552724) (xy 366.241838 -117.550184) (xy 366.23778 -117.548816)
			(xy 366.229354 -117.54729) (xy 366.225074 -117.547136) (xy 366.20323 -117.547136) (xy 366.197789 -117.546999)
			(xy 366.187153 -117.5447) (xy 366.182148 -117.542564) (xy 366.168178 -117.536214) (xy 366.15901 -117.532529)
			(xy 366.139288 -117.531689) (xy 366.120699 -117.538332) (xy 366.11306 -117.544596) (xy 366.102646 -117.55374)
			(xy 366.082027 -117.570167) (xy 366.03713 -117.597797) (xy 365.988863 -117.618997) (xy 365.938141 -117.633366)
			(xy 365.885927 -117.640631) (xy 365.859568 -117.641116) (xy 365.85906 -117.641116) (xy 365.831321 -117.640616)
			(xy 365.776427 -117.632579) (xy 365.723275 -117.61668) (xy 365.672985 -117.593254) (xy 365.626615 -117.562794)
			(xy 365.585144 -117.525943) (xy 365.549444 -117.483476) (xy 365.520267 -117.436289) (xy 365.49823 -117.385375)
			(xy 365.483794 -117.331807) (xy 365.480092 -117.304312) (xy 365.478314 -117.289072) (xy 365.477298 -117.259608)
			(xy 365.477685 -117.233975) (xy 365.48449 -117.183165) (xy 365.498034 -117.133722) (xy 365.518071 -117.086536)
			(xy 365.544242 -117.042456) (xy 365.559848 -117.022118) (xy 365.56188 -117.019578) (xy 365.564166 -117.016784)
			(xy 365.567468 -117.009164) (xy 365.568484 -117.006624) (xy 365.569869 -117.002505) (xy 365.571394 -116.99395)
			(xy 365.571532 -116.989606) (xy 365.571532 -116.968778) (xy 365.571674 -116.963338) (xy 365.573981 -116.952706)
			(xy 365.576104 -116.947696) (xy 365.58093 -116.937536) (xy 365.584232 -116.927122) (xy 365.584232 -116.906294)
			(xy 365.581946 -116.89842) (xy 365.574326 -116.878608) (xy 365.568484 -116.872004) (xy 365.555693 -116.856698)
			(xy 365.533041 -116.823863) (xy 365.523272 -116.806472) (xy 365.5187 -116.797582) (xy 365.51743 -116.795042)
			(xy 365.515652 -116.791486) (xy 365.503538 -116.765354) (xy 365.486436 -116.710353) (xy 365.477794 -116.653407)
			(xy 365.477298 -116.624608) (xy 365.477685 -116.598975) (xy 365.48449 -116.548165) (xy 365.498034 -116.498722)
			(xy 365.518071 -116.451536) (xy 365.544242 -116.407456) (xy 365.559848 -116.387118) (xy 365.56188 -116.384578)
			(xy 365.564166 -116.381784) (xy 365.567468 -116.374164) (xy 365.568484 -116.371624) (xy 365.569869 -116.367505)
			(xy 365.571394 -116.35895) (xy 365.571532 -116.354606) (xy 365.571532 -116.333778) (xy 365.571674 -116.328338)
			(xy 365.573981 -116.317706) (xy 365.576104 -116.312696) (xy 365.582454 -116.298726) (xy 365.58613 -116.289561)
			(xy 365.586953 -116.269849) (xy 365.580295 -116.251277) (xy 365.574072 -116.243608) (xy 365.564928 -116.233194)
			(xy 365.548496 -116.212577) (xy 365.520855 -116.167682) (xy 365.499645 -116.119416) (xy 365.485268 -116.068693)
			(xy 365.477995 -116.016476) (xy 365.477552 -115.990116) (xy 365.477552 -115.989608) (xy 365.478037 -115.962355)
			(xy 365.485793 -115.908405) (xy 365.501147 -115.856107) (xy 365.523787 -115.806526) (xy 365.553252 -115.760672)
			(xy 365.588943 -115.719477) (xy 365.630133 -115.683781) (xy 365.675984 -115.65431) (xy 365.725562 -115.631663)
			(xy 365.777858 -115.616303) (xy 365.831807 -115.608541) (xy 365.85906 -115.6081) (xy 365.884606 -115.608513)
			(xy 365.93524 -115.615336) (xy 365.984512 -115.628854) (xy 366.03154 -115.648823) (xy 366.075484 -115.674887)
			(xy 366.095788 -115.690396) (xy 366.100614 -115.694206) (xy 366.10671 -115.697254) (xy 366.118394 -115.701064)
			(xy 366.1283 -115.70208) (xy 366.14989 -115.70208) (xy 366.155331 -115.702218) (xy 366.165966 -115.704517)
			(xy 366.170972 -115.706652) (xy 366.18037 -115.711224) (xy 366.184827 -115.713264) (xy 366.194289 -115.715816)
			(xy 366.199166 -115.716304) (xy 366.209072 -115.716812) (xy 366.218724 -115.71351) (xy 366.23625 -115.707668)
			(xy 366.24387 -115.701064) (xy 366.254153 -115.692336) (xy 366.275763 -115.676191) (xy 366.28705 -115.668806)
			(xy 366.287812 -115.668298) (xy 366.291114 -115.666012) (xy 366.29467 -115.663726) (xy 366.300258 -115.647978)
			(xy 366.302704 -115.640251) (xy 366.303106 -115.624058) (xy 366.30102 -115.616228) (xy 364.513622 -109.71911)
			(xy 364.511671 -109.71339) (xy 364.50551 -109.702995) (xy 364.50143 -109.698536) (xy 364.477808 -109.674152)
			(xy 364.472728 -109.672374) (xy 364.44677 -109.662846) (xy 364.397693 -109.63737) (xy 364.352805 -109.605081)
			(xy 364.313045 -109.566654) (xy 364.279244 -109.522893) (xy 364.25211 -109.474713) (xy 364.232211 -109.423123)
			(xy 364.225586 -109.396276) (xy 364.219998 -109.365796) (xy 364.217712 -109.350048) (xy 364.217712 -109.346492)
			(xy 364.217204 -109.34192) (xy 364.215453 -109.313659) (xy 364.219312 -109.25717) (xy 364.231471 -109.20187)
			(xy 364.251663 -109.148972) (xy 364.279445 -109.099636) (xy 364.296452 -109.076998) (xy 364.30338 -109.066992)
			(xy 364.307907 -109.043116) (xy 364.305088 -109.031278) (xy 362.51388 -103.121714) (xy 362.513118 -103.119174)
			(xy 362.512864 -103.118412) (xy 362.511848 -103.115364) (xy 360.650282 -96.973644) (xy 358.148636 -88.720168)
			(xy 358.14587 -88.712328) (xy 358.136153 -88.69885) (xy 358.129586 -88.693752) (xy 358.123744 -88.689434)
			(xy 358.108504 -88.684608) (xy 358.09809 -88.684608) (xy 358.09682 -88.684608) (xy 358.069549 -88.684123)
			(xy 358.01556 -88.676364) (xy 357.963226 -88.661001) (xy 357.91361 -88.638346) (xy 357.867723 -88.608862)
			(xy 357.8265 -88.573147) (xy 357.790778 -88.53193) (xy 357.761285 -88.486048) (xy 357.738622 -88.436436)
			(xy 357.72325 -88.384104) (xy 357.715482 -88.330117) (xy 357.715058 -88.302846) (xy 357.715528 -88.275836)
			(xy 357.723144 -88.222355) (xy 357.738214 -88.17048) (xy 357.760441 -88.121244) (xy 357.78938 -88.075629)
			(xy 357.824454 -88.034544) (xy 357.864964 -87.998807) (xy 357.88727 -87.983568) (xy 357.887524 -87.983314)
			(xy 357.894112 -87.978582) (xy 357.904218 -87.965908) (xy 357.907336 -87.958422) (xy 357.91013 -87.950548)
			(xy 357.910638 -87.934546) (xy 357.903018 -87.909654) (xy 357.729282 -87.337392) (xy 357.294942 -85.904578)
			(xy 357.28135 -85.857744) (xy 357.262287 -85.7621) (xy 357.252661 -85.66505) (xy 357.252016 -85.616288)
			(xy 357.252016 -85.614256) (xy 357.25227 -85.607652) (xy 357.25227 -85.60689) (xy 357.333804 -75.715622)
			(xy 357.442008 -62.603634) (xy 357.442008 -61.016134) (xy 357.439722 -61.01461) (xy 357.434134 -61.011562)
			(xy 357.4034 -61.004196) (xy 357.376246 -60.996958) (xy 357.324266 -60.975602) (xy 357.275978 -60.946859)
			(xy 357.232423 -60.911349) (xy 357.194542 -60.869841) (xy 357.163153 -60.823229) (xy 357.138934 -60.77252)
			(xy 357.122407 -60.718809) (xy 357.11393 -60.663257) (xy 357.113686 -60.607062) (xy 357.121679 -60.551437)
			(xy 357.137738 -60.497585) (xy 357.161515 -60.446668) (xy 357.192497 -60.399784) (xy 357.230016 -60.357947)
			(xy 357.27326 -60.32206) (xy 357.321297 -60.292898) (xy 357.347012 -60.281566) (xy 357.366316 -60.273946)
			(xy 357.372412 -60.271914) (xy 357.381302 -60.26912) (xy 357.390954 -60.266072) (xy 357.39832 -60.26023)
			(xy 357.407311 -60.25209) (xy 357.417107 -60.229942) (xy 357.417116 -60.217812) (xy 357.399082 -59.898026)
			(xy 357.388922 -59.717432) (xy 357.388922 -59.715908) (xy 357.306626 -58.808112) (xy 357.305965 -58.802494)
			(xy 357.302511 -58.791723) (xy 357.299768 -58.786776) (xy 357.296974 -58.782204) (xy 357.2891 -58.774076)
			(xy 357.28402 -58.770774) (xy 357.26143 -58.755571) (xy 357.220388 -58.719788) (xy 357.184836 -58.678545)
			(xy 357.155494 -58.632676) (xy 357.132956 -58.583108) (xy 357.117676 -58.530845) (xy 357.109964 -58.476944)
			(xy 357.109522 -58.449718) (xy 357.109977 -58.42316) (xy 357.117328 -58.370554) (xy 357.131891 -58.319473)
			(xy 357.153386 -58.2709) (xy 357.181399 -58.225771) (xy 357.215389 -58.184954) (xy 357.234744 -58.166762)
			(xy 357.235252 -58.166254) (xy 357.237538 -58.164222) (xy 357.2383 -58.16346) (xy 357.242364 -58.152538)
			(xy 357.244208 -58.147151) (xy 357.245743 -58.135871) (xy 357.245412 -58.130186) (xy 357.174292 -57.343548)
			(xy 357.172394 -57.321181) (xy 357.170364 -57.276333) (xy 357.170228 -57.253886) (xy 357.170228 -57.253378)
			(xy 357.170736 -57.215786) (xy 357.170736 -57.215278) (xy 357.187754 -56.129936) (xy 357.187754 -56.12638)
			(xy 356.985316 -52.520342) (xy 356.940358 -51.716686) (xy 356.939796 -51.712541) (xy 356.937506 -51.704497)
			(xy 356.935786 -51.700684) (xy 356.931722 -51.692302) (xy 356.923848 -51.68519) (xy 356.923594 -51.684936)
			(xy 356.91826 -51.68011) (xy 356.848918 -51.645566) (xy 356.843592 -51.643107) (xy 356.832176 -51.64042)
			(xy 356.826312 -51.640232) (xy 356.798372 -51.640232) (xy 356.785164 -51.64201) (xy 356.778814 -51.643788)
			(xy 356.772718 -51.647344) (xy 356.750444 -51.660224) (xy 356.703168 -51.680531) (xy 356.653589 -51.694291)
			(xy 356.60261 -51.701254) (xy 356.576884 -51.7017) (xy 356.57663 -51.7017) (xy 356.550054 -51.701242)
			(xy 356.497416 -51.693866) (xy 356.446313 -51.679252) (xy 356.397733 -51.657684) (xy 356.352619 -51.629579)
			(xy 356.311844 -51.595483) (xy 356.276199 -51.556055) (xy 356.260908 -51.534314) (xy 356.258114 -51.53025)
			(xy 356.248208 -51.520344) (xy 356.24008 -51.51374) (xy 356.21468 -51.497738) (xy 356.202488 -51.496722)
			(xy 356.174802 -51.493928) (xy 356.174294 -51.493928) (xy 356.135178 -51.489864) (xy 356.130836 -51.489508)
			(xy 356.122148 -51.490144) (xy 356.117906 -51.491134) (xy 356.115874 -51.491642) (xy 356.114604 -51.49215)
			(xy 356.112826 -51.492658) (xy 356.106476 -51.494944) (xy 356.096316 -51.501548) (xy 356.092252 -51.505866)
			(xy 356.084989 -51.513472) (xy 356.069742 -51.527961) (xy 356.061772 -51.534822) (xy 356.038242 -51.554045)
			(xy 355.986293 -51.58555) (xy 355.930006 -51.608422) (xy 355.870806 -51.62208) (xy 355.840538 -51.624738)
			(xy 355.82098 -51.6255) (xy 355.814122 -51.6255) (xy 355.812852 -51.6255) (xy 355.812598 -51.6255)
			(xy 355.793802 -51.624992) (xy 355.792278 -51.624992) (xy 355.789484 -51.624738) (xy 355.788468 -51.624738)
			(xy 355.762604 -51.622528) (xy 355.711776 -51.611986) (xy 355.66285 -51.594644) (xy 355.61673 -51.570821)
			(xy 355.57427 -51.540959) (xy 355.536256 -51.505611) (xy 355.519482 -51.4858) (xy 355.509322 -51.473354)
			(xy 355.509068 -51.472846) (xy 355.508814 -51.472846) (xy 355.50856 -51.472338) (xy 355.508306 -51.472084)
			(xy 355.506782 -51.470306) (xy 355.506274 -51.469544) (xy 355.505512 -51.468528) (xy 355.505258 -51.46802)
			(xy 355.499416 -51.45913) (xy 355.482642 -51.433481) (xy 355.45663 -51.377993) (xy 355.439836 -51.319057)
			(xy 355.435662 -51.288696) (xy 355.434646 -51.279298) (xy 355.433376 -51.25974) (xy 355.433122 -51.243992)
			(xy 355.433122 -51.243484) (xy 355.433122 -51.24323) (xy 355.434138 -51.214528) (xy 355.4349 -51.203606)
			(xy 355.43109 -51.193192) (xy 355.429083 -51.188095) (xy 355.423193 -51.178862) (xy 355.419406 -51.174904)
			(xy 355.41712 -51.172618) (xy 355.416104 -51.153568) (xy 355.416032 -51.144398) (xy 355.42164 -51.126954)
			(xy 355.427026 -51.119532) (xy 355.511608 -51.01209) (xy 355.511862 -51.011582) (xy 355.512116 -51.011328)
			(xy 355.51364 -51.00955) (xy 355.51491 -51.007772) (xy 355.515164 -51.007518) (xy 355.51618 -51.006248)
			(xy 355.516688 -51.005486) (xy 355.51999 -51.000914) (xy 355.523546 -50.99304) (xy 355.525175 -50.988577)
			(xy 355.526967 -50.979247) (xy 355.527102 -50.974498) (xy 355.527102 -50.953162) (xy 355.527246 -50.947723)
			(xy 355.529554 -50.937092) (xy 355.531674 -50.93208) (xy 355.538024 -50.91811) (xy 355.541693 -50.908944)
			(xy 355.542509 -50.889236) (xy 355.535856 -50.870666) (xy 355.529642 -50.862992) (xy 355.520498 -50.852578)
			(xy 355.504068 -50.83196) (xy 355.476432 -50.787065) (xy 355.455225 -50.738798) (xy 355.440851 -50.688076)
			(xy 355.433581 -50.63586) (xy 355.433122 -50.6095) (xy 355.433122 -50.608992) (xy 355.433586 -50.58174)
			(xy 355.441344 -50.527792) (xy 355.456701 -50.475497) (xy 355.479344 -50.425919) (xy 355.508813 -50.380069)
			(xy 355.544507 -50.33888) (xy 355.5857 -50.30319) (xy 355.631553 -50.273726) (xy 355.681132 -50.251088)
			(xy 355.733429 -50.235736) (xy 355.787378 -50.227983) (xy 355.81463 -50.227484) (xy 355.842235 -50.227974)
			(xy 355.896867 -50.235934) (xy 355.949782 -50.251684) (xy 355.999876 -50.274894) (xy 356.046102 -50.305081)
			(xy 356.087495 -50.341614) (xy 356.105714 -50.362358) (xy 356.105968 -50.362612) (xy 356.107746 -50.364644)
			(xy 356.115366 -50.37201) (xy 356.118644 -50.375043) (xy 356.126054 -50.380023) (xy 356.130098 -50.381916)
			(xy 356.147878 -50.38979) (xy 356.15372 -50.391822) (xy 356.15499 -50.39233) (xy 356.168198 -50.394108)
			(xy 356.218744 -50.394108) (xy 356.230936 -50.392584) (xy 356.247192 -50.38852) (xy 356.252018 -50.386234)
			(xy 356.263194 -50.3809) (xy 356.26802 -50.378614) (xy 356.277418 -50.371502) (xy 356.281482 -50.366676)
			(xy 356.281736 -50.366422) (xy 356.28326 -50.364644) (xy 356.283514 -50.36439) (xy 356.301506 -50.343595)
			(xy 356.34245 -50.306887) (xy 356.388241 -50.276442) (xy 356.437931 -50.25289) (xy 356.490489 -50.236719)
			(xy 356.544824 -50.228266) (xy 356.572312 -50.227484) (xy 356.576122 -50.227484) (xy 356.577138 -50.227484)
			(xy 356.58171 -50.227484) (xy 356.613628 -50.228558) (xy 356.676445 -50.240054) (xy 356.706678 -50.250344)
			(xy 356.71506 -50.253392) (xy 356.736904 -50.253392) (xy 356.744111 -50.253139) (xy 356.757922 -50.249012)
			(xy 356.764082 -50.245264) (xy 356.788466 -50.227992) (xy 356.788974 -50.227992) (xy 356.832662 -50.19675)
			(xy 356.83571 -50.193956) (xy 356.837742 -50.191924) (xy 356.844835 -50.184011) (xy 356.852444 -50.164196)
			(xy 356.852474 -50.15357) (xy 356.846632 -50.04943) (xy 356.846124 -50.038762) (xy 356.841298 -50.029364)
			(xy 356.838893 -50.024752) (xy 356.832494 -50.016554) (xy 356.828598 -50.013108) (xy 356.811072 -49.998376)
			(xy 356.810564 -49.998376) (xy 356.772718 -49.967134) (xy 356.768892 -49.964079) (xy 356.760325 -49.959343)
			(xy 356.7557 -49.957736) (xy 356.746048 -49.954688) (xy 356.735634 -49.955704) (xy 356.699312 -49.957482)
			(xy 356.699058 -49.957482) (xy 356.673209 -49.957056) (xy 356.621981 -49.950105) (xy 356.572151 -49.936335)
			(xy 356.524623 -49.915994) (xy 356.480259 -49.889453) (xy 356.45979 -49.873662) (xy 356.459536 -49.873408)
			(xy 356.452678 -49.868074) (xy 356.444804 -49.86528) (xy 356.440625 -49.863874) (xy 356.43194 -49.862349)
			(xy 356.427532 -49.862232) (xy 356.408228 -49.862232) (xy 356.402787 -49.862094) (xy 356.392152 -49.859796)
			(xy 356.387146 -49.85766) (xy 356.376986 -49.852834) (xy 356.370958 -49.850337) (xy 356.3581 -49.848143)
			(xy 356.351586 -49.848516) (xy 356.347932 -49.848952) (xy 356.340794 -49.850743) (xy 356.337362 -49.852072)
			(xy 356.331012 -49.854612) (xy 356.309304 -49.874565) (xy 356.260966 -49.908324) (xy 356.208061 -49.934348)
			(xy 356.151816 -49.952033) (xy 356.093538 -49.960969) (xy 356.064058 -49.961546) (xy 356.063804 -49.961546)
			(xy 356.03658 -49.961063) (xy 355.982673 -49.953394) (xy 355.930373 -49.93825) (xy 355.880709 -49.915929)
			(xy 355.834662 -49.886871) (xy 355.813614 -49.869598) (xy 355.805994 -49.863502) (xy 355.800406 -49.862232)
			(xy 355.773228 -49.862232) (xy 355.767787 -49.862094) (xy 355.757152 -49.859796) (xy 355.752146 -49.85766)
			(xy 355.741986 -49.852834) (xy 355.735958 -49.850337) (xy 355.7231 -49.848143) (xy 355.716586 -49.848516)
			(xy 355.712932 -49.848952) (xy 355.705794 -49.850743) (xy 355.702362 -49.852072) (xy 355.696012 -49.854612)
			(xy 355.674304 -49.874565) (xy 355.625966 -49.908324) (xy 355.573061 -49.934348) (xy 355.516816 -49.952033)
			(xy 355.458538 -49.960969) (xy 355.429058 -49.961546) (xy 355.428804 -49.961546) (xy 355.40158 -49.961063)
			(xy 355.347673 -49.953394) (xy 355.295373 -49.93825) (xy 355.245709 -49.915929) (xy 355.199662 -49.886871)
			(xy 355.178614 -49.869598) (xy 355.170994 -49.863502) (xy 355.165406 -49.862232) (xy 355.138228 -49.862232)
			(xy 355.132787 -49.862094) (xy 355.122152 -49.859796) (xy 355.117146 -49.85766) (xy 355.103176 -49.85131)
			(xy 355.094008 -49.847626) (xy 355.074287 -49.846787) (xy 355.055698 -49.85343) (xy 355.048058 -49.859692)
			(xy 355.037644 -49.868836) (xy 355.017025 -49.885263) (xy 354.972128 -49.912893) (xy 354.923861 -49.934093)
			(xy 354.873139 -49.948462) (xy 354.820925 -49.955726) (xy 354.794566 -49.956212) (xy 354.794058 -49.956212)
			(xy 354.766808 -49.955723) (xy 354.712865 -49.947962) (xy 354.660574 -49.932603) (xy 354.611002 -49.909959)
			(xy 354.565156 -49.880491) (xy 354.523971 -49.8448) (xy 354.488283 -49.80361) (xy 354.458821 -49.757761)
			(xy 354.436182 -49.708186) (xy 354.420829 -49.655894) (xy 354.413074 -49.60195) (xy 354.413074 -49.54745)
			(xy 354.420829 -49.493506) (xy 354.436182 -49.441214) (xy 354.458821 -49.391639) (xy 354.488283 -49.34579)
			(xy 354.523971 -49.3046) (xy 354.565156 -49.268909) (xy 354.611002 -49.239441) (xy 354.660574 -49.216797)
			(xy 354.712865 -49.201438) (xy 354.766808 -49.193677) (xy 354.794058 -49.193196) (xy 354.794312 -49.193196)
			(xy 354.819824 -49.193616) (xy 354.870394 -49.200404) (xy 354.919609 -49.21387) (xy 354.96659 -49.233775)
			(xy 355.0105 -49.259762) (xy 355.030786 -49.275238) (xy 355.03612 -49.279556) (xy 355.044502 -49.283112)
			(xy 355.047042 -49.284128) (xy 355.051161 -49.285517) (xy 355.059715 -49.287049) (xy 355.06406 -49.287176)
			(xy 355.084888 -49.287176) (xy 355.090329 -49.287314) (xy 355.100965 -49.289612) (xy 355.10597 -49.291748)
			(xy 355.11994 -49.298098) (xy 355.12603 -49.300609) (xy 355.139017 -49.302797) (xy 355.145594 -49.302416)
			(xy 355.155246 -49.300638) (xy 355.164644 -49.292256) (xy 355.165406 -49.291748) (xy 355.16566 -49.291494)
			(xy 355.16693 -49.290224) (xy 355.188481 -49.271091) (xy 355.236188 -49.238762) (xy 355.288162 -49.213866)
			(xy 355.343253 -49.196955) (xy 355.400244 -49.188401) (xy 355.429058 -49.187862) (xy 355.456227 -49.188323)
			(xy 355.510027 -49.195943) (xy 355.562226 -49.211038) (xy 355.61179 -49.233309) (xy 355.657738 -49.262315)
			(xy 355.67874 -49.279556) (xy 355.68382 -49.28362) (xy 355.686106 -49.285398) (xy 355.698806 -49.287176)
			(xy 355.719888 -49.287176) (xy 355.725329 -49.287314) (xy 355.735965 -49.289612) (xy 355.74097 -49.291748)
			(xy 355.75494 -49.298098) (xy 355.76103 -49.300609) (xy 355.774017 -49.302797) (xy 355.780594 -49.302416)
			(xy 355.790246 -49.300638) (xy 355.799644 -49.292256) (xy 355.800406 -49.291748) (xy 355.80066 -49.291494)
			(xy 355.80193 -49.290224) (xy 355.823481 -49.271091) (xy 355.871188 -49.238762) (xy 355.923162 -49.213866)
			(xy 355.978253 -49.196955) (xy 356.035244 -49.188401) (xy 356.064058 -49.187862) (xy 356.091227 -49.188323)
			(xy 356.145027 -49.195943) (xy 356.197226 -49.211038) (xy 356.24679 -49.233309) (xy 356.292738 -49.262315)
			(xy 356.31374 -49.279556) (xy 356.31882 -49.28362) (xy 356.321106 -49.285398) (xy 356.333806 -49.287176)
			(xy 356.354888 -49.287176) (xy 356.360329 -49.287314) (xy 356.370965 -49.289612) (xy 356.37597 -49.291748)
			(xy 356.386892 -49.297336) (xy 356.390226 -49.298918) (xy 356.397239 -49.301209) (xy 356.400862 -49.301908)
			(xy 356.414578 -49.302416) (xy 356.42423 -49.301146) (xy 356.437438 -49.294796) (xy 356.443534 -49.289716)
			(xy 356.464306 -49.271709) (xy 356.510052 -49.241222) (xy 356.559691 -49.217599) (xy 356.612201 -49.201328)
			(xy 356.6665 -49.192742) (xy 356.693978 -49.191926) (xy 356.704392 -49.191672) (xy 356.716076 -49.186592)
			(xy 356.719458 -49.18485) (xy 356.725707 -49.180515) (xy 356.728522 -49.177956) (xy 356.750112 -49.15535)
			(xy 356.75062 -49.154842) (xy 356.779322 -49.1236) (xy 356.779576 -49.123092) (xy 356.77983 -49.123092)
			(xy 356.780084 -49.122838) (xy 356.7811 -49.121568) (xy 356.786902 -49.113966) (xy 356.792908 -49.095824)
			(xy 356.792784 -49.086262) (xy 356.65537 -46.63948) (xy 356.524306 -44.305728) (xy 356.524052 -44.301664)
			(xy 355.9937 -40.375586) (xy 355.98993 -40.346131) (xy 355.985481 -40.28691) (xy 355.98481 -40.257222)
			(xy 355.978714 -39.8653) (xy 355.976682 -39.725346) (xy 355.976199 -39.720384) (xy 355.973519 -39.710783)
			(xy 355.971348 -39.706296) (xy 355.971348 -39.706042) (xy 355.952115 -39.666102) (xy 355.919995 -39.583471)
			(xy 355.895339 -39.498314) (xy 355.878343 -39.411304) (xy 355.869141 -39.323129) (xy 355.86797 -39.278814)
			(xy 355.8667 -39.196518) (xy 355.86035 -38.783514) (xy 355.86035 -38.78326) (xy 355.860096 -38.768528)
			(xy 355.860096 -38.76802) (xy 355.860504 -38.727689) (xy 355.86704 -38.647291) (xy 355.880054 -38.567685)
			(xy 355.899462 -38.489392) (xy 355.911912 -38.451028) (xy 355.914086 -38.443578) (xy 355.914337 -38.428069)
			(xy 355.91242 -38.420548) (xy 355.911404 -38.417246) (xy 355.897057 -38.377312) (xy 355.874399 -38.295531)
			(xy 355.858763 -38.212122) (xy 355.850261 -38.127687) (xy 355.849174 -38.085268) (xy 355.846634 -37.927534)
			(xy 355.845618 -37.854128) (xy 355.841554 -37.589714) (xy 355.841554 -37.58946) (xy 355.8413 -37.574728)
			(xy 355.8413 -37.57422) (xy 355.842002 -37.522073) (xy 355.852942 -37.418354) (xy 355.863144 -37.36721)
			(xy 355.868732 -37.342572) (xy 355.870764 -37.334444) (xy 355.863398 -37.260276) (xy 355.858064 -37.250878)
			(xy 355.834037 -37.207233) (xy 355.793865 -37.116055) (xy 355.763056 -37.021303) (xy 355.751892 -36.972748)
			(xy 355.749606 -36.96208) (xy 355.74859 -36.957) (xy 355.747828 -36.952682) (xy 355.745579 -36.945437)
			(xy 355.73743 -36.932649) (xy 355.731826 -36.927536) (xy 355.731572 -36.927282) (xy 355.729286 -36.92525)
			(xy 355.705664 -36.9062) (xy 355.694742 -36.900104) (xy 355.687122 -36.89731) (xy 355.679502 -36.896802)
			(xy 355.678486 -36.896802) (xy 355.651679 -36.895098) (xy 355.598902 -36.885102) (xy 355.548049 -36.867802)
			(xy 355.500126 -36.843541) (xy 355.456079 -36.812797) (xy 355.41678 -36.776179) (xy 355.383006 -36.734411)
			(xy 355.355425 -36.688318) (xy 355.334581 -36.638812) (xy 355.320888 -36.586872) (xy 355.317298 -36.560252)
			(xy 355.315774 -36.546536) (xy 355.314504 -36.515548) (xy 355.314997 -36.487477) (xy 355.323212 -36.431939)
			(xy 355.339471 -36.378203) (xy 355.363424 -36.327428) (xy 355.394555 -36.280707) (xy 355.432193 -36.23905)
			(xy 355.475525 -36.203353) (xy 355.523617 -36.174387) (xy 355.575433 -36.152776) (xy 355.60254 -36.14547)
			(xy 355.612954 -36.14293) (xy 355.62286 -36.13531) (xy 355.628194 -36.130738) (xy 355.633782 -36.123372)
			(xy 355.657404 -36.080446) (xy 355.657404 -36.079938) (xy 355.668072 -36.060634) (xy 355.671031 -36.05491)
			(xy 355.674249 -36.042437) (xy 355.674422 -36.035996) (xy 355.674422 -36.023042) (xy 355.67239 -36.009326)
			(xy 355.67112 -36.005262) (xy 355.65842 -35.96132) (xy 355.65334 -35.941508) (xy 355.651816 -35.935412)
			(xy 355.644436 -35.903059) (xy 355.633506 -35.837598) (xy 355.629972 -35.804602) (xy 355.628702 -35.791648)
			(xy 355.624892 -35.752532) (xy 355.60508 -35.55365) (xy 355.603963 -35.54786) (xy 355.599474 -35.536958)
			(xy 355.59619 -35.53206) (xy 355.59111 -35.525964) (xy 355.58984 -35.524694) (xy 355.581204 -35.517582)
			(xy 355.556058 -35.518852) (xy 355.553518 -35.518852) (xy 355.541072 -35.51936) (xy 355.515672 -35.519868)
			(xy 355.503226 -35.519868) (xy 355.45683 -35.518988) (xy 355.364497 -35.509669) (xy 355.273429 -35.491807)
			(xy 355.184417 -35.465557) (xy 355.09823 -35.431146) (xy 355.015615 -35.388872) (xy 354.976176 -35.36442)
			(xy 354.971858 -35.365182) (xy 354.969826 -35.36569) (xy 354.953582 -35.368458) (xy 354.92077 -35.371507)
			(xy 354.904294 -35.371786) (xy 354.900992 -35.371786) (xy 354.873912 -35.371312) (xy 354.820297 -35.363653)
			(xy 354.768303 -35.34849) (xy 354.718975 -35.326127) (xy 354.673305 -35.297015) (xy 354.63221 -35.261737)
			(xy 354.596517 -35.221003) (xy 354.566941 -35.175632) (xy 354.544078 -35.126534) (xy 354.528387 -35.074697)
			(xy 354.520183 -35.021162) (xy 354.519484 -34.994088) (xy 354.519484 -34.990024) (xy 354.519993 -34.96277)
			(xy 354.527784 -34.908821) (xy 354.543155 -34.856524) (xy 354.554028 -34.831528) (xy 354.556314 -34.826448)
			(xy 354.558092 -34.81832) (xy 354.552768 -34.800887) (xy 354.543242 -34.765699) (xy 354.539042 -34.747962)
			(xy 354.530914 -34.709608) (xy 354.522661 -34.663251) (xy 354.513887 -34.569494) (xy 354.513388 -34.52241)
			(xy 354.513822 -34.479823) (xy 354.521061 -34.394958) (xy 354.535513 -34.31102) (xy 354.557072 -34.228621)
			(xy 354.585582 -34.148361) (xy 354.602796 -34.109406) (xy 354.605982 -34.100273) (xy 354.605986 -34.080945)
			(xy 354.602796 -34.071814) (xy 354.585586 -34.032858) (xy 354.55709 -33.952595) (xy 354.535536 -33.870195)
			(xy 354.521082 -33.786259) (xy 354.513832 -33.701396) (xy 354.513388 -33.65881) (xy 354.513388 -33.657794)
			(xy 354.514016 -33.607927) (xy 354.524023 -33.508696) (xy 354.543895 -33.410961) (xy 354.558092 -33.363154)
			(xy 354.557076 -33.358582) (xy 354.55352 -33.348168) (xy 354.54971 -33.339532) (xy 354.54971 -33.339278)
			(xy 354.547678 -33.333944) (xy 354.536756 -33.304226) (xy 354.536756 -33.303972) (xy 354.53574 -33.301178)
			(xy 354.535232 -33.299146) (xy 354.534978 -33.298384) (xy 354.534978 -33.29813) (xy 354.530119 -33.280914)
			(xy 354.523249 -33.245804) (xy 354.521262 -33.228026) (xy 354.519484 -33.1978) (xy 354.519484 -33.188402)
			(xy 354.520092 -33.161234) (xy 354.528056 -33.107481) (xy 354.543566 -33.055401) (xy 354.566309 -33.006049)
			(xy 354.595824 -32.960423) (xy 354.631514 -32.919447) (xy 354.672658 -32.883949) (xy 354.718421 -32.854648)
			(xy 354.76788 -32.832137) (xy 354.820032 -32.816872) (xy 354.873822 -32.80916) (xy 354.900992 -32.808672)
			(xy 354.905564 -32.808672) (xy 354.921657 -32.80901) (xy 354.953705 -32.81206) (xy 354.969572 -32.814768)
			(xy 354.976938 -32.816038) (xy 355.016279 -32.791746) (xy 355.098645 -32.749723) (xy 355.184547 -32.715506)
			(xy 355.273248 -32.689388) (xy 355.363987 -32.671595) (xy 355.455983 -32.662279) (xy 355.50221 -32.661352)
			(xy 355.514402 -32.661352) (xy 355.56102 -32.66208) (xy 355.653818 -32.671157) (xy 355.745363 -32.688857)
			(xy 355.834856 -32.715026) (xy 355.921515 -32.749435) (xy 356.004584 -32.791784) (xy 356.044246 -32.816292)
			(xy 356.050596 -32.815022) (xy 356.05339 -32.814514) (xy 356.053898 -32.814514) (xy 356.05974 -32.813498)
			(xy 356.061772 -32.81299) (xy 356.065836 -32.812482) (xy 356.066852 -32.812482) (xy 356.080931 -32.810534)
			(xy 356.109282 -32.808497) (xy 356.123494 -32.808418) (xy 356.125272 -32.808418) (xy 356.162356 -32.810704)
			(xy 356.18127 -32.813011) (xy 356.21855 -32.820902) (xy 356.236778 -32.826452) (xy 356.237286 -32.826452)
			(xy 356.237794 -32.826706) (xy 356.24008 -32.827468) (xy 356.244906 -32.828992) (xy 356.254812 -32.830262)
			(xy 356.263236 -32.830583) (xy 356.279565 -32.826435) (xy 356.286816 -32.822134) (xy 356.326186 -32.79394)
			(xy 356.326694 -32.79394) (xy 356.355904 -32.772604) (xy 356.355904 -32.77235) (xy 356.359437 -32.769604)
			(xy 356.365571 -32.76309) (xy 356.368096 -32.759396) (xy 356.367588 -32.741108) (xy 356.367588 -32.722312)
			(xy 356.368022 -32.679725) (xy 356.375261 -32.59486) (xy 356.389713 -32.510922) (xy 356.411272 -32.428523)
			(xy 356.439781 -32.348263) (xy 356.456996 -32.309308) (xy 356.460183 -32.300175) (xy 356.460187 -32.280847)
			(xy 356.456996 -32.271716) (xy 356.439786 -32.23276) (xy 356.41129 -32.152497) (xy 356.389736 -32.070097)
			(xy 356.375281 -31.986161) (xy 356.368032 -31.901298) (xy 356.367588 -31.858712) (xy 356.367588 -31.841186)
			(xy 356.367588 -31.839662) (xy 356.368096 -31.820866) (xy 356.36579 -31.81752) (xy 356.360298 -31.811529)
			(xy 356.357174 -31.808928) (xy 356.35311 -31.80588) (xy 356.350824 -31.804102) (xy 356.349554 -31.80334)
			(xy 356.333298 -31.791656) (xy 356.325678 -31.786068) (xy 356.28961 -31.759906) (xy 356.284321 -31.756717)
			(xy 356.272631 -31.752743) (xy 356.266496 -31.752032) (xy 356.265988 -31.752032) (xy 356.261924 -31.751778)
			(xy 356.24262 -31.751778) (xy 356.235 -31.754064) (xy 356.208743 -31.761893) (xy 356.154684 -31.770822)
			(xy 356.127304 -31.771844) (xy 356.122986 -31.771844) (xy 356.118668 -31.772098) (xy 356.11308 -31.772098)
			(xy 356.10038 -31.771336) (xy 356.099872 -31.771336) (xy 356.072694 -31.769304) (xy 356.06609 -31.768542)
			(xy 356.059486 -31.76778) (xy 356.054914 -31.767526) (xy 356.028752 -31.774892) (xy 356.02291 -31.778448)
			(xy 355.989499 -31.797999) (xy 355.920173 -31.832458) (xy 355.848383 -31.861436) (xy 355.811582 -31.873444)
			(xy 355.76324 -31.888058) (xy 355.664346 -31.908567) (xy 355.563884 -31.918965) (xy 355.513386 -31.919672)
			(xy 355.506528 -31.919672) (xy 355.506274 -31.919926) (xy 355.461914 -31.919237) (xy 355.373576 -31.91095)
			(xy 355.286323 -31.894853) (xy 355.200844 -31.871072) (xy 355.117814 -31.839796) (xy 355.037889 -31.801271)
			(xy 354.999544 -31.778956) (xy 354.995988 -31.77667) (xy 354.990814 -31.774405) (xy 354.97979 -31.77196)
			(xy 354.974144 -31.771844) (xy 354.900992 -31.771844) (xy 354.873844 -31.771365) (xy 354.820096 -31.763667)
			(xy 354.767983 -31.748426) (xy 354.718557 -31.725952) (xy 354.672815 -31.696698) (xy 354.631683 -31.661255)
			(xy 354.595991 -31.620339) (xy 354.56646 -31.574776) (xy 354.543687 -31.525487) (xy 354.528131 -31.473467)
			(xy 354.520107 -31.419767) (xy 354.519484 -31.392622) (xy 354.519484 -31.389828) (xy 354.519977 -31.361597)
			(xy 354.528264 -31.305748) (xy 354.544692 -31.251731) (xy 354.556314 -31.225998) (xy 354.558092 -31.218632)
			(xy 354.544055 -31.171265) (xy 354.524293 -31.074463) (xy 354.51418 -30.976183) (xy 354.513388 -30.926786)
			(xy 354.513388 -30.922468) (xy 354.513824 -30.879882) (xy 354.521066 -30.795018) (xy 354.535522 -30.711081)
			(xy 354.557084 -30.628683) (xy 354.585597 -30.548425) (xy 354.602796 -30.509464) (xy 354.605974 -30.500331)
			(xy 354.605963 -30.48101) (xy 354.602796 -30.471872) (xy 354.585584 -30.432916) (xy 354.557083 -30.352654)
			(xy 354.535524 -30.270254) (xy 354.521065 -30.186318) (xy 354.513811 -30.101454) (xy 354.513388 -30.058868)
			(xy 354.513388 -30.05836) (xy 354.514032 -30.008319) (xy 354.524107 -29.908744) (xy 354.54409 -29.810676)
			(xy 354.558346 -29.762704) (xy 354.556568 -29.755084) (xy 354.554282 -29.750258) (xy 354.543275 -29.725168)
			(xy 354.527766 -29.672621) (xy 354.519945 -29.618394) (xy 354.519484 -29.591) (xy 354.519484 -29.590238)
			(xy 354.519945 -29.562983) (xy 354.527697 -29.509028) (xy 354.54305 -29.456725) (xy 354.56569 -29.407139)
			(xy 354.595157 -29.361281) (xy 354.630851 -29.320083) (xy 354.672044 -29.284385) (xy 354.717899 -29.254912)
			(xy 354.767482 -29.232266) (xy 354.819783 -29.216907) (xy 354.873737 -29.209148) (xy 354.900992 -29.20873)
			(xy 354.902008 -29.20873) (xy 354.91886 -29.208892) (xy 354.952438 -29.211815) (xy 354.969064 -29.214572)
			(xy 354.977192 -29.216096) (xy 355.017119 -29.191466) (xy 355.100757 -29.148959) (xy 355.188014 -29.114486)
			(xy 355.27812 -29.088353) (xy 355.37028 -29.070788) (xy 355.463682 -29.061947) (xy 355.510592 -29.06141)
			(xy 355.510846 -29.06141) (xy 355.557756 -29.061962) (xy 355.651158 -29.070797) (xy 355.74332 -29.088356)
			(xy 355.833427 -29.114485) (xy 355.920686 -29.148953) (xy 356.004326 -29.191455) (xy 356.044246 -29.216096)
			(xy 356.045262 -29.215842) (xy 356.050342 -29.214826) (xy 356.05212 -29.214572) (xy 356.068997 -29.211771)
			(xy 356.103085 -29.208845) (xy 356.120192 -29.20873) (xy 356.120954 -29.20873) (xy 356.149396 -29.209313)
			(xy 356.205637 -29.217855) (xy 356.232968 -29.225748) (xy 356.240334 -29.228034) (xy 356.263448 -29.228034)
			(xy 356.269186 -29.227826) (xy 356.280343 -29.225129) (xy 356.285546 -29.2227) (xy 356.286816 -29.222192)
			(xy 356.288086 -29.22143) (xy 356.289356 -29.220668) (xy 356.291642 -29.219398) (xy 356.312978 -29.20365)
			(xy 356.31374 -29.203142) (xy 356.336854 -29.186378) (xy 356.354126 -29.173932) (xy 356.356158 -29.172408)
			(xy 356.357174 -29.171646) (xy 356.360338 -29.169016) (xy 356.365825 -29.162885) (xy 356.368096 -29.159454)
			(xy 356.367588 -29.137356) (xy 356.367588 -29.12237) (xy 356.368024 -29.079784) (xy 356.375266 -28.99492)
			(xy 356.389721 -28.910983) (xy 356.411284 -28.828585) (xy 356.439796 -28.748327) (xy 356.456996 -28.709366)
			(xy 356.460175 -28.700233) (xy 356.460164 -28.680911) (xy 356.456996 -28.671774) (xy 356.439784 -28.632818)
			(xy 356.411283 -28.552556) (xy 356.389724 -28.470156) (xy 356.375265 -28.38622) (xy 356.36801 -28.301356)
			(xy 356.367588 -28.25877) (xy 356.368076 -28.211623) (xy 356.37685 -28.117738) (xy 356.385114 -28.071318)
			(xy 356.388761 -28.052831) (xy 356.397272 -28.016118) (xy 356.402132 -27.997912) (xy 356.412292 -27.96286)
			(xy 356.412292 -27.962606) (xy 356.410514 -27.954224) (xy 356.408228 -27.949144) (xy 356.407974 -27.948636)
			(xy 356.39743 -27.924428) (xy 356.382372 -27.873819) (xy 356.374453 -27.821614) (xy 356.373684 -27.79522)
			(xy 356.373684 -27.789886) (xy 356.374184 -27.762645) (xy 356.381966 -27.70872) (xy 356.397339 -27.65645)
			(xy 356.419992 -27.606899) (xy 356.449464 -27.561075) (xy 356.485156 -27.51991) (xy 356.52634 -27.484241)
			(xy 356.57218 -27.454793) (xy 356.621743 -27.432167) (xy 356.674021 -27.416822) (xy 356.72795 -27.40907)
			(xy 356.755192 -27.408632) (xy 356.771917 -27.40881) (xy 356.80524 -27.411731) (xy 356.82174 -27.414474)
			(xy 356.831392 -27.415998) (xy 356.883208 -27.385264) (xy 356.883716 -27.385264) (xy 356.896162 -27.378152)
			(xy 356.899972 -27.368754) (xy 356.919784 -27.295348) (xy 356.91953 -27.281632) (xy 356.917752 -27.275028)
			(xy 356.913434 -27.259534) (xy 356.910386 -27.2542) (xy 356.89869 -27.232664) (xy 356.880272 -27.187249)
			(xy 356.867811 -27.139853) (xy 356.861513 -27.091251) (xy 356.86111 -27.066748) (xy 356.86111 -27.057604)
			(xy 356.861364 -27.05354) (xy 356.861364 -27.052778) (xy 356.86365 -27.022552) (xy 356.866754 -26.998918)
			(xy 356.878101 -26.95262) (xy 356.895146 -26.908103) (xy 356.906068 -26.886916) (xy 356.918897 -26.863799)
			(xy 356.949966 -26.821021) (xy 356.986645 -26.782944) (xy 357.00716 -26.766266) (xy 357.009192 -26.764742)
			(xy 357.016304 -26.757884) (xy 357.029258 -26.742136) (xy 357.031798 -26.736802) (xy 357.034338 -26.725118)
			(xy 357.030274 -26.647394) (xy 357.029766 -26.634948) (xy 357.011478 -26.603452) (xy 357.006906 -26.59888)
			(xy 356.99573 -26.58745) (xy 356.98938 -26.583132) (xy 356.967481 -26.567859) (xy 356.92777 -26.532172)
			(xy 356.893418 -26.4913) (xy 356.865097 -26.446041) (xy 356.843358 -26.397277) (xy 356.828626 -26.345959)
			(xy 356.821187 -26.293089) (xy 356.820724 -26.266394) (xy 356.82121 -26.239143) (xy 356.828966 -26.185195)
			(xy 356.844321 -26.1329) (xy 356.866963 -26.083323) (xy 356.896429 -26.037473) (xy 356.93212 -25.996282)
			(xy 356.973311 -25.960591) (xy 357.019161 -25.931125) (xy 357.068738 -25.908483) (xy 357.121033 -25.893128)
			(xy 357.174981 -25.885372) (xy 357.229483 -25.885372) (xy 357.283431 -25.893128) (xy 357.335726 -25.908483)
			(xy 357.385303 -25.931125) (xy 357.431153 -25.960591) (xy 357.472344 -25.996282) (xy 357.508035 -26.037473)
			(xy 357.537501 -26.083323) (xy 357.560143 -26.1329) (xy 357.575498 -26.185195) (xy 357.583254 -26.239143)
			(xy 357.58374 -26.266394) (xy 357.583188 -26.295552) (xy 357.574317 -26.35319) (xy 357.55678 -26.408808)
			(xy 357.530986 -26.46111) (xy 357.497536 -26.508878) (xy 357.457207 -26.551002) (xy 357.434388 -26.569162)
			(xy 357.431594 -26.571194) (xy 357.42499 -26.577798) (xy 357.420418 -26.58364) (xy 357.416348 -26.589982)
			(xy 357.4117 -26.60431) (xy 357.411274 -26.611834) (xy 357.415084 -26.69667) (xy 357.41991 -26.706068)
			(xy 357.420926 -26.708354) (xy 357.429816 -26.72334) (xy 357.433372 -26.729182) (xy 357.44912 -26.745438)
			(xy 357.45547 -26.749756) (xy 357.47733 -26.764967) (xy 357.516982 -26.80052) (xy 357.551298 -26.841247)
			(xy 357.579611 -26.886353) (xy 357.601369 -26.934962) (xy 357.616149 -26.986127) (xy 357.623662 -27.038851)
			(xy 357.624126 -27.065478) (xy 357.624126 -27.072082) (xy 357.623223 -27.101233) (xy 357.613654 -27.158761)
			(xy 357.605076 -27.186636) (xy 357.603298 -27.191716) (xy 357.602028 -27.204162) (xy 357.601902 -27.207943)
			(xy 357.602674 -27.215468) (xy 357.603552 -27.219148) (xy 357.605584 -27.225244) (xy 357.64089 -27.29611)
			(xy 357.641906 -27.297634) (xy 357.6447 -27.30119) (xy 357.66375 -27.307286) (xy 357.701059 -27.319401)
			(xy 357.759233 -27.342846) (xy 364.823756 -27.342846) (xy 364.823756 -26.479246) (xy 364.824246 -26.449278)
			(xy 364.832069 -26.389856) (xy 364.847582 -26.331963) (xy 364.870518 -26.27659) (xy 364.900485 -26.224684)
			(xy 364.936972 -26.177134) (xy 364.979352 -26.134754) (xy 365.026902 -26.098267) (xy 365.078808 -26.0683)
			(xy 365.134181 -26.045364) (xy 365.192074 -26.029851) (xy 365.251496 -26.022028) (xy 365.311432 -26.022028)
			(xy 365.370854 -26.029851) (xy 365.428747 -26.045364) (xy 365.48412 -26.0683) (xy 365.536026 -26.098267)
			(xy 365.583576 -26.134754) (xy 365.625956 -26.177134) (xy 365.662443 -26.224684) (xy 365.69241 -26.27659)
			(xy 365.715346 -26.331963) (xy 365.723095 -26.360882) (xy 367.389662 -26.360882) (xy 367.393733 -26.30526)
			(xy 367.405859 -26.250823) (xy 367.425782 -26.198732) (xy 367.453078 -26.150097) (xy 367.487164 -26.105954)
			(xy 367.527313 -26.067245) (xy 367.572671 -26.034794) (xy 367.622271 -26.009293) (xy 367.675055 -25.991286)
			(xy 367.729898 -25.981156) (xy 367.785632 -25.979119) (xy 367.841069 -25.985219) (xy 367.895026 -25.999325)
			(xy 367.946355 -26.021137) (xy 367.993961 -26.050191) (xy 368.036829 -26.085866) (xy 368.074046 -26.127403)
			(xy 368.104819 -26.173916) (xy 368.128491 -26.224413) (xy 368.144559 -26.27782) (xy 368.150727 -26.319734)
			(xy 373.142 -26.319734) (xy 373.146071 -26.264112) (xy 373.158197 -26.209675) (xy 373.17812 -26.157584)
			(xy 373.205416 -26.108949) (xy 373.239502 -26.064806) (xy 373.279651 -26.026097) (xy 373.325009 -25.993646)
			(xy 373.374609 -25.968145) (xy 373.427393 -25.950138) (xy 373.482236 -25.940008) (xy 373.53797 -25.937971)
			(xy 373.593407 -25.944071) (xy 373.647364 -25.958177) (xy 373.698693 -25.979989) (xy 373.746299 -26.009043)
			(xy 373.775964 -26.03373) (xy 379.567946 -26.03373) (xy 379.572017 -25.978108) (xy 379.584143 -25.923671)
			(xy 379.604066 -25.87158) (xy 379.631362 -25.822945) (xy 379.665448 -25.778802) (xy 379.705597 -25.740093)
			(xy 379.750955 -25.707642) (xy 379.800555 -25.682141) (xy 379.853339 -25.664134) (xy 379.908182 -25.654004)
			(xy 379.963916 -25.651967) (xy 380.019353 -25.658067) (xy 380.07331 -25.672173) (xy 380.124639 -25.693985)
			(xy 380.172245 -25.723039) (xy 380.215113 -25.758714) (xy 380.25233 -25.800251) (xy 380.283103 -25.846764)
			(xy 380.306775 -25.897261) (xy 380.322843 -25.950668) (xy 380.330963 -26.005844) (xy 380.331472 -26.03373)
			(xy 380.330963 -26.061616) (xy 380.322843 -26.116792) (xy 380.306775 -26.170199) (xy 380.283103 -26.220696)
			(xy 380.25233 -26.267209) (xy 380.215113 -26.308746) (xy 380.172245 -26.344421) (xy 380.124639 -26.373475)
			(xy 380.07331 -26.395287) (xy 380.019353 -26.409393) (xy 379.963916 -26.415493) (xy 379.908182 -26.413456)
			(xy 379.853339 -26.403326) (xy 379.800555 -26.385319) (xy 379.750955 -26.359818) (xy 379.705597 -26.327367)
			(xy 379.665448 -26.288658) (xy 379.631362 -26.244515) (xy 379.604066 -26.19588) (xy 379.584143 -26.143789)
			(xy 379.572017 -26.089352) (xy 379.567946 -26.03373) (xy 373.775964 -26.03373) (xy 373.789167 -26.044718)
			(xy 373.826384 -26.086255) (xy 373.857157 -26.132768) (xy 373.880829 -26.183265) (xy 373.896897 -26.236672)
			(xy 373.905017 -26.291848) (xy 373.905526 -26.319734) (xy 373.905017 -26.34762) (xy 373.896897 -26.402796)
			(xy 373.880829 -26.456203) (xy 373.857157 -26.5067) (xy 373.826384 -26.553213) (xy 373.789167 -26.59475)
			(xy 373.746299 -26.630425) (xy 373.698693 -26.659479) (xy 373.647364 -26.681291) (xy 373.593407 -26.695397)
			(xy 373.53797 -26.701497) (xy 373.482236 -26.69946) (xy 373.427393 -26.68933) (xy 373.374609 -26.671323)
			(xy 373.325009 -26.645822) (xy 373.279651 -26.613371) (xy 373.239502 -26.574662) (xy 373.205416 -26.530519)
			(xy 373.17812 -26.481884) (xy 373.158197 -26.429793) (xy 373.146071 -26.375356) (xy 373.142 -26.319734)
			(xy 368.150727 -26.319734) (xy 368.152679 -26.332996) (xy 368.153188 -26.360882) (xy 368.152679 -26.388768)
			(xy 368.144559 -26.443944) (xy 368.128491 -26.497351) (xy 368.104819 -26.547848) (xy 368.074046 -26.594361)
			(xy 368.036829 -26.635898) (xy 367.993961 -26.671573) (xy 367.946355 -26.700627) (xy 367.895026 -26.722439)
			(xy 367.841069 -26.736545) (xy 367.785632 -26.742645) (xy 367.729898 -26.740608) (xy 367.675055 -26.730478)
			(xy 367.622271 -26.712471) (xy 367.572671 -26.68697) (xy 367.527313 -26.654519) (xy 367.487164 -26.61581)
			(xy 367.453078 -26.571667) (xy 367.425782 -26.523032) (xy 367.405859 -26.470941) (xy 367.393733 -26.416504)
			(xy 367.389662 -26.360882) (xy 365.723095 -26.360882) (xy 365.730859 -26.389856) (xy 365.738682 -26.449278)
			(xy 365.739172 -26.479246) (xy 365.739172 -26.971244) (xy 369.151152 -26.971244) (xy 369.155223 -26.915622)
			(xy 369.167349 -26.861185) (xy 369.187272 -26.809094) (xy 369.214568 -26.760459) (xy 369.248654 -26.716316)
			(xy 369.288803 -26.677607) (xy 369.334161 -26.645156) (xy 369.383761 -26.619655) (xy 369.436545 -26.601648)
			(xy 369.491388 -26.591518) (xy 369.547122 -26.589481) (xy 369.602559 -26.595581) (xy 369.656516 -26.609687)
			(xy 369.707845 -26.631499) (xy 369.755451 -26.660553) (xy 369.798319 -26.696228) (xy 369.835536 -26.737765)
			(xy 369.866309 -26.784278) (xy 369.889981 -26.834775) (xy 369.906049 -26.888182) (xy 369.914169 -26.943358)
			(xy 369.914678 -26.971244) (xy 369.914169 -26.99913) (xy 369.906049 -27.054306) (xy 369.889981 -27.107713)
			(xy 369.866309 -27.15821) (xy 369.835536 -27.204723) (xy 369.798319 -27.24626) (xy 369.755451 -27.281935)
			(xy 369.707845 -27.310989) (xy 369.656516 -27.332801) (xy 369.602559 -27.346907) (xy 369.547122 -27.353007)
			(xy 369.491388 -27.35097) (xy 369.436545 -27.34084) (xy 369.383761 -27.322833) (xy 369.334161 -27.297332)
			(xy 369.288803 -27.264881) (xy 369.248654 -27.226172) (xy 369.214568 -27.182029) (xy 369.187272 -27.133394)
			(xy 369.167349 -27.081303) (xy 369.155223 -27.026866) (xy 369.151152 -26.971244) (xy 365.739172 -26.971244)
			(xy 365.739172 -27.342846) (xy 365.738682 -27.372814) (xy 365.730859 -27.432236) (xy 365.715346 -27.490129)
			(xy 365.69241 -27.545502) (xy 365.662443 -27.597408) (xy 365.625956 -27.644958) (xy 365.583576 -27.687338)
			(xy 365.536026 -27.723825) (xy 365.48412 -27.753792) (xy 365.428747 -27.776728) (xy 365.370854 -27.792241)
			(xy 365.311432 -27.800064) (xy 365.251496 -27.800064) (xy 365.192074 -27.792241) (xy 365.134181 -27.776728)
			(xy 365.078808 -27.753792) (xy 365.026902 -27.723825) (xy 364.979352 -27.687338) (xy 364.936972 -27.644958)
			(xy 364.900485 -27.597408) (xy 364.870518 -27.545502) (xy 364.847582 -27.490129) (xy 364.832069 -27.432236)
			(xy 364.824246 -27.372814) (xy 364.823756 -27.342846) (xy 357.759233 -27.342846) (xy 357.773821 -27.348725)
			(xy 357.844049 -27.383685) (xy 357.877872 -27.403552) (xy 357.883703 -27.40686) (xy 357.896576 -27.410587)
			(xy 357.903272 -27.410918) (xy 357.909876 -27.410664) (xy 357.919561 -27.409655) (xy 357.939002 -27.408512)
			(xy 357.948738 -27.408378) (xy 357.949246 -27.408378) (xy 357.968296 -27.408886) (xy 357.977948 -27.409648)
			(xy 358.004957 -27.41218) (xy 358.057918 -27.423912) (xy 358.108685 -27.443025) (xy 358.156235 -27.469133)
			(xy 358.199608 -27.501711) (xy 358.237932 -27.540103) (xy 358.254554 -27.56154) (xy 358.256586 -27.56408)
			(xy 358.300983 -27.571473) (xy 358.388323 -27.593233) (xy 358.473348 -27.622773) (xy 358.555367 -27.659852)
			(xy 358.633711 -27.704169) (xy 358.707745 -27.755364) (xy 358.776865 -27.81302) (xy 358.809036 -27.844496)
			(xy 359.720134 -28.755594) (xy 359.754391 -28.790558) (xy 359.816609 -28.866134) (xy 359.84434 -28.90647)
			(xy 359.874312 -28.951428) (xy 359.880154 -28.95854) (xy 360.035856 -29.114242) (xy 367.147348 -29.114242)
			(xy 367.147348 -28.250642) (xy 367.147838 -28.220658) (xy 367.155666 -28.161202) (xy 367.171187 -28.103277)
			(xy 367.194136 -28.047873) (xy 367.22412 -27.995939) (xy 367.260626 -27.948363) (xy 367.303031 -27.905958)
			(xy 367.350607 -27.869452) (xy 367.402541 -27.839468) (xy 367.457945 -27.816519) (xy 367.51587 -27.800998)
			(xy 367.575326 -27.79317) (xy 367.635294 -27.79317) (xy 367.69475 -27.800998) (xy 367.752675 -27.816519)
			(xy 367.808079 -27.839468) (xy 367.860013 -27.869452) (xy 367.907589 -27.905958) (xy 367.949994 -27.948363)
			(xy 367.9865 -27.995939) (xy 368.016484 -28.047873) (xy 368.039433 -28.103277) (xy 368.054954 -28.161202)
			(xy 368.062782 -28.220658) (xy 368.063272 -28.250642) (xy 368.063272 -28.469082) (xy 372.052594 -28.469082)
			(xy 372.056665 -28.41346) (xy 372.068791 -28.359023) (xy 372.088714 -28.306932) (xy 372.11601 -28.258297)
			(xy 372.150096 -28.214154) (xy 372.190245 -28.175445) (xy 372.235603 -28.142994) (xy 372.285203 -28.117493)
			(xy 372.337987 -28.099486) (xy 372.39283 -28.089356) (xy 372.448564 -28.087319) (xy 372.504001 -28.093419)
			(xy 372.557958 -28.107525) (xy 372.609287 -28.129337) (xy 372.625343 -28.139136) (xy 376.698 -28.139136)
			(xy 376.702071 -28.083514) (xy 376.714197 -28.029077) (xy 376.73412 -27.976986) (xy 376.761416 -27.928351)
			(xy 376.795502 -27.884208) (xy 376.835651 -27.845499) (xy 376.881009 -27.813048) (xy 376.930609 -27.787547)
			(xy 376.983393 -27.76954) (xy 377.038236 -27.75941) (xy 377.09397 -27.757373) (xy 377.149407 -27.763473)
			(xy 377.203364 -27.777579) (xy 377.254693 -27.799391) (xy 377.302299 -27.828445) (xy 377.345167 -27.86412)
			(xy 377.382384 -27.905657) (xy 377.413157 -27.95217) (xy 377.436829 -28.002667) (xy 377.452897 -28.056074)
			(xy 377.461017 -28.11125) (xy 377.461526 -28.139136) (xy 377.968 -28.139136) (xy 377.972071 -28.083514)
			(xy 377.984197 -28.029077) (xy 378.00412 -27.976986) (xy 378.031416 -27.928351) (xy 378.065502 -27.884208)
			(xy 378.105651 -27.845499) (xy 378.151009 -27.813048) (xy 378.200609 -27.787547) (xy 378.253393 -27.76954)
			(xy 378.308236 -27.75941) (xy 378.36397 -27.757373) (xy 378.419407 -27.763473) (xy 378.473364 -27.777579)
			(xy 378.524693 -27.799391) (xy 378.572299 -27.828445) (xy 378.615167 -27.86412) (xy 378.652384 -27.905657)
			(xy 378.683157 -27.95217) (xy 378.706829 -28.002667) (xy 378.722897 -28.056074) (xy 378.731017 -28.11125)
			(xy 378.731526 -28.139136) (xy 378.731017 -28.167022) (xy 378.722897 -28.222198) (xy 378.706829 -28.275605)
			(xy 378.683157 -28.326102) (xy 378.652384 -28.372615) (xy 378.615167 -28.414152) (xy 378.572299 -28.449827)
			(xy 378.524693 -28.478881) (xy 378.473364 -28.500693) (xy 378.419407 -28.514799) (xy 378.36397 -28.520899)
			(xy 378.308236 -28.518862) (xy 378.253393 -28.508732) (xy 378.200609 -28.490725) (xy 378.151009 -28.465224)
			(xy 378.105651 -28.432773) (xy 378.065502 -28.394064) (xy 378.031416 -28.349921) (xy 378.00412 -28.301286)
			(xy 377.984197 -28.249195) (xy 377.972071 -28.194758) (xy 377.968 -28.139136) (xy 377.461526 -28.139136)
			(xy 377.461017 -28.167022) (xy 377.452897 -28.222198) (xy 377.436829 -28.275605) (xy 377.413157 -28.326102)
			(xy 377.382384 -28.372615) (xy 377.345167 -28.414152) (xy 377.302299 -28.449827) (xy 377.254693 -28.478881)
			(xy 377.203364 -28.500693) (xy 377.149407 -28.514799) (xy 377.09397 -28.520899) (xy 377.038236 -28.518862)
			(xy 376.983393 -28.508732) (xy 376.930609 -28.490725) (xy 376.881009 -28.465224) (xy 376.835651 -28.432773)
			(xy 376.795502 -28.394064) (xy 376.761416 -28.349921) (xy 376.73412 -28.301286) (xy 376.714197 -28.249195)
			(xy 376.702071 -28.194758) (xy 376.698 -28.139136) (xy 372.625343 -28.139136) (xy 372.656893 -28.158391)
			(xy 372.699761 -28.194066) (xy 372.736978 -28.235603) (xy 372.767751 -28.282116) (xy 372.791423 -28.332613)
			(xy 372.807491 -28.38602) (xy 372.815611 -28.441196) (xy 372.81612 -28.469082) (xy 372.815611 -28.496968)
			(xy 372.807491 -28.552144) (xy 372.791423 -28.605551) (xy 372.767751 -28.656048) (xy 372.736978 -28.702561)
			(xy 372.699761 -28.744098) (xy 372.656893 -28.779773) (xy 372.609287 -28.808827) (xy 372.557958 -28.830639)
			(xy 372.504001 -28.844745) (xy 372.448564 -28.850845) (xy 372.39283 -28.848808) (xy 372.337987 -28.838678)
			(xy 372.285203 -28.820671) (xy 372.235603 -28.79517) (xy 372.190245 -28.762719) (xy 372.150096 -28.72401)
			(xy 372.11601 -28.679867) (xy 372.088714 -28.631232) (xy 372.068791 -28.579141) (xy 372.056665 -28.524704)
			(xy 372.052594 -28.469082) (xy 368.063272 -28.469082) (xy 368.063272 -29.114242) (xy 368.062782 -29.144226)
			(xy 368.054954 -29.203682) (xy 368.039433 -29.261607) (xy 368.016484 -29.317011) (xy 367.9865 -29.368945)
			(xy 367.949994 -29.416521) (xy 367.907589 -29.458926) (xy 367.860013 -29.495432) (xy 367.808079 -29.525416)
			(xy 367.752675 -29.548365) (xy 367.69475 -29.563886) (xy 367.635294 -29.571714) (xy 367.575326 -29.571714)
			(xy 367.51587 -29.563886) (xy 367.457945 -29.548365) (xy 367.402541 -29.525416) (xy 367.350607 -29.495432)
			(xy 367.303031 -29.458926) (xy 367.260626 -29.416521) (xy 367.22412 -29.368945) (xy 367.194136 -29.317011)
			(xy 367.171187 -29.261607) (xy 367.155666 -29.203682) (xy 367.147838 -29.144226) (xy 367.147348 -29.114242)
			(xy 360.035856 -29.114242) (xy 360.133392 -29.211778) (xy 360.136802 -29.215063) (xy 360.144602 -29.22043)
			(xy 360.148886 -29.222446) (xy 360.153712 -29.224224) (xy 360.154982 -29.224732) (xy 360.15549 -29.224732)
			(xy 360.157268 -29.22524) (xy 360.157776 -29.225494) (xy 360.161586 -29.226764) (xy 360.162348 -29.227018)
			(xy 360.162602 -29.227018) (xy 360.172254 -29.23032) (xy 360.192066 -29.23794) (xy 360.194606 -29.238956)
			(xy 360.198162 -29.24048) (xy 360.199686 -29.241242) (xy 360.209592 -29.24556) (xy 360.215942 -29.248862)
			(xy 360.21645 -29.249116) (xy 360.231944 -29.257244) (xy 360.237532 -29.260546) (xy 360.253534 -29.270452)
			(xy 360.26344 -29.277056) (xy 360.267758 -29.280104) (xy 360.292271 -29.298457) (xy 360.335663 -29.34166)
			(xy 360.371598 -29.391239) (xy 360.399153 -29.44592) (xy 360.408982 -29.474922) (xy 360.416166 -29.499103)
			(xy 360.424831 -29.548797) (xy 360.426254 -29.573982) (xy 360.426254 -29.576014) (xy 360.426695 -29.582742)
			(xy 360.430685 -29.595617) (xy 360.434128 -29.601414) (xy 360.828336 -30.19171) (xy 360.831384 -30.196282)
			(xy 360.932476 -30.297374) (xy 361.555636 -30.92069) (xy 369.789456 -30.92069) (xy 369.789456 -30.05709)
			(xy 369.789946 -30.027106) (xy 369.797774 -29.96765) (xy 369.813295 -29.909725) (xy 369.836244 -29.854321)
			(xy 369.866228 -29.802387) (xy 369.902734 -29.754811) (xy 369.945139 -29.712406) (xy 369.992715 -29.6759)
			(xy 370.044649 -29.645916) (xy 370.100053 -29.622967) (xy 370.157978 -29.607446) (xy 370.217434 -29.599618)
			(xy 370.277402 -29.599618) (xy 370.336858 -29.607446) (xy 370.394783 -29.622967) (xy 370.450187 -29.645916)
			(xy 370.502121 -29.6759) (xy 370.549697 -29.712406) (xy 370.592102 -29.754811) (xy 370.628608 -29.802387)
			(xy 370.658592 -29.854321) (xy 370.681541 -29.909725) (xy 370.697062 -29.96765) (xy 370.70489 -30.027106)
			(xy 370.70538 -30.05709) (xy 370.70538 -30.376876) (xy 375.188988 -30.376876) (xy 375.189528 -30.347959)
			(xy 375.198248 -30.290788) (xy 375.215499 -30.235588) (xy 375.240887 -30.183625) (xy 375.273828 -30.136091)
			(xy 375.313569 -30.094075) (xy 375.336054 -30.075886) (xy 375.344867 -30.068285) (xy 375.355045 -30.047379)
			(xy 375.355612 -30.035754) (xy 375.355612 -29.955998) (xy 375.355056 -29.944368) (xy 375.344879 -29.923459)
			(xy 375.336054 -29.915866) (xy 375.313545 -29.897706) (xy 375.273813 -29.855678) (xy 375.240879 -29.808137)
			(xy 375.215495 -29.756169) (xy 375.198244 -29.700967) (xy 375.18952 -29.643794) (xy 375.188988 -29.614876)
			(xy 375.189474 -29.587625) (xy 375.19723 -29.533677) (xy 375.212585 -29.481382) (xy 375.235227 -29.431805)
			(xy 375.264693 -29.385955) (xy 375.300384 -29.344764) (xy 375.341575 -29.309073) (xy 375.387425 -29.279607)
			(xy 375.437002 -29.256965) (xy 375.489297 -29.24161) (xy 375.543245 -29.233854) (xy 375.597747 -29.233854)
			(xy 375.651695 -29.24161) (xy 375.70399 -29.256965) (xy 375.753567 -29.279607) (xy 375.799417 -29.309073)
			(xy 375.840608 -29.344764) (xy 375.876299 -29.385955) (xy 375.905765 -29.431805) (xy 375.928407 -29.481382)
			(xy 375.943762 -29.533677) (xy 375.951518 -29.587625) (xy 375.952004 -29.614876) (xy 375.951505 -29.643794)
			(xy 375.942777 -29.700968) (xy 375.925518 -29.756169) (xy 375.900123 -29.808131) (xy 375.867174 -29.855664)
			(xy 375.827427 -29.897678) (xy 375.804938 -29.915866) (xy 375.796146 -29.923487) (xy 375.785956 -29.944378)
			(xy 375.78538 -29.955998) (xy 375.78538 -30.035754) (xy 375.785909 -30.047387) (xy 375.796106 -30.068296)
			(xy 375.804938 -30.075886) (xy 375.827423 -30.094075) (xy 375.867156 -30.136097) (xy 375.900094 -30.183632)
			(xy 375.925482 -30.235594) (xy 375.942738 -30.290791) (xy 375.951468 -30.34796) (xy 375.952004 -30.376876)
			(xy 378.229114 -30.376876) (xy 378.229681 -30.347961) (xy 378.238399 -30.290792) (xy 378.255647 -30.235594)
			(xy 378.28103 -30.183632) (xy 378.313965 -30.136096) (xy 378.353698 -30.094077) (xy 378.37618 -30.075886)
			(xy 378.384997 -30.068289) (xy 378.395172 -30.04738) (xy 378.395738 -30.035754) (xy 378.395738 -29.955998)
			(xy 378.395208 -29.944364) (xy 378.385015 -29.923453) (xy 378.37618 -29.915866) (xy 378.353676 -29.897699)
			(xy 378.313943 -29.855674) (xy 378.281007 -29.808134) (xy 378.255622 -29.756168) (xy 378.23837 -29.700966)
			(xy 378.229646 -29.643793) (xy 378.229114 -29.614876) (xy 378.2296 -29.587625) (xy 378.237356 -29.533677)
			(xy 378.252711 -29.481382) (xy 378.275353 -29.431805) (xy 378.304819 -29.385955) (xy 378.34051 -29.344764)
			(xy 378.381701 -29.309073) (xy 378.427551 -29.279607) (xy 378.477128 -29.256965) (xy 378.529423 -29.24161)
			(xy 378.583371 -29.233854) (xy 378.637873 -29.233854) (xy 378.691821 -29.24161) (xy 378.744116 -29.256965)
			(xy 378.793693 -29.279607) (xy 378.839543 -29.309073) (xy 378.880734 -29.344764) (xy 378.916425 -29.385955)
			(xy 378.945891 -29.431805) (xy 378.968533 -29.481382) (xy 378.983888 -29.533677) (xy 378.991644 -29.587625)
			(xy 378.99213 -29.614876) (xy 378.991621 -29.643794) (xy 378.982894 -29.700966) (xy 378.965636 -29.756167)
			(xy 378.940243 -29.808129) (xy 378.907296 -29.855662) (xy 378.867551 -29.897677) (xy 378.845064 -29.915866)
			(xy 378.836276 -29.923492) (xy 378.826083 -29.944379) (xy 378.825506 -29.955998) (xy 378.825506 -30.035754)
			(xy 378.826026 -30.047388) (xy 378.836228 -30.068298) (xy 378.845064 -30.075886) (xy 378.867533 -30.094094)
			(xy 378.907271 -30.136109) (xy 378.940213 -30.18364) (xy 378.965604 -30.235598) (xy 378.982863 -30.290793)
			(xy 378.991594 -30.347961) (xy 378.99213 -30.376876) (xy 378.991644 -30.404127) (xy 378.983888 -30.458075)
			(xy 378.968533 -30.51037) (xy 378.945891 -30.559947) (xy 378.916425 -30.605797) (xy 378.880734 -30.646988)
			(xy 378.839543 -30.682679) (xy 378.793693 -30.712145) (xy 378.744116 -30.734787) (xy 378.691821 -30.750142)
			(xy 378.637873 -30.757898) (xy 378.583371 -30.757898) (xy 378.529423 -30.750142) (xy 378.477128 -30.734787)
			(xy 378.427551 -30.712145) (xy 378.381701 -30.682679) (xy 378.34051 -30.646988) (xy 378.304819 -30.605797)
			(xy 378.275353 -30.559947) (xy 378.252711 -30.51037) (xy 378.237356 -30.458075) (xy 378.2296 -30.404127)
			(xy 378.229114 -30.376876) (xy 375.952004 -30.376876) (xy 375.951518 -30.404127) (xy 375.943762 -30.458075)
			(xy 375.928407 -30.51037) (xy 375.905765 -30.559947) (xy 375.876299 -30.605797) (xy 375.840608 -30.646988)
			(xy 375.799417 -30.682679) (xy 375.753567 -30.712145) (xy 375.70399 -30.734787) (xy 375.651695 -30.750142)
			(xy 375.597747 -30.757898) (xy 375.543245 -30.757898) (xy 375.489297 -30.750142) (xy 375.437002 -30.734787)
			(xy 375.387425 -30.712145) (xy 375.341575 -30.682679) (xy 375.300384 -30.646988) (xy 375.264693 -30.605797)
			(xy 375.235227 -30.559947) (xy 375.212585 -30.51037) (xy 375.19723 -30.458075) (xy 375.189474 -30.404127)
			(xy 375.188988 -30.376876) (xy 370.70538 -30.376876) (xy 370.70538 -30.92069) (xy 370.70489 -30.950674)
			(xy 370.697062 -31.01013) (xy 370.681541 -31.068055) (xy 370.658592 -31.123459) (xy 370.628608 -31.175393)
			(xy 370.592102 -31.222969) (xy 370.549697 -31.265374) (xy 370.502121 -31.30188) (xy 370.450187 -31.331864)
			(xy 370.394783 -31.354813) (xy 370.336858 -31.370334) (xy 370.277402 -31.378162) (xy 370.217434 -31.378162)
			(xy 370.157978 -31.370334) (xy 370.100053 -31.354813) (xy 370.044649 -31.331864) (xy 369.992715 -31.30188)
			(xy 369.945139 -31.265374) (xy 369.902734 -31.222969) (xy 369.866228 -31.175393) (xy 369.836244 -31.123459)
			(xy 369.813295 -31.068055) (xy 369.797774 -31.01013) (xy 369.789946 -30.950674) (xy 369.789456 -30.92069)
			(xy 361.555636 -30.92069) (xy 361.947968 -31.31312) (xy 361.981662 -31.347611) (xy 362.042949 -31.422059)
			(xy 362.096763 -31.502075) (xy 362.142603 -31.586912) (xy 362.161836 -31.631128) (xy 362.466382 -32.353504)
			(xy 362.618386 -32.714184) (xy 367.147348 -32.714184) (xy 367.147348 -31.850584) (xy 367.147838 -31.8206)
			(xy 367.155666 -31.761144) (xy 367.171187 -31.703219) (xy 367.194136 -31.647815) (xy 367.22412 -31.595881)
			(xy 367.260626 -31.548305) (xy 367.303031 -31.5059) (xy 367.350607 -31.469394) (xy 367.402541 -31.43941)
			(xy 367.457945 -31.416461) (xy 367.51587 -31.40094) (xy 367.575326 -31.393112) (xy 367.635294 -31.393112)
			(xy 367.69475 -31.40094) (xy 367.752675 -31.416461) (xy 367.808079 -31.43941) (xy 367.860013 -31.469394)
			(xy 367.907589 -31.5059) (xy 367.949994 -31.548305) (xy 367.965016 -31.567882) (xy 375.298714 -31.567882)
			(xy 375.302785 -31.51226) (xy 375.314911 -31.457823) (xy 375.334834 -31.405732) (xy 375.36213 -31.357097)
			(xy 375.396216 -31.312954) (xy 375.436365 -31.274245) (xy 375.481723 -31.241794) (xy 375.531323 -31.216293)
			(xy 375.584107 -31.198286) (xy 375.63895 -31.188156) (xy 375.694684 -31.186119) (xy 375.750121 -31.192219)
			(xy 375.804078 -31.206325) (xy 375.855407 -31.228137) (xy 375.903013 -31.257191) (xy 375.945881 -31.292866)
			(xy 375.983098 -31.334403) (xy 376.013871 -31.380916) (xy 376.037543 -31.431413) (xy 376.053611 -31.48482)
			(xy 376.061731 -31.539996) (xy 376.06224 -31.567882) (xy 376.061731 -31.595768) (xy 376.053611 -31.650944)
			(xy 376.037543 -31.704351) (xy 376.030551 -31.719266) (xy 376.585478 -31.719266) (xy 376.589549 -31.663644)
			(xy 376.601675 -31.609207) (xy 376.621598 -31.557116) (xy 376.648894 -31.508481) (xy 376.68298 -31.464338)
			(xy 376.723129 -31.425629) (xy 376.768487 -31.393178) (xy 376.818087 -31.367677) (xy 376.870871 -31.34967)
			(xy 376.925714 -31.33954) (xy 376.981448 -31.337503) (xy 377.036885 -31.343603) (xy 377.090842 -31.357709)
			(xy 377.142171 -31.379521) (xy 377.189777 -31.408575) (xy 377.232645 -31.44425) (xy 377.269862 -31.485787)
			(xy 377.300635 -31.5323) (xy 377.324307 -31.582797) (xy 377.340375 -31.636204) (xy 377.344525 -31.664402)
			(xy 377.861066 -31.664402) (xy 377.865137 -31.60878) (xy 377.877263 -31.554343) (xy 377.897186 -31.502252)
			(xy 377.924482 -31.453617) (xy 377.958568 -31.409474) (xy 377.998717 -31.370765) (xy 378.044075 -31.338314)
			(xy 378.093675 -31.312813) (xy 378.146459 -31.294806) (xy 378.201302 -31.284676) (xy 378.257036 -31.282639)
			(xy 378.312473 -31.288739) (xy 378.36643 -31.302845) (xy 378.417759 -31.324657) (xy 378.465365 -31.353711)
			(xy 378.508233 -31.389386) (xy 378.54545 -31.430923) (xy 378.576223 -31.477436) (xy 378.599895 -31.527933)
			(xy 378.615963 -31.58134) (xy 378.624083 -31.636516) (xy 378.624592 -31.664402) (xy 378.624083 -31.692288)
			(xy 378.615963 -31.747464) (xy 378.607023 -31.777178) (xy 379.12624 -31.777178) (xy 379.130311 -31.721556)
			(xy 379.142437 -31.667119) (xy 379.16236 -31.615028) (xy 379.189656 -31.566393) (xy 379.223742 -31.52225)
			(xy 379.263891 -31.483541) (xy 379.309249 -31.45109) (xy 379.358849 -31.425589) (xy 379.411633 -31.407582)
			(xy 379.466476 -31.397452) (xy 379.52221 -31.395415) (xy 379.577647 -31.401515) (xy 379.631604 -31.415621)
			(xy 379.682933 -31.437433) (xy 379.730539 -31.466487) (xy 379.773407 -31.502162) (xy 379.810624 -31.543699)
			(xy 379.841397 -31.590212) (xy 379.865069 -31.640709) (xy 379.881137 -31.694116) (xy 379.889257 -31.749292)
			(xy 379.889766 -31.777178) (xy 379.889257 -31.805064) (xy 379.881137 -31.86024) (xy 379.865069 -31.913647)
			(xy 379.841397 -31.964144) (xy 379.810624 -32.010657) (xy 379.773407 -32.052194) (xy 379.730539 -32.087869)
			(xy 379.682933 -32.116923) (xy 379.631604 -32.138735) (xy 379.577647 -32.152841) (xy 379.52221 -32.158941)
			(xy 379.466476 -32.156904) (xy 379.411633 -32.146774) (xy 379.358849 -32.128767) (xy 379.309249 -32.103266)
			(xy 379.263891 -32.070815) (xy 379.223742 -32.032106) (xy 379.189656 -31.987963) (xy 379.16236 -31.939328)
			(xy 379.142437 -31.887237) (xy 379.130311 -31.8328) (xy 379.12624 -31.777178) (xy 378.607023 -31.777178)
			(xy 378.599895 -31.800871) (xy 378.576223 -31.851368) (xy 378.54545 -31.897881) (xy 378.508233 -31.939418)
			(xy 378.465365 -31.975093) (xy 378.417759 -32.004147) (xy 378.36643 -32.025959) (xy 378.312473 -32.040065)
			(xy 378.257036 -32.046165) (xy 378.201302 -32.044128) (xy 378.146459 -32.033998) (xy 378.093675 -32.015991)
			(xy 378.044075 -31.99049) (xy 377.998717 -31.958039) (xy 377.958568 -31.91933) (xy 377.924482 -31.875187)
			(xy 377.897186 -31.826552) (xy 377.877263 -31.774461) (xy 377.865137 -31.720024) (xy 377.861066 -31.664402)
			(xy 377.344525 -31.664402) (xy 377.348495 -31.69138) (xy 377.349004 -31.719266) (xy 377.348495 -31.747152)
			(xy 377.340375 -31.802328) (xy 377.324307 -31.855735) (xy 377.300635 -31.906232) (xy 377.269862 -31.952745)
			(xy 377.232645 -31.994282) (xy 377.189777 -32.029957) (xy 377.142171 -32.059011) (xy 377.090842 -32.080823)
			(xy 377.036885 -32.094929) (xy 376.981448 -32.101029) (xy 376.925714 -32.098992) (xy 376.870871 -32.088862)
			(xy 376.818087 -32.070855) (xy 376.768487 -32.045354) (xy 376.723129 -32.012903) (xy 376.68298 -31.974194)
			(xy 376.648894 -31.930051) (xy 376.621598 -31.881416) (xy 376.601675 -31.829325) (xy 376.589549 -31.774888)
			(xy 376.585478 -31.719266) (xy 376.030551 -31.719266) (xy 376.013871 -31.754848) (xy 375.983098 -31.801361)
			(xy 375.945881 -31.842898) (xy 375.903013 -31.878573) (xy 375.855407 -31.907627) (xy 375.804078 -31.929439)
			(xy 375.750121 -31.943545) (xy 375.694684 -31.949645) (xy 375.63895 -31.947608) (xy 375.584107 -31.937478)
			(xy 375.531323 -31.919471) (xy 375.481723 -31.89397) (xy 375.436365 -31.861519) (xy 375.396216 -31.82281)
			(xy 375.36213 -31.778667) (xy 375.334834 -31.730032) (xy 375.314911 -31.677941) (xy 375.302785 -31.623504)
			(xy 375.298714 -31.567882) (xy 367.965016 -31.567882) (xy 367.9865 -31.595881) (xy 368.016484 -31.647815)
			(xy 368.039433 -31.703219) (xy 368.054954 -31.761144) (xy 368.062782 -31.8206) (xy 368.063272 -31.850584)
			(xy 368.063272 -32.714184) (xy 368.062782 -32.744168) (xy 368.054954 -32.803624) (xy 368.039433 -32.861549)
			(xy 368.016484 -32.916953) (xy 367.9865 -32.968887) (xy 367.949994 -33.016463) (xy 367.907589 -33.058868)
			(xy 367.860013 -33.095374) (xy 367.808079 -33.125358) (xy 367.752675 -33.148307) (xy 367.69475 -33.163828)
			(xy 367.635294 -33.171656) (xy 367.575326 -33.171656) (xy 367.51587 -33.163828) (xy 367.457945 -33.148307)
			(xy 367.402541 -33.125358) (xy 367.350607 -33.095374) (xy 367.303031 -33.058868) (xy 367.260626 -33.016463)
			(xy 367.22412 -32.968887) (xy 367.194136 -32.916953) (xy 367.171187 -32.861549) (xy 367.155666 -32.803624)
			(xy 367.147838 -32.744168) (xy 367.147348 -32.714184) (xy 362.618386 -32.714184) (xy 362.657136 -32.806132)
			(xy 362.659224 -32.8108) (xy 362.664979 -32.819252) (xy 362.668566 -32.822896) (xy 362.675932 -32.830008)
			(xy 362.682536 -32.832548) (xy 362.707875 -32.842528) (xy 362.755665 -32.868639) (xy 362.799259 -32.901278)
			(xy 362.837771 -32.939782) (xy 362.870419 -32.983369) (xy 362.89654 -33.031154) (xy 362.915603 -33.082167)
			(xy 362.927223 -33.135371) (xy 362.929678 -33.162494) (xy 362.930694 -33.17875) (xy 362.930694 -33.190434)
			(xy 362.930236 -33.216341) (xy 362.923192 -33.267676) (xy 362.909291 -33.317593) (xy 362.899452 -33.341564)
			(xy 362.895388 -33.351216) (xy 362.895388 -33.360614) (xy 362.895415 -33.365825) (xy 362.897343 -33.376064)
			(xy 362.899198 -33.380934) (xy 363.379392 -34.520886) (xy 369.789456 -34.520886) (xy 369.789456 -33.657286)
			(xy 369.789946 -33.627302) (xy 369.797774 -33.567846) (xy 369.813295 -33.509921) (xy 369.836244 -33.454517)
			(xy 369.866228 -33.402583) (xy 369.902734 -33.355007) (xy 369.945139 -33.312602) (xy 369.992715 -33.276096)
			(xy 370.044649 -33.246112) (xy 370.100053 -33.223163) (xy 370.157978 -33.207642) (xy 370.217434 -33.199814)
			(xy 370.277402 -33.199814) (xy 370.336858 -33.207642) (xy 370.394783 -33.223163) (xy 370.450187 -33.246112)
			(xy 370.502121 -33.276096) (xy 370.549697 -33.312602) (xy 370.592102 -33.355007) (xy 370.628608 -33.402583)
			(xy 370.658592 -33.454517) (xy 370.681541 -33.509921) (xy 370.697062 -33.567846) (xy 370.70489 -33.627302)
			(xy 370.70538 -33.657286) (xy 370.70538 -34.520886) (xy 370.70489 -34.55087) (xy 370.697062 -34.610326)
			(xy 370.681541 -34.668251) (xy 370.658592 -34.723655) (xy 370.628608 -34.775589) (xy 370.592102 -34.823165)
			(xy 370.549697 -34.86557) (xy 370.502121 -34.902076) (xy 370.450187 -34.93206) (xy 370.394783 -34.955009)
			(xy 370.336858 -34.97053) (xy 370.277402 -34.978358) (xy 370.217434 -34.978358) (xy 370.157978 -34.97053)
			(xy 370.100053 -34.955009) (xy 370.044649 -34.93206) (xy 369.992715 -34.902076) (xy 369.945139 -34.86557)
			(xy 369.902734 -34.823165) (xy 369.866228 -34.775589) (xy 369.836244 -34.723655) (xy 369.813295 -34.668251)
			(xy 369.797774 -34.610326) (xy 369.789946 -34.55087) (xy 369.789456 -34.520886) (xy 363.379392 -34.520886)
			(xy 363.69278 -35.264852) (xy 378.202442 -35.264852) (xy 378.206513 -35.20923) (xy 378.218639 -35.154793)
			(xy 378.238562 -35.102702) (xy 378.265858 -35.054067) (xy 378.299944 -35.009924) (xy 378.340093 -34.971215)
			(xy 378.385451 -34.938764) (xy 378.435051 -34.913263) (xy 378.487835 -34.895256) (xy 378.542678 -34.885126)
			(xy 378.598412 -34.883089) (xy 378.653849 -34.889189) (xy 378.707806 -34.903295) (xy 378.759135 -34.925107)
			(xy 378.806741 -34.954161) (xy 378.849609 -34.989836) (xy 378.886826 -35.031373) (xy 378.917599 -35.077886)
			(xy 378.941271 -35.128383) (xy 378.957339 -35.18179) (xy 378.965459 -35.236966) (xy 378.965968 -35.264852)
			(xy 378.965459 -35.292738) (xy 378.957339 -35.347914) (xy 378.941271 -35.401321) (xy 378.917599 -35.451818)
			(xy 378.886826 -35.498331) (xy 378.849609 -35.539868) (xy 378.806741 -35.575543) (xy 378.759135 -35.604597)
			(xy 378.707806 -35.626409) (xy 378.653849 -35.640515) (xy 378.598412 -35.646615) (xy 378.542678 -35.644578)
			(xy 378.487835 -35.634448) (xy 378.435051 -35.616441) (xy 378.385451 -35.59094) (xy 378.340093 -35.558489)
			(xy 378.299944 -35.51978) (xy 378.265858 -35.475637) (xy 378.238562 -35.427002) (xy 378.218639 -35.374911)
			(xy 378.206513 -35.320474) (xy 378.202442 -35.264852) (xy 363.69278 -35.264852) (xy 363.950531 -35.876738)
			(xy 367.017298 -35.876738) (xy 367.021369 -35.821116) (xy 367.033495 -35.766679) (xy 367.053418 -35.714588)
			(xy 367.080714 -35.665953) (xy 367.1148 -35.62181) (xy 367.154949 -35.583101) (xy 367.200307 -35.55065)
			(xy 367.249907 -35.525149) (xy 367.302691 -35.507142) (xy 367.357534 -35.497012) (xy 367.413268 -35.494975)
			(xy 367.468705 -35.501075) (xy 367.522662 -35.515181) (xy 367.573991 -35.536993) (xy 367.621597 -35.566047)
			(xy 367.664465 -35.601722) (xy 367.701682 -35.643259) (xy 367.732455 -35.689772) (xy 367.756127 -35.740269)
			(xy 367.772195 -35.793676) (xy 367.780315 -35.848852) (xy 367.780824 -35.876738) (xy 371.088918 -35.876738)
			(xy 371.092989 -35.821116) (xy 371.105115 -35.766679) (xy 371.125038 -35.714588) (xy 371.152334 -35.665953)
			(xy 371.18642 -35.62181) (xy 371.226569 -35.583101) (xy 371.271927 -35.55065) (xy 371.321527 -35.525149)
			(xy 371.374311 -35.507142) (xy 371.429154 -35.497012) (xy 371.484888 -35.494975) (xy 371.540325 -35.501075)
			(xy 371.594282 -35.515181) (xy 371.645611 -35.536993) (xy 371.693217 -35.566047) (xy 371.736085 -35.601722)
			(xy 371.773302 -35.643259) (xy 371.804075 -35.689772) (xy 371.827747 -35.740269) (xy 371.843815 -35.793676)
			(xy 371.851935 -35.848852) (xy 371.852444 -35.876738) (xy 371.851935 -35.904624) (xy 371.843815 -35.9598)
			(xy 371.827747 -36.013207) (xy 371.804075 -36.063704) (xy 371.773302 -36.110217) (xy 371.736085 -36.151754)
			(xy 371.693217 -36.187429) (xy 371.645611 -36.216483) (xy 371.594282 -36.238295) (xy 371.540325 -36.252401)
			(xy 371.484888 -36.258501) (xy 371.429154 -36.256464) (xy 371.374311 -36.246334) (xy 371.321527 -36.228327)
			(xy 371.271927 -36.202826) (xy 371.226569 -36.170375) (xy 371.18642 -36.131666) (xy 371.152334 -36.087523)
			(xy 371.125038 -36.038888) (xy 371.105115 -35.986797) (xy 371.092989 -35.93236) (xy 371.088918 -35.876738)
			(xy 367.780824 -35.876738) (xy 367.780315 -35.904624) (xy 367.772195 -35.9598) (xy 367.756127 -36.013207)
			(xy 367.732455 -36.063704) (xy 367.701682 -36.110217) (xy 367.664465 -36.151754) (xy 367.621597 -36.187429)
			(xy 367.573991 -36.216483) (xy 367.522662 -36.238295) (xy 367.468705 -36.252401) (xy 367.413268 -36.258501)
			(xy 367.357534 -36.256464) (xy 367.302691 -36.246334) (xy 367.249907 -36.228327) (xy 367.200307 -36.202826)
			(xy 367.154949 -36.170375) (xy 367.1148 -36.131666) (xy 367.080714 -36.087523) (xy 367.053418 -36.038888)
			(xy 367.033495 -35.986797) (xy 367.021369 -35.93236) (xy 367.017298 -35.876738) (xy 363.950531 -35.876738)
			(xy 364.21727 -36.50996) (xy 368.913916 -36.50996) (xy 368.917987 -36.454338) (xy 368.930113 -36.399901)
			(xy 368.950036 -36.34781) (xy 368.977332 -36.299175) (xy 369.011418 -36.255032) (xy 369.051567 -36.216323)
			(xy 369.096925 -36.183872) (xy 369.146525 -36.158371) (xy 369.199309 -36.140364) (xy 369.254152 -36.130234)
			(xy 369.309886 -36.128197) (xy 369.365323 -36.134297) (xy 369.41928 -36.148403) (xy 369.470609 -36.170215)
			(xy 369.518215 -36.199269) (xy 369.561083 -36.234944) (xy 369.5983 -36.276481) (xy 369.629073 -36.322994)
			(xy 369.652745 -36.373491) (xy 369.668813 -36.426898) (xy 369.672738 -36.453572) (xy 372.228616 -36.453572)
			(xy 372.232687 -36.39795) (xy 372.244813 -36.343513) (xy 372.264736 -36.291422) (xy 372.292032 -36.242787)
			(xy 372.326118 -36.198644) (xy 372.366267 -36.159935) (xy 372.411625 -36.127484) (xy 372.461225 -36.101983)
			(xy 372.514009 -36.083976) (xy 372.568852 -36.073846) (xy 372.624586 -36.071809) (xy 372.680023 -36.077909)
			(xy 372.73398 -36.092015) (xy 372.785309 -36.113827) (xy 372.832915 -36.142881) (xy 372.875783 -36.178556)
			(xy 372.913 -36.220093) (xy 372.943773 -36.266606) (xy 372.953309 -36.286948) (xy 379.500382 -36.286948)
			(xy 379.504453 -36.231326) (xy 379.516579 -36.176889) (xy 379.536502 -36.124798) (xy 379.563798 -36.076163)
			(xy 379.597884 -36.03202) (xy 379.638033 -35.993311) (xy 379.683391 -35.96086) (xy 379.732991 -35.935359)
			(xy 379.785775 -35.917352) (xy 379.840618 -35.907222) (xy 379.896352 -35.905185) (xy 379.951789 -35.911285)
			(xy 380.005746 -35.925391) (xy 380.057075 -35.947203) (xy 380.104681 -35.976257) (xy 380.147549 -36.011932)
			(xy 380.184766 -36.053469) (xy 380.215539 -36.099982) (xy 380.239211 -36.150479) (xy 380.255279 -36.203886)
			(xy 380.263399 -36.259062) (xy 380.263908 -36.286948) (xy 380.263399 -36.314834) (xy 380.255279 -36.37001)
			(xy 380.239211 -36.423417) (xy 380.215539 -36.473914) (xy 380.184766 -36.520427) (xy 380.147549 -36.561964)
			(xy 380.104681 -36.597639) (xy 380.057075 -36.626693) (xy 380.005746 -36.648505) (xy 379.951789 -36.662611)
			(xy 379.896352 -36.668711) (xy 379.840618 -36.666674) (xy 379.785775 -36.656544) (xy 379.732991 -36.638537)
			(xy 379.683391 -36.613036) (xy 379.638033 -36.580585) (xy 379.597884 -36.541876) (xy 379.563798 -36.497733)
			(xy 379.536502 -36.449098) (xy 379.516579 -36.397007) (xy 379.504453 -36.34257) (xy 379.500382 -36.286948)
			(xy 372.953309 -36.286948) (xy 372.967445 -36.317103) (xy 372.983513 -36.37051) (xy 372.991633 -36.425686)
			(xy 372.992142 -36.453572) (xy 372.991633 -36.481458) (xy 372.983513 -36.536634) (xy 372.967445 -36.590041)
			(xy 372.943773 -36.640538) (xy 372.913 -36.687051) (xy 372.875783 -36.728588) (xy 372.832915 -36.764263)
			(xy 372.785309 -36.793317) (xy 372.73398 -36.815129) (xy 372.680023 -36.829235) (xy 372.624586 -36.835335)
			(xy 372.568852 -36.833298) (xy 372.514009 -36.823168) (xy 372.461225 -36.805161) (xy 372.411625 -36.77966)
			(xy 372.366267 -36.747209) (xy 372.326118 -36.7085) (xy 372.292032 -36.664357) (xy 372.264736 -36.615722)
			(xy 372.244813 -36.563631) (xy 372.232687 -36.509194) (xy 372.228616 -36.453572) (xy 369.672738 -36.453572)
			(xy 369.676933 -36.482074) (xy 369.677442 -36.50996) (xy 369.676933 -36.537846) (xy 369.668813 -36.593022)
			(xy 369.652745 -36.646429) (xy 369.629073 -36.696926) (xy 369.5983 -36.743439) (xy 369.561083 -36.784976)
			(xy 369.518215 -36.820651) (xy 369.470609 -36.849705) (xy 369.41928 -36.871517) (xy 369.365323 -36.885623)
			(xy 369.309886 -36.891723) (xy 369.254152 -36.889686) (xy 369.199309 -36.879556) (xy 369.146525 -36.861549)
			(xy 369.096925 -36.836048) (xy 369.051567 -36.803597) (xy 369.011418 -36.764888) (xy 368.977332 -36.720745)
			(xy 368.950036 -36.67211) (xy 368.930113 -36.620019) (xy 368.917987 -36.565582) (xy 368.913916 -36.50996)
			(xy 364.21727 -36.50996) (xy 364.550452 -37.300916) (xy 364.569172 -37.346963) (xy 364.598449 -37.44196)
			(xy 364.605157 -37.47516) (xy 366.05921 -37.47516) (xy 366.063281 -37.419538) (xy 366.075407 -37.365101)
			(xy 366.09533 -37.31301) (xy 366.122626 -37.264375) (xy 366.156712 -37.220232) (xy 366.196861 -37.181523)
			(xy 366.242219 -37.149072) (xy 366.291819 -37.123571) (xy 366.344603 -37.105564) (xy 366.399446 -37.095434)
			(xy 366.45518 -37.093397) (xy 366.510617 -37.099497) (xy 366.564574 -37.113603) (xy 366.615903 -37.135415)
			(xy 366.663509 -37.164469) (xy 366.706377 -37.200144) (xy 366.743594 -37.241681) (xy 366.774367 -37.288194)
			(xy 366.798039 -37.338691) (xy 366.814107 -37.392098) (xy 366.822227 -37.447274) (xy 366.822736 -37.47516)
			(xy 366.822227 -37.503046) (xy 366.814107 -37.558222) (xy 366.798039 -37.611629) (xy 366.774367 -37.662126)
			(xy 366.774214 -37.662358) (xy 368.248436 -37.662358) (xy 368.252507 -37.606736) (xy 368.264633 -37.552299)
			(xy 368.284556 -37.500208) (xy 368.311852 -37.451573) (xy 368.345938 -37.40743) (xy 368.386087 -37.368721)
			(xy 368.431445 -37.33627) (xy 368.481045 -37.310769) (xy 368.533829 -37.292762) (xy 368.588672 -37.282632)
			(xy 368.644406 -37.280595) (xy 368.699843 -37.286695) (xy 368.7538 -37.300801) (xy 368.805129 -37.322613)
			(xy 368.852735 -37.351667) (xy 368.895603 -37.387342) (xy 368.93282 -37.428879) (xy 368.963593 -37.475392)
			(xy 368.987265 -37.525889) (xy 369.003333 -37.579296) (xy 369.011453 -37.634472) (xy 369.011962 -37.662358)
			(xy 369.011453 -37.690244) (xy 369.003333 -37.74542) (xy 368.994699 -37.774118) (xy 379.764796 -37.774118)
			(xy 379.768867 -37.718496) (xy 379.780993 -37.664059) (xy 379.800916 -37.611968) (xy 379.828212 -37.563333)
			(xy 379.862298 -37.51919) (xy 379.902447 -37.480481) (xy 379.947805 -37.44803) (xy 379.997405 -37.422529)
			(xy 380.050189 -37.404522) (xy 380.105032 -37.394392) (xy 380.160766 -37.392355) (xy 380.216203 -37.398455)
			(xy 380.27016 -37.412561) (xy 380.321489 -37.434373) (xy 380.369095 -37.463427) (xy 380.411963 -37.499102)
			(xy 380.44918 -37.540639) (xy 380.479953 -37.587152) (xy 380.503625 -37.637649) (xy 380.519693 -37.691056)
			(xy 380.527813 -37.746232) (xy 380.528322 -37.774118) (xy 380.527813 -37.802004) (xy 380.519693 -37.85718)
			(xy 380.503625 -37.910587) (xy 380.479953 -37.961084) (xy 380.44918 -38.007597) (xy 380.411963 -38.049134)
			(xy 380.369095 -38.084809) (xy 380.321489 -38.113863) (xy 380.27016 -38.135675) (xy 380.216203 -38.149781)
			(xy 380.160766 -38.155881) (xy 380.105032 -38.153844) (xy 380.050189 -38.143714) (xy 379.997405 -38.125707)
			(xy 379.947805 -38.100206) (xy 379.902447 -38.067755) (xy 379.862298 -38.029046) (xy 379.828212 -37.984903)
			(xy 379.800916 -37.936268) (xy 379.780993 -37.884177) (xy 379.768867 -37.82974) (xy 379.764796 -37.774118)
			(xy 368.994699 -37.774118) (xy 368.987265 -37.798827) (xy 368.963593 -37.849324) (xy 368.93282 -37.895837)
			(xy 368.895603 -37.937374) (xy 368.852735 -37.973049) (xy 368.805129 -38.002103) (xy 368.7538 -38.023915)
			(xy 368.699843 -38.038021) (xy 368.644406 -38.044121) (xy 368.588672 -38.042084) (xy 368.533829 -38.031954)
			(xy 368.481045 -38.013947) (xy 368.431445 -37.988446) (xy 368.386087 -37.955995) (xy 368.345938 -37.917286)
			(xy 368.311852 -37.873143) (xy 368.284556 -37.824508) (xy 368.264633 -37.772417) (xy 368.252507 -37.71798)
			(xy 368.248436 -37.662358) (xy 366.774214 -37.662358) (xy 366.743594 -37.708639) (xy 366.706377 -37.750176)
			(xy 366.663509 -37.785851) (xy 366.615903 -37.814905) (xy 366.564574 -37.836717) (xy 366.510617 -37.850823)
			(xy 366.45518 -37.856923) (xy 366.399446 -37.854886) (xy 366.344603 -37.844756) (xy 366.291819 -37.826749)
			(xy 366.242219 -37.801248) (xy 366.196861 -37.768797) (xy 366.156712 -37.730088) (xy 366.122626 -37.685945)
			(xy 366.09533 -37.63731) (xy 366.075407 -37.585219) (xy 366.063281 -37.530782) (xy 366.05921 -37.47516)
			(xy 364.605157 -37.47516) (xy 364.618136 -37.539397) (xy 364.628038 -37.638309) (xy 364.628684 -37.688012)
			(xy 364.628684 -37.704522) (xy 364.628684 -37.705538) (xy 364.611684 -38.729951) (xy 372.000997 -38.729951)
			(xy 372.000997 -38.675449) (xy 372.008754 -38.621501) (xy 372.02411 -38.569206) (xy 372.046753 -38.519629)
			(xy 372.076221 -38.473779) (xy 372.111914 -38.43259) (xy 372.153106 -38.3969) (xy 372.198959 -38.367437)
			(xy 372.248538 -38.344798) (xy 372.300834 -38.329447) (xy 372.354783 -38.321695) (xy 372.382034 -38.321234)
			(xy 372.410337 -38.32176) (xy 372.466325 -38.330103) (xy 372.520464 -38.346631) (xy 372.571565 -38.37098)
			(xy 372.618505 -38.402615) (xy 372.660254 -38.440842) (xy 372.695892 -38.48482) (xy 372.71071 -38.50894)
			(xy 372.718328 -38.52096) (xy 372.738943 -38.540561) (xy 372.76417 -38.553704) (xy 372.792047 -38.559365)
			(xy 372.820403 -38.557104) (xy 372.84703 -38.547097) (xy 372.869856 -38.530122) (xy 372.878858 -38.5191)
			(xy 372.897073 -38.496248) (xy 372.93923 -38.455783) (xy 372.98706 -38.422212) (xy 373.039446 -38.396321)
			(xy 373.095165 -38.378714) (xy 373.152917 -38.369801) (xy 373.182134 -38.36924) (xy 373.209387 -38.369632)
			(xy 373.263338 -38.377394) (xy 373.315635 -38.392754) (xy 373.365214 -38.4154) (xy 373.411066 -38.44487)
			(xy 373.452258 -38.480566) (xy 373.48795 -38.521761) (xy 373.517417 -38.567616) (xy 373.540058 -38.617197)
			(xy 373.555414 -38.669495) (xy 373.56317 -38.723447) (xy 373.56317 -38.777953) (xy 373.555414 -38.831905)
			(xy 373.540058 -38.884203) (xy 373.517417 -38.933784) (xy 373.48795 -38.979639) (xy 373.452258 -39.020834)
			(xy 373.411066 -39.05653) (xy 373.365214 -39.086) (xy 373.315635 -39.108646) (xy 373.263338 -39.124006)
			(xy 373.209387 -39.131768) (xy 373.182134 -39.132256) (xy 373.15383 -39.13176) (xy 373.097841 -39.123412)
			(xy 373.043701 -39.10688) (xy 372.992599 -39.082526) (xy 372.945659 -39.050885) (xy 372.903912 -39.012654)
			(xy 372.868275 -38.968672) (xy 372.853458 -38.94455) (xy 372.845881 -38.932501) (xy 372.825258 -38.9129)
			(xy 372.800021 -38.899759) (xy 372.772137 -38.894102) (xy 372.743774 -38.896369) (xy 372.717142 -38.906383)
			(xy 372.694313 -38.923364) (xy 372.68531 -38.93439) (xy 372.66711 -38.957255) (xy 372.624951 -38.99772)
			(xy 372.577118 -39.031289) (xy 372.524728 -39.057178) (xy 372.469006 -39.074783) (xy 372.411252 -39.083692)
			(xy 372.382034 -39.08425) (xy 372.354783 -39.083705) (xy 372.300834 -39.075953) (xy 372.248538 -39.060602)
			(xy 372.198959 -39.037963) (xy 372.153106 -39.0085) (xy 372.111914 -38.97281) (xy 372.076221 -38.931621)
			(xy 372.046753 -38.885771) (xy 372.02411 -38.836194) (xy 372.008754 -38.783899) (xy 372.000997 -38.729951)
			(xy 364.611684 -38.729951) (xy 364.609126 -38.884098) (xy 364.604046 -39.18585) (xy 364.602691 -39.233199)
			(xy 364.592135 -39.327338) (xy 364.582964 -39.37381) (xy 364.556548 -39.500556) (xy 364.457829 -39.97198)
			(xy 374.195846 -39.97198) (xy 374.199917 -39.916358) (xy 374.212043 -39.861921) (xy 374.231966 -39.80983)
			(xy 374.259262 -39.761195) (xy 374.293348 -39.717052) (xy 374.333497 -39.678343) (xy 374.378855 -39.645892)
			(xy 374.428455 -39.620391) (xy 374.481239 -39.602384) (xy 374.536082 -39.592254) (xy 374.591816 -39.590217)
			(xy 374.647253 -39.596317) (xy 374.70121 -39.610423) (xy 374.752539 -39.632235) (xy 374.800145 -39.661289)
			(xy 374.843013 -39.696964) (xy 374.88023 -39.738501) (xy 374.911003 -39.785014) (xy 374.934675 -39.835511)
			(xy 374.950743 -39.888918) (xy 374.958863 -39.944094) (xy 374.959372 -39.97198) (xy 374.958863 -39.999866)
			(xy 374.950743 -40.055042) (xy 374.934675 -40.108449) (xy 374.911003 -40.158946) (xy 374.88023 -40.205459)
			(xy 374.843013 -40.246996) (xy 374.800145 -40.282671) (xy 374.752539 -40.311725) (xy 374.70121 -40.333537)
			(xy 374.647253 -40.347643) (xy 374.591816 -40.353743) (xy 374.536082 -40.351706) (xy 374.481239 -40.341576)
			(xy 374.428455 -40.323569) (xy 374.378855 -40.298068) (xy 374.333497 -40.265617) (xy 374.293348 -40.226908)
			(xy 374.259262 -40.182765) (xy 374.231966 -40.13413) (xy 374.212043 -40.082039) (xy 374.199917 -40.027602)
			(xy 374.195846 -39.97198) (xy 364.457829 -39.97198) (xy 364.294166 -40.753538) (xy 364.292427 -40.764506)
			(xy 364.297419 -40.78612) (xy 364.303818 -40.795194) (xy 364.307374 -40.799258) (xy 364.37316 -40.860726)
			(xy 364.377951 -40.86495) (xy 364.389129 -40.871122) (xy 364.395258 -40.872918) (xy 364.400846 -40.874188)
			(xy 364.414054 -40.874188) (xy 364.420912 -40.872156) (xy 364.446236 -40.8655) (xy 364.498109 -40.858364)
			(xy 364.52429 -40.857932) (xy 364.525052 -40.857932) (xy 364.553573 -40.858457) (xy 364.609986 -40.866906)
			(xy 364.664528 -40.88361) (xy 364.715997 -40.908201) (xy 364.763261 -40.940138) (xy 364.78464 -40.959024)
			(xy 364.785656 -40.96004) (xy 364.787942 -40.961818) (xy 364.79734 -40.966898) (xy 364.811564 -40.974518)
			(xy 364.82147 -40.976804) (xy 364.880652 -40.976804) (xy 364.885401 -40.976667) (xy 364.894733 -40.974882)
			(xy 364.899194 -40.973248) (xy 364.912402 -40.968168) (xy 364.915958 -40.966898) (xy 364.927642 -40.96004)
			(xy 364.928912 -40.95877) (xy 364.93069 -40.957246) (xy 364.951754 -40.93905) (xy 364.998161 -40.908317)
			(xy 365.048535 -40.88464) (xy 365.101811 -40.868522) (xy 365.156861 -40.860302) (xy 365.18469 -40.85971)
			(xy 365.194596 -40.859964) (xy 365.224137 -40.861268) (xy 365.282311 -40.87186) (xy 365.338157 -40.891291)
			(xy 365.390341 -40.919096) (xy 365.414306 -40.936418) (xy 365.437568 -40.954546) (xy 365.478744 -40.996761)
			(xy 365.512933 -41.04481) (xy 365.539319 -41.097549) (xy 365.557274 -41.153721) (xy 365.566369 -41.211987)
			(xy 365.56696 -41.241472) (xy 365.566499 -41.268736) (xy 365.55874 -41.322709) (xy 365.543378 -41.375027)
			(xy 365.520724 -41.424627) (xy 365.491241 -41.470496) (xy 365.473742 -41.491408) (xy 365.454874 -41.512394)
			(xy 365.412031 -41.549124) (xy 365.36425 -41.579151) (xy 365.312571 -41.601819) (xy 365.258119 -41.616637)
			(xy 365.230156 -41.62044) (xy 365.209582 -41.62298) (xy 365.203486 -41.623234) (xy 365.185198 -41.623234)
			(xy 365.157313 -41.622734) (xy 365.102141 -41.614579) (xy 365.048747 -41.598473) (xy 364.998268 -41.57476)
			(xy 364.951783 -41.543945) (xy 364.93069 -41.525698) (xy 364.928912 -41.524174) (xy 364.927642 -41.522904)
			(xy 364.915958 -41.516046) (xy 364.912402 -41.514776) (xy 364.899194 -41.509696) (xy 364.894741 -41.508032)
			(xy 364.885405 -41.506249) (xy 364.880652 -41.50614) (xy 364.827312 -41.50614) (xy 364.815374 -41.507664)
			(xy 364.809278 -41.509188) (xy 364.797086 -41.514268) (xy 364.79226 -41.517062) (xy 364.787942 -41.520872)
			(xy 364.78718 -41.521634) (xy 364.765728 -41.540957) (xy 364.718112 -41.573604) (xy 364.666146 -41.598758)
			(xy 364.611001 -41.615851) (xy 364.553919 -41.624499) (xy 364.525052 -41.625012) (xy 364.498689 -41.62458)
			(xy 364.446457 -41.617377) (xy 364.3957 -41.6031) (xy 364.347373 -41.582016) (xy 364.302383 -41.554521)
			(xy 364.28172 -41.538144) (xy 364.280196 -41.536874) (xy 364.270442 -41.530206) (xy 364.247254 -41.525819)
			(xy 364.235746 -41.528492) (xy 364.15091 -41.55821) (xy 364.141766 -41.562274) (xy 364.132897 -41.568167)
			(xy 364.120561 -41.585494) (xy 364.11789 -41.595802) (xy 363.759968 -43.305222) (xy 366.607344 -43.305222)
			(xy 366.607812 -43.277852) (xy 366.615628 -43.223672) (xy 366.631116 -43.171169) (xy 366.653957 -43.121422)
			(xy 366.683682 -43.075455) (xy 366.701324 -43.054524) (xy 366.701578 -43.05427) (xy 366.707151 -43.047174)
			(xy 366.713404 -43.030264) (xy 366.71377 -43.02125) (xy 366.71377 -42.954194) (xy 366.713423 -42.945176)
			(xy 366.707169 -42.928259) (xy 366.701578 -42.921174) (xy 366.701324 -42.921174) (xy 366.701324 -42.92092)
			(xy 366.683685 -42.899988) (xy 366.653972 -42.854016) (xy 366.631136 -42.804268) (xy 366.615645 -42.751767)
			(xy 366.607817 -42.697591) (xy 366.607344 -42.670222) (xy 366.607896 -42.641484) (xy 366.616514 -42.584659)
			(xy 366.633558 -42.529769) (xy 366.658643 -42.478057) (xy 366.691201 -42.430692) (xy 366.710468 -42.409364)
			(xy 366.717072 -42.402506) (xy 366.724184 -42.384472) (xy 366.724184 -42.295572) (xy 366.717072 -42.277538)
			(xy 366.710468 -42.27068) (xy 366.691222 -42.249333) (xy 366.65866 -42.201972) (xy 366.633571 -42.150264)
			(xy 366.616522 -42.095376) (xy 366.607899 -42.038553) (xy 366.607896 -41.981079) (xy 366.616515 -41.924255)
			(xy 366.633559 -41.869366) (xy 366.658644 -41.817655) (xy 366.691201 -41.770292) (xy 366.710468 -41.748964)
			(xy 366.717072 -41.742106) (xy 366.724184 -41.724072) (xy 366.724184 -41.635172) (xy 366.717072 -41.617138)
			(xy 366.710468 -41.61028) (xy 366.691213 -41.58894) (xy 366.658643 -41.541582) (xy 366.633547 -41.489874)
			(xy 366.616493 -41.434986) (xy 366.607867 -41.37816) (xy 366.607344 -41.349422) (xy 366.60783 -41.322171)
			(xy 366.615586 -41.268223) (xy 366.630941 -41.215928) (xy 366.653583 -41.166351) (xy 366.683049 -41.120501)
			(xy 366.71874 -41.07931) (xy 366.759931 -41.043619) (xy 366.805781 -41.014153) (xy 366.855358 -40.991511)
			(xy 366.907653 -40.976156) (xy 366.961601 -40.9684) (xy 367.016103 -40.9684) (xy 367.039224 -40.971724)
			(xy 374.894092 -40.971724) (xy 374.898163 -40.916102) (xy 374.910289 -40.861665) (xy 374.930212 -40.809574)
			(xy 374.957508 -40.760939) (xy 374.991594 -40.716796) (xy 375.031743 -40.678087) (xy 375.077101 -40.645636)
			(xy 375.126701 -40.620135) (xy 375.179485 -40.602128) (xy 375.234328 -40.591998) (xy 375.290062 -40.589961)
			(xy 375.345499 -40.596061) (xy 375.399456 -40.610167) (xy 375.450785 -40.631979) (xy 375.498391 -40.661033)
			(xy 375.541259 -40.696708) (xy 375.578476 -40.738245) (xy 375.609249 -40.784758) (xy 375.632921 -40.835255)
			(xy 375.648989 -40.888662) (xy 375.657109 -40.943838) (xy 375.657618 -40.971724) (xy 375.657109 -40.99961)
			(xy 375.648989 -41.054786) (xy 375.632921 -41.108193) (xy 375.609249 -41.15869) (xy 375.578476 -41.205203)
			(xy 375.541259 -41.24674) (xy 375.498391 -41.282415) (xy 375.450785 -41.311469) (xy 375.399456 -41.333281)
			(xy 375.345499 -41.347387) (xy 375.290062 -41.353487) (xy 375.234328 -41.35145) (xy 375.179485 -41.34132)
			(xy 375.126701 -41.323313) (xy 375.077101 -41.297812) (xy 375.031743 -41.265361) (xy 374.991594 -41.226652)
			(xy 374.957508 -41.182509) (xy 374.930212 -41.133874) (xy 374.910289 -41.081783) (xy 374.898163 -41.027346)
			(xy 374.894092 -40.971724) (xy 367.039224 -40.971724) (xy 367.070051 -40.976156) (xy 367.122346 -40.991511)
			(xy 367.171923 -41.014153) (xy 367.217773 -41.043619) (xy 367.258964 -41.07931) (xy 367.294655 -41.120501)
			(xy 367.324121 -41.166351) (xy 367.346763 -41.215928) (xy 367.362118 -41.268223) (xy 367.369874 -41.322171)
			(xy 367.37036 -41.349422) (xy 367.369834 -41.378161) (xy 367.361209 -41.434987) (xy 367.344159 -41.489877)
			(xy 367.319068 -41.541589) (xy 367.286505 -41.588952) (xy 367.267236 -41.61028) (xy 367.260632 -41.617138)
			(xy 367.25352 -41.635172) (xy 367.25352 -41.724072) (xy 367.260632 -41.742106) (xy 367.267236 -41.748964)
			(xy 367.28653 -41.770271) (xy 367.319098 -41.817636) (xy 367.344191 -41.86935) (xy 367.361242 -41.924245)
			(xy 367.369863 -41.981075) (xy 367.369861 -42.038557) (xy 367.361234 -42.095387) (xy 367.34418 -42.150279)
			(xy 367.319082 -42.201992) (xy 367.28651 -42.249354) (xy 367.267236 -42.27068) (xy 367.260632 -42.277538)
			(xy 367.25352 -42.295572) (xy 367.25352 -42.384472) (xy 367.260632 -42.402506) (xy 367.267236 -42.409364)
			(xy 367.286513 -42.430686) (xy 367.319079 -42.478049) (xy 367.344171 -42.529762) (xy 367.36122 -42.584654)
			(xy 367.369841 -42.641483) (xy 367.37036 -42.670222) (xy 367.369917 -42.697593) (xy 367.362095 -42.751774)
			(xy 367.346601 -42.804277) (xy 367.326044 -42.849038) (xy 369.192046 -42.849038) (xy 369.196117 -42.793416)
			(xy 369.208243 -42.738979) (xy 369.228166 -42.686888) (xy 369.255462 -42.638253) (xy 369.289548 -42.59411)
			(xy 369.329697 -42.555401) (xy 369.375055 -42.52295) (xy 369.424655 -42.497449) (xy 369.477439 -42.479442)
			(xy 369.532282 -42.469312) (xy 369.588016 -42.467275) (xy 369.643453 -42.473375) (xy 369.69741 -42.487481)
			(xy 369.748739 -42.509293) (xy 369.796345 -42.538347) (xy 369.839213 -42.574022) (xy 369.87643 -42.615559)
			(xy 369.907203 -42.662072) (xy 369.930875 -42.712569) (xy 369.946943 -42.765976) (xy 369.955063 -42.821152)
			(xy 369.955424 -42.84091) (xy 375.233182 -42.84091) (xy 375.237253 -42.785288) (xy 375.249379 -42.730851)
			(xy 375.269302 -42.67876) (xy 375.296598 -42.630125) (xy 375.330684 -42.585982) (xy 375.370833 -42.547273)
			(xy 375.416191 -42.514822) (xy 375.465791 -42.489321) (xy 375.518575 -42.471314) (xy 375.573418 -42.461184)
			(xy 375.629152 -42.459147) (xy 375.684589 -42.465247) (xy 375.738546 -42.479353) (xy 375.789875 -42.501165)
			(xy 375.837481 -42.530219) (xy 375.880349 -42.565894) (xy 375.917566 -42.607431) (xy 375.948339 -42.653944)
			(xy 375.972011 -42.704441) (xy 375.988079 -42.757848) (xy 375.996199 -42.813024) (xy 375.996708 -42.84091)
			(xy 375.996199 -42.868796) (xy 375.988079 -42.923972) (xy 375.972011 -42.977379) (xy 375.948339 -43.027876)
			(xy 375.917566 -43.074389) (xy 375.880349 -43.115926) (xy 375.837481 -43.151601) (xy 375.789875 -43.180655)
			(xy 375.738546 -43.202467) (xy 375.684589 -43.216573) (xy 375.629152 -43.222673) (xy 375.573418 -43.220636)
			(xy 375.518575 -43.210506) (xy 375.465791 -43.192499) (xy 375.416191 -43.166998) (xy 375.370833 -43.134547)
			(xy 375.330684 -43.095838) (xy 375.296598 -43.051695) (xy 375.269302 -43.00306) (xy 375.249379 -42.950969)
			(xy 375.237253 -42.896532) (xy 375.233182 -42.84091) (xy 369.955424 -42.84091) (xy 369.955572 -42.849038)
			(xy 369.955063 -42.876924) (xy 369.946943 -42.9321) (xy 369.930875 -42.985507) (xy 369.907203 -43.036004)
			(xy 369.87643 -43.082517) (xy 369.839213 -43.124054) (xy 369.796345 -43.159729) (xy 369.748739 -43.188783)
			(xy 369.69741 -43.210595) (xy 369.643453 -43.224701) (xy 369.588016 -43.230801) (xy 369.532282 -43.228764)
			(xy 369.477439 -43.218634) (xy 369.424655 -43.200627) (xy 369.375055 -43.175126) (xy 369.329697 -43.142675)
			(xy 369.289548 -43.103966) (xy 369.255462 -43.059823) (xy 369.228166 -43.011188) (xy 369.208243 -42.959097)
			(xy 369.196117 -42.90466) (xy 369.192046 -42.849038) (xy 367.326044 -42.849038) (xy 367.323754 -42.854024)
			(xy 367.294024 -42.899989) (xy 367.27638 -42.92092) (xy 367.276126 -42.921174) (xy 367.270536 -42.928258)
			(xy 367.264293 -42.945177) (xy 367.263934 -42.954194) (xy 367.263934 -43.02125) (xy 367.264308 -43.030265)
			(xy 367.270543 -43.047183) (xy 367.276126 -43.05427) (xy 367.27638 -43.05427) (xy 367.27638 -43.054524)
			(xy 367.293994 -43.075476) (xy 367.32371 -43.121443) (xy 367.346551 -43.171186) (xy 367.362048 -43.223682)
			(xy 367.369883 -43.277854) (xy 367.37036 -43.305222) (xy 367.369874 -43.332473) (xy 367.362118 -43.386421)
			(xy 367.346763 -43.438716) (xy 367.324121 -43.488293) (xy 367.294655 -43.534143) (xy 367.258964 -43.575334)
			(xy 367.217773 -43.611025) (xy 367.171923 -43.640491) (xy 367.122346 -43.663133) (xy 367.070051 -43.678488)
			(xy 367.016103 -43.686244) (xy 366.961601 -43.686244) (xy 366.907653 -43.678488) (xy 366.855358 -43.663133)
			(xy 366.805781 -43.640491) (xy 366.759931 -43.611025) (xy 366.71874 -43.575334) (xy 366.683049 -43.534143)
			(xy 366.653583 -43.488293) (xy 366.630941 -43.438716) (xy 366.615586 -43.386421) (xy 366.60783 -43.332473)
			(xy 366.607344 -43.305222) (xy 363.759968 -43.305222) (xy 363.746034 -43.37177) (xy 363.74578 -43.373294)
			(xy 363.690538 -43.73626) (xy 368.513104 -43.73626) (xy 368.517175 -43.680638) (xy 368.529301 -43.626201)
			(xy 368.549224 -43.57411) (xy 368.57652 -43.525475) (xy 368.610606 -43.481332) (xy 368.650755 -43.442623)
			(xy 368.696113 -43.410172) (xy 368.745713 -43.384671) (xy 368.798497 -43.366664) (xy 368.85334 -43.356534)
			(xy 368.909074 -43.354497) (xy 368.964511 -43.360597) (xy 369.018468 -43.374703) (xy 369.069797 -43.396515)
			(xy 369.117403 -43.425569) (xy 369.160271 -43.461244) (xy 369.197488 -43.502781) (xy 369.228261 -43.549294)
			(xy 369.236487 -43.566842) (xy 371.633494 -43.566842) (xy 371.637565 -43.51122) (xy 371.649691 -43.456783)
			(xy 371.669614 -43.404692) (xy 371.69691 -43.356057) (xy 371.730996 -43.311914) (xy 371.771145 -43.273205)
			(xy 371.816503 -43.240754) (xy 371.866103 -43.215253) (xy 371.918887 -43.197246) (xy 371.97373 -43.187116)
			(xy 372.029464 -43.185079) (xy 372.084901 -43.191179) (xy 372.138858 -43.205285) (xy 372.190187 -43.227097)
			(xy 372.237793 -43.256151) (xy 372.280661 -43.291826) (xy 372.317878 -43.333363) (xy 372.348651 -43.379876)
			(xy 372.372323 -43.430373) (xy 372.388391 -43.48378) (xy 372.396511 -43.538956) (xy 372.39702 -43.566842)
			(xy 372.396511 -43.594728) (xy 372.388391 -43.649904) (xy 372.372323 -43.703311) (xy 372.348651 -43.753808)
			(xy 372.317878 -43.800321) (xy 372.280661 -43.841858) (xy 372.262574 -43.85691) (xy 373.019826 -43.85691)
			(xy 373.023897 -43.801288) (xy 373.036023 -43.746851) (xy 373.055946 -43.69476) (xy 373.083242 -43.646125)
			(xy 373.117328 -43.601982) (xy 373.157477 -43.563273) (xy 373.202835 -43.530822) (xy 373.252435 -43.505321)
			(xy 373.305219 -43.487314) (xy 373.360062 -43.477184) (xy 373.415796 -43.475147) (xy 373.471233 -43.481247)
			(xy 373.52519 -43.495353) (xy 373.576519 -43.517165) (xy 373.624125 -43.546219) (xy 373.666993 -43.581894)
			(xy 373.70421 -43.623431) (xy 373.734983 -43.669944) (xy 373.758655 -43.720441) (xy 373.774723 -43.773848)
			(xy 373.782843 -43.829024) (xy 373.783352 -43.85691) (xy 373.782843 -43.884796) (xy 373.774723 -43.939972)
			(xy 373.758655 -43.993379) (xy 373.734983 -44.043876) (xy 373.70421 -44.090389) (xy 373.666993 -44.131926)
			(xy 373.624125 -44.167601) (xy 373.576519 -44.196655) (xy 373.52519 -44.218467) (xy 373.471233 -44.232573)
			(xy 373.415796 -44.238673) (xy 373.360062 -44.236636) (xy 373.305219 -44.226506) (xy 373.252435 -44.208499)
			(xy 373.202835 -44.182998) (xy 373.157477 -44.150547) (xy 373.117328 -44.111838) (xy 373.083242 -44.067695)
			(xy 373.055946 -44.01906) (xy 373.036023 -43.966969) (xy 373.023897 -43.912532) (xy 373.019826 -43.85691)
			(xy 372.262574 -43.85691) (xy 372.237793 -43.877533) (xy 372.190187 -43.906587) (xy 372.138858 -43.928399)
			(xy 372.084901 -43.942505) (xy 372.029464 -43.948605) (xy 371.97373 -43.946568) (xy 371.918887 -43.936438)
			(xy 371.866103 -43.918431) (xy 371.816503 -43.89293) (xy 371.771145 -43.860479) (xy 371.730996 -43.82177)
			(xy 371.69691 -43.777627) (xy 371.669614 -43.728992) (xy 371.649691 -43.676901) (xy 371.637565 -43.622464)
			(xy 371.633494 -43.566842) (xy 369.236487 -43.566842) (xy 369.251933 -43.599791) (xy 369.268001 -43.653198)
			(xy 369.276121 -43.708374) (xy 369.27663 -43.73626) (xy 369.276121 -43.764146) (xy 369.268001 -43.819322)
			(xy 369.251933 -43.872729) (xy 369.228261 -43.923226) (xy 369.197488 -43.969739) (xy 369.160271 -44.011276)
			(xy 369.117403 -44.046951) (xy 369.069797 -44.076005) (xy 369.018468 -44.097817) (xy 368.964511 -44.111923)
			(xy 368.909074 -44.118023) (xy 368.85334 -44.115986) (xy 368.798497 -44.105856) (xy 368.745713 -44.087849)
			(xy 368.696113 -44.062348) (xy 368.650755 -44.029897) (xy 368.610606 -43.991188) (xy 368.57652 -43.947045)
			(xy 368.549224 -43.89841) (xy 368.529301 -43.846319) (xy 368.517175 -43.791882) (xy 368.513104 -43.73626)
			(xy 363.690538 -43.73626) (xy 363.480782 -45.114464) (xy 368.36553 -45.114464) (xy 368.369601 -45.058842)
			(xy 368.381727 -45.004405) (xy 368.40165 -44.952314) (xy 368.428946 -44.903679) (xy 368.463032 -44.859536)
			(xy 368.503181 -44.820827) (xy 368.548539 -44.788376) (xy 368.598139 -44.762875) (xy 368.650923 -44.744868)
			(xy 368.705766 -44.734738) (xy 368.7615 -44.732701) (xy 368.816937 -44.738801) (xy 368.870894 -44.752907)
			(xy 368.922223 -44.774719) (xy 368.969829 -44.803773) (xy 369.012697 -44.839448) (xy 369.042679 -44.87291)
			(xy 375.233182 -44.87291) (xy 375.237253 -44.817288) (xy 375.249379 -44.762851) (xy 375.269302 -44.71076)
			(xy 375.296598 -44.662125) (xy 375.330684 -44.617982) (xy 375.370833 -44.579273) (xy 375.416191 -44.546822)
			(xy 375.465791 -44.521321) (xy 375.518575 -44.503314) (xy 375.573418 -44.493184) (xy 375.629152 -44.491147)
			(xy 375.684589 -44.497247) (xy 375.738546 -44.511353) (xy 375.789875 -44.533165) (xy 375.837481 -44.562219)
			(xy 375.880349 -44.597894) (xy 375.917566 -44.639431) (xy 375.948339 -44.685944) (xy 375.972011 -44.736441)
			(xy 375.988079 -44.789848) (xy 375.996199 -44.845024) (xy 375.996708 -44.87291) (xy 375.996199 -44.900796)
			(xy 375.988079 -44.955972) (xy 375.972011 -45.009379) (xy 375.948339 -45.059876) (xy 375.917566 -45.106389)
			(xy 375.880349 -45.147926) (xy 375.837481 -45.183601) (xy 375.789875 -45.212655) (xy 375.738546 -45.234467)
			(xy 375.684589 -45.248573) (xy 375.629152 -45.254673) (xy 375.573418 -45.252636) (xy 375.518575 -45.242506)
			(xy 375.465791 -45.224499) (xy 375.416191 -45.198998) (xy 375.370833 -45.166547) (xy 375.330684 -45.127838)
			(xy 375.296598 -45.083695) (xy 375.269302 -45.03506) (xy 375.249379 -44.982969) (xy 375.237253 -44.928532)
			(xy 375.233182 -44.87291) (xy 369.042679 -44.87291) (xy 369.049914 -44.880985) (xy 369.080687 -44.927498)
			(xy 369.104359 -44.977995) (xy 369.120427 -45.031402) (xy 369.128547 -45.086578) (xy 369.129056 -45.114464)
			(xy 369.128547 -45.14235) (xy 369.120427 -45.197526) (xy 369.104359 -45.250933) (xy 369.080687 -45.30143)
			(xy 369.049914 -45.347943) (xy 369.044272 -45.35424) (xy 373.003824 -45.35424) (xy 373.007895 -45.298618)
			(xy 373.020021 -45.244181) (xy 373.039944 -45.19209) (xy 373.06724 -45.143455) (xy 373.101326 -45.099312)
			(xy 373.141475 -45.060603) (xy 373.186833 -45.028152) (xy 373.236433 -45.002651) (xy 373.289217 -44.984644)
			(xy 373.34406 -44.974514) (xy 373.399794 -44.972477) (xy 373.455231 -44.978577) (xy 373.509188 -44.992683)
			(xy 373.560517 -45.014495) (xy 373.608123 -45.043549) (xy 373.650991 -45.079224) (xy 373.688208 -45.120761)
			(xy 373.718981 -45.167274) (xy 373.742653 -45.217771) (xy 373.758721 -45.271178) (xy 373.766841 -45.326354)
			(xy 373.76735 -45.35424) (xy 373.766841 -45.382126) (xy 373.758721 -45.437302) (xy 373.742653 -45.490709)
			(xy 373.718981 -45.541206) (xy 373.688208 -45.587719) (xy 373.650991 -45.629256) (xy 373.608123 -45.664931)
			(xy 373.560517 -45.693985) (xy 373.509188 -45.715797) (xy 373.455231 -45.729903) (xy 373.399794 -45.736003)
			(xy 373.34406 -45.733966) (xy 373.289217 -45.723836) (xy 373.236433 -45.705829) (xy 373.186833 -45.680328)
			(xy 373.141475 -45.647877) (xy 373.101326 -45.609168) (xy 373.06724 -45.565025) (xy 373.039944 -45.51639)
			(xy 373.020021 -45.464299) (xy 373.007895 -45.409862) (xy 373.003824 -45.35424) (xy 369.044272 -45.35424)
			(xy 369.012697 -45.38948) (xy 368.969829 -45.425155) (xy 368.922223 -45.454209) (xy 368.870894 -45.476021)
			(xy 368.816937 -45.490127) (xy 368.7615 -45.496227) (xy 368.705766 -45.49419) (xy 368.650923 -45.48406)
			(xy 368.598139 -45.466053) (xy 368.548539 -45.440552) (xy 368.503181 -45.408101) (xy 368.463032 -45.369392)
			(xy 368.428946 -45.325249) (xy 368.40165 -45.276614) (xy 368.381727 -45.224523) (xy 368.369601 -45.170086)
			(xy 368.36553 -45.114464) (xy 363.480782 -45.114464) (xy 363.333496 -46.082204) (xy 366.352582 -46.082204)
			(xy 366.353081 -46.054953) (xy 366.360837 -46.001007) (xy 366.376191 -45.948713) (xy 366.398831 -45.899136)
			(xy 366.428296 -45.853286) (xy 366.463986 -45.812096) (xy 366.505175 -45.776405) (xy 366.551024 -45.746938)
			(xy 366.6006 -45.724296) (xy 366.652893 -45.70894) (xy 366.706839 -45.701182) (xy 366.73409 -45.700696)
			(xy 366.760992 -45.701166) (xy 366.814262 -45.708736) (xy 366.86594 -45.723714) (xy 366.915002 -45.745803)
			(xy 366.960474 -45.774564) (xy 367.001456 -45.809428) (xy 367.037134 -45.849703) (xy 367.052352 -45.871892)
			(xy 367.059464 -45.882814) (xy 367.082324 -45.894752) (xy 367.194592 -45.89272) (xy 367.216944 -45.879766)
			(xy 367.223802 -45.86859) (xy 367.238736 -45.844997) (xy 367.274413 -45.802045) (xy 367.315969 -45.764751)
			(xy 367.362517 -45.733913) (xy 367.413062 -45.710188) (xy 367.466526 -45.694084) (xy 367.521766 -45.685944)
			(xy 367.549684 -45.685456) (xy 367.576677 -45.685926) (xy 367.630125 -45.69353) (xy 367.681968 -45.708588)
			(xy 367.731173 -45.7308) (xy 367.776757 -45.759723) (xy 367.797588 -45.776896) (xy 367.805716 -45.784008)
			(xy 367.82629 -45.790104) (xy 367.911634 -45.779182) (xy 367.922185 -45.777434) (xy 367.940465 -45.766361)
			(xy 367.94694 -45.757846) (xy 367.962275 -45.736602) (xy 367.997865 -45.698149) (xy 368.038385 -45.664932)
			(xy 368.083072 -45.637575) (xy 368.131083 -45.616593) (xy 368.181514 -45.602383) (xy 368.233416 -45.595211)
			(xy 368.259614 -45.594778) (xy 368.286864 -45.595293) (xy 368.340808 -45.603051) (xy 368.393099 -45.618407)
			(xy 368.442672 -45.641048) (xy 368.488519 -45.670513) (xy 368.529706 -45.706204) (xy 368.565395 -45.747392)
			(xy 368.594859 -45.79324) (xy 368.617498 -45.842814) (xy 368.632852 -45.895106) (xy 368.640608 -45.94905)
			(xy 368.640608 -46.00355) (xy 368.632852 -46.057494) (xy 368.617498 -46.109786) (xy 368.594859 -46.15936)
			(xy 368.565395 -46.205208) (xy 368.529706 -46.246396) (xy 368.488519 -46.282087) (xy 368.442672 -46.311552)
			(xy 368.393099 -46.334193) (xy 368.340808 -46.349549) (xy 368.286864 -46.357307) (xy 368.259614 -46.357794)
			(xy 368.232622 -46.357313) (xy 368.179175 -46.34971) (xy 368.127332 -46.334654) (xy 368.078127 -46.312445)
			(xy 368.032542 -46.283525) (xy 368.01171 -46.266354) (xy 368.003582 -46.259242) (xy 367.983008 -46.253146)
			(xy 367.897664 -46.264068) (xy 367.887117 -46.265832) (xy 367.868837 -46.276895) (xy 367.862358 -46.285404)
			(xy 367.844747 -46.309706) (xy 367.80315 -46.352965) (xy 367.779554 -46.37151) (xy 367.77168 -46.377352)
			(xy 367.761266 -46.394878) (xy 367.748058 -46.485302) (xy 367.752884 -46.504606) (xy 367.758726 -46.51248)
			(xy 367.758726 -46.512734) (xy 367.776223 -46.537482) (xy 367.804028 -46.591333) (xy 367.822967 -46.648904)
			(xy 367.83017 -46.693836) (xy 372.976394 -46.693836) (xy 372.97688 -46.666585) (xy 372.984636 -46.612637)
			(xy 372.999991 -46.560342) (xy 373.022633 -46.510765) (xy 373.052099 -46.464915) (xy 373.08779 -46.423724)
			(xy 373.128981 -46.388033) (xy 373.174831 -46.358567) (xy 373.224408 -46.335925) (xy 373.276703 -46.32057)
			(xy 373.330651 -46.312814) (xy 373.385153 -46.312814) (xy 373.439101 -46.32057) (xy 373.491396 -46.335925)
			(xy 373.540973 -46.358567) (xy 373.586823 -46.388033) (xy 373.628014 -46.423724) (xy 373.663705 -46.464915)
			(xy 373.693171 -46.510765) (xy 373.715813 -46.560342) (xy 373.731168 -46.612637) (xy 373.738924 -46.666585)
			(xy 373.73941 -46.693836) (xy 373.738936 -46.720263) (xy 373.731627 -46.772611) (xy 373.717154 -46.823446)
			(xy 373.695795 -46.871793) (xy 373.68226 -46.894496) (xy 373.682006 -46.89475) (xy 373.676669 -46.904768)
			(xy 373.674414 -46.927318) (xy 373.677688 -46.938184) (xy 373.70385 -47.01286) (xy 373.708235 -47.023375)
			(xy 373.724323 -47.039463) (xy 373.734838 -47.043848) (xy 373.735092 -47.043848) (xy 373.759611 -47.052892)
			(xy 373.806062 -47.07684) (xy 373.848813 -47.1069) (xy 373.887063 -47.142511) (xy 373.920098 -47.183007)
			(xy 373.9473 -47.227631) (xy 373.968161 -47.275548) (xy 373.98229 -47.325863) (xy 373.989423 -47.377635)
			(xy 373.989854 -47.403766) (xy 373.989368 -47.431017) (xy 373.987845 -47.441612) (xy 375.261884 -47.441612)
			(xy 375.265955 -47.38599) (xy 375.278081 -47.331553) (xy 375.298004 -47.279462) (xy 375.3253 -47.230827)
			(xy 375.359386 -47.186684) (xy 375.399535 -47.147975) (xy 375.444893 -47.115524) (xy 375.494493 -47.090023)
			(xy 375.547277 -47.072016) (xy 375.60212 -47.061886) (xy 375.657854 -47.059849) (xy 375.713291 -47.065949)
			(xy 375.767248 -47.080055) (xy 375.818577 -47.101867) (xy 375.866183 -47.130921) (xy 375.909051 -47.166596)
			(xy 375.946268 -47.208133) (xy 375.977041 -47.254646) (xy 376.000713 -47.305143) (xy 376.016781 -47.35855)
			(xy 376.024901 -47.413726) (xy 376.02541 -47.441612) (xy 376.024901 -47.469498) (xy 376.016781 -47.524674)
			(xy 376.000713 -47.578081) (xy 375.977041 -47.628578) (xy 375.946268 -47.675091) (xy 375.909051 -47.716628)
			(xy 375.866183 -47.752303) (xy 375.818577 -47.781357) (xy 375.767248 -47.803169) (xy 375.713291 -47.817275)
			(xy 375.657854 -47.823375) (xy 375.60212 -47.821338) (xy 375.547277 -47.811208) (xy 375.494493 -47.793201)
			(xy 375.444893 -47.7677) (xy 375.399535 -47.735249) (xy 375.359386 -47.69654) (xy 375.3253 -47.652397)
			(xy 375.298004 -47.603762) (xy 375.278081 -47.551671) (xy 375.265955 -47.497234) (xy 375.261884 -47.441612)
			(xy 373.987845 -47.441612) (xy 373.981612 -47.484965) (xy 373.966257 -47.53726) (xy 373.943615 -47.586837)
			(xy 373.914149 -47.632687) (xy 373.878458 -47.673878) (xy 373.837267 -47.709569) (xy 373.791417 -47.739035)
			(xy 373.74184 -47.761677) (xy 373.689545 -47.777032) (xy 373.635597 -47.784788) (xy 373.581095 -47.784788)
			(xy 373.527147 -47.777032) (xy 373.474852 -47.761677) (xy 373.425275 -47.739035) (xy 373.379425 -47.709569)
			(xy 373.338234 -47.673878) (xy 373.302543 -47.632687) (xy 373.273077 -47.586837) (xy 373.250435 -47.53726)
			(xy 373.23508 -47.484965) (xy 373.227324 -47.431017) (xy 373.226838 -47.403766) (xy 373.227306 -47.377338)
			(xy 373.234616 -47.324991) (xy 373.249091 -47.274156) (xy 373.270452 -47.225809) (xy 373.283988 -47.203106)
			(xy 373.284242 -47.202852) (xy 373.289577 -47.192833) (xy 373.291836 -47.170284) (xy 373.28856 -47.159418)
			(xy 373.262398 -47.084742) (xy 373.258036 -47.074215) (xy 373.241932 -47.058131) (xy 373.23141 -47.053754)
			(xy 373.231156 -47.053754) (xy 373.206648 -47.044682) (xy 373.160196 -47.020739) (xy 373.117444 -46.990684)
			(xy 373.079192 -46.955077) (xy 373.046155 -46.914585) (xy 373.018951 -46.869964) (xy 372.998089 -46.822049)
			(xy 372.983959 -46.771736) (xy 372.976825 -46.719966) (xy 372.976394 -46.693836) (xy 367.83017 -46.693836)
			(xy 367.83256 -46.708745) (xy 367.833148 -46.739048) (xy 367.832667 -46.766299) (xy 367.824905 -46.820244)
			(xy 367.809546 -46.872537) (xy 367.786902 -46.922112) (xy 367.757434 -46.96796) (xy 367.721743 -47.009148)
			(xy 367.680553 -47.044839) (xy 367.634705 -47.074306) (xy 367.585129 -47.096949) (xy 367.532837 -47.112307)
			(xy 367.478891 -47.120068) (xy 367.45164 -47.120556) (xy 367.425606 -47.120136) (xy 367.374022 -47.113041)
			(xy 367.32388 -47.099005) (xy 367.276109 -47.078289) (xy 367.231596 -47.051275) (xy 367.211102 -47.035212)
			(xy 367.203351 -47.02946) (xy 367.184936 -47.023726) (xy 367.175288 -47.024036) (xy 367.095532 -47.030386)
			(xy 367.077752 -47.039022) (xy 367.071402 -47.046388) (xy 367.053243 -47.066055) (xy 367.012331 -47.100575)
			(xy 366.966997 -47.129042) (xy 366.918131 -47.150895) (xy 366.866692 -47.165708) (xy 366.813687 -47.17319)
			(xy 366.786922 -47.173642) (xy 366.759673 -47.173101) (xy 366.705729 -47.165349) (xy 366.653437 -47.149998)
			(xy 366.603863 -47.127362) (xy 366.558014 -47.097901) (xy 366.516824 -47.062216) (xy 366.481132 -47.021031)
			(xy 366.451665 -46.975187) (xy 366.429021 -46.925615) (xy 366.413663 -46.873326) (xy 366.405903 -46.819383)
			(xy 366.405414 -46.792134) (xy 366.405935 -46.76336) (xy 366.414586 -46.706465) (xy 366.431683 -46.651515)
			(xy 366.456838 -46.599755) (xy 366.489479 -46.552359) (xy 366.508792 -46.531022) (xy 366.516158 -46.523148)
			(xy 366.52327 -46.503336) (xy 366.515904 -46.40707) (xy 366.505998 -46.388274) (xy 366.497616 -46.38167)
			(xy 366.47543 -46.363446) (xy 366.436221 -46.321511) (xy 366.403735 -46.274175) (xy 366.378707 -46.222507)
			(xy 366.361701 -46.167672) (xy 366.3531 -46.110909) (xy 366.352582 -46.082204) (xy 363.333496 -46.082204)
			(xy 362.994894 -48.30699) (xy 372.853964 -48.30699) (xy 372.858035 -48.251368) (xy 372.870161 -48.196931)
			(xy 372.890084 -48.14484) (xy 372.91738 -48.096205) (xy 372.951466 -48.052062) (xy 372.991615 -48.013353)
			(xy 373.036973 -47.980902) (xy 373.086573 -47.955401) (xy 373.139357 -47.937394) (xy 373.1942 -47.927264)
			(xy 373.249934 -47.925227) (xy 373.305371 -47.931327) (xy 373.359328 -47.945433) (xy 373.410657 -47.967245)
			(xy 373.458263 -47.996299) (xy 373.501131 -48.031974) (xy 373.538348 -48.073511) (xy 373.569121 -48.120024)
			(xy 373.592793 -48.170521) (xy 373.608861 -48.223928) (xy 373.616981 -48.279104) (xy 373.61749 -48.30699)
			(xy 373.616981 -48.334876) (xy 373.608861 -48.390052) (xy 373.592793 -48.443459) (xy 373.569121 -48.493956)
			(xy 373.538348 -48.540469) (xy 373.501131 -48.582006) (xy 373.458263 -48.617681) (xy 373.410657 -48.646735)
			(xy 373.359328 -48.668547) (xy 373.305371 -48.682653) (xy 373.249934 -48.688753) (xy 373.1942 -48.686716)
			(xy 373.139357 -48.676586) (xy 373.086573 -48.658579) (xy 373.036973 -48.633078) (xy 372.991615 -48.600627)
			(xy 372.951466 -48.561918) (xy 372.91738 -48.517775) (xy 372.890084 -48.46914) (xy 372.870161 -48.417049)
			(xy 372.858035 -48.362612) (xy 372.853964 -48.30699) (xy 362.994894 -48.30699) (xy 362.927011 -48.753014)
			(xy 369.468398 -48.753014) (xy 369.472469 -48.697392) (xy 369.484595 -48.642955) (xy 369.504518 -48.590864)
			(xy 369.531814 -48.542229) (xy 369.5659 -48.498086) (xy 369.606049 -48.459377) (xy 369.651407 -48.426926)
			(xy 369.701007 -48.401425) (xy 369.753791 -48.383418) (xy 369.808634 -48.373288) (xy 369.864368 -48.371251)
			(xy 369.919805 -48.377351) (xy 369.973762 -48.391457) (xy 370.025091 -48.413269) (xy 370.072697 -48.442323)
			(xy 370.115565 -48.477998) (xy 370.152782 -48.519535) (xy 370.183555 -48.566048) (xy 370.207227 -48.616545)
			(xy 370.223295 -48.669952) (xy 370.231415 -48.725128) (xy 370.231924 -48.753014) (xy 370.231415 -48.7809)
			(xy 370.223295 -48.836076) (xy 370.207227 -48.889483) (xy 370.205831 -48.89246) (xy 371.514114 -48.89246)
			(xy 371.518185 -48.836838) (xy 371.530311 -48.782401) (xy 371.550234 -48.73031) (xy 371.57753 -48.681675)
			(xy 371.611616 -48.637532) (xy 371.651765 -48.598823) (xy 371.697123 -48.566372) (xy 371.746723 -48.540871)
			(xy 371.799507 -48.522864) (xy 371.85435 -48.512734) (xy 371.910084 -48.510697) (xy 371.965521 -48.516797)
			(xy 372.019478 -48.530903) (xy 372.070807 -48.552715) (xy 372.118413 -48.581769) (xy 372.161281 -48.617444)
			(xy 372.198498 -48.658981) (xy 372.229271 -48.705494) (xy 372.252943 -48.755991) (xy 372.269011 -48.809398)
			(xy 372.277131 -48.864574) (xy 372.27764 -48.89246) (xy 372.277131 -48.920346) (xy 372.274693 -48.93691)
			(xy 375.233182 -48.93691) (xy 375.237253 -48.881288) (xy 375.249379 -48.826851) (xy 375.269302 -48.77476)
			(xy 375.296598 -48.726125) (xy 375.330684 -48.681982) (xy 375.370833 -48.643273) (xy 375.416191 -48.610822)
			(xy 375.465791 -48.585321) (xy 375.518575 -48.567314) (xy 375.573418 -48.557184) (xy 375.629152 -48.555147)
			(xy 375.684589 -48.561247) (xy 375.738546 -48.575353) (xy 375.789875 -48.597165) (xy 375.837481 -48.626219)
			(xy 375.880349 -48.661894) (xy 375.917566 -48.703431) (xy 375.948339 -48.749944) (xy 375.972011 -48.800441)
			(xy 375.988079 -48.853848) (xy 375.996199 -48.909024) (xy 375.996708 -48.93691) (xy 375.996199 -48.964796)
			(xy 375.988079 -49.019972) (xy 375.972011 -49.073379) (xy 375.948339 -49.123876) (xy 375.917566 -49.170389)
			(xy 375.880349 -49.211926) (xy 375.837481 -49.247601) (xy 375.789875 -49.276655) (xy 375.738546 -49.298467)
			(xy 375.684589 -49.312573) (xy 375.629152 -49.318673) (xy 375.573418 -49.316636) (xy 375.518575 -49.306506)
			(xy 375.465791 -49.288499) (xy 375.416191 -49.262998) (xy 375.370833 -49.230547) (xy 375.330684 -49.191838)
			(xy 375.296598 -49.147695) (xy 375.269302 -49.09906) (xy 375.249379 -49.046969) (xy 375.237253 -48.992532)
			(xy 375.233182 -48.93691) (xy 372.274693 -48.93691) (xy 372.269011 -48.975522) (xy 372.252943 -49.028929)
			(xy 372.229271 -49.079426) (xy 372.198498 -49.125939) (xy 372.161281 -49.167476) (xy 372.118413 -49.203151)
			(xy 372.070807 -49.232205) (xy 372.019478 -49.254017) (xy 371.965521 -49.268123) (xy 371.910084 -49.274223)
			(xy 371.85435 -49.272186) (xy 371.799507 -49.262056) (xy 371.746723 -49.244049) (xy 371.697123 -49.218548)
			(xy 371.651765 -49.186097) (xy 371.611616 -49.147388) (xy 371.57753 -49.103245) (xy 371.550234 -49.05461)
			(xy 371.530311 -49.002519) (xy 371.518185 -48.948082) (xy 371.514114 -48.89246) (xy 370.205831 -48.89246)
			(xy 370.183555 -48.93998) (xy 370.152782 -48.986493) (xy 370.115565 -49.02803) (xy 370.072697 -49.063705)
			(xy 370.025091 -49.092759) (xy 369.973762 -49.114571) (xy 369.919805 -49.128677) (xy 369.864368 -49.134777)
			(xy 369.808634 -49.13274) (xy 369.753791 -49.12261) (xy 369.701007 -49.104603) (xy 369.651407 -49.079102)
			(xy 369.606049 -49.046651) (xy 369.5659 -49.007942) (xy 369.531814 -48.963799) (xy 369.504518 -48.915164)
			(xy 369.484595 -48.863073) (xy 369.472469 -48.808636) (xy 369.468398 -48.753014) (xy 362.927011 -48.753014)
			(xy 362.744392 -49.95291) (xy 375.233182 -49.95291) (xy 375.237253 -49.897288) (xy 375.249379 -49.842851)
			(xy 375.269302 -49.79076) (xy 375.296598 -49.742125) (xy 375.330684 -49.697982) (xy 375.370833 -49.659273)
			(xy 375.416191 -49.626822) (xy 375.465791 -49.601321) (xy 375.518575 -49.583314) (xy 375.573418 -49.573184)
			(xy 375.629152 -49.571147) (xy 375.684589 -49.577247) (xy 375.738546 -49.591353) (xy 375.789875 -49.613165)
			(xy 375.837481 -49.642219) (xy 375.880349 -49.677894) (xy 375.917566 -49.719431) (xy 375.948339 -49.765944)
			(xy 375.972011 -49.816441) (xy 375.988079 -49.869848) (xy 375.996199 -49.925024) (xy 375.996708 -49.95291)
			(xy 375.996199 -49.980796) (xy 375.988079 -50.035972) (xy 375.972011 -50.089379) (xy 375.948339 -50.139876)
			(xy 375.917566 -50.186389) (xy 375.880349 -50.227926) (xy 375.837481 -50.263601) (xy 375.789875 -50.292655)
			(xy 375.738546 -50.314467) (xy 375.684589 -50.328573) (xy 375.629152 -50.334673) (xy 375.573418 -50.332636)
			(xy 375.518575 -50.322506) (xy 375.465791 -50.304499) (xy 375.416191 -50.278998) (xy 375.370833 -50.246547)
			(xy 375.330684 -50.207838) (xy 375.296598 -50.163695) (xy 375.269302 -50.11506) (xy 375.249379 -50.062969)
			(xy 375.237253 -50.008532) (xy 375.233182 -49.95291) (xy 362.744392 -49.95291) (xy 362.731558 -50.037238)
			(xy 362.727748 -50.06213) (xy 362.727494 -50.063908) (xy 362.726732 -50.068988) (xy 362.62183 -50.758598)
			(xy 362.58212 -51.019456) (xy 373.049544 -51.019456) (xy 373.053615 -50.963834) (xy 373.065741 -50.909397)
			(xy 373.085664 -50.857306) (xy 373.11296 -50.808671) (xy 373.147046 -50.764528) (xy 373.187195 -50.725819)
			(xy 373.232553 -50.693368) (xy 373.282153 -50.667867) (xy 373.334937 -50.64986) (xy 373.38978 -50.63973)
			(xy 373.445514 -50.637693) (xy 373.500951 -50.643793) (xy 373.554908 -50.657899) (xy 373.606237 -50.679711)
			(xy 373.653843 -50.708765) (xy 373.696711 -50.74444) (xy 373.733928 -50.785977) (xy 373.764701 -50.83249)
			(xy 373.788373 -50.882987) (xy 373.804441 -50.936394) (xy 373.812561 -50.99157) (xy 373.81307 -51.019456)
			(xy 373.812561 -51.047342) (xy 373.804441 -51.102518) (xy 373.788373 -51.155925) (xy 373.764701 -51.206422)
			(xy 373.739845 -51.243992) (xy 381.43307 -51.243992) (xy 381.433514 -51.216621) (xy 381.441335 -51.16244)
			(xy 381.456828 -51.109936) (xy 381.479675 -51.060189) (xy 381.509406 -51.014224) (xy 381.52705 -50.993294)
			(xy 381.527304 -50.99304) (xy 381.53288 -50.985946) (xy 381.539133 -50.969035) (xy 381.539496 -50.96002)
			(xy 381.539496 -50.892964) (xy 381.539157 -50.883945) (xy 381.532897 -50.867028) (xy 381.527304 -50.859944)
			(xy 381.52705 -50.859944) (xy 381.52705 -50.85969) (xy 381.509401 -50.838766) (xy 381.479689 -50.792792)
			(xy 381.456854 -50.743042) (xy 381.441365 -50.69054) (xy 381.433541 -50.636362) (xy 381.43307 -50.608992)
			(xy 381.43357 -50.581742) (xy 381.441327 -50.527795) (xy 381.456682 -50.475502) (xy 381.479323 -50.425927)
			(xy 381.508788 -50.380077) (xy 381.544478 -50.338888) (xy 381.585666 -50.303196) (xy 381.631514 -50.27373)
			(xy 381.681089 -50.251087) (xy 381.733382 -50.23573) (xy 381.787328 -50.227971) (xy 381.814578 -50.227484)
			(xy 381.843496 -50.227986) (xy 381.900669 -50.236714) (xy 381.95587 -50.253973) (xy 382.007832 -50.279368)
			(xy 382.055365 -50.312316) (xy 382.09738 -50.352062) (xy 382.115568 -50.37455) (xy 382.12319 -50.383341)
			(xy 382.14408 -50.393532) (xy 382.1557 -50.394108) (xy 382.235456 -50.394108) (xy 382.24709 -50.393584)
			(xy 382.267999 -50.383384) (xy 382.275588 -50.37455) (xy 382.293773 -50.352062) (xy 382.335796 -50.312329)
			(xy 382.383332 -50.279392) (xy 382.435294 -50.254005) (xy 382.490492 -50.236749) (xy 382.547662 -50.22802)
			(xy 382.576578 -50.227484) (xy 382.60383 -50.227976) (xy 382.657779 -50.23573) (xy 382.710076 -50.251082)
			(xy 382.759656 -50.273722) (xy 382.805509 -50.303187) (xy 382.846701 -50.338877) (xy 382.882395 -50.380067)
			(xy 382.911864 -50.425918) (xy 382.934507 -50.475496) (xy 382.949864 -50.527791) (xy 382.957622 -50.58174)
			(xy 382.958086 -50.608992) (xy 382.957618 -50.635306) (xy 382.950384 -50.687435) (xy 382.936065 -50.738078)
			(xy 382.914933 -50.786277) (xy 382.887387 -50.83112) (xy 382.853948 -50.87176) (xy 382.834896 -50.889916)
			(xy 382.827485 -50.897429) (xy 382.818966 -50.916716) (xy 382.818386 -50.927254) (xy 382.818386 -51.00193)
			(xy 382.818943 -51.012476) (xy 382.827459 -51.031772) (xy 382.834896 -51.039268) (xy 382.853977 -51.057398)
			(xy 382.887432 -51.098033) (xy 382.914988 -51.142879) (xy 382.936122 -51.191085) (xy 382.950433 -51.241737)
			(xy 382.957651 -51.293874) (xy 382.958086 -51.320192) (xy 382.957637 -51.347446) (xy 382.949881 -51.401398)
			(xy 382.934525 -51.453698) (xy 382.911881 -51.503279) (xy 382.882412 -51.549133) (xy 382.846717 -51.590327)
			(xy 382.805522 -51.626021) (xy 382.759667 -51.655488) (xy 382.710085 -51.678129) (xy 382.657785 -51.693484)
			(xy 382.603832 -51.701238) (xy 382.576578 -51.7017) (xy 382.548912 -51.701205) (xy 382.494162 -51.693203)
			(xy 382.44114 -51.677383) (xy 382.390956 -51.654077) (xy 382.344661 -51.623773) (xy 382.303223 -51.587106)
			(xy 382.267511 -51.544842) (xy 382.252474 -51.521614) (xy 382.245859 -51.511919) (xy 382.225982 -51.499486)
			(xy 382.214374 -51.497738) (xy 382.134364 -51.489864) (xy 382.122725 -51.489214) (xy 382.100886 -51.497306)
			(xy 382.092454 -51.505358) (xy 382.0922 -51.505612) (xy 382.074104 -51.524178) (xy 382.033775 -51.556757)
			(xy 381.989404 -51.583572) (xy 381.941808 -51.604127) (xy 381.891867 -51.618044) (xy 381.8405 -51.625066)
			(xy 381.814578 -51.6255) (xy 381.787326 -51.625043) (xy 381.733377 -51.617283) (xy 381.681081 -51.601925)
			(xy 381.631503 -51.57928) (xy 381.585652 -51.549811) (xy 381.544462 -51.514117) (xy 381.508771 -51.472924)
			(xy 381.479305 -51.427071) (xy 381.456665 -51.377491) (xy 381.441311 -51.325194) (xy 381.433555 -51.271244)
			(xy 381.43307 -51.243992) (xy 373.739845 -51.243992) (xy 373.733928 -51.252935) (xy 373.696711 -51.294472)
			(xy 373.653843 -51.330147) (xy 373.606237 -51.359201) (xy 373.554908 -51.381013) (xy 373.500951 -51.395119)
			(xy 373.445514 -51.401219) (xy 373.38978 -51.399182) (xy 373.334937 -51.389052) (xy 373.282153 -51.371045)
			(xy 373.232553 -51.345544) (xy 373.187195 -51.313093) (xy 373.147046 -51.274384) (xy 373.11296 -51.230241)
			(xy 373.085664 -51.181606) (xy 373.065741 -51.129515) (xy 373.053615 -51.075078) (xy 373.049544 -51.019456)
			(xy 362.58212 -51.019456) (xy 362.574078 -51.072288) (xy 362.54182 -51.283616) (xy 362.54182 -51.284378)
			(xy 362.541566 -51.286156) (xy 362.427734 -52.035456) (xy 375.24131 -52.035456) (xy 375.245381 -51.979834)
			(xy 375.257507 -51.925397) (xy 375.27743 -51.873306) (xy 375.304726 -51.824671) (xy 375.338812 -51.780528)
			(xy 375.378961 -51.741819) (xy 375.424319 -51.709368) (xy 375.473919 -51.683867) (xy 375.526703 -51.66586)
			(xy 375.581546 -51.65573) (xy 375.63728 -51.653693) (xy 375.692717 -51.659793) (xy 375.746674 -51.673899)
			(xy 375.798003 -51.695711) (xy 375.845609 -51.724765) (xy 375.888477 -51.76044) (xy 375.925694 -51.801977)
			(xy 375.956467 -51.84849) (xy 375.980139 -51.898987) (xy 375.996207 -51.952394) (xy 376.004327 -52.00757)
			(xy 376.004836 -52.035456) (xy 376.004327 -52.063342) (xy 375.996207 -52.118518) (xy 375.980139 -52.171925)
			(xy 375.956467 -52.222422) (xy 375.925694 -52.268935) (xy 375.888477 -52.310472) (xy 375.845609 -52.346147)
			(xy 375.798003 -52.375201) (xy 375.746674 -52.397013) (xy 375.692717 -52.411119) (xy 375.63728 -52.417219)
			(xy 375.581546 -52.415182) (xy 375.526703 -52.405052) (xy 375.473919 -52.387045) (xy 375.424319 -52.361544)
			(xy 375.378961 -52.329093) (xy 375.338812 -52.290384) (xy 375.304726 -52.246241) (xy 375.27743 -52.197606)
			(xy 375.257507 -52.145515) (xy 375.245381 -52.091078) (xy 375.24131 -52.035456) (xy 362.427734 -52.035456)
			(xy 362.416852 -52.107084) (xy 362.416344 -52.113688) (xy 362.410502 -52.479448) (xy 362.410547 -52.485288)
			(xy 362.412986 -52.496705) (xy 362.415328 -52.502054) (xy 362.417614 -52.50688) (xy 362.425488 -52.516532)
			(xy 362.430822 -52.520342) (xy 362.454167 -52.538527) (xy 362.495492 -52.580879) (xy 362.529806 -52.629087)
			(xy 362.556291 -52.682002) (xy 362.574317 -52.738362) (xy 362.583453 -52.796826) (xy 362.583984 -52.826412)
			(xy 362.582968 -52.855876) (xy 362.58119 -52.871116) (xy 362.58119 -52.87137) (xy 362.579268 -52.886157)
			(xy 362.573419 -52.915401) (xy 362.569506 -52.92979) (xy 362.56233 -52.953812) (xy 362.542545 -52.999878)
			(xy 362.516904 -53.042961) (xy 362.501688 -53.062886) (xy 362.498894 -53.066442) (xy 362.49229 -53.078888)
			(xy 362.48975 -53.090064) (xy 362.48975 -53.117242) (xy 362.489605 -53.122681) (xy 362.487294 -53.133311)
			(xy 362.485178 -53.138324) (xy 362.478828 -53.152294) (xy 362.475157 -53.161459) (xy 362.474341 -53.181167)
			(xy 362.481002 -53.199733) (xy 362.48721 -53.207412) (xy 362.496354 -53.217826) (xy 362.512454 -53.238024)
			(xy 362.539651 -53.281936) (xy 362.560696 -53.329107) (xy 362.575206 -53.37868) (xy 362.582917 -53.429753)
			(xy 362.58373 -53.45557) (xy 362.58373 -53.461666) (xy 362.583121 -53.491575) (xy 362.573741 -53.550654)
			(xy 362.555267 -53.607549) (xy 362.528151 -53.66087) (xy 362.511086 -53.68544) (xy 362.504736 -53.694076)
			(xy 362.500926 -53.698902) (xy 362.495592 -53.707538) (xy 362.495084 -53.708554) (xy 362.492625 -53.71388)
			(xy 362.489936 -53.725296) (xy 362.48975 -53.73116) (xy 362.48975 -53.752242) (xy 362.489605 -53.757681)
			(xy 362.487294 -53.768311) (xy 362.485178 -53.773324) (xy 362.478828 -53.787294) (xy 362.475157 -53.796459)
			(xy 362.474341 -53.816167) (xy 362.481002 -53.834733) (xy 362.48721 -53.842412) (xy 362.496354 -53.852826)
			(xy 362.512454 -53.873024) (xy 362.539651 -53.916936) (xy 362.560696 -53.964107) (xy 362.575206 -54.01368)
			(xy 362.582917 -54.064753) (xy 362.58373 -54.09057) (xy 362.58373 -54.096666) (xy 362.583121 -54.126575)
			(xy 362.573741 -54.185654) (xy 362.555267 -54.242549) (xy 362.528151 -54.29587) (xy 362.511086 -54.32044)
			(xy 362.504736 -54.329076) (xy 362.500926 -54.333902) (xy 362.495592 -54.342538) (xy 362.495084 -54.343554)
			(xy 362.492625 -54.34888) (xy 362.489936 -54.360296) (xy 362.48975 -54.36616) (xy 362.48975 -54.387242)
			(xy 362.489605 -54.392681) (xy 362.487294 -54.403311) (xy 362.485178 -54.408324) (xy 362.478828 -54.422294)
			(xy 362.475157 -54.431459) (xy 362.474341 -54.451167) (xy 362.481002 -54.469733) (xy 362.48721 -54.477412)
			(xy 362.496354 -54.487826) (xy 362.512425 -54.507983) (xy 362.53958 -54.551801) (xy 362.560608 -54.598869)
			(xy 362.575129 -54.648332) (xy 362.582879 -54.699297) (xy 362.58373 -54.725062) (xy 362.58373 -54.731158)
			(xy 362.583984 -54.731412) (xy 362.58346 -54.759847) (xy 362.578772 -54.791102) (xy 364.476538 -54.791102)
			(xy 364.476996 -54.763731) (xy 364.484814 -54.709552) (xy 364.500305 -54.657048) (xy 364.523149 -54.607301)
			(xy 364.552875 -54.561335) (xy 364.570518 -54.540404) (xy 364.570772 -54.54015) (xy 364.576352 -54.533059)
			(xy 364.582601 -54.516145) (xy 364.582964 -54.50713) (xy 364.582964 -54.440074) (xy 364.582627 -54.431055)
			(xy 364.576367 -54.414138) (xy 364.570772 -54.407054) (xy 364.570518 -54.407054) (xy 364.570518 -54.4068)
			(xy 364.55288 -54.385865) (xy 364.523155 -54.339898) (xy 364.500311 -54.290152) (xy 364.484814 -54.23765)
			(xy 364.476986 -54.183472) (xy 364.476986 -54.128731) (xy 364.484814 -54.074553) (xy 364.500309 -54.022051)
			(xy 364.523154 -53.972305) (xy 364.552878 -53.926337) (xy 364.570518 -53.905404) (xy 364.570772 -53.90515)
			(xy 364.576352 -53.898059) (xy 364.582601 -53.881145) (xy 364.582964 -53.87213) (xy 364.582964 -53.805074)
			(xy 364.582627 -53.796055) (xy 364.576367 -53.779138) (xy 364.570772 -53.772054) (xy 364.570518 -53.772054)
			(xy 364.570518 -53.7718) (xy 364.55288 -53.750865) (xy 364.523155 -53.704898) (xy 364.500311 -53.655152)
			(xy 364.484814 -53.60265) (xy 364.476986 -53.548472) (xy 364.476986 -53.493731) (xy 364.484814 -53.439553)
			(xy 364.500309 -53.387051) (xy 364.523154 -53.337305) (xy 364.552878 -53.291337) (xy 364.570518 -53.270404)
			(xy 364.570772 -53.27015) (xy 364.576352 -53.263059) (xy 364.582601 -53.246145) (xy 364.582964 -53.23713)
			(xy 364.582964 -53.170074) (xy 364.582627 -53.161055) (xy 364.576367 -53.144138) (xy 364.570772 -53.137054)
			(xy 364.570518 -53.137054) (xy 364.570518 -53.1368) (xy 364.552868 -53.115876) (xy 364.523157 -53.069902)
			(xy 364.500323 -53.020152) (xy 364.484835 -52.967649) (xy 364.47701 -52.913472) (xy 364.476538 -52.886102)
			(xy 364.477024 -52.858851) (xy 364.48478 -52.804903) (xy 364.500135 -52.752608) (xy 364.522777 -52.703031)
			(xy 364.552243 -52.657181) (xy 364.587934 -52.61599) (xy 364.629125 -52.580299) (xy 364.674975 -52.550833)
			(xy 364.724552 -52.528191) (xy 364.776847 -52.512836) (xy 364.830795 -52.50508) (xy 364.885297 -52.50508)
			(xy 364.939245 -52.512836) (xy 364.99154 -52.528191) (xy 365.030649 -52.546052) (xy 369.979673 -52.546052)
			(xy 369.979673 -52.491548) (xy 369.98743 -52.4376) (xy 370.002785 -52.385304) (xy 370.025427 -52.335726)
			(xy 370.054894 -52.289875) (xy 370.090586 -52.248685) (xy 370.131777 -52.212993) (xy 370.177628 -52.183526)
			(xy 370.227206 -52.160885) (xy 370.279502 -52.14553) (xy 370.33345 -52.137773) (xy 370.360702 -52.13731)
			(xy 370.388072 -52.137772) (xy 370.442252 -52.145591) (xy 370.494755 -52.161081) (xy 370.544502 -52.183923)
			(xy 370.590468 -52.213648) (xy 370.6114 -52.23129) (xy 370.611654 -52.231544) (xy 370.618746 -52.237123)
			(xy 370.635659 -52.243373) (xy 370.644674 -52.243736) (xy 370.71173 -52.243736) (xy 370.720747 -52.243386)
			(xy 370.737664 -52.237133) (xy 370.74475 -52.231544) (xy 370.74475 -52.23129) (xy 370.745004 -52.23129)
			(xy 370.765937 -52.213649) (xy 370.811905 -52.183925) (xy 370.861651 -52.161079) (xy 370.914153 -52.145583)
			(xy 370.968331 -52.137754) (xy 371.023073 -52.137754) (xy 371.077251 -52.145583) (xy 371.129753 -52.161079)
			(xy 371.179499 -52.183925) (xy 371.225467 -52.213649) (xy 371.2464 -52.23129) (xy 371.246654 -52.231544)
			(xy 371.253746 -52.237123) (xy 371.270659 -52.243373) (xy 371.279674 -52.243736) (xy 371.34673 -52.243736)
			(xy 371.355747 -52.243386) (xy 371.372664 -52.237133) (xy 371.37975 -52.231544) (xy 371.37975 -52.23129)
			(xy 371.380004 -52.23129) (xy 371.400922 -52.213634) (xy 371.446899 -52.183925) (xy 371.49665 -52.161093)
			(xy 371.549154 -52.145605) (xy 371.603332 -52.137782) (xy 371.630702 -52.13731) (xy 371.657954 -52.13776)
			(xy 371.711905 -52.145517) (xy 371.764201 -52.160873) (xy 371.813781 -52.183515) (xy 371.859633 -52.212983)
			(xy 371.900825 -52.248676) (xy 371.936518 -52.289868) (xy 371.965986 -52.335721) (xy 371.988628 -52.3853)
			(xy 372.003983 -52.437597) (xy 372.01174 -52.491548) (xy 372.01174 -52.546052) (xy 372.005795 -52.587398)
			(xy 373.055386 -52.587398) (xy 373.059457 -52.531776) (xy 373.071583 -52.477339) (xy 373.091506 -52.425248)
			(xy 373.118802 -52.376613) (xy 373.152888 -52.33247) (xy 373.193037 -52.293761) (xy 373.238395 -52.26131)
			(xy 373.287995 -52.235809) (xy 373.340779 -52.217802) (xy 373.395622 -52.207672) (xy 373.451356 -52.205635)
			(xy 373.506793 -52.211735) (xy 373.56075 -52.225841) (xy 373.612079 -52.247653) (xy 373.659685 -52.276707)
			(xy 373.702553 -52.312382) (xy 373.73977 -52.353919) (xy 373.770543 -52.400432) (xy 373.794215 -52.450929)
			(xy 373.810283 -52.504336) (xy 373.817879 -52.555952) (xy 380.883879 -52.555952) (xy 380.883879 -52.501448)
			(xy 380.891636 -52.447498) (xy 380.906993 -52.395202) (xy 380.929635 -52.345624) (xy 380.959103 -52.299772)
			(xy 380.994797 -52.258582) (xy 381.03599 -52.22289) (xy 381.081843 -52.193425) (xy 381.131423 -52.170785)
			(xy 381.18372 -52.155432) (xy 381.23767 -52.147678) (xy 381.264922 -52.147216) (xy 381.292293 -52.147665)
			(xy 381.346473 -52.155487) (xy 381.398976 -52.170979) (xy 381.448723 -52.193825) (xy 381.494689 -52.223553)
			(xy 381.51562 -52.241196) (xy 381.515874 -52.24145) (xy 381.522959 -52.247038) (xy 381.539877 -52.253283)
			(xy 381.548894 -52.253642) (xy 381.61595 -52.253642) (xy 381.624966 -52.253274) (xy 381.641884 -52.247035)
			(xy 381.64897 -52.24145) (xy 381.64897 -52.241196) (xy 381.649224 -52.241196) (xy 381.670173 -52.223578)
			(xy 381.716142 -52.193864) (xy 381.765885 -52.171023) (xy 381.818381 -52.155527) (xy 381.872554 -52.147693)
			(xy 381.899922 -52.147216) (xy 381.927174 -52.147655) (xy 381.981123 -52.155415) (xy 382.033418 -52.170773)
			(xy 382.082996 -52.193417) (xy 382.128846 -52.222885) (xy 382.170036 -52.258579) (xy 382.205728 -52.299771)
			(xy 382.235194 -52.345624) (xy 382.257835 -52.395203) (xy 382.27319 -52.447499) (xy 382.280946 -52.501448)
			(xy 382.280946 -52.555952) (xy 382.27319 -52.609901) (xy 382.257835 -52.662197) (xy 382.235194 -52.711776)
			(xy 382.205728 -52.757629) (xy 382.170036 -52.798821) (xy 382.128846 -52.834515) (xy 382.082996 -52.863983)
			(xy 382.033418 -52.886627) (xy 381.981123 -52.901985) (xy 381.927174 -52.909745) (xy 381.899922 -52.910232)
			(xy 381.872551 -52.90977) (xy 381.818372 -52.901953) (xy 381.765868 -52.886464) (xy 381.716121 -52.863621)
			(xy 381.670155 -52.833895) (xy 381.649224 -52.816252) (xy 381.64897 -52.815998) (xy 381.641868 -52.810434)
			(xy 381.624963 -52.804174) (xy 381.61595 -52.803806) (xy 381.548894 -52.803806) (xy 381.539877 -52.804159)
			(xy 381.52296 -52.810409) (xy 381.515874 -52.815998) (xy 381.515874 -52.816252) (xy 381.51562 -52.816252)
			(xy 381.494685 -52.833888) (xy 381.448714 -52.863602) (xy 381.398967 -52.886439) (xy 381.346467 -52.901931)
			(xy 381.292291 -52.909759) (xy 381.264922 -52.910232) (xy 381.23767 -52.909722) (xy 381.18372 -52.901968)
			(xy 381.131423 -52.886615) (xy 381.081843 -52.863975) (xy 381.03599 -52.83451) (xy 380.994797 -52.798818)
			(xy 380.959103 -52.757628) (xy 380.929635 -52.711776) (xy 380.906993 -52.662198) (xy 380.891636 -52.609902)
			(xy 380.883879 -52.555952) (xy 373.817879 -52.555952) (xy 373.818403 -52.559512) (xy 373.818912 -52.587398)
			(xy 373.818403 -52.615284) (xy 373.810283 -52.67046) (xy 373.794215 -52.723867) (xy 373.770543 -52.774364)
			(xy 373.73977 -52.820877) (xy 373.702553 -52.862414) (xy 373.659685 -52.898089) (xy 373.612079 -52.927143)
			(xy 373.56075 -52.948955) (xy 373.506793 -52.963061) (xy 373.451356 -52.969161) (xy 373.395622 -52.967124)
			(xy 373.340779 -52.956994) (xy 373.287995 -52.938987) (xy 373.238395 -52.913486) (xy 373.193037 -52.881035)
			(xy 373.152888 -52.842326) (xy 373.118802 -52.798183) (xy 373.091506 -52.749548) (xy 373.071583 -52.697457)
			(xy 373.059457 -52.64302) (xy 373.055386 -52.587398) (xy 372.005795 -52.587398) (xy 372.003983 -52.600003)
			(xy 371.988628 -52.6523) (xy 371.965986 -52.701879) (xy 371.936518 -52.747732) (xy 371.900825 -52.788924)
			(xy 371.859633 -52.824617) (xy 371.813781 -52.854085) (xy 371.764201 -52.876727) (xy 371.711905 -52.892083)
			(xy 371.657954 -52.89984) (xy 371.630702 -52.900326) (xy 371.603331 -52.899877) (xy 371.54915 -52.892058)
			(xy 371.496646 -52.876566) (xy 371.4469 -52.85372) (xy 371.400934 -52.82399) (xy 371.380004 -52.806346)
			(xy 371.37975 -52.806092) (xy 371.372654 -52.800519) (xy 371.355744 -52.794265) (xy 371.34673 -52.7939)
			(xy 371.279674 -52.7939) (xy 371.270656 -52.794245) (xy 371.253739 -52.800501) (xy 371.246654 -52.806092)
			(xy 371.2464 -52.806346) (xy 371.225467 -52.823987) (xy 371.179499 -52.853711) (xy 371.129753 -52.876557)
			(xy 371.077251 -52.892053) (xy 371.023073 -52.899882) (xy 370.968331 -52.899882) (xy 370.914153 -52.892053)
			(xy 370.861651 -52.876557) (xy 370.811905 -52.853711) (xy 370.765937 -52.823987) (xy 370.745004 -52.806346)
			(xy 370.74475 -52.806092) (xy 370.737654 -52.800519) (xy 370.720744 -52.794265) (xy 370.71173 -52.7939)
			(xy 370.644674 -52.7939) (xy 370.635656 -52.794245) (xy 370.618739 -52.800501) (xy 370.611654 -52.806092)
			(xy 370.611654 -52.806346) (xy 370.6114 -52.806346) (xy 370.590472 -52.82399) (xy 370.544499 -52.853703)
			(xy 370.49475 -52.876539) (xy 370.442249 -52.892029) (xy 370.388072 -52.899854) (xy 370.360702 -52.900326)
			(xy 370.33345 -52.899827) (xy 370.279502 -52.89207) (xy 370.227206 -52.876715) (xy 370.177628 -52.854074)
			(xy 370.131777 -52.824607) (xy 370.090586 -52.788915) (xy 370.054894 -52.747725) (xy 370.025427 -52.701874)
			(xy 370.002785 -52.652296) (xy 369.98743 -52.6) (xy 369.979673 -52.546052) (xy 365.030649 -52.546052)
			(xy 365.041117 -52.550833) (xy 365.086967 -52.580299) (xy 365.128158 -52.61599) (xy 365.163849 -52.657181)
			(xy 365.193315 -52.703031) (xy 365.215957 -52.752608) (xy 365.231312 -52.804903) (xy 365.239068 -52.858851)
			(xy 365.239554 -52.886102) (xy 365.2391 -52.913473) (xy 365.231281 -52.967653) (xy 365.21579 -53.020157)
			(xy 365.192945 -53.069903) (xy 365.163217 -53.115869) (xy 365.145574 -53.1368) (xy 365.14532 -53.137054)
			(xy 365.139737 -53.144143) (xy 365.13349 -53.161058) (xy 365.133128 -53.170074) (xy 365.133128 -53.23713)
			(xy 365.133465 -53.246149) (xy 365.139726 -53.263066) (xy 365.14532 -53.27015) (xy 365.145574 -53.27015)
			(xy 365.145574 -53.270404) (xy 365.163217 -53.291335) (xy 365.192941 -53.337303) (xy 365.215786 -53.38705)
			(xy 365.231283 -53.439552) (xy 365.239111 -53.493731) (xy 365.239111 -53.548472) (xy 365.231282 -53.602651)
			(xy 365.215785 -53.655153) (xy 365.19294 -53.704899) (xy 365.163215 -53.750867) (xy 365.146644 -53.77053)
			(xy 365.510826 -53.77053) (xy 365.511356 -53.741613) (xy 365.520081 -53.684442) (xy 365.537336 -53.629243)
			(xy 365.562726 -53.577281) (xy 365.595668 -53.529747) (xy 365.635407 -53.48773) (xy 365.657892 -53.46954)
			(xy 365.66667 -53.461904) (xy 365.67687 -53.441025) (xy 365.67745 -53.429408) (xy 365.67745 -53.349652)
			(xy 365.676942 -53.338016) (xy 365.666733 -53.317105) (xy 365.657892 -53.30952) (xy 365.635416 -53.29132)
			(xy 365.595681 -53.249302) (xy 365.562741 -53.201769) (xy 365.537352 -53.149809) (xy 365.520094 -53.094613)
			(xy 365.511362 -53.037445) (xy 365.510826 -53.00853) (xy 365.511283 -52.981276) (xy 365.519037 -52.927323)
			(xy 365.534391 -52.875023) (xy 365.557033 -52.825441) (xy 365.586501 -52.779586) (xy 365.622195 -52.738392)
			(xy 365.663389 -52.702698) (xy 365.709245 -52.673231) (xy 365.758827 -52.65059) (xy 365.811127 -52.635236)
			(xy 365.86508 -52.627483) (xy 365.892334 -52.627022) (xy 365.918649 -52.62746) (xy 365.970779 -52.6347)
			(xy 366.021423 -52.649024) (xy 366.069622 -52.670162) (xy 366.114464 -52.697714) (xy 366.155103 -52.731158)
			(xy 366.173258 -52.750212) (xy 366.180792 -52.757599) (xy 366.200063 -52.766131) (xy 366.210596 -52.766722)
			(xy 366.285272 -52.766722) (xy 366.295821 -52.766185) (xy 366.315115 -52.757654) (xy 366.32261 -52.750212)
			(xy 366.34077 -52.731161) (xy 366.381399 -52.697703) (xy 366.426238 -52.670143) (xy 366.474438 -52.649004)
			(xy 366.525085 -52.634686) (xy 366.577218 -52.627461) (xy 366.603534 -52.627022) (xy 366.630787 -52.627446)
			(xy 366.684739 -52.635208) (xy 366.737037 -52.650569) (xy 366.786616 -52.673216) (xy 366.832468 -52.702689)
			(xy 366.873658 -52.738387) (xy 366.909349 -52.779584) (xy 366.938814 -52.82544) (xy 366.961453 -52.875023)
			(xy 366.976805 -52.927324) (xy 366.984558 -52.981276) (xy 366.985042 -53.00853) (xy 366.98458 -53.036197)
			(xy 366.982349 -53.051456) (xy 375.24131 -53.051456) (xy 375.245381 -52.995834) (xy 375.257507 -52.941397)
			(xy 375.27743 -52.889306) (xy 375.304726 -52.840671) (xy 375.338812 -52.796528) (xy 375.378961 -52.757819)
			(xy 375.424319 -52.725368) (xy 375.473919 -52.699867) (xy 375.526703 -52.68186) (xy 375.581546 -52.67173)
			(xy 375.63728 -52.669693) (xy 375.692717 -52.675793) (xy 375.746674 -52.689899) (xy 375.798003 -52.711711)
			(xy 375.845609 -52.740765) (xy 375.888477 -52.77644) (xy 375.925694 -52.817977) (xy 375.956467 -52.86449)
			(xy 375.980139 -52.914987) (xy 375.996207 -52.968394) (xy 376.004327 -53.02357) (xy 376.004836 -53.051456)
			(xy 376.004327 -53.079342) (xy 375.996207 -53.134518) (xy 375.980139 -53.187925) (xy 375.956467 -53.238422)
			(xy 375.925694 -53.284935) (xy 375.888477 -53.326472) (xy 375.845609 -53.362147) (xy 375.798003 -53.391201)
			(xy 375.746674 -53.413013) (xy 375.692717 -53.427119) (xy 375.63728 -53.433219) (xy 375.581546 -53.431182)
			(xy 375.526703 -53.421052) (xy 375.473919 -53.403045) (xy 375.424319 -53.377544) (xy 375.378961 -53.345093)
			(xy 375.338812 -53.306384) (xy 375.304726 -53.262241) (xy 375.27743 -53.213606) (xy 375.257507 -53.161515)
			(xy 375.245381 -53.107078) (xy 375.24131 -53.051456) (xy 366.982349 -53.051456) (xy 366.976575 -53.09095)
			(xy 366.960752 -53.143974) (xy 366.937441 -53.194159) (xy 366.907131 -53.240454) (xy 366.870457 -53.28189)
			(xy 366.828187 -53.317599) (xy 366.804956 -53.332634) (xy 366.795266 -53.339255) (xy 366.782828 -53.359128)
			(xy 366.78108 -53.370734) (xy 366.773206 -53.450744) (xy 366.772568 -53.462382) (xy 366.780654 -53.484219)
			(xy 366.7887 -53.492654) (xy 366.788954 -53.492908) (xy 366.807513 -53.511012) (xy 366.840095 -53.551337)
			(xy 366.866912 -53.595707) (xy 366.887469 -53.643301) (xy 366.901387 -53.693242) (xy 366.908408 -53.744608)
			(xy 366.908842 -53.77053) (xy 366.90835 -53.79778) (xy 366.90059 -53.851726) (xy 366.885233 -53.904019)
			(xy 366.862591 -53.953594) (xy 366.833125 -53.999442) (xy 366.797434 -54.040631) (xy 366.756246 -54.076322)
			(xy 366.710397 -54.105789) (xy 366.660822 -54.128432) (xy 366.60853 -54.14379) (xy 366.554584 -54.15155)
			(xy 366.527334 -54.152038) (xy 366.499964 -54.151567) (xy 366.445784 -54.143753) (xy 366.393281 -54.128266)
			(xy 366.343534 -54.105425) (xy 366.297567 -54.0757) (xy 366.276636 -54.058058) (xy 366.276382 -54.057804)
			(xy 366.269304 -54.052204) (xy 366.252381 -54.045965) (xy 366.243362 -54.045612) (xy 366.176306 -54.045612)
			(xy 366.167289 -54.045969) (xy 366.150372 -54.052216) (xy 366.143286 -54.057804) (xy 366.143286 -54.058058)
			(xy 366.143032 -54.058058) (xy 366.122093 -54.075689) (xy 366.076123 -54.105404) (xy 366.026377 -54.128242)
			(xy 365.973878 -54.143734) (xy 365.919703 -54.151564) (xy 365.892334 -54.152038) (xy 365.865083 -54.151513)
			(xy 365.811136 -54.143762) (xy 365.758841 -54.128411) (xy 365.709263 -54.105775) (xy 365.663411 -54.076313)
			(xy 365.622219 -54.040626) (xy 365.586525 -53.99944) (xy 365.557056 -53.953593) (xy 365.534411 -53.904019)
			(xy 365.519052 -53.851726) (xy 365.511291 -53.797781) (xy 365.510826 -53.77053) (xy 365.146644 -53.77053)
			(xy 365.145574 -53.7718) (xy 365.14532 -53.772054) (xy 365.139737 -53.779143) (xy 365.13349 -53.796058)
			(xy 365.133128 -53.805074) (xy 365.133128 -53.87213) (xy 365.133465 -53.881149) (xy 365.139726 -53.898066)
			(xy 365.14532 -53.90515) (xy 365.145574 -53.90515) (xy 365.145574 -53.905404) (xy 365.163217 -53.926335)
			(xy 365.192941 -53.972303) (xy 365.215786 -54.02205) (xy 365.231283 -54.074552) (xy 365.239111 -54.128731)
			(xy 365.239111 -54.183472) (xy 365.231282 -54.237651) (xy 365.215785 -54.290153) (xy 365.201993 -54.320186)
			(xy 367.430558 -54.320186) (xy 367.431002 -54.292815) (xy 367.438823 -54.238634) (xy 367.454316 -54.18613)
			(xy 367.477163 -54.136384) (xy 367.506894 -54.090418) (xy 367.524538 -54.069488) (xy 367.524792 -54.069234)
			(xy 367.53037 -54.062141) (xy 367.536622 -54.045229) (xy 367.536984 -54.036214) (xy 367.536984 -53.969158)
			(xy 367.536603 -53.960144) (xy 367.530372 -53.943226) (xy 367.524792 -53.936138) (xy 367.524538 -53.936138)
			(xy 367.524538 -53.935884) (xy 367.506931 -53.914926) (xy 367.477213 -53.868961) (xy 367.45437 -53.81922)
			(xy 367.438872 -53.766725) (xy 367.431036 -53.712554) (xy 367.430558 -53.685186) (xy 367.431044 -53.657935)
			(xy 367.4388 -53.603987) (xy 367.454155 -53.551692) (xy 367.476797 -53.502115) (xy 367.506263 -53.456265)
			(xy 367.541954 -53.415074) (xy 367.583145 -53.379383) (xy 367.628995 -53.349917) (xy 367.678572 -53.327275)
			(xy 367.730867 -53.31192) (xy 367.784815 -53.304164) (xy 367.839317 -53.304164) (xy 367.893265 -53.31192)
			(xy 367.94556 -53.327275) (xy 367.995137 -53.349917) (xy 368.040987 -53.379383) (xy 368.082178 -53.415074)
			(xy 368.117869 -53.456265) (xy 368.143759 -53.496551) (xy 380.433564 -53.496551) (xy 380.433564 -53.442049)
			(xy 380.44132 -53.388101) (xy 380.456675 -53.335806) (xy 380.479315 -53.286228) (xy 380.508781 -53.240377)
			(xy 380.544471 -53.199186) (xy 380.585661 -53.163493) (xy 380.63151 -53.134025) (xy 380.681087 -53.111382)
			(xy 380.733381 -53.096024) (xy 380.787329 -53.088265) (xy 380.81458 -53.087778) (xy 380.841951 -53.088237)
			(xy 380.896131 -53.096053) (xy 380.948635 -53.111543) (xy 380.998382 -53.134387) (xy 381.044347 -53.164115)
			(xy 381.065278 -53.181758) (xy 381.065532 -53.182012) (xy 381.072633 -53.187578) (xy 381.089539 -53.193837)
			(xy 381.098552 -53.194204) (xy 381.165608 -53.194204) (xy 381.174625 -53.19385) (xy 381.191542 -53.1876)
			(xy 381.198628 -53.182012) (xy 381.198628 -53.181758) (xy 381.198882 -53.181758) (xy 381.219804 -53.164107)
			(xy 381.26578 -53.134398) (xy 381.315531 -53.111565) (xy 381.368033 -53.096077) (xy 381.42221 -53.088251)
			(xy 381.44958 -53.087778) (xy 381.476833 -53.088268) (xy 381.530784 -53.096022) (xy 381.583082 -53.111376)
			(xy 381.632663 -53.134017) (xy 381.678517 -53.163483) (xy 381.719711 -53.199175) (xy 381.755405 -53.240367)
			(xy 381.784874 -53.286219) (xy 381.807517 -53.335799) (xy 381.822873 -53.388097) (xy 381.830631 -53.442047)
			(xy 381.830631 -53.496553) (xy 381.822873 -53.550503) (xy 381.807517 -53.602801) (xy 381.784874 -53.652381)
			(xy 381.755405 -53.698233) (xy 381.719711 -53.739425) (xy 381.678517 -53.775117) (xy 381.632663 -53.804583)
			(xy 381.583082 -53.827224) (xy 381.530784 -53.842578) (xy 381.476833 -53.850332) (xy 381.44958 -53.850794)
			(xy 381.422209 -53.850341) (xy 381.36803 -53.84252) (xy 381.315526 -53.827028) (xy 381.26578 -53.804184)
			(xy 381.219813 -53.774456) (xy 381.198882 -53.756814) (xy 381.198628 -53.75656) (xy 381.191541 -53.750974)
			(xy 381.174624 -53.744728) (xy 381.165608 -53.744368) (xy 381.098552 -53.744368) (xy 381.089538 -53.744757)
			(xy 381.072622 -53.750983) (xy 381.065532 -53.75656) (xy 381.065532 -53.756814) (xy 381.065278 -53.756814)
			(xy 381.044329 -53.774432) (xy 380.998361 -53.804147) (xy 380.948617 -53.826986) (xy 380.896121 -53.842482)
			(xy 380.841948 -53.850317) (xy 380.81458 -53.850794) (xy 380.787329 -53.850335) (xy 380.733381 -53.842576)
			(xy 380.681087 -53.827218) (xy 380.63151 -53.804575) (xy 380.585661 -53.775107) (xy 380.544471 -53.739414)
			(xy 380.508781 -53.698223) (xy 380.479315 -53.652372) (xy 380.456675 -53.602794) (xy 380.44132 -53.550499)
			(xy 380.433564 -53.496551) (xy 368.143759 -53.496551) (xy 368.147335 -53.502115) (xy 368.169977 -53.551692)
			(xy 368.185332 -53.603987) (xy 368.193088 -53.657935) (xy 368.193574 -53.685186) (xy 368.193106 -53.712556)
			(xy 368.18529 -53.766735) (xy 368.169801 -53.819239) (xy 368.14696 -53.868986) (xy 368.117235 -53.914952)
			(xy 368.099594 -53.935884) (xy 368.09934 -53.936138) (xy 368.093766 -53.943233) (xy 368.087513 -53.960144)
			(xy 368.087148 -53.969158) (xy 368.087148 -54.036214) (xy 368.087488 -54.045233) (xy 368.093746 -54.06215)
			(xy 368.09934 -54.069234) (xy 368.099594 -54.069234) (xy 368.099594 -54.069488) (xy 368.11724 -54.090415)
			(xy 368.146951 -54.136389) (xy 368.169786 -54.186138) (xy 368.185275 -54.23864) (xy 368.193101 -54.292816)
			(xy 368.193574 -54.320186) (xy 368.193088 -54.347437) (xy 368.185332 -54.401385) (xy 368.169977 -54.45368)
			(xy 368.147335 -54.503257) (xy 368.117869 -54.549107) (xy 368.082178 -54.590298) (xy 368.040987 -54.625989)
			(xy 367.995137 -54.655455) (xy 367.94556 -54.678097) (xy 367.893265 -54.693452) (xy 367.839317 -54.701208)
			(xy 367.784815 -54.701208) (xy 367.730867 -54.693452) (xy 367.678572 -54.678097) (xy 367.628995 -54.655455)
			(xy 367.583145 -54.625989) (xy 367.541954 -54.590298) (xy 367.506263 -54.549107) (xy 367.476797 -54.503257)
			(xy 367.454155 -54.45368) (xy 367.4388 -54.401385) (xy 367.431044 -54.347437) (xy 367.430558 -54.320186)
			(xy 365.201993 -54.320186) (xy 365.19294 -54.339899) (xy 365.163215 -54.385867) (xy 365.145574 -54.4068)
			(xy 365.14532 -54.407054) (xy 365.139737 -54.414143) (xy 365.13349 -54.431058) (xy 365.133128 -54.440074)
			(xy 365.133128 -54.50713) (xy 365.133465 -54.516149) (xy 365.139726 -54.533066) (xy 365.14532 -54.54015)
			(xy 365.145574 -54.54015) (xy 365.145574 -54.540404) (xy 365.163224 -54.561327) (xy 365.192935 -54.607302)
			(xy 365.21577 -54.657052) (xy 365.231258 -54.709555) (xy 365.239082 -54.763732) (xy 365.239199 -54.770528)
			(xy 368.37112 -54.770528) (xy 368.371598 -54.743158) (xy 368.379412 -54.688979) (xy 368.394898 -54.636476)
			(xy 368.417737 -54.586729) (xy 368.44746 -54.540762) (xy 368.4651 -54.51983) (xy 368.465354 -54.519576)
			(xy 368.470963 -54.512505) (xy 368.477195 -54.495576) (xy 368.477546 -54.486556) (xy 368.477546 -54.4195)
			(xy 368.477201 -54.410482) (xy 368.470946 -54.393564) (xy 368.465354 -54.38648) (xy 368.4651 -54.38648)
			(xy 368.4651 -54.386226) (xy 368.44746 -54.365295) (xy 368.417748 -54.319322) (xy 368.394912 -54.269574)
			(xy 368.379422 -54.217073) (xy 368.371594 -54.162897) (xy 368.37112 -54.135528) (xy 368.371606 -54.108277)
			(xy 368.379362 -54.054329) (xy 368.394717 -54.002034) (xy 368.417359 -53.952457) (xy 368.446825 -53.906607)
			(xy 368.482516 -53.865416) (xy 368.523707 -53.829725) (xy 368.569557 -53.800259) (xy 368.619134 -53.777617)
			(xy 368.671429 -53.762262) (xy 368.725377 -53.754506) (xy 368.779879 -53.754506) (xy 368.833827 -53.762262)
			(xy 368.886122 -53.777617) (xy 368.935699 -53.800259) (xy 368.981549 -53.829725) (xy 369.02274 -53.865416)
			(xy 369.058431 -53.906607) (xy 369.087897 -53.952457) (xy 369.092972 -53.96357) (xy 373.07215 -53.96357)
			(xy 373.076221 -53.907948) (xy 373.088347 -53.853511) (xy 373.10827 -53.80142) (xy 373.135566 -53.752785)
			(xy 373.169652 -53.708642) (xy 373.209801 -53.669933) (xy 373.255159 -53.637482) (xy 373.304759 -53.611981)
			(xy 373.357543 -53.593974) (xy 373.412386 -53.583844) (xy 373.46812 -53.581807) (xy 373.523557 -53.587907)
			(xy 373.577514 -53.602013) (xy 373.628843 -53.623825) (xy 373.676449 -53.652879) (xy 373.719317 -53.688554)
			(xy 373.756534 -53.730091) (xy 373.787307 -53.776604) (xy 373.810979 -53.827101) (xy 373.827047 -53.880508)
			(xy 373.835167 -53.935684) (xy 373.835676 -53.96357) (xy 373.835167 -53.991456) (xy 373.827047 -54.046632)
			(xy 373.810979 -54.100039) (xy 373.787307 -54.150536) (xy 373.756534 -54.197049) (xy 373.719317 -54.238586)
			(xy 373.676449 -54.274261) (xy 373.628843 -54.303315) (xy 373.577514 -54.325127) (xy 373.523557 -54.339233)
			(xy 373.46812 -54.345333) (xy 373.412386 -54.343296) (xy 373.357543 -54.333166) (xy 373.304759 -54.315159)
			(xy 373.255159 -54.289658) (xy 373.209801 -54.257207) (xy 373.169652 -54.218498) (xy 373.135566 -54.174355)
			(xy 373.10827 -54.12572) (xy 373.088347 -54.073629) (xy 373.076221 -54.019192) (xy 373.07215 -53.96357)
			(xy 369.092972 -53.96357) (xy 369.110539 -54.002034) (xy 369.125894 -54.054329) (xy 369.13365 -54.108277)
			(xy 369.134136 -54.135528) (xy 369.133702 -54.1629) (xy 369.125879 -54.217081) (xy 369.110383 -54.269585)
			(xy 369.087534 -54.319331) (xy 369.057801 -54.365296) (xy 369.040156 -54.386226) (xy 369.039902 -54.38648)
			(xy 369.034318 -54.393568) (xy 369.02807 -54.410484) (xy 369.02771 -54.4195) (xy 369.02771 -54.486556)
			(xy 369.028086 -54.495571) (xy 369.03432 -54.512488) (xy 369.039902 -54.519576) (xy 369.040156 -54.519576)
			(xy 369.040156 -54.51983) (xy 369.057769 -54.540783) (xy 369.087486 -54.58675) (xy 369.110328 -54.636492)
			(xy 369.125825 -54.688988) (xy 369.133659 -54.74316) (xy 369.134136 -54.770528) (xy 369.13365 -54.797779)
			(xy 369.125894 -54.851727) (xy 369.110539 -54.904022) (xy 369.087897 -54.953599) (xy 369.065113 -54.989051)
			(xy 378.201168 -54.989051) (xy 378.201168 -54.934549) (xy 378.208924 -54.880602) (xy 378.224278 -54.828308)
			(xy 378.246918 -54.778732) (xy 378.276382 -54.732881) (xy 378.312072 -54.691691) (xy 378.35326 -54.655998)
			(xy 378.399109 -54.62653) (xy 378.448684 -54.603887) (xy 378.500977 -54.588529) (xy 378.554923 -54.58077)
			(xy 378.582174 -54.580282) (xy 378.610265 -54.580797) (xy 378.665841 -54.589021) (xy 378.71961 -54.605308)
			(xy 378.770407 -54.629308) (xy 378.817134 -54.660499) (xy 378.85878 -54.698208) (xy 378.894443 -54.741619)
			(xy 378.909326 -54.765448) (xy 378.91466 -54.774338) (xy 378.931678 -54.78653) (xy 379.024896 -54.80685)
			(xy 379.04547 -54.802532) (xy 379.054106 -54.79669) (xy 379.078166 -54.780684) (xy 379.130099 -54.755343)
			(xy 379.185258 -54.738119) (xy 379.242383 -54.729406) (xy 379.271276 -54.728872) (xy 379.298527 -54.729378)
			(xy 379.352476 -54.737131) (xy 379.404772 -54.752483) (xy 379.45435 -54.775121) (xy 379.500203 -54.804585)
			(xy 379.541395 -54.840274) (xy 379.577089 -54.881462) (xy 379.606558 -54.927311) (xy 379.629202 -54.976887)
			(xy 379.64456 -55.029181) (xy 379.652319 -55.083129) (xy 379.652784 -55.11038) (xy 379.65231 -55.13775)
			(xy 379.644495 -55.191929) (xy 379.629008 -55.244432) (xy 379.606168 -55.294179) (xy 379.576445 -55.340146)
			(xy 379.558804 -55.361078) (xy 379.55855 -55.361332) (xy 379.55298 -55.36843) (xy 379.546724 -55.385338)
			(xy 379.546358 -55.394352) (xy 379.546358 -55.461408) (xy 379.546699 -55.470427) (xy 379.552956 -55.487344)
			(xy 379.55855 -55.494428) (xy 379.558804 -55.494428) (xy 379.558804 -55.494682) (xy 379.576424 -55.515631)
			(xy 379.606147 -55.561597) (xy 379.628992 -55.611341) (xy 379.644488 -55.66384) (xy 379.652318 -55.718016)
			(xy 379.65232 -55.772754) (xy 379.644495 -55.826931) (xy 379.629002 -55.879431) (xy 379.606162 -55.929177)
			(xy 379.576442 -55.975145) (xy 379.558804 -55.996078) (xy 379.55855 -55.996332) (xy 379.55298 -56.00343)
			(xy 379.546724 -56.020338) (xy 379.546358 -56.029352) (xy 379.546358 -56.096408) (xy 379.546699 -56.105427)
			(xy 379.552956 -56.122344) (xy 379.55855 -56.129428) (xy 379.558804 -56.129428) (xy 379.558804 -56.129682)
			(xy 379.576449 -56.15061) (xy 379.60616 -56.196584) (xy 379.628994 -56.246332) (xy 379.644484 -56.298834)
			(xy 379.652311 -56.353011) (xy 379.652784 -56.38038) (xy 379.652298 -56.407631) (xy 379.644542 -56.461579)
			(xy 379.629187 -56.513874) (xy 379.606545 -56.563451) (xy 379.577079 -56.609301) (xy 379.541388 -56.650492)
			(xy 379.500197 -56.686183) (xy 379.454347 -56.715649) (xy 379.40477 -56.738291) (xy 379.352475 -56.753646)
			(xy 379.298527 -56.761402) (xy 379.244025 -56.761402) (xy 379.190077 -56.753646) (xy 379.137782 -56.738291)
			(xy 379.088205 -56.715649) (xy 379.042355 -56.686183) (xy 379.001164 -56.650492) (xy 378.965473 -56.609301)
			(xy 378.936007 -56.563451) (xy 378.913365 -56.513874) (xy 378.89801 -56.461579) (xy 378.890254 -56.407631)
			(xy 378.889768 -56.38038) (xy 378.890206 -56.353009) (xy 378.898028 -56.298828) (xy 378.913523 -56.246324)
			(xy 378.936371 -56.196577) (xy 378.966103 -56.150612) (xy 378.983748 -56.129682) (xy 378.984002 -56.129428)
			(xy 378.989583 -56.122338) (xy 378.995833 -56.105424) (xy 378.996194 -56.096408) (xy 378.996194 -56.029352)
			(xy 378.995813 -56.020338) (xy 378.989582 -56.00342) (xy 378.984002 -55.996332) (xy 378.983748 -55.996332)
			(xy 378.983748 -55.996078) (xy 378.966087 -55.975162) (xy 378.936361 -55.929191) (xy 378.913516 -55.879443)
			(xy 378.89802 -55.826938) (xy 378.890193 -55.772757) (xy 378.890195 -55.718013) (xy 378.898027 -55.663833)
			(xy 378.913526 -55.611329) (xy 378.936376 -55.561582) (xy 378.966105 -55.515614) (xy 378.983748 -55.494682)
			(xy 378.984002 -55.494428) (xy 378.989583 -55.487338) (xy 378.995833 -55.470424) (xy 378.996194 -55.461408)
			(xy 378.996194 -55.394352) (xy 378.995813 -55.385338) (xy 378.989582 -55.36842) (xy 378.984002 -55.361332)
			(xy 378.983748 -55.360824) (xy 378.972801 -55.348092) (xy 378.952962 -55.320999) (xy 378.944124 -55.306722)
			(xy 378.93879 -55.297832) (xy 378.921772 -55.28564) (xy 378.828554 -55.26532) (xy 378.80798 -55.269638)
			(xy 378.799344 -55.27548) (xy 378.775268 -55.291461) (xy 378.723341 -55.316809) (xy 378.668187 -55.33404)
			(xy 378.611066 -55.342761) (xy 378.582174 -55.343298) (xy 378.554923 -55.34283) (xy 378.500977 -55.335071)
			(xy 378.448684 -55.319713) (xy 378.399109 -55.29707) (xy 378.35326 -55.267602) (xy 378.312072 -55.231909)
			(xy 378.276382 -55.190719) (xy 378.246918 -55.144868) (xy 378.224278 -55.095292) (xy 378.208924 -55.042998)
			(xy 378.201168 -54.989051) (xy 369.065113 -54.989051) (xy 369.058431 -54.999449) (xy 369.02274 -55.04064)
			(xy 368.981549 -55.076331) (xy 368.935699 -55.105797) (xy 368.886122 -55.128439) (xy 368.833827 -55.143794)
			(xy 368.779879 -55.15155) (xy 368.725377 -55.15155) (xy 368.671429 -55.143794) (xy 368.619134 -55.128439)
			(xy 368.569557 -55.105797) (xy 368.523707 -55.076331) (xy 368.482516 -55.04064) (xy 368.446825 -54.999449)
			(xy 368.417359 -54.953599) (xy 368.394717 -54.904022) (xy 368.379362 -54.851727) (xy 368.371606 -54.797779)
			(xy 368.37112 -54.770528) (xy 365.239199 -54.770528) (xy 365.239554 -54.791102) (xy 365.239068 -54.818353)
			(xy 365.231312 -54.872301) (xy 365.215957 -54.924596) (xy 365.193315 -54.974173) (xy 365.163849 -55.020023)
			(xy 365.128158 -55.061214) (xy 365.086967 -55.096905) (xy 365.041117 -55.126371) (xy 364.99154 -55.149013)
			(xy 364.939245 -55.164368) (xy 364.885297 -55.172124) (xy 364.830795 -55.172124) (xy 364.776847 -55.164368)
			(xy 364.724552 -55.149013) (xy 364.674975 -55.126371) (xy 364.629125 -55.096905) (xy 364.587934 -55.061214)
			(xy 364.552243 -55.020023) (xy 364.522777 -54.974173) (xy 364.500135 -54.924596) (xy 364.48478 -54.872301)
			(xy 364.477024 -54.818353) (xy 364.476538 -54.791102) (xy 362.578772 -54.791102) (xy 362.575024 -54.816089)
			(xy 362.558341 -54.870458) (xy 362.533779 -54.921751) (xy 362.501883 -54.968834) (xy 362.463356 -55.010667)
			(xy 362.419051 -55.046323) (xy 362.394754 -55.061104) (xy 362.390944 -55.06339) (xy 362.38199 -55.070419)
			(xy 362.370779 -55.090197) (xy 362.369354 -55.10149) (xy 362.359702 -55.722266) (xy 374.134124 -55.722266)
			(xy 374.138195 -55.666644) (xy 374.150321 -55.612207) (xy 374.170244 -55.560116) (xy 374.19754 -55.511481)
			(xy 374.231626 -55.467338) (xy 374.271775 -55.428629) (xy 374.317133 -55.396178) (xy 374.366733 -55.370677)
			(xy 374.419517 -55.35267) (xy 374.47436 -55.34254) (xy 374.530094 -55.340503) (xy 374.585531 -55.346603)
			(xy 374.639488 -55.360709) (xy 374.690817 -55.382521) (xy 374.738423 -55.411575) (xy 374.749569 -55.420851)
			(xy 376.524768 -55.420851) (xy 376.524768 -55.366349) (xy 376.532524 -55.312402) (xy 376.547878 -55.260108)
			(xy 376.570518 -55.210532) (xy 376.599982 -55.164681) (xy 376.635672 -55.123491) (xy 376.67686 -55.087798)
			(xy 376.722709 -55.05833) (xy 376.772284 -55.035687) (xy 376.824577 -55.020329) (xy 376.878523 -55.01257)
			(xy 376.905774 -55.012082) (xy 376.932087 -55.012572) (xy 376.984214 -55.019803) (xy 377.034856 -55.034118)
			(xy 377.083055 -55.055247) (xy 377.127899 -55.082788) (xy 377.16854 -55.116223) (xy 377.186698 -55.135272)
			(xy 377.194222 -55.142671) (xy 377.2135 -55.151198) (xy 377.224036 -55.151782) (xy 377.298712 -55.151782)
			(xy 377.309265 -55.151278) (xy 377.32856 -55.142726) (xy 377.33605 -55.135272) (xy 377.354183 -55.116194)
			(xy 377.394818 -55.08274) (xy 377.439663 -55.055184) (xy 377.487868 -55.03405) (xy 377.53852 -55.019738)
			(xy 377.590657 -55.012518) (xy 377.616974 -55.012082) (xy 377.644227 -55.012564) (xy 377.69818 -55.020317)
			(xy 377.750479 -55.035671) (xy 377.800061 -55.058311) (xy 377.845917 -55.087778) (xy 377.887111 -55.12347)
			(xy 377.922807 -55.164663) (xy 377.952276 -55.210516) (xy 377.97492 -55.260096) (xy 377.990277 -55.312395)
			(xy 377.998035 -55.366347) (xy 377.998035 -55.420853) (xy 377.990277 -55.474805) (xy 377.97492 -55.527104)
			(xy 377.952276 -55.576684) (xy 377.922807 -55.622537) (xy 377.887111 -55.66373) (xy 377.845917 -55.699422)
			(xy 377.800061 -55.728889) (xy 377.750479 -55.751529) (xy 377.69818 -55.766883) (xy 377.644227 -55.774636)
			(xy 377.616974 -55.775098) (xy 377.590659 -55.774649) (xy 377.53853 -55.76741) (xy 377.487887 -55.753088)
			(xy 377.439688 -55.731952) (xy 377.394845 -55.704402) (xy 377.354206 -55.670961) (xy 377.33605 -55.651908)
			(xy 377.328548 -55.644484) (xy 377.309253 -55.635972) (xy 377.298712 -55.635398) (xy 377.224036 -55.635398)
			(xy 377.213487 -55.635934) (xy 377.194192 -55.644464) (xy 377.186698 -55.651908) (xy 377.168538 -55.670959)
			(xy 377.127909 -55.704416) (xy 377.08307 -55.731976) (xy 377.03487 -55.753115) (xy 376.984223 -55.767433)
			(xy 376.93209 -55.774659) (xy 376.905774 -55.775098) (xy 376.878523 -55.77463) (xy 376.824577 -55.766871)
			(xy 376.772284 -55.751513) (xy 376.722709 -55.72887) (xy 376.67686 -55.699402) (xy 376.635672 -55.663709)
			(xy 376.599982 -55.622519) (xy 376.570518 -55.576668) (xy 376.547878 -55.527092) (xy 376.532524 -55.474798)
			(xy 376.524768 -55.420851) (xy 374.749569 -55.420851) (xy 374.781291 -55.44725) (xy 374.818508 -55.488787)
			(xy 374.849281 -55.5353) (xy 374.872953 -55.585797) (xy 374.889021 -55.639204) (xy 374.897141 -55.69438)
			(xy 374.89765 -55.722266) (xy 374.897141 -55.750152) (xy 374.889021 -55.805328) (xy 374.872953 -55.858735)
			(xy 374.849281 -55.909232) (xy 374.818508 -55.955745) (xy 374.781291 -55.997282) (xy 374.738423 -56.032957)
			(xy 374.690817 -56.062011) (xy 374.639488 -56.083823) (xy 374.585531 -56.097929) (xy 374.530094 -56.104029)
			(xy 374.47436 -56.101992) (xy 374.419517 -56.091862) (xy 374.366733 -56.073855) (xy 374.317133 -56.048354)
			(xy 374.271775 -56.015903) (xy 374.231626 -55.977194) (xy 374.19754 -55.933051) (xy 374.170244 -55.884416)
			(xy 374.150321 -55.832325) (xy 374.138195 -55.777888) (xy 374.134124 -55.722266) (xy 362.359702 -55.722266)
			(xy 362.348526 -56.441086) (xy 362.348694 -56.448168) (xy 362.352438 -56.461825) (xy 362.355892 -56.46801)
			(xy 362.363004 -56.479948) (xy 362.365798 -56.481472) (xy 362.374434 -56.48579) (xy 362.397621 -56.498006)
			(xy 362.44071 -56.527838) (xy 362.479317 -56.563281) (xy 362.512715 -56.60367) (xy 362.540277 -56.648245)
			(xy 362.561485 -56.696171) (xy 362.575942 -56.746546) (xy 362.583376 -56.798425) (xy 362.583984 -56.824626)
			(xy 362.583984 -56.829706) (xy 362.58246 -56.860186) (xy 362.58119 -56.871108) (xy 362.58119 -56.871362)
			(xy 362.579268 -56.88615) (xy 362.573419 -56.915393) (xy 362.569506 -56.929782) (xy 362.562331 -56.953804)
			(xy 362.542546 -56.999871) (xy 362.540723 -57.002934) (xy 369.863624 -57.002934) (xy 369.864125 -56.974842)
			(xy 369.872349 -56.919265) (xy 369.888637 -56.865495) (xy 369.912638 -56.814697) (xy 369.943833 -56.76797)
			(xy 369.981545 -56.726325) (xy 370.024959 -56.690664) (xy 370.04879 -56.675782) (xy 370.05768 -56.670448)
			(xy 370.069872 -56.65343) (xy 370.090192 -56.560212) (xy 370.085874 -56.539638) (xy 370.080032 -56.531002)
			(xy 370.064034 -56.506937) (xy 370.03869 -56.455006) (xy 370.021464 -56.399848) (xy 370.012748 -56.342724)
			(xy 370.012214 -56.313832) (xy 370.012685 -56.286579) (xy 370.020438 -56.232627) (xy 370.035791 -56.180328)
			(xy 370.058432 -56.130747) (xy 370.087899 -56.084892) (xy 370.123592 -56.043699) (xy 370.164784 -56.008005)
			(xy 370.210638 -55.978537) (xy 370.260219 -55.955895) (xy 370.312517 -55.94054) (xy 370.366469 -55.932786)
			(xy 370.393722 -55.932324) (xy 370.421093 -55.932771) (xy 370.475273 -55.940593) (xy 370.527777 -55.956086)
			(xy 370.577523 -55.978932) (xy 370.623489 -56.008661) (xy 370.64442 -56.026304) (xy 370.644674 -56.026558)
			(xy 370.651759 -56.032147) (xy 370.668677 -56.038391) (xy 370.677694 -56.03875) (xy 370.74475 -56.03875)
			(xy 370.753766 -56.03838) (xy 370.770683 -56.032143) (xy 370.77777 -56.026558) (xy 370.77777 -56.026304)
			(xy 370.778024 -56.026304) (xy 370.798957 -56.008663) (xy 370.844925 -55.978939) (xy 370.894671 -55.956093)
			(xy 370.947173 -55.940597) (xy 371.001351 -55.932768) (xy 371.056093 -55.932768) (xy 371.110271 -55.940597)
			(xy 371.162773 -55.956093) (xy 371.212519 -55.978939) (xy 371.258487 -56.008663) (xy 371.27942 -56.026304)
			(xy 371.279674 -56.026558) (xy 371.286759 -56.032147) (xy 371.303677 -56.038391) (xy 371.312694 -56.03875)
			(xy 371.37975 -56.03875) (xy 371.388766 -56.03838) (xy 371.405683 -56.032143) (xy 371.41277 -56.026558)
			(xy 371.41277 -56.026304) (xy 371.413024 -56.026304) (xy 371.433974 -56.008688) (xy 371.479942 -55.978972)
			(xy 371.529685 -55.956132) (xy 371.582182 -55.940635) (xy 371.636354 -55.932801) (xy 371.663722 -55.932324)
			(xy 371.690975 -55.932747) (xy 371.744924 -55.940507) (xy 371.797221 -55.955865) (xy 371.846799 -55.97851)
			(xy 371.892651 -56.007979) (xy 371.933842 -56.043674) (xy 371.969534 -56.084867) (xy 371.999001 -56.13072)
			(xy 372.021642 -56.1803) (xy 372.036998 -56.232597) (xy 372.044754 -56.286547) (xy 372.044754 -56.297068)
			(xy 372.386604 -56.297068) (xy 372.390675 -56.241446) (xy 372.402801 -56.187009) (xy 372.422724 -56.134918)
			(xy 372.45002 -56.086283) (xy 372.484106 -56.04214) (xy 372.524255 -56.003431) (xy 372.569613 -55.97098)
			(xy 372.619213 -55.945479) (xy 372.671997 -55.927472) (xy 372.72684 -55.917342) (xy 372.782574 -55.915305)
			(xy 372.838011 -55.921405) (xy 372.891968 -55.935511) (xy 372.943297 -55.957323) (xy 372.990903 -55.986377)
			(xy 373.033771 -56.022052) (xy 373.070988 -56.063589) (xy 373.101761 -56.110102) (xy 373.125433 -56.160599)
			(xy 373.141501 -56.214006) (xy 373.149621 -56.269182) (xy 373.15013 -56.297068) (xy 373.149621 -56.324954)
			(xy 373.141501 -56.38013) (xy 373.125433 -56.433537) (xy 373.101761 -56.484034) (xy 373.070988 -56.530547)
			(xy 373.033771 -56.572084) (xy 372.990903 -56.607759) (xy 372.943297 -56.636813) (xy 372.891968 -56.658625)
			(xy 372.838011 -56.672731) (xy 372.782574 -56.678831) (xy 372.72684 -56.676794) (xy 372.671997 -56.666664)
			(xy 372.619213 -56.648657) (xy 372.569613 -56.623156) (xy 372.524255 -56.590705) (xy 372.484106 -56.551996)
			(xy 372.45002 -56.507853) (xy 372.422724 -56.459218) (xy 372.402801 -56.407127) (xy 372.390675 -56.35269)
			(xy 372.386604 -56.297068) (xy 372.044754 -56.297068) (xy 372.044754 -56.341053) (xy 372.036998 -56.395003)
			(xy 372.021642 -56.4473) (xy 371.999001 -56.49688) (xy 371.969534 -56.542733) (xy 371.933842 -56.583926)
			(xy 371.892651 -56.619621) (xy 371.846799 -56.64909) (xy 371.797221 -56.671735) (xy 371.744924 -56.687093)
			(xy 371.690975 -56.694853) (xy 371.663722 -56.69534) (xy 371.636352 -56.694876) (xy 371.582172 -56.68706)
			(xy 371.529668 -56.671571) (xy 371.479921 -56.648728) (xy 371.433955 -56.619002) (xy 371.413024 -56.60136)
			(xy 371.41277 -56.601106) (xy 371.405667 -56.595543) (xy 371.388763 -56.589282) (xy 371.37975 -56.588914)
			(xy 371.312694 -56.588914) (xy 371.303676 -56.589265) (xy 371.286759 -56.595516) (xy 371.279674 -56.601106)
			(xy 371.279674 -56.60136) (xy 371.27942 -56.60136) (xy 371.258487 -56.619001) (xy 371.212519 -56.648725)
			(xy 371.162773 -56.671571) (xy 371.110271 -56.687067) (xy 371.056093 -56.694896) (xy 371.001351 -56.694896)
			(xy 370.947173 -56.687067) (xy 370.894671 -56.671571) (xy 370.844925 -56.648725) (xy 370.798957 -56.619001)
			(xy 370.778024 -56.60136) (xy 370.77777 -56.601106) (xy 370.770667 -56.595543) (xy 370.753763 -56.589282)
			(xy 370.74475 -56.588914) (xy 370.677694 -56.588914) (xy 370.668676 -56.589265) (xy 370.651759 -56.595516)
			(xy 370.644674 -56.601106) (xy 370.644166 -56.60136) (xy 370.631431 -56.612304) (xy 370.60434 -56.632145)
			(xy 370.590064 -56.640984) (xy 370.581174 -56.646318) (xy 370.568982 -56.663336) (xy 370.548662 -56.756554)
			(xy 370.55298 -56.777128) (xy 370.558822 -56.785764) (xy 370.574811 -56.809834) (xy 370.600156 -56.861764)
			(xy 370.617384 -56.91692) (xy 370.626103 -56.974042) (xy 370.62664 -57.002934) (xy 370.626154 -57.030185)
			(xy 370.618398 -57.084133) (xy 370.603043 -57.136428) (xy 370.580401 -57.186005) (xy 370.550935 -57.231855)
			(xy 370.515244 -57.273046) (xy 370.474053 -57.308737) (xy 370.428203 -57.338203) (xy 370.378626 -57.360845)
			(xy 370.326331 -57.3762) (xy 370.272383 -57.383956) (xy 370.217881 -57.383956) (xy 370.163933 -57.3762)
			(xy 370.111638 -57.360845) (xy 370.062061 -57.338203) (xy 370.016211 -57.308737) (xy 369.97502 -57.273046)
			(xy 369.939329 -57.231855) (xy 369.909863 -57.186005) (xy 369.887221 -57.136428) (xy 369.871866 -57.084133)
			(xy 369.86411 -57.030185) (xy 369.863624 -57.002934) (xy 362.540723 -57.002934) (xy 362.516906 -57.042954)
			(xy 362.501688 -57.062878) (xy 362.498894 -57.066434) (xy 362.49229 -57.07888) (xy 362.48975 -57.090056)
			(xy 362.48975 -57.117996) (xy 362.489638 -57.123093) (xy 362.487591 -57.133079) (xy 362.485686 -57.137808)
			(xy 362.478828 -57.153556) (xy 362.478574 -57.154318) (xy 362.476034 -57.159906) (xy 362.475018 -57.167526)
			(xy 362.475018 -57.180226) (xy 362.476288 -57.18937) (xy 362.482384 -57.20207) (xy 362.487718 -57.208166)
			(xy 362.489242 -57.209944) (xy 362.490512 -57.211468) (xy 362.492036 -57.212992) (xy 362.494322 -57.215786)
			(xy 362.500672 -57.22366) (xy 362.50499 -57.229248) (xy 362.5088 -57.234328) (xy 362.526433 -57.259124)
			(xy 362.554431 -57.313139) (xy 362.573501 -57.370914) (xy 362.583158 -57.430984) (xy 362.58373 -57.461404)
			(xy 362.58373 -57.461658) (xy 362.583353 -57.48528) (xy 378.906022 -57.48528) (xy 378.910093 -57.429658)
			(xy 378.922219 -57.375221) (xy 378.942142 -57.32313) (xy 378.969438 -57.274495) (xy 379.003524 -57.230352)
			(xy 379.043673 -57.191643) (xy 379.089031 -57.159192) (xy 379.138631 -57.133691) (xy 379.191415 -57.115684)
			(xy 379.246258 -57.105554) (xy 379.301992 -57.103517) (xy 379.357429 -57.109617) (xy 379.411386 -57.123723)
			(xy 379.462715 -57.145535) (xy 379.510321 -57.174589) (xy 379.553189 -57.210264) (xy 379.590406 -57.251801)
			(xy 379.621179 -57.298314) (xy 379.644851 -57.348811) (xy 379.660919 -57.402218) (xy 379.669039 -57.457394)
			(xy 379.669548 -57.48528) (xy 379.669039 -57.513166) (xy 379.660919 -57.568342) (xy 379.644851 -57.621749)
			(xy 379.621179 -57.672246) (xy 379.590406 -57.718759) (xy 379.553189 -57.760296) (xy 379.510321 -57.795971)
			(xy 379.462715 -57.825025) (xy 379.411386 -57.846837) (xy 379.357429 -57.860943) (xy 379.301992 -57.867043)
			(xy 379.246258 -57.865006) (xy 379.191415 -57.854876) (xy 379.138631 -57.836869) (xy 379.089031 -57.811368)
			(xy 379.043673 -57.778917) (xy 379.003524 -57.740208) (xy 378.969438 -57.696065) (xy 378.942142 -57.64743)
			(xy 378.922219 -57.595339) (xy 378.910093 -57.540902) (xy 378.906022 -57.48528) (xy 362.583353 -57.48528)
			(xy 362.583328 -57.486821) (xy 362.576709 -57.53671) (xy 362.563579 -57.585294) (xy 362.544168 -57.631726)
			(xy 362.518813 -57.675199) (xy 362.50372 -57.695338) (xy 362.503212 -57.695846) (xy 362.496354 -57.70626)
			(xy 362.493328 -57.711967) (xy 362.489993 -57.724442) (xy 362.48975 -57.730898) (xy 362.48975 -57.752996)
			(xy 362.489638 -57.758093) (xy 362.487591 -57.768079) (xy 362.485686 -57.772808) (xy 362.478828 -57.788556)
			(xy 362.478574 -57.789318) (xy 362.476034 -57.794906) (xy 362.475018 -57.802526) (xy 362.475018 -57.815226)
			(xy 362.476288 -57.82437) (xy 362.482384 -57.83707) (xy 362.487718 -57.843166) (xy 362.489242 -57.844944)
			(xy 362.490512 -57.846468) (xy 362.492036 -57.847992) (xy 362.494322 -57.850786) (xy 362.500672 -57.85866)
			(xy 362.50499 -57.864248) (xy 362.5088 -57.869328) (xy 362.526433 -57.894124) (xy 362.554431 -57.948139)
			(xy 362.573501 -58.005914) (xy 362.583158 -58.065984) (xy 362.58373 -58.096404) (xy 362.58373 -58.096658)
			(xy 362.583328 -58.121821) (xy 362.576709 -58.17171) (xy 362.563579 -58.220294) (xy 362.544168 -58.266726)
			(xy 362.518813 -58.310199) (xy 362.50372 -58.330338) (xy 362.503212 -58.330846) (xy 362.496354 -58.34126)
			(xy 362.493328 -58.346967) (xy 362.489993 -58.359442) (xy 362.48975 -58.365898) (xy 362.48975 -58.387234)
			(xy 362.489606 -58.392673) (xy 362.487296 -58.403304) (xy 362.485178 -58.408316) (xy 362.478828 -58.420508)
			(xy 362.476661 -58.425446) (xy 362.474228 -58.435949) (xy 362.474002 -58.441336) (xy 362.474002 -58.444892)
			(xy 362.47451 -58.450734) (xy 362.47578 -58.457338) (xy 362.482638 -58.471816) (xy 362.487464 -58.47715)
			(xy 362.505533 -58.498238) (xy 362.536021 -58.544652) (xy 362.559474 -58.594988) (xy 362.575399 -58.648187)
			(xy 362.579969 -58.679334) (xy 370.295424 -58.679334) (xy 370.29584 -58.653018) (xy 370.303084 -58.600887)
			(xy 370.317413 -58.550243) (xy 370.338555 -58.502044) (xy 370.36611 -58.457202) (xy 370.399558 -58.416565)
			(xy 370.418614 -58.39841) (xy 370.426015 -58.390889) (xy 370.43454 -58.371608) (xy 370.435124 -58.361072)
			(xy 370.435124 -58.286396) (xy 370.434603 -58.275846) (xy 370.426061 -58.256551) (xy 370.418614 -58.249058)
			(xy 370.399548 -58.230913) (xy 370.366091 -58.190281) (xy 370.338533 -58.145439) (xy 370.317396 -58.097236)
			(xy 370.303082 -58.046587) (xy 370.29586 -57.994451) (xy 370.295424 -57.968134) (xy 370.29591 -57.940883)
			(xy 370.303666 -57.886935) (xy 370.319021 -57.83464) (xy 370.341663 -57.785063) (xy 370.371129 -57.739213)
			(xy 370.40682 -57.698022) (xy 370.448011 -57.662331) (xy 370.493861 -57.632865) (xy 370.543438 -57.610223)
			(xy 370.595733 -57.594868) (xy 370.649681 -57.587112) (xy 370.704183 -57.587112) (xy 370.758131 -57.594868)
			(xy 370.810426 -57.610223) (xy 370.860003 -57.632865) (xy 370.905853 -57.662331) (xy 370.947044 -57.698022)
			(xy 370.982735 -57.739213) (xy 371.012201 -57.785063) (xy 371.034843 -57.83464) (xy 371.050198 -57.886935)
			(xy 371.057954 -57.940883) (xy 371.05844 -57.968134) (xy 371.058014 -57.99445) (xy 371.050774 -58.046581)
			(xy 371.043506 -58.072274) (xy 374.293636 -58.072274) (xy 374.297707 -58.016652) (xy 374.309833 -57.962215)
			(xy 374.329756 -57.910124) (xy 374.357052 -57.861489) (xy 374.391138 -57.817346) (xy 374.431287 -57.778637)
			(xy 374.476645 -57.746186) (xy 374.526245 -57.720685) (xy 374.579029 -57.702678) (xy 374.633872 -57.692548)
			(xy 374.689606 -57.690511) (xy 374.745043 -57.696611) (xy 374.799 -57.710717) (xy 374.850329 -57.732529)
			(xy 374.897935 -57.761583) (xy 374.940803 -57.797258) (xy 374.97802 -57.838795) (xy 375.008793 -57.885308)
			(xy 375.032465 -57.935805) (xy 375.048533 -57.989212) (xy 375.056653 -58.044388) (xy 375.057162 -58.072274)
			(xy 375.057092 -58.076084) (xy 379.658116 -58.076084) (xy 379.662187 -58.020462) (xy 379.674313 -57.966025)
			(xy 379.694236 -57.913934) (xy 379.721532 -57.865299) (xy 379.755618 -57.821156) (xy 379.795767 -57.782447)
			(xy 379.841125 -57.749996) (xy 379.890725 -57.724495) (xy 379.943509 -57.706488) (xy 379.998352 -57.696358)
			(xy 380.054086 -57.694321) (xy 380.109523 -57.700421) (xy 380.16348 -57.714527) (xy 380.214809 -57.736339)
			(xy 380.262415 -57.765393) (xy 380.305283 -57.801068) (xy 380.3425 -57.842605) (xy 380.358836 -57.867296)
			(xy 381.9431 -57.867296) (xy 381.947171 -57.811674) (xy 381.959297 -57.757237) (xy 381.97922 -57.705146)
			(xy 382.006516 -57.656511) (xy 382.040602 -57.612368) (xy 382.080751 -57.573659) (xy 382.126109 -57.541208)
			(xy 382.175709 -57.515707) (xy 382.228493 -57.4977) (xy 382.283336 -57.48757) (xy 382.33907 -57.485533)
			(xy 382.394507 -57.491633) (xy 382.448464 -57.505739) (xy 382.499793 -57.527551) (xy 382.547399 -57.556605)
			(xy 382.590267 -57.59228) (xy 382.627484 -57.633817) (xy 382.658257 -57.68033) (xy 382.681929 -57.730827)
			(xy 382.697997 -57.784234) (xy 382.706117 -57.83941) (xy 382.706626 -57.867296) (xy 382.706117 -57.895182)
			(xy 382.697997 -57.950358) (xy 382.681929 -58.003765) (xy 382.658257 -58.054262) (xy 382.627484 -58.100775)
			(xy 382.590267 -58.142312) (xy 382.547399 -58.177987) (xy 382.499793 -58.207041) (xy 382.448464 -58.228853)
			(xy 382.394507 -58.242959) (xy 382.33907 -58.249059) (xy 382.283336 -58.247022) (xy 382.228493 -58.236892)
			(xy 382.175709 -58.218885) (xy 382.126109 -58.193384) (xy 382.080751 -58.160933) (xy 382.040602 -58.122224)
			(xy 382.006516 -58.078081) (xy 381.97922 -58.029446) (xy 381.959297 -57.977355) (xy 381.947171 -57.922918)
			(xy 381.9431 -57.867296) (xy 380.358836 -57.867296) (xy 380.373273 -57.889118) (xy 380.396945 -57.939615)
			(xy 380.413013 -57.993022) (xy 380.421133 -58.048198) (xy 380.421642 -58.076084) (xy 380.421133 -58.10397)
			(xy 380.413013 -58.159146) (xy 380.396945 -58.212553) (xy 380.373273 -58.26305) (xy 380.3425 -58.309563)
			(xy 380.305283 -58.3511) (xy 380.262415 -58.386775) (xy 380.214809 -58.415829) (xy 380.16348 -58.437641)
			(xy 380.109523 -58.451747) (xy 380.054086 -58.457847) (xy 379.998352 -58.45581) (xy 379.943509 -58.44568)
			(xy 379.890725 -58.427673) (xy 379.841125 -58.402172) (xy 379.795767 -58.369721) (xy 379.755618 -58.331012)
			(xy 379.721532 -58.286869) (xy 379.694236 -58.238234) (xy 379.674313 -58.186143) (xy 379.662187 -58.131706)
			(xy 379.658116 -58.076084) (xy 375.057092 -58.076084) (xy 375.056653 -58.10016) (xy 375.048533 -58.155336)
			(xy 375.032465 -58.208743) (xy 375.008793 -58.25924) (xy 374.97802 -58.305753) (xy 374.940803 -58.34729)
			(xy 374.897935 -58.382965) (xy 374.850329 -58.412019) (xy 374.799 -58.433831) (xy 374.745043 -58.447937)
			(xy 374.689606 -58.454037) (xy 374.633872 -58.452) (xy 374.579029 -58.44187) (xy 374.526245 -58.423863)
			(xy 374.476645 -58.398362) (xy 374.431287 -58.365911) (xy 374.391138 -58.327202) (xy 374.357052 -58.283059)
			(xy 374.329756 -58.234424) (xy 374.309833 -58.182333) (xy 374.297707 -58.127896) (xy 374.293636 -58.072274)
			(xy 371.043506 -58.072274) (xy 371.036448 -58.097225) (xy 371.015308 -58.145424) (xy 370.987753 -58.190267)
			(xy 370.954306 -58.230903) (xy 370.93525 -58.249058) (xy 370.927872 -58.2566) (xy 370.919333 -58.275864)
			(xy 370.91874 -58.286396) (xy 370.91874 -58.361072) (xy 370.919259 -58.371623) (xy 370.9278 -58.390919)
			(xy 370.93525 -58.39841) (xy 370.954313 -58.416558) (xy 370.987767 -58.45719) (xy 371.015324 -58.502033)
			(xy 371.036461 -58.550235) (xy 371.039567 -58.561224) (xy 380.86233 -58.561224) (xy 380.866401 -58.505602)
			(xy 380.878527 -58.451165) (xy 380.89845 -58.399074) (xy 380.925746 -58.350439) (xy 380.959832 -58.306296)
			(xy 380.999981 -58.267587) (xy 381.045339 -58.235136) (xy 381.094939 -58.209635) (xy 381.147723 -58.191628)
			(xy 381.202566 -58.181498) (xy 381.2583 -58.179461) (xy 381.313737 -58.185561) (xy 381.367694 -58.199667)
			(xy 381.419023 -58.221479) (xy 381.466629 -58.250533) (xy 381.509497 -58.286208) (xy 381.546714 -58.327745)
			(xy 381.577487 -58.374258) (xy 381.601159 -58.424755) (xy 381.617227 -58.478162) (xy 381.625347 -58.533338)
			(xy 381.625856 -58.561224) (xy 381.625347 -58.58911) (xy 381.617227 -58.644286) (xy 381.601159 -58.697693)
			(xy 381.577487 -58.74819) (xy 381.546714 -58.794703) (xy 381.509497 -58.83624) (xy 381.466629 -58.871915)
			(xy 381.419023 -58.900969) (xy 381.367694 -58.922781) (xy 381.313737 -58.936887) (xy 381.2583 -58.942987)
			(xy 381.202566 -58.94095) (xy 381.147723 -58.93082) (xy 381.094939 -58.912813) (xy 381.045339 -58.887312)
			(xy 380.999981 -58.854861) (xy 380.959832 -58.816152) (xy 380.925746 -58.772009) (xy 380.89845 -58.723374)
			(xy 380.878527 -58.671283) (xy 380.866401 -58.616846) (xy 380.86233 -58.561224) (xy 371.039567 -58.561224)
			(xy 371.050777 -58.600883) (xy 371.058002 -58.653018) (xy 371.05844 -58.679334) (xy 371.057954 -58.706585)
			(xy 371.050198 -58.760533) (xy 371.034843 -58.812828) (xy 371.012201 -58.862405) (xy 370.982735 -58.908255)
			(xy 370.947044 -58.949446) (xy 370.905853 -58.985137) (xy 370.860003 -59.014603) (xy 370.810426 -59.037245)
			(xy 370.758131 -59.0526) (xy 370.704183 -59.060356) (xy 370.649681 -59.060356) (xy 370.595733 -59.0526)
			(xy 370.543438 -59.037245) (xy 370.493861 -59.014603) (xy 370.448011 -58.985137) (xy 370.40682 -58.949446)
			(xy 370.371129 -58.908255) (xy 370.341663 -58.862405) (xy 370.319021 -58.812828) (xy 370.303666 -58.760533)
			(xy 370.29591 -58.706585) (xy 370.295424 -58.679334) (xy 362.579969 -58.679334) (xy 362.583461 -58.70313)
			(xy 362.583984 -58.730896) (xy 362.583984 -58.731404) (xy 362.58373 -58.734706) (xy 362.58373 -58.741818)
			(xy 362.583476 -58.74385) (xy 362.583476 -58.750708) (xy 362.582968 -58.755788) (xy 362.582968 -58.757058)
			(xy 362.580682 -58.782712) (xy 362.580682 -58.783474) (xy 362.577591 -58.803252) (xy 362.567788 -58.842067)
			(xy 362.561124 -58.860944) (xy 362.558838 -58.86704) (xy 362.554266 -58.879486) (xy 362.550202 -58.887868)
			(xy 362.549948 -58.88863) (xy 362.543687 -58.902193) (xy 362.529321 -58.928387) (xy 362.521246 -58.940954)
			(xy 362.520738 -58.941462) (xy 362.516166 -58.948574) (xy 362.51261 -58.953908) (xy 362.503212 -58.982864)
			(xy 362.503466 -58.987944) (xy 362.521836 -59.174634) (xy 379.393194 -59.174634) (xy 379.397265 -59.119012)
			(xy 379.409391 -59.064575) (xy 379.429314 -59.012484) (xy 379.45661 -58.963849) (xy 379.490696 -58.919706)
			(xy 379.530845 -58.880997) (xy 379.576203 -58.848546) (xy 379.625803 -58.823045) (xy 379.678587 -58.805038)
			(xy 379.73343 -58.794908) (xy 379.789164 -58.792871) (xy 379.844601 -58.798971) (xy 379.898558 -58.813077)
			(xy 379.949887 -58.834889) (xy 379.997493 -58.863943) (xy 380.040361 -58.899618) (xy 380.077578 -58.941155)
			(xy 380.108351 -58.987668) (xy 380.132023 -59.038165) (xy 380.148091 -59.091572) (xy 380.156211 -59.146748)
			(xy 380.15672 -59.174634) (xy 380.156211 -59.20252) (xy 380.148091 -59.257696) (xy 380.132023 -59.311103)
			(xy 380.108351 -59.3616) (xy 380.077578 -59.408113) (xy 380.040361 -59.44965) (xy 379.997493 -59.485325)
			(xy 379.949887 -59.514379) (xy 379.898558 -59.536191) (xy 379.844601 -59.550297) (xy 379.789164 -59.556397)
			(xy 379.73343 -59.55436) (xy 379.678587 -59.54423) (xy 379.625803 -59.526223) (xy 379.576203 -59.500722)
			(xy 379.530845 -59.468271) (xy 379.490696 -59.429562) (xy 379.45661 -59.385419) (xy 379.429314 -59.336784)
			(xy 379.409391 -59.284693) (xy 379.397265 -59.230256) (xy 379.393194 -59.174634) (xy 362.521836 -59.174634)
			(xy 362.576872 -59.733942) (xy 362.599478 -59.96178) (xy 362.601739 -59.986164) (xy 362.603372 -60.01925)
			(xy 370.435884 -60.01925) (xy 370.435884 -59.96475) (xy 370.44364 -59.910804) (xy 370.458994 -59.858511)
			(xy 370.481634 -59.808936) (xy 370.511098 -59.763087) (xy 370.546788 -59.721898) (xy 370.587976 -59.686207)
			(xy 370.633824 -59.65674) (xy 370.683398 -59.634099) (xy 370.73569 -59.618743) (xy 370.789636 -59.610985)
			(xy 370.816886 -59.610498) (xy 370.844256 -59.610973) (xy 370.898435 -59.618789) (xy 370.950938 -59.634276)
			(xy 371.000685 -59.657115) (xy 371.046652 -59.686838) (xy 371.067584 -59.704478) (xy 371.067838 -59.704732)
			(xy 371.074936 -59.710302) (xy 371.091844 -59.716558) (xy 371.100858 -59.716924) (xy 371.167914 -59.716924)
			(xy 371.176931 -59.716568) (xy 371.193847 -59.710319) (xy 371.200934 -59.704732) (xy 371.200934 -59.704478)
			(xy 371.201188 -59.704478) (xy 371.222121 -59.686837) (xy 371.268089 -59.657113) (xy 371.317835 -59.634267)
			(xy 371.370337 -59.618771) (xy 371.424515 -59.610942) (xy 371.479257 -59.610942) (xy 371.533435 -59.618771)
			(xy 371.585937 -59.634267) (xy 371.635683 -59.657113) (xy 371.681651 -59.686837) (xy 371.702584 -59.704478)
			(xy 371.702838 -59.704732) (xy 371.709936 -59.710302) (xy 371.726844 -59.716558) (xy 371.735858 -59.716924)
			(xy 371.802914 -59.716924) (xy 371.811931 -59.716568) (xy 371.828847 -59.710319) (xy 371.835934 -59.704732)
			(xy 371.835934 -59.704478) (xy 371.836188 -59.704478) (xy 371.857111 -59.686828) (xy 371.903087 -59.657118)
			(xy 371.952836 -59.634285) (xy 372.005339 -59.618796) (xy 372.059516 -59.610971) (xy 372.086886 -59.610498)
			(xy 372.11414 -59.610948) (xy 372.168093 -59.618704) (xy 372.220394 -59.634059) (xy 372.269976 -59.656701)
			(xy 372.315832 -59.686169) (xy 372.357027 -59.721863) (xy 372.392723 -59.763057) (xy 372.422192 -59.808911)
			(xy 372.444836 -59.858493) (xy 372.460193 -59.910793) (xy 372.467951 -59.964746) (xy 372.467951 -60.019254)
			(xy 372.460193 -60.073207) (xy 372.444836 -60.125507) (xy 372.422192 -60.175089) (xy 372.392723 -60.220943)
			(xy 372.357027 -60.262137) (xy 372.315832 -60.297831) (xy 372.269976 -60.327299) (xy 372.220394 -60.349941)
			(xy 372.168093 -60.365296) (xy 372.11414 -60.373052) (xy 372.086886 -60.373514) (xy 372.059516 -60.373053)
			(xy 372.005336 -60.365233) (xy 371.952833 -60.349743) (xy 371.903087 -60.3269) (xy 371.85712 -60.297175)
			(xy 371.836188 -60.279534) (xy 371.835934 -60.27928) (xy 371.828844 -60.273699) (xy 371.81193 -60.26745)
			(xy 371.802914 -60.267088) (xy 371.735858 -60.267088) (xy 371.726844 -60.267476) (xy 371.709927 -60.273702)
			(xy 371.702838 -60.27928) (xy 371.702584 -60.279534) (xy 371.681651 -60.297175) (xy 371.635683 -60.326899)
			(xy 371.585937 -60.349745) (xy 371.533435 -60.365241) (xy 371.479257 -60.37307) (xy 371.424515 -60.37307)
			(xy 371.370337 -60.365241) (xy 371.317835 -60.349745) (xy 371.268089 -60.326899) (xy 371.222121 -60.297175)
			(xy 371.201188 -60.279534) (xy 371.200934 -60.27928) (xy 371.193844 -60.273699) (xy 371.17693 -60.26745)
			(xy 371.167914 -60.267088) (xy 371.100858 -60.267088) (xy 371.091844 -60.267476) (xy 371.074927 -60.273702)
			(xy 371.067838 -60.27928) (xy 371.067838 -60.279534) (xy 371.067584 -60.279534) (xy 371.046635 -60.297152)
			(xy 371.000667 -60.326866) (xy 370.950923 -60.349706) (xy 370.898426 -60.365202) (xy 370.844254 -60.373036)
			(xy 370.816886 -60.373514) (xy 370.789636 -60.373015) (xy 370.73569 -60.365257) (xy 370.683398 -60.349901)
			(xy 370.633824 -60.32726) (xy 370.587976 -60.297793) (xy 370.546788 -60.262102) (xy 370.511098 -60.220913)
			(xy 370.481634 -60.175064) (xy 370.458994 -60.125489) (xy 370.44364 -60.073196) (xy 370.435884 -60.01925)
			(xy 362.603372 -60.01925) (xy 362.604154 -60.035082) (xy 362.604304 -60.05957) (xy 362.604304 -60.633356)
			(xy 382.097024 -60.633356) (xy 382.101095 -60.577734) (xy 382.113221 -60.523297) (xy 382.133144 -60.471206)
			(xy 382.16044 -60.422571) (xy 382.194526 -60.378428) (xy 382.234675 -60.339719) (xy 382.280033 -60.307268)
			(xy 382.329633 -60.281767) (xy 382.382417 -60.26376) (xy 382.43726 -60.25363) (xy 382.492994 -60.251593)
			(xy 382.548431 -60.257693) (xy 382.602388 -60.271799) (xy 382.653717 -60.293611) (xy 382.701323 -60.322665)
			(xy 382.744191 -60.35834) (xy 382.781408 -60.399877) (xy 382.812181 -60.44639) (xy 382.835853 -60.496887)
			(xy 382.851921 -60.550294) (xy 382.860041 -60.60547) (xy 382.86055 -60.633356) (xy 382.860041 -60.661242)
			(xy 382.851921 -60.716418) (xy 382.835853 -60.769825) (xy 382.812181 -60.820322) (xy 382.781408 -60.866835)
			(xy 382.744191 -60.908372) (xy 382.701323 -60.944047) (xy 382.653717 -60.973101) (xy 382.602388 -60.994913)
			(xy 382.548431 -61.009019) (xy 382.492994 -61.015119) (xy 382.43726 -61.013082) (xy 382.382417 -61.002952)
			(xy 382.329633 -60.984945) (xy 382.280033 -60.959444) (xy 382.234675 -60.926993) (xy 382.194526 -60.888284)
			(xy 382.16044 -60.844141) (xy 382.133144 -60.795506) (xy 382.113221 -60.743415) (xy 382.101095 -60.688978)
			(xy 382.097024 -60.633356) (xy 362.604304 -60.633356) (xy 362.604304 -61.487812) (xy 380.60452 -61.487812)
			(xy 380.608591 -61.43219) (xy 380.620717 -61.377753) (xy 380.64064 -61.325662) (xy 380.667936 -61.277027)
			(xy 380.702022 -61.232884) (xy 380.742171 -61.194175) (xy 380.787529 -61.161724) (xy 380.837129 -61.136223)
			(xy 380.889913 -61.118216) (xy 380.944756 -61.108086) (xy 381.00049 -61.106049) (xy 381.055927 -61.112149)
			(xy 381.109884 -61.126255) (xy 381.161213 -61.148067) (xy 381.208819 -61.177121) (xy 381.251687 -61.212796)
			(xy 381.288904 -61.254333) (xy 381.319677 -61.300846) (xy 381.343349 -61.351343) (xy 381.359417 -61.40475)
			(xy 381.367537 -61.459926) (xy 381.368046 -61.487812) (xy 381.367537 -61.515698) (xy 381.359417 -61.570874)
			(xy 381.343349 -61.624281) (xy 381.319677 -61.674778) (xy 381.288904 -61.721291) (xy 381.251687 -61.762828)
			(xy 381.208819 -61.798503) (xy 381.161213 -61.827557) (xy 381.109884 -61.849369) (xy 381.055927 -61.863475)
			(xy 381.00049 -61.869575) (xy 380.944756 -61.867538) (xy 380.889913 -61.857408) (xy 380.837129 -61.839401)
			(xy 380.787529 -61.8139) (xy 380.742171 -61.781449) (xy 380.702022 -61.74274) (xy 380.667936 -61.698597)
			(xy 380.64064 -61.649962) (xy 380.620717 -61.597871) (xy 380.608591 -61.543434) (xy 380.60452 -61.487812)
			(xy 362.604304 -61.487812) (xy 362.604304 -61.851032) (xy 362.60405 -61.858398) (xy 362.60405 -61.85916)
			(xy 362.601944 -62.121034) (xy 378.542294 -62.121034) (xy 378.546365 -62.065412) (xy 378.558491 -62.010975)
			(xy 378.578414 -61.958884) (xy 378.60571 -61.910249) (xy 378.639796 -61.866106) (xy 378.679945 -61.827397)
			(xy 378.725303 -61.794946) (xy 378.774903 -61.769445) (xy 378.827687 -61.751438) (xy 378.88253 -61.741308)
			(xy 378.938264 -61.739271) (xy 378.993701 -61.745371) (xy 379.047658 -61.759477) (xy 379.098987 -61.781289)
			(xy 379.146593 -61.810343) (xy 379.189461 -61.846018) (xy 379.226678 -61.887555) (xy 379.257451 -61.934068)
			(xy 379.281123 -61.984565) (xy 379.297191 -62.037972) (xy 379.305311 -62.093148) (xy 379.30582 -62.121034)
			(xy 379.305311 -62.14892) (xy 379.297191 -62.204096) (xy 379.281123 -62.257503) (xy 379.257451 -62.308)
			(xy 379.226678 -62.354513) (xy 379.189461 -62.39605) (xy 379.146593 -62.431725) (xy 379.098987 -62.460779)
			(xy 379.047658 -62.482591) (xy 378.993701 -62.496697) (xy 378.938264 -62.502797) (xy 378.88253 -62.50076)
			(xy 378.827687 -62.49063) (xy 378.774903 -62.472623) (xy 378.725303 -62.447122) (xy 378.679945 -62.414671)
			(xy 378.639796 -62.375962) (xy 378.60571 -62.331819) (xy 378.578414 -62.283184) (xy 378.558491 -62.231093)
			(xy 378.546365 -62.176656) (xy 378.542294 -62.121034) (xy 362.601944 -62.121034) (xy 362.593159 -63.21355)
			(xy 370.420888 -63.21355) (xy 370.420888 -63.15905) (xy 370.428645 -63.105103) (xy 370.443999 -63.05281)
			(xy 370.46664 -63.003234) (xy 370.496105 -62.957385) (xy 370.531796 -62.916196) (xy 370.572985 -62.880505)
			(xy 370.618834 -62.85104) (xy 370.66841 -62.828399) (xy 370.720703 -62.813045) (xy 370.77465 -62.805288)
			(xy 370.8019 -62.804802) (xy 370.82927 -62.805268) (xy 370.883449 -62.813085) (xy 370.935953 -62.828575)
			(xy 370.985699 -62.851416) (xy 371.031666 -62.881141) (xy 371.052598 -62.898782) (xy 371.052852 -62.899036)
			(xy 371.059945 -62.904613) (xy 371.076857 -62.910864) (xy 371.085872 -62.911228) (xy 371.152928 -62.911228)
			(xy 371.161946 -62.910878) (xy 371.178862 -62.904625) (xy 371.185948 -62.899036) (xy 371.185948 -62.898782)
			(xy 371.186202 -62.898782) (xy 371.207135 -62.881141) (xy 371.253103 -62.851417) (xy 371.302849 -62.828571)
			(xy 371.355351 -62.813075) (xy 371.409529 -62.805246) (xy 371.464271 -62.805246) (xy 371.518449 -62.813075)
			(xy 371.570951 -62.828571) (xy 371.620697 -62.851417) (xy 371.666665 -62.881141) (xy 371.687598 -62.898782)
			(xy 371.687852 -62.899036) (xy 371.694945 -62.904613) (xy 371.711857 -62.910864) (xy 371.720872 -62.911228)
			(xy 371.787928 -62.911228) (xy 371.796946 -62.910878) (xy 371.813862 -62.904625) (xy 371.820948 -62.899036)
			(xy 371.820948 -62.898782) (xy 371.821202 -62.898782) (xy 371.84212 -62.881126) (xy 371.888097 -62.851417)
			(xy 371.937848 -62.828585) (xy 371.990352 -62.813098) (xy 372.04453 -62.805274) (xy 372.0719 -62.804802)
			(xy 372.099152 -62.805268) (xy 372.153101 -62.813025) (xy 372.205397 -62.82838) (xy 372.254976 -62.851022)
			(xy 372.300827 -62.880489) (xy 372.342019 -62.916181) (xy 372.377711 -62.957373) (xy 372.407178 -63.003224)
			(xy 372.42982 -63.052803) (xy 372.439636 -63.086234) (xy 375.687588 -63.086234) (xy 375.691659 -63.030612)
			(xy 375.703785 -62.976175) (xy 375.723708 -62.924084) (xy 375.751004 -62.875449) (xy 375.78509 -62.831306)
			(xy 375.825239 -62.792597) (xy 375.870597 -62.760146) (xy 375.920197 -62.734645) (xy 375.972981 -62.716638)
			(xy 376.027824 -62.706508) (xy 376.083558 -62.704471) (xy 376.138995 -62.710571) (xy 376.192952 -62.724677)
			(xy 376.213112 -62.733244) (xy 381.966151 -62.733244) (xy 381.966152 -62.678737) (xy 381.973911 -62.624785)
			(xy 381.989268 -62.572487) (xy 382.011913 -62.522906) (xy 382.041383 -62.477053) (xy 382.077079 -62.435861)
			(xy 382.118273 -62.400168) (xy 382.164129 -62.370701) (xy 382.213711 -62.34806) (xy 382.26601 -62.332705)
			(xy 382.319963 -62.32495) (xy 382.347216 -62.324488) (xy 382.370771 -62.324865) (xy 382.417515 -62.330724)
			(xy 382.440434 -62.336172) (xy 382.454192 -62.339197) (xy 382.482341 -62.338344) (xy 382.509188 -62.32984)
			(xy 382.532695 -62.314331) (xy 382.551076 -62.292995) (xy 382.562935 -62.267451) (xy 382.567372 -62.239641)
			(xy 382.564049 -62.211676) (xy 382.559052 -62.198504) (xy 382.549741 -62.175115) (xy 382.536616 -62.126514)
			(xy 382.529993 -62.076609) (xy 382.529588 -62.051438) (xy 382.530014 -62.024182) (xy 382.537767 -61.970223)
			(xy 382.55312 -61.917918) (xy 382.575761 -61.868329) (xy 382.605229 -61.822468) (xy 382.640923 -61.781267)
			(xy 382.682118 -61.745566) (xy 382.727975 -61.716091) (xy 382.777559 -61.693442) (xy 382.829863 -61.67808)
			(xy 382.88382 -61.670319) (xy 382.938332 -61.670315) (xy 382.99229 -61.67807) (xy 383.044596 -61.693425)
			(xy 383.094183 -61.716068) (xy 383.140043 -61.745537) (xy 383.181243 -61.781233) (xy 383.216943 -61.822429)
			(xy 383.246416 -61.868287) (xy 383.269063 -61.917873) (xy 383.284423 -61.970176) (xy 383.292182 -62.024134)
			(xy 383.292184 -62.078646) (xy 383.284427 -62.132604) (xy 383.26907 -62.184909) (xy 383.246426 -62.234495)
			(xy 383.216955 -62.280355) (xy 383.181257 -62.321553) (xy 383.140059 -62.357251) (xy 383.094201 -62.386723)
			(xy 383.044614 -62.409368) (xy 382.99231 -62.424726) (xy 382.938352 -62.432483) (xy 382.911096 -62.432946)
			(xy 382.887541 -62.432566) (xy 382.840797 -62.426709) (xy 382.817878 -62.421262) (xy 382.804124 -62.418202)
			(xy 382.775968 -62.419052) (xy 382.749113 -62.427557) (xy 382.7256 -62.44307) (xy 382.707216 -62.464414)
			(xy 382.695357 -62.489966) (xy 382.690925 -62.517784) (xy 382.694257 -62.545756) (xy 382.69926 -62.55893)
			(xy 382.708582 -62.582315) (xy 382.721703 -62.630918) (xy 382.728321 -62.680825) (xy 382.728724 -62.705996)
			(xy 382.728249 -62.733249) (xy 382.720492 -62.787202) (xy 382.705136 -62.839501) (xy 382.682494 -62.889082)
			(xy 382.653025 -62.934936) (xy 382.617331 -62.97613) (xy 382.576137 -63.011824) (xy 382.530283 -63.041293)
			(xy 382.480702 -63.063936) (xy 382.428403 -63.079292) (xy 382.374451 -63.087049) (xy 382.319944 -63.087048)
			(xy 382.265992 -63.079291) (xy 382.213693 -63.063934) (xy 382.164112 -63.04129) (xy 382.118258 -63.011821)
			(xy 382.077065 -62.976126) (xy 382.041372 -62.934932) (xy 382.011904 -62.889077) (xy 381.989262 -62.839496)
			(xy 381.973907 -62.787196) (xy 381.966151 -62.733244) (xy 376.213112 -62.733244) (xy 376.244281 -62.746489)
			(xy 376.291887 -62.775543) (xy 376.334755 -62.811218) (xy 376.371972 -62.852755) (xy 376.402745 -62.899268)
			(xy 376.426417 -62.949765) (xy 376.442485 -63.003172) (xy 376.450605 -63.058348) (xy 376.451114 -63.086234)
			(xy 376.450605 -63.11412) (xy 376.442485 -63.169296) (xy 376.426417 -63.222703) (xy 376.402745 -63.2732)
			(xy 376.402592 -63.273432) (xy 377.876814 -63.273432) (xy 377.880885 -63.21781) (xy 377.893011 -63.163373)
			(xy 377.912934 -63.111282) (xy 377.94023 -63.062647) (xy 377.974316 -63.018504) (xy 378.014465 -62.979795)
			(xy 378.059823 -62.947344) (xy 378.109423 -62.921843) (xy 378.162207 -62.903836) (xy 378.21705 -62.893706)
			(xy 378.272784 -62.891669) (xy 378.328221 -62.897769) (xy 378.382178 -62.911875) (xy 378.433507 -62.933687)
			(xy 378.481113 -62.962741) (xy 378.523981 -62.998416) (xy 378.561198 -63.039953) (xy 378.591971 -63.086466)
			(xy 378.615643 -63.136963) (xy 378.631711 -63.19037) (xy 378.639831 -63.245546) (xy 378.64034 -63.273432)
			(xy 378.639831 -63.301318) (xy 378.631711 -63.356494) (xy 378.615643 -63.409901) (xy 378.591971 -63.460398)
			(xy 378.561198 -63.506911) (xy 378.523981 -63.548448) (xy 378.481113 -63.584123) (xy 378.433507 -63.613177)
			(xy 378.382178 -63.634989) (xy 378.328221 -63.649095) (xy 378.272784 -63.655195) (xy 378.21705 -63.653158)
			(xy 378.162207 -63.643028) (xy 378.109423 -63.625021) (xy 378.059823 -63.59952) (xy 378.014465 -63.567069)
			(xy 377.974316 -63.52836) (xy 377.94023 -63.484217) (xy 377.912934 -63.435582) (xy 377.893011 -63.383491)
			(xy 377.880885 -63.329054) (xy 377.876814 -63.273432) (xy 376.402592 -63.273432) (xy 376.371972 -63.319713)
			(xy 376.334755 -63.36125) (xy 376.291887 -63.396925) (xy 376.244281 -63.425979) (xy 376.192952 -63.447791)
			(xy 376.138995 -63.461897) (xy 376.083558 -63.467997) (xy 376.027824 -63.46596) (xy 375.972981 -63.45583)
			(xy 375.920197 -63.437823) (xy 375.870597 -63.412322) (xy 375.825239 -63.379871) (xy 375.78509 -63.341162)
			(xy 375.751004 -63.297019) (xy 375.723708 -63.248384) (xy 375.703785 -63.196293) (xy 375.691659 -63.141856)
			(xy 375.687588 -63.086234) (xy 372.439636 -63.086234) (xy 372.445175 -63.105099) (xy 372.452932 -63.159048)
			(xy 372.452932 -63.213552) (xy 372.445175 -63.267501) (xy 372.42982 -63.319797) (xy 372.407178 -63.369376)
			(xy 372.377711 -63.415227) (xy 372.342019 -63.456419) (xy 372.300827 -63.492111) (xy 372.254976 -63.521578)
			(xy 372.205397 -63.54422) (xy 372.153101 -63.559575) (xy 372.099152 -63.567332) (xy 372.0719 -63.567818)
			(xy 372.044529 -63.567372) (xy 371.990348 -63.559552) (xy 371.937844 -63.54406) (xy 371.888097 -63.521213)
			(xy 371.842132 -63.491482) (xy 371.821202 -63.473838) (xy 371.820948 -63.473584) (xy 371.813853 -63.46801)
			(xy 371.796943 -63.461756) (xy 371.787928 -63.461392) (xy 371.720872 -63.461392) (xy 371.711854 -63.461738)
			(xy 371.694937 -63.467993) (xy 371.687852 -63.473584) (xy 371.687598 -63.473838) (xy 371.666665 -63.491479)
			(xy 371.620697 -63.521203) (xy 371.570951 -63.544049) (xy 371.518449 -63.559545) (xy 371.464271 -63.567374)
			(xy 371.409529 -63.567374) (xy 371.355351 -63.559545) (xy 371.302849 -63.544049) (xy 371.253103 -63.521203)
			(xy 371.207135 -63.491479) (xy 371.186202 -63.473838) (xy 371.185948 -63.473584) (xy 371.178853 -63.46801)
			(xy 371.161943 -63.461756) (xy 371.152928 -63.461392) (xy 371.085872 -63.461392) (xy 371.076854 -63.461738)
			(xy 371.059937 -63.467993) (xy 371.052852 -63.473584) (xy 371.052852 -63.473838) (xy 371.052598 -63.473838)
			(xy 371.031683 -63.491498) (xy 370.985705 -63.521205) (xy 370.935953 -63.544037) (xy 370.883449 -63.559523)
			(xy 370.82927 -63.567347) (xy 370.8019 -63.567818) (xy 370.77465 -63.567312) (xy 370.720703 -63.559555)
			(xy 370.66841 -63.544201) (xy 370.618834 -63.52156) (xy 370.572985 -63.492095) (xy 370.531796 -63.456404)
			(xy 370.496105 -63.415215) (xy 370.46664 -63.369366) (xy 370.443999 -63.31979) (xy 370.428645 -63.267497)
			(xy 370.420888 -63.21355) (xy 362.593159 -63.21355) (xy 362.592112 -63.34379) (xy 362.592112 -65.100962)
			(xy 368.432586 -65.100962) (xy 368.436657 -65.04534) (xy 368.448783 -64.990903) (xy 368.468706 -64.938812)
			(xy 368.496002 -64.890177) (xy 368.530088 -64.846034) (xy 368.570237 -64.807325) (xy 368.615595 -64.774874)
			(xy 368.665195 -64.749373) (xy 368.717979 -64.731366) (xy 368.772822 -64.721236) (xy 368.828556 -64.719199)
			(xy 368.883993 -64.725299) (xy 368.93795 -64.739405) (xy 368.989279 -64.761217) (xy 369.036885 -64.790271)
			(xy 369.079753 -64.825946) (xy 369.11697 -64.867483) (xy 369.147743 -64.913996) (xy 369.171415 -64.964493)
			(xy 369.187483 -65.0179) (xy 369.195603 -65.073076) (xy 369.196112 -65.100962) (xy 369.19569 -65.124076)
			(xy 380.407416 -65.124076) (xy 380.411487 -65.068454) (xy 380.423613 -65.014017) (xy 380.443536 -64.961926)
			(xy 380.470832 -64.913291) (xy 380.504918 -64.869148) (xy 380.545067 -64.830439) (xy 380.590425 -64.797988)
			(xy 380.640025 -64.772487) (xy 380.692809 -64.75448) (xy 380.747652 -64.74435) (xy 380.803386 -64.742313)
			(xy 380.858823 -64.748413) (xy 380.91278 -64.762519) (xy 380.964109 -64.784331) (xy 381.011715 -64.813385)
			(xy 381.054583 -64.84906) (xy 381.0918 -64.890597) (xy 381.122573 -64.93711) (xy 381.146245 -64.987607)
			(xy 381.162313 -65.041014) (xy 381.170433 -65.09619) (xy 381.170942 -65.124076) (xy 381.170433 -65.151962)
			(xy 381.162313 -65.207138) (xy 381.146245 -65.260545) (xy 381.122573 -65.311042) (xy 381.0918 -65.357555)
			(xy 381.054583 -65.399092) (xy 381.011715 -65.434767) (xy 380.964109 -65.463821) (xy 380.91278 -65.485633)
			(xy 380.858823 -65.499739) (xy 380.803386 -65.505839) (xy 380.747652 -65.503802) (xy 380.692809 -65.493672)
			(xy 380.640025 -65.475665) (xy 380.590425 -65.450164) (xy 380.545067 -65.417713) (xy 380.504918 -65.379004)
			(xy 380.470832 -65.334861) (xy 380.443536 -65.286226) (xy 380.423613 -65.234135) (xy 380.411487 -65.179698)
			(xy 380.407416 -65.124076) (xy 369.19569 -65.124076) (xy 369.195603 -65.128848) (xy 369.187483 -65.184024)
			(xy 369.171415 -65.237431) (xy 369.147743 -65.287928) (xy 369.11697 -65.334441) (xy 369.079753 -65.375978)
			(xy 369.036885 -65.411653) (xy 368.989279 -65.440707) (xy 368.93795 -65.462519) (xy 368.883993 -65.476625)
			(xy 368.828556 -65.482725) (xy 368.772822 -65.480688) (xy 368.717979 -65.470558) (xy 368.665195 -65.452551)
			(xy 368.615595 -65.42705) (xy 368.570237 -65.394599) (xy 368.530088 -65.35589) (xy 368.496002 -65.311747)
			(xy 368.468706 -65.263112) (xy 368.448783 -65.211021) (xy 368.436657 -65.156584) (xy 368.432586 -65.100962)
			(xy 362.592112 -65.100962) (xy 362.592112 -65.439036) (xy 362.591858 -65.444624) (xy 362.591858 -65.46469)
			(xy 362.591858 -65.465198) (xy 362.591604 -65.48247) (xy 362.591604 -65.482978) (xy 362.59135 -65.498472)
			(xy 362.59135 -65.49898) (xy 362.591096 -65.52184) (xy 362.592112 -65.533016) (xy 362.59444 -65.542285)
			(xy 362.604907 -65.558258) (xy 362.620512 -65.569265) (xy 362.629704 -65.571878) (xy 362.639356 -65.574418)
			(xy 362.648287 -65.576246) (xy 362.666388 -65.574178) (xy 362.674662 -65.570354) (xy 362.682282 -65.566036)
			(xy 362.692442 -65.560448) (xy 362.696506 -65.558162) (xy 362.70311 -65.553082) (xy 362.706666 -65.54978)
			(xy 362.710476 -65.543938) (xy 362.725788 -65.521883) (xy 362.761598 -65.481879) (xy 362.802643 -65.447267)
			(xy 362.848119 -65.418725) (xy 362.897134 -65.396812) (xy 362.948729 -65.381957) (xy 363.001893 -65.374452)
			(xy 363.028738 -65.374012) (xy 363.055987 -65.374501) (xy 363.109929 -65.382262) (xy 363.162218 -65.39762)
			(xy 363.211789 -65.420264) (xy 363.257634 -65.449732) (xy 363.298818 -65.485423) (xy 363.334503 -65.526613)
			(xy 363.363964 -65.572461) (xy 363.3866 -65.622036) (xy 363.40195 -65.674327) (xy 363.409703 -65.728271)
			(xy 363.410246 -65.75552) (xy 363.409747 -65.783259) (xy 363.401712 -65.838151) (xy 363.385814 -65.891302)
			(xy 363.362387 -65.94159) (xy 363.331927 -65.987957) (xy 363.295074 -66.029426) (xy 363.252605 -66.065121)
			(xy 363.205416 -66.094291) (xy 363.154501 -66.116322) (xy 363.100932 -66.130749) (xy 363.073442 -66.134488)
			(xy 363.059726 -66.136012) (xy 363.032808 -66.137741) (xy 362.978965 -66.134513) (xy 362.926113 -66.123736)
			(xy 362.875305 -66.105626) (xy 362.827553 -66.080543) (xy 362.783807 -66.048987) (xy 362.76407 -66.030602)
			(xy 362.757212 -66.023744) (xy 362.735368 -66.0146) (xy 362.726699 -66.011552) (xy 362.70834 -66.011148)
			(xy 362.699554 -66.013838) (xy 362.647992 -66.034666) (xy 362.647484 -66.034666) (xy 362.613702 -66.048128)
			(xy 362.603621 -66.053329) (xy 362.588961 -66.070599) (xy 362.585508 -66.081402) (xy 362.584492 -66.086736)
			(xy 362.579666 -66.43878) (xy 362.577126 -66.64198) (xy 362.575348 -66.791078) (xy 362.575671 -66.801113)
			(xy 362.583186 -66.819716) (xy 362.59727 -66.834004) (xy 362.606336 -66.838322) (xy 362.633006 -66.848482)
			(xy 362.633514 -66.848482) (xy 362.697268 -66.87185) (xy 362.70579 -66.874614) (xy 362.723695 -66.874634)
			(xy 362.740512 -66.86849) (xy 362.74756 -66.86296) (xy 362.75391 -66.85661) (xy 362.75518 -66.855086)
			(xy 362.773451 -66.83416) (xy 362.815003 -66.79729) (xy 362.861451 -66.766818) (xy 362.911818 -66.743384)
			(xy 362.965045 -66.727482) (xy 363.020012 -66.719445) (xy 363.047788 -66.718942) (xy 363.073613 -66.719366)
			(xy 363.124795 -66.726314) (xy 363.174576 -66.740085) (xy 363.222051 -66.760429) (xy 363.266358 -66.786976)
			(xy 363.286802 -66.802762) (xy 363.287056 -66.803016) (xy 363.293914 -66.80835) (xy 363.301788 -66.811144)
			(xy 363.305967 -66.81255) (xy 363.314652 -66.814076) (xy 363.31906 -66.814192) (xy 363.338618 -66.814192)
			(xy 363.344058 -66.814333) (xy 363.354691 -66.816638) (xy 363.3597 -66.818764) (xy 363.37367 -66.825114)
			(xy 363.382836 -66.828788) (xy 363.402549 -66.829611) (xy 363.421124 -66.82296) (xy 363.428788 -66.816732)
			(xy 363.439202 -66.807588) (xy 363.459819 -66.791157) (xy 363.504715 -66.763519) (xy 363.552981 -66.742311)
			(xy 363.603704 -66.727934) (xy 363.65592 -66.720662) (xy 363.68228 -66.720212) (xy 363.682788 -66.720212)
			(xy 363.71004 -66.720674) (xy 363.763989 -66.72843) (xy 363.816286 -66.743784) (xy 363.865865 -66.766424)
			(xy 363.911717 -66.795891) (xy 363.952909 -66.831582) (xy 363.988602 -66.872773) (xy 364.01807 -66.918624)
			(xy 364.040712 -66.968203) (xy 364.056068 -67.020499) (xy 364.063825 -67.074448) (xy 364.063825 -67.128952)
			(xy 364.056068 -67.182901) (xy 364.040712 -67.235197) (xy 364.01807 -67.284776) (xy 363.988602 -67.330627)
			(xy 363.952909 -67.371818) (xy 363.911717 -67.407509) (xy 363.865865 -67.436976) (xy 363.816286 -67.459616)
			(xy 363.763989 -67.47497) (xy 363.71004 -67.482726) (xy 363.682788 -67.483228) (xy 363.657241 -67.482818)
			(xy 363.606603 -67.476001) (xy 363.557328 -67.46249) (xy 363.510295 -67.442526) (xy 363.466345 -67.416467)
			(xy 363.44606 -67.400932) (xy 363.441234 -67.397122) (xy 363.435646 -67.394582) (xy 363.430312 -67.391788)
			(xy 363.419136 -67.389248) (xy 363.391958 -67.389248) (xy 363.386519 -67.389103) (xy 363.375889 -67.386792)
			(xy 363.370876 -67.384676) (xy 363.3597 -67.379088) (xy 363.350432 -67.375165) (xy 363.330362 -67.374016)
			(xy 363.311371 -67.380613) (xy 363.303566 -67.386962) (xy 363.303312 -67.386962) (xy 363.282141 -67.405226)
			(xy 363.235496 -67.436053) (xy 363.184861 -67.459765) (xy 363.131315 -67.475856) (xy 363.075998 -67.483984)
			(xy 363.048042 -67.484498) (xy 363.047788 -67.484498) (xy 363.019741 -67.484005) (xy 362.964249 -67.475808)
			(xy 362.910549 -67.459592) (xy 362.859795 -67.435705) (xy 362.813075 -67.40466) (xy 362.771392 -67.367122)
			(xy 362.753148 -67.345814) (xy 362.749338 -67.341242) (xy 362.741718 -67.3354) (xy 362.729018 -67.32905)
			(xy 362.724126 -67.326975) (xy 362.713754 -67.324676) (xy 362.708444 -67.324478) (xy 362.694474 -67.324478)
			(xy 362.690593 -67.324577) (xy 362.682935 -67.325846) (xy 362.679234 -67.327018) (xy 362.65231 -67.335908)
			(xy 362.651802 -67.335908) (xy 362.600494 -67.353688) (xy 362.592427 -67.357105) (xy 362.579045 -67.368396)
			(xy 362.570199 -67.383505) (xy 362.568236 -67.392042) (xy 362.567728 -67.39509) (xy 362.566573 -67.488054)
			(xy 367.079274 -67.488054) (xy 367.083345 -67.432432) (xy 367.095471 -67.377995) (xy 367.115394 -67.325904)
			(xy 367.14269 -67.277269) (xy 367.176776 -67.233126) (xy 367.216925 -67.194417) (xy 367.262283 -67.161966)
			(xy 367.311883 -67.136465) (xy 367.364667 -67.118458) (xy 367.41951 -67.108328) (xy 367.475244 -67.106291)
			(xy 367.530681 -67.112391) (xy 367.584638 -67.126497) (xy 367.635967 -67.148309) (xy 367.683573 -67.177363)
			(xy 367.726441 -67.213038) (xy 367.763658 -67.254575) (xy 367.794431 -67.301088) (xy 367.818103 -67.351585)
			(xy 367.834171 -67.404992) (xy 367.842291 -67.460168) (xy 367.8428 -67.488054) (xy 367.842291 -67.51594)
			(xy 367.839106 -67.537584) (xy 368.371372 -67.537584) (xy 368.375443 -67.481962) (xy 368.387569 -67.427525)
			(xy 368.407492 -67.375434) (xy 368.434788 -67.326799) (xy 368.468874 -67.282656) (xy 368.509023 -67.243947)
			(xy 368.554381 -67.211496) (xy 368.603981 -67.185995) (xy 368.656765 -67.167988) (xy 368.711608 -67.157858)
			(xy 368.767342 -67.155821) (xy 368.822779 -67.161921) (xy 368.876736 -67.176027) (xy 368.928065 -67.197839)
			(xy 368.975671 -67.226893) (xy 369.018539 -67.262568) (xy 369.055756 -67.304105) (xy 369.086529 -67.350618)
			(xy 369.110201 -67.401115) (xy 369.126269 -67.454522) (xy 369.134389 -67.509698) (xy 369.134898 -67.537584)
			(xy 369.134389 -67.56547) (xy 369.130344 -67.592956) (xy 369.645436 -67.592956) (xy 369.649507 -67.537334)
			(xy 369.661633 -67.482897) (xy 369.681556 -67.430806) (xy 369.708852 -67.382171) (xy 369.742938 -67.338028)
			(xy 369.783087 -67.299319) (xy 369.828445 -67.266868) (xy 369.878045 -67.241367) (xy 369.930829 -67.22336)
			(xy 369.985672 -67.21323) (xy 370.041406 -67.211193) (xy 370.096843 -67.217293) (xy 370.1508 -67.231399)
			(xy 370.202129 -67.253211) (xy 370.249735 -67.282265) (xy 370.292603 -67.31794) (xy 370.32982 -67.359477)
			(xy 370.360593 -67.40599) (xy 370.384265 -67.456487) (xy 370.400333 -67.509894) (xy 370.40845 -67.565048)
			(xy 372.746816 -67.565048) (xy 372.746816 -67.510553) (xy 372.754571 -67.456612) (xy 372.769924 -67.404324)
			(xy 372.792561 -67.354754) (xy 372.822022 -67.308909) (xy 372.857708 -67.267723) (xy 372.898891 -67.232035)
			(xy 372.944734 -67.202572) (xy 372.994304 -67.179931) (xy 373.046591 -67.164576) (xy 373.100531 -67.156818)
			(xy 373.127778 -67.15633) (xy 373.155148 -67.156802) (xy 373.209327 -67.164617) (xy 373.261831 -67.180104)
			(xy 373.311578 -67.202945) (xy 373.357544 -67.232669) (xy 373.378476 -67.25031) (xy 373.37873 -67.250564)
			(xy 373.385827 -67.256135) (xy 373.402736 -67.262389) (xy 373.41175 -67.262756) (xy 373.478806 -67.262756)
			(xy 373.487824 -67.262411) (xy 373.504742 -67.256156) (xy 373.511826 -67.250564) (xy 373.511826 -67.25031)
			(xy 373.51208 -67.25031) (xy 373.53301 -67.232668) (xy 373.578983 -67.202957) (xy 373.628731 -67.180121)
			(xy 373.681232 -67.164631) (xy 373.735409 -67.156803) (xy 373.762778 -67.15633) (xy 373.790035 -67.156715)
			(xy 373.843993 -67.164471) (xy 373.896299 -67.179826) (xy 373.945887 -67.20247) (xy 373.991748 -67.23194)
			(xy 374.032947 -67.267637) (xy 374.068647 -67.308835) (xy 374.09812 -67.354694) (xy 374.120766 -67.40428)
			(xy 374.136125 -67.456585) (xy 374.143883 -67.510543) (xy 374.143883 -67.565057) (xy 374.136125 -67.619015)
			(xy 374.120766 -67.67132) (xy 374.09812 -67.720906) (xy 374.068647 -67.766765) (xy 374.032947 -67.807963)
			(xy 373.991748 -67.84366) (xy 373.945887 -67.87313) (xy 373.896299 -67.895774) (xy 373.843993 -67.911129)
			(xy 373.790035 -67.918885) (xy 373.762778 -67.919346) (xy 373.735407 -67.918906) (xy 373.681226 -67.911084)
			(xy 373.628722 -67.895589) (xy 373.578976 -67.872742) (xy 373.53301 -67.843011) (xy 373.51208 -67.825366)
			(xy 373.511826 -67.825112) (xy 373.504735 -67.819532) (xy 373.487822 -67.813281) (xy 373.478806 -67.81292)
			(xy 373.41175 -67.81292) (xy 373.402735 -67.813297) (xy 373.385818 -67.81953) (xy 373.37873 -67.825112)
			(xy 373.37873 -67.825366) (xy 373.378476 -67.825366) (xy 373.357522 -67.842978) (xy 373.311556 -67.872695)
			(xy 373.261814 -67.895537) (xy 373.209318 -67.911034) (xy 373.155146 -67.918869) (xy 373.127778 -67.919346)
			(xy 373.100531 -67.918782) (xy 373.046591 -67.911024) (xy 372.994304 -67.895669) (xy 372.944734 -67.873028)
			(xy 372.898891 -67.843565) (xy 372.857708 -67.807877) (xy 372.822022 -67.766691) (xy 372.792561 -67.720846)
			(xy 372.769924 -67.671276) (xy 372.754571 -67.618988) (xy 372.746816 -67.565048) (xy 370.40845 -67.565048)
			(xy 370.408453 -67.56507) (xy 370.408962 -67.592956) (xy 370.408453 -67.620842) (xy 370.400333 -67.676018)
			(xy 370.384265 -67.729425) (xy 370.360593 -67.779922) (xy 370.32982 -67.826435) (xy 370.292603 -67.867972)
			(xy 370.249735 -67.903647) (xy 370.202129 -67.932701) (xy 370.1508 -67.954513) (xy 370.096843 -67.968619)
			(xy 370.041406 -67.974719) (xy 369.985672 -67.972682) (xy 369.930829 -67.962552) (xy 369.878045 -67.944545)
			(xy 369.828445 -67.919044) (xy 369.783087 -67.886593) (xy 369.742938 -67.847884) (xy 369.708852 -67.803741)
			(xy 369.681556 -67.755106) (xy 369.661633 -67.703015) (xy 369.649507 -67.648578) (xy 369.645436 -67.592956)
			(xy 369.130344 -67.592956) (xy 369.126269 -67.620646) (xy 369.110201 -67.674053) (xy 369.086529 -67.72455)
			(xy 369.055756 -67.771063) (xy 369.018539 -67.8126) (xy 368.975671 -67.848275) (xy 368.928065 -67.877329)
			(xy 368.876736 -67.899141) (xy 368.822779 -67.913247) (xy 368.767342 -67.919347) (xy 368.711608 -67.91731)
			(xy 368.656765 -67.90718) (xy 368.603981 -67.889173) (xy 368.554381 -67.863672) (xy 368.509023 -67.831221)
			(xy 368.468874 -67.792512) (xy 368.434788 -67.748369) (xy 368.407492 -67.699734) (xy 368.387569 -67.647643)
			(xy 368.375443 -67.593206) (xy 368.371372 -67.537584) (xy 367.839106 -67.537584) (xy 367.834171 -67.571116)
			(xy 367.818103 -67.624523) (xy 367.794431 -67.67502) (xy 367.763658 -67.721533) (xy 367.726441 -67.76307)
			(xy 367.683573 -67.798745) (xy 367.635967 -67.827799) (xy 367.584638 -67.849611) (xy 367.530681 -67.863717)
			(xy 367.475244 -67.869817) (xy 367.41951 -67.86778) (xy 367.364667 -67.85765) (xy 367.311883 -67.839643)
			(xy 367.262283 -67.814142) (xy 367.216925 -67.781691) (xy 367.176776 -67.742982) (xy 367.14269 -67.698839)
			(xy 367.115394 -67.650204) (xy 367.095471 -67.598113) (xy 367.083345 -67.543676) (xy 367.079274 -67.488054)
			(xy 362.566573 -67.488054) (xy 362.552996 -68.580508) (xy 362.55292 -68.586604) (xy 364.925356 -68.586604)
			(xy 364.925811 -68.559233) (xy 364.933629 -68.505053) (xy 364.94912 -68.452549) (xy 364.971965 -68.402803)
			(xy 365.001693 -68.356837) (xy 365.019336 -68.335906) (xy 365.01959 -68.335652) (xy 365.02516 -68.328554)
			(xy 365.031417 -68.311646) (xy 365.031782 -68.302632) (xy 365.031782 -68.235576) (xy 365.03144 -68.226557)
			(xy 365.025183 -68.20964) (xy 365.01959 -68.202556) (xy 365.019336 -68.202556) (xy 365.019336 -68.202302)
			(xy 365.00169 -68.181375) (xy 364.971978 -68.135402) (xy 364.949143 -68.085653) (xy 364.933653 -68.033151)
			(xy 364.925828 -67.978974) (xy 364.925356 -67.951604) (xy 364.925881 -67.924354) (xy 364.933636 -67.87041)
			(xy 364.948989 -67.818118) (xy 364.971627 -67.768543) (xy 365.00109 -67.722695) (xy 365.036777 -67.681505)
			(xy 365.077963 -67.645814) (xy 365.123808 -67.616346) (xy 365.173381 -67.593703) (xy 365.225671 -67.578345)
			(xy 365.279615 -67.570584) (xy 365.306864 -67.570096) (xy 365.333179 -67.570522) (xy 365.38531 -67.577766)
			(xy 365.435953 -67.592093) (xy 365.484152 -67.613233) (xy 365.528994 -67.640786) (xy 365.569632 -67.674231)
			(xy 365.587788 -67.693286) (xy 365.595314 -67.700682) (xy 365.614591 -67.70921) (xy 365.625126 -67.709796)
			(xy 365.699802 -67.709796) (xy 365.710354 -67.709282) (xy 365.729649 -67.700736) (xy 365.73714 -67.693286)
			(xy 365.75528 -67.674215) (xy 365.795914 -67.64076) (xy 365.840757 -67.613203) (xy 365.888961 -67.592068)
			(xy 365.939611 -67.577754) (xy 365.991747 -67.570533) (xy 366.018064 -67.570096) (xy 366.045433 -67.570584)
			(xy 366.099612 -67.578397) (xy 366.152114 -67.593881) (xy 366.201862 -67.616718) (xy 366.247829 -67.646437)
			(xy 366.268762 -67.664076) (xy 366.269016 -67.66433) (xy 366.276091 -67.669933) (xy 366.293017 -67.676169)
			(xy 366.302036 -67.676522) (xy 366.369092 -67.676522) (xy 366.378108 -67.676156) (xy 366.395025 -67.669914)
			(xy 366.402112 -67.66433) (xy 366.402112 -67.664076) (xy 366.402366 -67.664076) (xy 366.423297 -67.646436)
			(xy 366.46927 -67.616725) (xy 366.519018 -67.59389) (xy 366.571519 -67.578399) (xy 366.625695 -67.57057)
			(xy 366.653064 -67.570096) (xy 366.680316 -67.570589) (xy 366.734266 -67.578341) (xy 366.786564 -67.593693)
			(xy 366.836144 -67.616331) (xy 366.881998 -67.645796) (xy 366.923191 -67.681487) (xy 366.958885 -67.722677)
			(xy 366.988353 -67.768528) (xy 367.010996 -67.818106) (xy 367.026352 -67.870402) (xy 367.034109 -67.924352)
			(xy 367.034572 -67.951604) (xy 367.034115 -67.978975) (xy 367.026296 -68.033154) (xy 367.010805 -68.085658)
			(xy 366.987961 -68.135405) (xy 366.958234 -68.181371) (xy 366.940592 -68.202302) (xy 366.940338 -68.202556)
			(xy 366.934756 -68.209646) (xy 366.928508 -68.22656) (xy 366.928146 -68.235576) (xy 366.928146 -68.302632)
			(xy 366.928478 -68.311652) (xy 366.934742 -68.328569) (xy 366.940338 -68.335652) (xy 366.940592 -68.335652)
			(xy 366.940592 -68.335906) (xy 366.958246 -68.356826) (xy 366.987956 -68.402802) (xy 367.010789 -68.452553)
			(xy 367.026277 -68.505056) (xy 367.0341 -68.559234) (xy 367.034572 -68.586604) (xy 367.034148 -68.613859)
			(xy 367.02639 -68.667813) (xy 367.011031 -68.720114) (xy 366.994399 -68.75653) (xy 370.47043 -68.75653)
			(xy 370.470906 -68.72916) (xy 370.478721 -68.674981) (xy 370.494207 -68.622478) (xy 370.517046 -68.572731)
			(xy 370.546769 -68.526764) (xy 370.56441 -68.505832) (xy 370.564664 -68.505578) (xy 370.570273 -68.498507)
			(xy 370.576505 -68.481578) (xy 370.576856 -68.472558) (xy 370.576856 -68.405502) (xy 370.576507 -68.396484)
			(xy 370.570255 -68.379567) (xy 370.564664 -68.372482) (xy 370.56441 -68.372482) (xy 370.56441 -68.372228)
			(xy 370.546772 -68.351295) (xy 370.51706 -68.305323) (xy 370.494223 -68.255575) (xy 370.478732 -68.203075)
			(xy 370.470904 -68.148899) (xy 370.47043 -68.12153) (xy 370.470883 -68.094276) (xy 370.478637 -68.040323)
			(xy 370.493991 -67.988023) (xy 370.516633 -67.93844) (xy 370.546102 -67.892585) (xy 370.581797 -67.851391)
			(xy 370.622991 -67.815697) (xy 370.668847 -67.786229) (xy 370.71843 -67.763589) (xy 370.770731 -67.748236)
			(xy 370.824684 -67.740483) (xy 370.851938 -67.740022) (xy 370.879307 -67.740519) (xy 370.933485 -67.748329)
			(xy 370.985988 -67.76381) (xy 371.035736 -67.786645) (xy 371.081704 -67.816364) (xy 371.102636 -67.834002)
			(xy 371.10289 -67.834256) (xy 371.10997 -67.839851) (xy 371.126892 -67.846091) (xy 371.13591 -67.846448)
			(xy 371.202966 -67.846448) (xy 371.211983 -67.846086) (xy 371.2289 -67.839843) (xy 371.235986 -67.834256)
			(xy 371.235986 -67.834002) (xy 371.23624 -67.834002) (xy 371.257184 -67.816378) (xy 371.303154 -67.786664)
			(xy 371.352898 -67.763825) (xy 371.405396 -67.74833) (xy 371.45957 -67.740498) (xy 371.486938 -67.740022)
			(xy 371.513253 -67.740457) (xy 371.565383 -67.747698) (xy 371.616027 -67.762023) (xy 371.664226 -67.783161)
			(xy 371.709069 -67.810713) (xy 371.749707 -67.844158) (xy 371.767862 -67.863212) (xy 371.775394 -67.870601)
			(xy 371.794666 -67.879132) (xy 371.8052 -67.879722) (xy 371.879876 -67.879722) (xy 371.890425 -67.879187)
			(xy 371.90972 -67.870655) (xy 371.917214 -67.863212) (xy 371.935372 -67.844159) (xy 371.976001 -67.810701)
			(xy 372.020841 -67.783141) (xy 372.069041 -67.762002) (xy 372.119688 -67.747685) (xy 372.171822 -67.74046)
			(xy 372.198138 -67.740022) (xy 372.225392 -67.740443) (xy 372.279343 -67.748205) (xy 372.331641 -67.763566)
			(xy 372.38122 -67.786214) (xy 372.427072 -67.815687) (xy 372.468263 -67.851386) (xy 372.503954 -67.892583)
			(xy 372.533418 -67.938439) (xy 372.556057 -67.988023) (xy 372.571409 -68.040323) (xy 372.579162 -68.094276)
			(xy 372.579646 -68.12153) (xy 372.579211 -68.148901) (xy 372.571387 -68.203082) (xy 372.555892 -68.255586)
			(xy 372.533043 -68.305333) (xy 372.503311 -68.351298) (xy 372.485666 -68.372228) (xy 372.485412 -68.372482)
			(xy 372.479828 -68.379571) (xy 372.473579 -68.396486) (xy 372.47322 -68.405502) (xy 372.47322 -68.472558)
			(xy 372.473593 -68.481573) (xy 372.479829 -68.498491) (xy 372.485412 -68.505578) (xy 372.485666 -68.505578)
			(xy 372.485666 -68.505832) (xy 372.503281 -68.526783) (xy 372.532998 -68.57275) (xy 372.555839 -68.622493)
			(xy 372.571336 -68.674989) (xy 372.579169 -68.729162) (xy 372.579646 -68.75653) (xy 372.57915 -68.78378)
			(xy 372.571391 -68.837726) (xy 372.556034 -68.890018) (xy 372.533392 -68.939593) (xy 372.503926 -68.985441)
			(xy 372.468236 -69.02663) (xy 372.427048 -69.062321) (xy 372.3812 -69.091788) (xy 372.331625 -69.114431)
			(xy 372.279333 -69.129789) (xy 372.225388 -69.13755) (xy 372.198138 -69.138038) (xy 372.171822 -69.137632)
			(xy 372.11969 -69.130387) (xy 372.069045 -69.116057) (xy 372.020846 -69.094914) (xy 371.976004 -69.067356)
			(xy 371.935368 -69.033905) (xy 371.917214 -69.014848) (xy 371.909683 -69.007458) (xy 371.89041 -68.998925)
			(xy 371.879876 -68.998338) (xy 371.8052 -68.998338) (xy 371.794647 -68.998842) (xy 371.775351 -69.007394)
			(xy 371.767862 -69.014848) (xy 371.749727 -69.033924) (xy 371.709092 -69.067378) (xy 371.664247 -69.094933)
			(xy 371.616042 -69.116067) (xy 371.565392 -69.130381) (xy 371.513255 -69.137601) (xy 371.486938 -69.138038)
			(xy 371.459568 -69.137565) (xy 371.405388 -69.129751) (xy 371.352885 -69.114264) (xy 371.303138 -69.091424)
			(xy 371.257171 -69.061699) (xy 371.23624 -69.044058) (xy 371.235986 -69.043804) (xy 371.228907 -69.038206)
			(xy 371.211985 -69.031966) (xy 371.202966 -69.031612) (xy 371.13591 -69.031612) (xy 371.126893 -69.031971)
			(xy 371.109976 -69.038217) (xy 371.10289 -69.043804) (xy 371.10289 -69.044058) (xy 371.102636 -69.044058)
			(xy 371.081696 -69.061687) (xy 371.035726 -69.091402) (xy 370.985981 -69.11424) (xy 370.933481 -69.129734)
			(xy 370.879307 -69.137563) (xy 370.851938 -69.138038) (xy 370.824687 -69.137509) (xy 370.77074 -69.129758)
			(xy 370.718446 -69.114409) (xy 370.668868 -69.091773) (xy 370.623016 -69.062312) (xy 370.581823 -69.026625)
			(xy 370.546129 -68.985439) (xy 370.51666 -68.939592) (xy 370.494015 -68.890018) (xy 370.478656 -68.837726)
			(xy 370.470895 -68.78378) (xy 370.47043 -68.75653) (xy 366.994399 -68.75653) (xy 366.988386 -68.769696)
			(xy 366.958914 -68.815551) (xy 366.923216 -68.856745) (xy 366.882019 -68.892438) (xy 366.836161 -68.921905)
			(xy 366.786576 -68.944545) (xy 366.734274 -68.959898) (xy 366.680319 -68.967651) (xy 366.653064 -68.968112)
			(xy 366.625693 -68.967664) (xy 366.571513 -68.959841) (xy 366.51901 -68.944348) (xy 366.469264 -68.921502)
			(xy 366.423297 -68.891775) (xy 366.402366 -68.874132) (xy 366.402112 -68.873878) (xy 366.395028 -68.868288)
			(xy 366.378109 -68.862044) (xy 366.369092 -68.861686) (xy 366.302036 -68.861686) (xy 366.293021 -68.862063)
			(xy 366.276104 -68.868297) (xy 366.269016 -68.873878) (xy 366.269016 -68.874132) (xy 366.268762 -68.874132)
			(xy 366.247821 -68.89176) (xy 366.20185 -68.921473) (xy 366.152105 -68.94431) (xy 366.099606 -68.959804)
			(xy 366.045433 -68.967636) (xy 366.018064 -68.968112) (xy 365.991749 -68.967665) (xy 365.93962 -68.960425)
			(xy 365.888977 -68.946102) (xy 365.840778 -68.924966) (xy 365.795935 -68.897416) (xy 365.755296 -68.863975)
			(xy 365.73714 -68.844922) (xy 365.729603 -68.837539) (xy 365.710335 -68.829003) (xy 365.699802 -68.828412)
			(xy 365.625126 -68.828412) (xy 365.614576 -68.828938) (xy 365.59528 -68.837475) (xy 365.587788 -68.844922)
			(xy 365.569636 -68.863981) (xy 365.529005 -68.897437) (xy 365.484164 -68.924995) (xy 365.435962 -68.946132)
			(xy 365.385314 -68.960449) (xy 365.33318 -68.967674) (xy 365.306864 -68.968112) (xy 365.279612 -68.967656)
			(xy 365.225663 -68.959894) (xy 365.173368 -68.944535) (xy 365.123791 -68.92189) (xy 365.077941 -68.89242)
			(xy 365.036752 -68.856726) (xy 365.001061 -68.815533) (xy 364.971595 -68.769681) (xy 364.948954 -68.720102)
			(xy 364.933599 -68.667805) (xy 364.925842 -68.613856) (xy 364.925356 -68.586604) (xy 362.55292 -68.586604)
			(xy 362.543852 -69.309234) (xy 362.525644 -71.555864) (xy 367.494564 -71.555864) (xy 367.498635 -71.500242)
			(xy 367.510761 -71.445805) (xy 367.530684 -71.393714) (xy 367.55798 -71.345079) (xy 367.592066 -71.300936)
			(xy 367.632215 -71.262227) (xy 367.677573 -71.229776) (xy 367.727173 -71.204275) (xy 367.779957 -71.186268)
			(xy 367.8348 -71.176138) (xy 367.890534 -71.174101) (xy 367.945971 -71.180201) (xy 367.999928 -71.194307)
			(xy 368.051257 -71.216119) (xy 368.098863 -71.245173) (xy 368.141731 -71.280848) (xy 368.178948 -71.322385)
			(xy 368.209721 -71.368898) (xy 368.233393 -71.419395) (xy 368.249461 -71.472802) (xy 368.257581 -71.527978)
			(xy 368.25809 -71.555864) (xy 368.257581 -71.58375) (xy 368.251742 -71.623428) (xy 369.003578 -71.623428)
			(xy 369.007649 -71.567806) (xy 369.019775 -71.513369) (xy 369.039698 -71.461278) (xy 369.066994 -71.412643)
			(xy 369.10108 -71.3685) (xy 369.141229 -71.329791) (xy 369.186587 -71.29734) (xy 369.236187 -71.271839)
			(xy 369.288971 -71.253832) (xy 369.343814 -71.243702) (xy 369.399548 -71.241665) (xy 369.454985 -71.247765)
			(xy 369.508942 -71.261871) (xy 369.560271 -71.283683) (xy 369.607877 -71.312737) (xy 369.650745 -71.348412)
			(xy 369.687962 -71.389949) (xy 369.718735 -71.436462) (xy 369.742407 -71.486959) (xy 369.758475 -71.540366)
			(xy 369.766595 -71.595542) (xy 369.767104 -71.623428) (xy 369.766595 -71.651314) (xy 369.758475 -71.70649)
			(xy 369.742407 -71.759897) (xy 369.718735 -71.810394) (xy 369.687962 -71.856907) (xy 369.650745 -71.898444)
			(xy 369.607877 -71.934119) (xy 369.560271 -71.963173) (xy 369.508942 -71.984985) (xy 369.454985 -71.999091)
			(xy 369.399548 -72.005191) (xy 369.343814 -72.003154) (xy 369.288971 -71.993024) (xy 369.236187 -71.975017)
			(xy 369.186587 -71.949516) (xy 369.141229 -71.917065) (xy 369.10108 -71.878356) (xy 369.066994 -71.834213)
			(xy 369.039698 -71.785578) (xy 369.019775 -71.733487) (xy 369.007649 -71.67905) (xy 369.003578 -71.623428)
			(xy 368.251742 -71.623428) (xy 368.249461 -71.638926) (xy 368.233393 -71.692333) (xy 368.209721 -71.74283)
			(xy 368.178948 -71.789343) (xy 368.141731 -71.83088) (xy 368.098863 -71.866555) (xy 368.051257 -71.895609)
			(xy 367.999928 -71.917421) (xy 367.945971 -71.931527) (xy 367.890534 -71.937627) (xy 367.8348 -71.93559)
			(xy 367.779957 -71.92546) (xy 367.727173 -71.907453) (xy 367.677573 -71.881952) (xy 367.632215 -71.849501)
			(xy 367.592066 -71.810792) (xy 367.55798 -71.766649) (xy 367.530684 -71.718014) (xy 367.510761 -71.665923)
			(xy 367.498635 -71.611486) (xy 367.494564 -71.555864) (xy 362.525644 -71.555864) (xy 362.496492 -75.152758)
			(xy 379.969266 -75.152758) (xy 379.973337 -75.097136) (xy 379.985463 -75.042699) (xy 380.005386 -74.990608)
			(xy 380.032682 -74.941973) (xy 380.066768 -74.89783) (xy 380.106917 -74.859121) (xy 380.152275 -74.82667)
			(xy 380.201875 -74.801169) (xy 380.254659 -74.783162) (xy 380.309502 -74.773032) (xy 380.365236 -74.770995)
			(xy 380.420673 -74.777095) (xy 380.47463 -74.791201) (xy 380.525959 -74.813013) (xy 380.573565 -74.842067)
			(xy 380.616433 -74.877742) (xy 380.65365 -74.919279) (xy 380.684423 -74.965792) (xy 380.708095 -75.016289)
			(xy 380.724088 -75.069446) (xy 381.604518 -75.069446) (xy 381.608589 -75.013824) (xy 381.620715 -74.959387)
			(xy 381.640638 -74.907296) (xy 381.667934 -74.858661) (xy 381.70202 -74.814518) (xy 381.742169 -74.775809)
			(xy 381.787527 -74.743358) (xy 381.837127 -74.717857) (xy 381.889911 -74.69985) (xy 381.944754 -74.68972)
			(xy 382.000488 -74.687683) (xy 382.055925 -74.693783) (xy 382.109882 -74.707889) (xy 382.161211 -74.729701)
			(xy 382.208817 -74.758755) (xy 382.251685 -74.79443) (xy 382.288902 -74.835967) (xy 382.319675 -74.88248)
			(xy 382.343347 -74.932977) (xy 382.359415 -74.986384) (xy 382.367535 -75.04156) (xy 382.368044 -75.069446)
			(xy 382.367535 -75.097332) (xy 382.359415 -75.152508) (xy 382.343347 -75.205915) (xy 382.319675 -75.256412)
			(xy 382.288902 -75.302925) (xy 382.251685 -75.344462) (xy 382.208817 -75.380137) (xy 382.161211 -75.409191)
			(xy 382.109882 -75.431003) (xy 382.055925 -75.445109) (xy 382.000488 -75.451209) (xy 381.944754 -75.449172)
			(xy 381.889911 -75.439042) (xy 381.837127 -75.421035) (xy 381.787527 -75.395534) (xy 381.742169 -75.363083)
			(xy 381.70202 -75.324374) (xy 381.667934 -75.280231) (xy 381.640638 -75.231596) (xy 381.620715 -75.179505)
			(xy 381.608589 -75.125068) (xy 381.604518 -75.069446) (xy 380.724088 -75.069446) (xy 380.724163 -75.069696)
			(xy 380.732283 -75.124872) (xy 380.732792 -75.152758) (xy 380.732283 -75.180644) (xy 380.724163 -75.23582)
			(xy 380.708095 -75.289227) (xy 380.684423 -75.339724) (xy 380.65365 -75.386237) (xy 380.616433 -75.427774)
			(xy 380.573565 -75.463449) (xy 380.525959 -75.492503) (xy 380.47463 -75.514315) (xy 380.420673 -75.528421)
			(xy 380.365236 -75.534521) (xy 380.309502 -75.532484) (xy 380.254659 -75.522354) (xy 380.201875 -75.504347)
			(xy 380.152275 -75.478846) (xy 380.106917 -75.446395) (xy 380.066768 -75.407686) (xy 380.032682 -75.363543)
			(xy 380.005386 -75.314908) (xy 379.985463 -75.262817) (xy 379.973337 -75.20838) (xy 379.969266 -75.152758)
			(xy 362.496492 -75.152758) (xy 362.450538 -80.8228) (xy 377.396754 -80.8228) (xy 377.400825 -80.767178)
			(xy 377.412951 -80.712741) (xy 377.432874 -80.66065) (xy 377.46017 -80.612015) (xy 377.494256 -80.567872)
			(xy 377.534405 -80.529163) (xy 377.579763 -80.496712) (xy 377.629363 -80.471211) (xy 377.682147 -80.453204)
			(xy 377.73699 -80.443074) (xy 377.792724 -80.441037) (xy 377.848161 -80.447137) (xy 377.902118 -80.461243)
			(xy 377.953447 -80.483055) (xy 378.001053 -80.512109) (xy 378.043921 -80.547784) (xy 378.081138 -80.589321)
			(xy 378.111911 -80.635834) (xy 378.116208 -80.645) (xy 380.871982 -80.645) (xy 380.876053 -80.589378)
			(xy 380.888179 -80.534941) (xy 380.908102 -80.48285) (xy 380.935398 -80.434215) (xy 380.969484 -80.390072)
			(xy 381.009633 -80.351363) (xy 381.054991 -80.318912) (xy 381.104591 -80.293411) (xy 381.157375 -80.275404)
			(xy 381.212218 -80.265274) (xy 381.267952 -80.263237) (xy 381.323389 -80.269337) (xy 381.377346 -80.283443)
			(xy 381.428675 -80.305255) (xy 381.476281 -80.334309) (xy 381.519149 -80.369984) (xy 381.556366 -80.411521)
			(xy 381.587139 -80.458034) (xy 381.610811 -80.508531) (xy 381.626879 -80.561938) (xy 381.634999 -80.617114)
			(xy 381.635508 -80.645) (xy 381.634999 -80.672886) (xy 381.626879 -80.728062) (xy 381.610811 -80.781469)
			(xy 381.587139 -80.831966) (xy 381.556366 -80.878479) (xy 381.519149 -80.920016) (xy 381.476281 -80.955691)
			(xy 381.428675 -80.984745) (xy 381.377346 -81.006557) (xy 381.323389 -81.020663) (xy 381.267952 -81.026763)
			(xy 381.212218 -81.024726) (xy 381.157375 -81.014596) (xy 381.104591 -80.996589) (xy 381.054991 -80.971088)
			(xy 381.009633 -80.938637) (xy 380.969484 -80.899928) (xy 380.935398 -80.855785) (xy 380.908102 -80.80715)
			(xy 380.888179 -80.755059) (xy 380.876053 -80.700622) (xy 380.871982 -80.645) (xy 378.116208 -80.645)
			(xy 378.135583 -80.686331) (xy 378.151651 -80.739738) (xy 378.159771 -80.794914) (xy 378.16028 -80.8228)
			(xy 378.159771 -80.850686) (xy 378.151651 -80.905862) (xy 378.135583 -80.959269) (xy 378.111911 -81.009766)
			(xy 378.081138 -81.056279) (xy 378.043921 -81.097816) (xy 378.001053 -81.133491) (xy 377.953447 -81.162545)
			(xy 377.902118 -81.184357) (xy 377.848161 -81.198463) (xy 377.792724 -81.204563) (xy 377.73699 -81.202526)
			(xy 377.682147 -81.192396) (xy 377.629363 -81.174389) (xy 377.579763 -81.148888) (xy 377.534405 -81.116437)
			(xy 377.494256 -81.077728) (xy 377.46017 -81.033585) (xy 377.432874 -80.98495) (xy 377.412951 -80.932859)
			(xy 377.400825 -80.878422) (xy 377.396754 -80.8228) (xy 362.450538 -80.8228) (xy 362.44506 -81.498694)
			(xy 364.632238 -81.498694) (xy 364.636309 -81.443072) (xy 364.648435 -81.388635) (xy 364.668358 -81.336544)
			(xy 364.695654 -81.287909) (xy 364.72974 -81.243766) (xy 364.769889 -81.205057) (xy 364.815247 -81.172606)
			(xy 364.864847 -81.147105) (xy 364.917631 -81.129098) (xy 364.972474 -81.118968) (xy 365.028208 -81.116931)
			(xy 365.083645 -81.123031) (xy 365.137602 -81.137137) (xy 365.188931 -81.158949) (xy 365.236537 -81.188003)
			(xy 365.279405 -81.223678) (xy 365.316622 -81.265215) (xy 365.347395 -81.311728) (xy 365.371067 -81.362225)
			(xy 365.387135 -81.415632) (xy 365.395255 -81.470808) (xy 365.395764 -81.498694) (xy 367.679222 -81.498694)
			(xy 367.683293 -81.443072) (xy 367.695419 -81.388635) (xy 367.715342 -81.336544) (xy 367.742638 -81.287909)
			(xy 367.776724 -81.243766) (xy 367.816873 -81.205057) (xy 367.862231 -81.172606) (xy 367.911831 -81.147105)
			(xy 367.964615 -81.129098) (xy 368.019458 -81.118968) (xy 368.075192 -81.116931) (xy 368.130629 -81.123031)
			(xy 368.184586 -81.137137) (xy 368.235915 -81.158949) (xy 368.283521 -81.188003) (xy 368.326389 -81.223678)
			(xy 368.363606 -81.265215) (xy 368.394379 -81.311728) (xy 368.418051 -81.362225) (xy 368.434119 -81.415632)
			(xy 368.442239 -81.470808) (xy 368.442748 -81.498694) (xy 370.219222 -81.498694) (xy 370.223293 -81.443072)
			(xy 370.235419 -81.388635) (xy 370.255342 -81.336544) (xy 370.282638 -81.287909) (xy 370.316724 -81.243766)
			(xy 370.356873 -81.205057) (xy 370.402231 -81.172606) (xy 370.451831 -81.147105) (xy 370.504615 -81.129098)
			(xy 370.559458 -81.118968) (xy 370.615192 -81.116931) (xy 370.670629 -81.123031) (xy 370.724586 -81.137137)
			(xy 370.775915 -81.158949) (xy 370.823521 -81.188003) (xy 370.866389 -81.223678) (xy 370.903606 -81.265215)
			(xy 370.934379 -81.311728) (xy 370.958051 -81.362225) (xy 370.974119 -81.415632) (xy 370.982239 -81.470808)
			(xy 370.982748 -81.498694) (xy 370.982239 -81.52658) (xy 370.981147 -81.534) (xy 380.998982 -81.534)
			(xy 381.003053 -81.478378) (xy 381.015179 -81.423941) (xy 381.035102 -81.37185) (xy 381.062398 -81.323215)
			(xy 381.096484 -81.279072) (xy 381.136633 -81.240363) (xy 381.181991 -81.207912) (xy 381.231591 -81.182411)
			(xy 381.284375 -81.164404) (xy 381.339218 -81.154274) (xy 381.394952 -81.152237) (xy 381.450389 -81.158337)
			(xy 381.504346 -81.172443) (xy 381.555675 -81.194255) (xy 381.603281 -81.223309) (xy 381.646149 -81.258984)
			(xy 381.683366 -81.300521) (xy 381.714139 -81.347034) (xy 381.737811 -81.397531) (xy 381.753879 -81.450938)
			(xy 381.761999 -81.506114) (xy 381.762508 -81.534) (xy 381.761999 -81.561886) (xy 381.753879 -81.617062)
			(xy 381.737811 -81.670469) (xy 381.714139 -81.720966) (xy 381.683366 -81.767479) (xy 381.646149 -81.809016)
			(xy 381.603281 -81.844691) (xy 381.555675 -81.873745) (xy 381.504346 -81.895557) (xy 381.450389 -81.909663)
			(xy 381.394952 -81.915763) (xy 381.339218 -81.913726) (xy 381.284375 -81.903596) (xy 381.231591 -81.885589)
			(xy 381.181991 -81.860088) (xy 381.136633 -81.827637) (xy 381.096484 -81.788928) (xy 381.062398 -81.744785)
			(xy 381.035102 -81.69615) (xy 381.015179 -81.644059) (xy 381.003053 -81.589622) (xy 380.998982 -81.534)
			(xy 370.981147 -81.534) (xy 370.974119 -81.581756) (xy 370.958051 -81.635163) (xy 370.934379 -81.68566)
			(xy 370.903606 -81.732173) (xy 370.866389 -81.77371) (xy 370.823521 -81.809385) (xy 370.775915 -81.838439)
			(xy 370.724586 -81.860251) (xy 370.670629 -81.874357) (xy 370.615192 -81.880457) (xy 370.559458 -81.87842)
			(xy 370.504615 -81.86829) (xy 370.451831 -81.850283) (xy 370.402231 -81.824782) (xy 370.356873 -81.792331)
			(xy 370.316724 -81.753622) (xy 370.282638 -81.709479) (xy 370.255342 -81.660844) (xy 370.235419 -81.608753)
			(xy 370.223293 -81.554316) (xy 370.219222 -81.498694) (xy 368.442748 -81.498694) (xy 368.442239 -81.52658)
			(xy 368.434119 -81.581756) (xy 368.418051 -81.635163) (xy 368.394379 -81.68566) (xy 368.363606 -81.732173)
			(xy 368.326389 -81.77371) (xy 368.283521 -81.809385) (xy 368.235915 -81.838439) (xy 368.184586 -81.860251)
			(xy 368.130629 -81.874357) (xy 368.075192 -81.880457) (xy 368.019458 -81.87842) (xy 367.964615 -81.86829)
			(xy 367.911831 -81.850283) (xy 367.862231 -81.824782) (xy 367.816873 -81.792331) (xy 367.776724 -81.753622)
			(xy 367.742638 -81.709479) (xy 367.715342 -81.660844) (xy 367.695419 -81.608753) (xy 367.683293 -81.554316)
			(xy 367.679222 -81.498694) (xy 365.395764 -81.498694) (xy 365.395255 -81.52658) (xy 365.387135 -81.581756)
			(xy 365.371067 -81.635163) (xy 365.347395 -81.68566) (xy 365.316622 -81.732173) (xy 365.279405 -81.77371)
			(xy 365.236537 -81.809385) (xy 365.188931 -81.838439) (xy 365.137602 -81.860251) (xy 365.083645 -81.874357)
			(xy 365.028208 -81.880457) (xy 364.972474 -81.87842) (xy 364.917631 -81.86829) (xy 364.864847 -81.850283)
			(xy 364.815247 -81.824782) (xy 364.769889 -81.792331) (xy 364.72974 -81.753622) (xy 364.695654 -81.709479)
			(xy 364.668358 -81.660844) (xy 364.648435 -81.608753) (xy 364.636309 -81.554316) (xy 364.632238 -81.498694)
			(xy 362.44506 -81.498694) (xy 362.441274 -81.9658) (xy 374.915428 -81.9658) (xy 374.919499 -81.910178)
			(xy 374.931625 -81.855741) (xy 374.951548 -81.80365) (xy 374.978844 -81.755015) (xy 375.01293 -81.710872)
			(xy 375.053079 -81.672163) (xy 375.098437 -81.639712) (xy 375.148037 -81.614211) (xy 375.200821 -81.596204)
			(xy 375.255664 -81.586074) (xy 375.311398 -81.584037) (xy 375.366835 -81.590137) (xy 375.420792 -81.604243)
			(xy 375.472121 -81.626055) (xy 375.519727 -81.655109) (xy 375.562595 -81.690784) (xy 375.599812 -81.732321)
			(xy 375.630585 -81.778834) (xy 375.654257 -81.829331) (xy 375.670325 -81.882738) (xy 375.678445 -81.937914)
			(xy 375.678954 -81.9658) (xy 377.153422 -81.9658) (xy 377.157493 -81.910178) (xy 377.169619 -81.855741)
			(xy 377.189542 -81.80365) (xy 377.216838 -81.755015) (xy 377.250924 -81.710872) (xy 377.291073 -81.672163)
			(xy 377.336431 -81.639712) (xy 377.386031 -81.614211) (xy 377.438815 -81.596204) (xy 377.493658 -81.586074)
			(xy 377.549392 -81.584037) (xy 377.604829 -81.590137) (xy 377.658786 -81.604243) (xy 377.710115 -81.626055)
			(xy 377.757721 -81.655109) (xy 377.800589 -81.690784) (xy 377.837806 -81.732321) (xy 377.868579 -81.778834)
			(xy 377.892251 -81.829331) (xy 377.908319 -81.882738) (xy 377.916439 -81.937914) (xy 377.916948 -81.9658)
			(xy 379.501652 -81.9658) (xy 379.505723 -81.910178) (xy 379.517849 -81.855741) (xy 379.537772 -81.80365)
			(xy 379.565068 -81.755015) (xy 379.599154 -81.710872) (xy 379.639303 -81.672163) (xy 379.684661 -81.639712)
			(xy 379.734261 -81.614211) (xy 379.787045 -81.596204) (xy 379.841888 -81.586074) (xy 379.897622 -81.584037)
			(xy 379.953059 -81.590137) (xy 380.007016 -81.604243) (xy 380.058345 -81.626055) (xy 380.105951 -81.655109)
			(xy 380.148819 -81.690784) (xy 380.186036 -81.732321) (xy 380.216809 -81.778834) (xy 380.240481 -81.829331)
			(xy 380.256549 -81.882738) (xy 380.264669 -81.937914) (xy 380.265178 -81.9658) (xy 380.264669 -81.993686)
			(xy 380.256549 -82.048862) (xy 380.240481 -82.102269) (xy 380.216809 -82.152766) (xy 380.186036 -82.199279)
			(xy 380.148819 -82.240816) (xy 380.105951 -82.276491) (xy 380.058345 -82.305545) (xy 380.007016 -82.327357)
			(xy 379.953059 -82.341463) (xy 379.897622 -82.347563) (xy 379.841888 -82.345526) (xy 379.787045 -82.335396)
			(xy 379.734261 -82.317389) (xy 379.684661 -82.291888) (xy 379.639303 -82.259437) (xy 379.599154 -82.220728)
			(xy 379.565068 -82.176585) (xy 379.537772 -82.12795) (xy 379.517849 -82.075859) (xy 379.505723 -82.021422)
			(xy 379.501652 -81.9658) (xy 377.916948 -81.9658) (xy 377.916439 -81.993686) (xy 377.908319 -82.048862)
			(xy 377.892251 -82.102269) (xy 377.868579 -82.152766) (xy 377.837806 -82.199279) (xy 377.800589 -82.240816)
			(xy 377.757721 -82.276491) (xy 377.710115 -82.305545) (xy 377.658786 -82.327357) (xy 377.604829 -82.341463)
			(xy 377.549392 -82.347563) (xy 377.493658 -82.345526) (xy 377.438815 -82.335396) (xy 377.386031 -82.317389)
			(xy 377.336431 -82.291888) (xy 377.291073 -82.259437) (xy 377.250924 -82.220728) (xy 377.216838 -82.176585)
			(xy 377.189542 -82.12795) (xy 377.169619 -82.075859) (xy 377.157493 -82.021422) (xy 377.153422 -81.9658)
			(xy 375.678954 -81.9658) (xy 375.678445 -81.993686) (xy 375.670325 -82.048862) (xy 375.654257 -82.102269)
			(xy 375.630585 -82.152766) (xy 375.599812 -82.199279) (xy 375.562595 -82.240816) (xy 375.519727 -82.276491)
			(xy 375.472121 -82.305545) (xy 375.420792 -82.327357) (xy 375.366835 -82.341463) (xy 375.311398 -82.347563)
			(xy 375.255664 -82.345526) (xy 375.200821 -82.335396) (xy 375.148037 -82.317389) (xy 375.098437 -82.291888)
			(xy 375.053079 -82.259437) (xy 375.01293 -82.220728) (xy 374.978844 -82.176585) (xy 374.951548 -82.12795)
			(xy 374.931625 -82.075859) (xy 374.919499 -82.021422) (xy 374.915428 -81.9658) (xy 362.441274 -81.9658)
			(xy 362.435796 -82.641694) (xy 363.896146 -82.641694) (xy 363.900217 -82.586072) (xy 363.912343 -82.531635)
			(xy 363.932266 -82.479544) (xy 363.959562 -82.430909) (xy 363.993648 -82.386766) (xy 364.033797 -82.348057)
			(xy 364.079155 -82.315606) (xy 364.128755 -82.290105) (xy 364.181539 -82.272098) (xy 364.236382 -82.261968)
			(xy 364.292116 -82.259931) (xy 364.347553 -82.266031) (xy 364.40151 -82.280137) (xy 364.452839 -82.301949)
			(xy 364.500445 -82.331003) (xy 364.543313 -82.366678) (xy 364.58053 -82.408215) (xy 364.611303 -82.454728)
			(xy 364.634975 -82.505225) (xy 364.651043 -82.558632) (xy 364.659163 -82.613808) (xy 364.659672 -82.641694)
			(xy 364.659163 -82.66958) (xy 364.651043 -82.724756) (xy 364.634975 -82.778163) (xy 364.611303 -82.82866)
			(xy 364.58053 -82.875173) (xy 364.543313 -82.91671) (xy 364.542013 -82.917792) (xy 367.650774 -82.917792)
			(xy 367.654845 -82.86217) (xy 367.666971 -82.807733) (xy 367.686894 -82.755642) (xy 367.71419 -82.707007)
			(xy 367.748276 -82.662864) (xy 367.788425 -82.624155) (xy 367.833783 -82.591704) (xy 367.883383 -82.566203)
			(xy 367.936167 -82.548196) (xy 367.99101 -82.538066) (xy 368.046744 -82.536029) (xy 368.102181 -82.542129)
			(xy 368.156138 -82.556235) (xy 368.207467 -82.578047) (xy 368.255073 -82.607101) (xy 368.296641 -82.641694)
			(xy 370.219222 -82.641694) (xy 370.223293 -82.586072) (xy 370.235419 -82.531635) (xy 370.255342 -82.479544)
			(xy 370.282638 -82.430909) (xy 370.316724 -82.386766) (xy 370.356873 -82.348057) (xy 370.402231 -82.315606)
			(xy 370.451831 -82.290105) (xy 370.504615 -82.272098) (xy 370.559458 -82.261968) (xy 370.615192 -82.259931)
			(xy 370.670629 -82.266031) (xy 370.724586 -82.280137) (xy 370.775915 -82.301949) (xy 370.823521 -82.331003)
			(xy 370.866389 -82.366678) (xy 370.903606 -82.408215) (xy 370.934379 -82.454728) (xy 370.958051 -82.505225)
			(xy 370.974119 -82.558632) (xy 370.982239 -82.613808) (xy 370.982748 -82.641694) (xy 370.982239 -82.66958)
			(xy 370.974119 -82.724756) (xy 370.958051 -82.778163) (xy 370.934379 -82.82866) (xy 370.903606 -82.875173)
			(xy 370.866389 -82.91671) (xy 370.823521 -82.952385) (xy 370.775915 -82.981439) (xy 370.724586 -83.003251)
			(xy 370.670629 -83.017357) (xy 370.615192 -83.023457) (xy 370.559458 -83.02142) (xy 370.504615 -83.01129)
			(xy 370.451831 -82.993283) (xy 370.402231 -82.967782) (xy 370.356873 -82.935331) (xy 370.316724 -82.896622)
			(xy 370.282638 -82.852479) (xy 370.255342 -82.803844) (xy 370.235419 -82.751753) (xy 370.223293 -82.697316)
			(xy 370.219222 -82.641694) (xy 368.296641 -82.641694) (xy 368.297941 -82.642776) (xy 368.335158 -82.684313)
			(xy 368.365931 -82.730826) (xy 368.389603 -82.781323) (xy 368.405671 -82.83473) (xy 368.413791 -82.889906)
			(xy 368.4143 -82.917792) (xy 368.413791 -82.945678) (xy 368.405671 -83.000854) (xy 368.389603 -83.054261)
			(xy 368.365931 -83.104758) (xy 368.363257 -83.1088) (xy 374.915428 -83.1088) (xy 374.919499 -83.053178)
			(xy 374.931625 -82.998741) (xy 374.951548 -82.94665) (xy 374.978844 -82.898015) (xy 375.01293 -82.853872)
			(xy 375.053079 -82.815163) (xy 375.098437 -82.782712) (xy 375.148037 -82.757211) (xy 375.200821 -82.739204)
			(xy 375.255664 -82.729074) (xy 375.311398 -82.727037) (xy 375.366835 -82.733137) (xy 375.420792 -82.747243)
			(xy 375.472121 -82.769055) (xy 375.519727 -82.798109) (xy 375.562595 -82.833784) (xy 375.599812 -82.875321)
			(xy 375.630585 -82.921834) (xy 375.654257 -82.972331) (xy 375.670325 -83.025738) (xy 375.678445 -83.080914)
			(xy 375.678954 -83.1088) (xy 377.280422 -83.1088) (xy 377.284493 -83.053178) (xy 377.296619 -82.998741)
			(xy 377.316542 -82.94665) (xy 377.343838 -82.898015) (xy 377.377924 -82.853872) (xy 377.418073 -82.815163)
			(xy 377.463431 -82.782712) (xy 377.513031 -82.757211) (xy 377.565815 -82.739204) (xy 377.620658 -82.729074)
			(xy 377.676392 -82.727037) (xy 377.731829 -82.733137) (xy 377.785786 -82.747243) (xy 377.837115 -82.769055)
			(xy 377.884721 -82.798109) (xy 377.927589 -82.833784) (xy 377.964806 -82.875321) (xy 377.995579 -82.921834)
			(xy 378.019251 -82.972331) (xy 378.035319 -83.025738) (xy 378.043439 -83.080914) (xy 378.043948 -83.1088)
			(xy 378.043439 -83.136686) (xy 378.035319 -83.191862) (xy 378.019251 -83.245269) (xy 377.995579 -83.295766)
			(xy 377.964806 -83.342279) (xy 377.927589 -83.383816) (xy 377.884721 -83.419491) (xy 377.837115 -83.448545)
			(xy 377.785786 -83.470357) (xy 377.731829 -83.484463) (xy 377.676392 -83.490563) (xy 377.620658 -83.488526)
			(xy 377.565815 -83.478396) (xy 377.513031 -83.460389) (xy 377.463431 -83.434888) (xy 377.418073 -83.402437)
			(xy 377.377924 -83.363728) (xy 377.343838 -83.319585) (xy 377.316542 -83.27095) (xy 377.296619 -83.218859)
			(xy 377.284493 -83.164422) (xy 377.280422 -83.1088) (xy 375.678954 -83.1088) (xy 375.678445 -83.136686)
			(xy 375.670325 -83.191862) (xy 375.654257 -83.245269) (xy 375.630585 -83.295766) (xy 375.599812 -83.342279)
			(xy 375.562595 -83.383816) (xy 375.519727 -83.419491) (xy 375.472121 -83.448545) (xy 375.420792 -83.470357)
			(xy 375.366835 -83.484463) (xy 375.311398 -83.490563) (xy 375.255664 -83.488526) (xy 375.200821 -83.478396)
			(xy 375.148037 -83.460389) (xy 375.098437 -83.434888) (xy 375.053079 -83.402437) (xy 375.01293 -83.363728)
			(xy 374.978844 -83.319585) (xy 374.951548 -83.27095) (xy 374.931625 -83.218859) (xy 374.919499 -83.164422)
			(xy 374.915428 -83.1088) (xy 368.363257 -83.1088) (xy 368.335158 -83.151271) (xy 368.297941 -83.192808)
			(xy 368.255073 -83.228483) (xy 368.207467 -83.257537) (xy 368.156138 -83.279349) (xy 368.102181 -83.293455)
			(xy 368.046744 -83.299555) (xy 367.99101 -83.297518) (xy 367.936167 -83.287388) (xy 367.883383 -83.269381)
			(xy 367.833783 -83.24388) (xy 367.788425 -83.211429) (xy 367.748276 -83.17272) (xy 367.71419 -83.128577)
			(xy 367.686894 -83.079942) (xy 367.666971 -83.027851) (xy 367.654845 -82.973414) (xy 367.650774 -82.917792)
			(xy 364.542013 -82.917792) (xy 364.500445 -82.952385) (xy 364.452839 -82.981439) (xy 364.40151 -83.003251)
			(xy 364.347553 -83.017357) (xy 364.292116 -83.023457) (xy 364.236382 -83.02142) (xy 364.181539 -83.01129)
			(xy 364.128755 -82.993283) (xy 364.079155 -82.967782) (xy 364.033797 -82.935331) (xy 363.993648 -82.896622)
			(xy 363.959562 -82.852479) (xy 363.932266 -82.803844) (xy 363.912343 -82.751753) (xy 363.900217 -82.697316)
			(xy 363.896146 -82.641694) (xy 362.435796 -82.641694) (xy 362.426532 -83.784694) (xy 365.080548 -83.784694)
			(xy 365.084619 -83.729072) (xy 365.096745 -83.674635) (xy 365.116668 -83.622544) (xy 365.143964 -83.573909)
			(xy 365.17805 -83.529766) (xy 365.218199 -83.491057) (xy 365.263557 -83.458606) (xy 365.313157 -83.433105)
			(xy 365.365941 -83.415098) (xy 365.420784 -83.404968) (xy 365.476518 -83.402931) (xy 365.531955 -83.409031)
			(xy 365.585912 -83.423137) (xy 365.637241 -83.444949) (xy 365.684847 -83.474003) (xy 365.727715 -83.509678)
			(xy 365.764932 -83.551215) (xy 365.795705 -83.597728) (xy 365.819377 -83.648225) (xy 365.835445 -83.701632)
			(xy 365.843565 -83.756808) (xy 365.844074 -83.784694) (xy 365.843565 -83.81258) (xy 365.835445 -83.867756)
			(xy 365.819377 -83.921163) (xy 365.795705 -83.97166) (xy 365.764932 -84.018173) (xy 365.727715 -84.05971)
			(xy 365.684847 -84.095385) (xy 365.637241 -84.124439) (xy 365.585912 -84.146251) (xy 365.531955 -84.160357)
			(xy 365.476518 -84.166457) (xy 365.420784 -84.16442) (xy 365.365941 -84.15429) (xy 365.313157 -84.136283)
			(xy 365.263557 -84.110782) (xy 365.218199 -84.078331) (xy 365.17805 -84.039622) (xy 365.143964 -83.995479)
			(xy 365.116668 -83.946844) (xy 365.096745 -83.894753) (xy 365.084619 -83.840316) (xy 365.080548 -83.784694)
			(xy 362.426532 -83.784694) (xy 362.417868 -84.85378) (xy 362.418122 -84.857844) (xy 362.419141 -84.864956)
			(xy 363.863634 -84.864956) (xy 363.867705 -84.809334) (xy 363.879831 -84.754897) (xy 363.899754 -84.702806)
			(xy 363.92705 -84.654171) (xy 363.961136 -84.610028) (xy 364.001285 -84.571319) (xy 364.046643 -84.538868)
			(xy 364.096243 -84.513367) (xy 364.149027 -84.49536) (xy 364.20387 -84.48523) (xy 364.259604 -84.483193)
			(xy 364.315041 -84.489293) (xy 364.368998 -84.503399) (xy 364.420327 -84.525211) (xy 364.467933 -84.554265)
			(xy 364.473791 -84.55914) (xy 367.596928 -84.55914) (xy 367.59742 -84.530678) (xy 367.605878 -84.474387)
			(xy 367.622614 -84.419979) (xy 367.647253 -84.368664) (xy 367.67925 -84.321584) (xy 367.717891 -84.279786)
			(xy 367.762318 -84.244198) (xy 367.786666 -84.229448) (xy 367.798256 -84.22222) (xy 367.817381 -84.202733)
			(xy 367.830658 -84.178874) (xy 367.837138 -84.152349) (xy 367.836356 -84.125056) (xy 367.828369 -84.098945)
			(xy 367.813747 -84.075885) (xy 367.803938 -84.06638) (xy 367.784723 -84.048244) (xy 367.751006 -84.007563)
			(xy 367.723225 -83.962618) (xy 367.70191 -83.914271) (xy 367.68747 -83.863445) (xy 367.68018 -83.811113)
			(xy 367.679732 -83.784694) (xy 367.680218 -83.757443) (xy 367.687974 -83.703495) (xy 367.703329 -83.6512)
			(xy 367.725971 -83.601623) (xy 367.755437 -83.555773) (xy 367.791128 -83.514582) (xy 367.832319 -83.478891)
			(xy 367.878169 -83.449425) (xy 367.927746 -83.426783) (xy 367.980041 -83.411428) (xy 368.033989 -83.403672)
			(xy 368.088491 -83.403672) (xy 368.142439 -83.411428) (xy 368.194734 -83.426783) (xy 368.244311 -83.449425)
			(xy 368.290161 -83.478891) (xy 368.331352 -83.514582) (xy 368.367043 -83.555773) (xy 368.396509 -83.601623)
			(xy 368.419151 -83.6512) (xy 368.434506 -83.703495) (xy 368.442262 -83.757443) (xy 368.442748 -83.784694)
			(xy 370.219222 -83.784694) (xy 370.223293 -83.729072) (xy 370.235419 -83.674635) (xy 370.255342 -83.622544)
			(xy 370.282638 -83.573909) (xy 370.316724 -83.529766) (xy 370.356873 -83.491057) (xy 370.402231 -83.458606)
			(xy 370.451831 -83.433105) (xy 370.504615 -83.415098) (xy 370.559458 -83.404968) (xy 370.615192 -83.402931)
			(xy 370.670629 -83.409031) (xy 370.724586 -83.423137) (xy 370.775915 -83.444949) (xy 370.823521 -83.474003)
			(xy 370.866389 -83.509678) (xy 370.903606 -83.551215) (xy 370.934379 -83.597728) (xy 370.958051 -83.648225)
			(xy 370.974119 -83.701632) (xy 370.982239 -83.756808) (xy 370.982748 -83.784694) (xy 370.982239 -83.81258)
			(xy 370.974119 -83.867756) (xy 370.958051 -83.921163) (xy 370.934379 -83.97166) (xy 370.903606 -84.018173)
			(xy 370.866389 -84.05971) (xy 370.823521 -84.095385) (xy 370.775915 -84.124439) (xy 370.724586 -84.146251)
			(xy 370.670629 -84.160357) (xy 370.615192 -84.166457) (xy 370.559458 -84.16442) (xy 370.504615 -84.15429)
			(xy 370.451831 -84.136283) (xy 370.402231 -84.110782) (xy 370.356873 -84.078331) (xy 370.316724 -84.039622)
			(xy 370.282638 -83.995479) (xy 370.255342 -83.946844) (xy 370.235419 -83.894753) (xy 370.223293 -83.840316)
			(xy 370.219222 -83.784694) (xy 368.442748 -83.784694) (xy 368.442216 -83.813155) (xy 368.433766 -83.869445)
			(xy 368.417039 -83.923852) (xy 368.392406 -83.975167) (xy 368.360416 -84.022248) (xy 368.321779 -84.064048)
			(xy 368.277356 -84.099636) (xy 368.25301 -84.114386) (xy 368.24139 -84.121569) (xy 368.222267 -84.141067)
			(xy 368.208993 -84.164935) (xy 368.202519 -84.191468) (xy 368.203306 -84.218768) (xy 368.211299 -84.244883)
			(xy 368.215685 -84.2518) (xy 374.915428 -84.2518) (xy 374.919499 -84.196178) (xy 374.931625 -84.141741)
			(xy 374.951548 -84.08965) (xy 374.978844 -84.041015) (xy 375.01293 -83.996872) (xy 375.053079 -83.958163)
			(xy 375.098437 -83.925712) (xy 375.148037 -83.900211) (xy 375.200821 -83.882204) (xy 375.255664 -83.872074)
			(xy 375.311398 -83.870037) (xy 375.366835 -83.876137) (xy 375.420792 -83.890243) (xy 375.472121 -83.912055)
			(xy 375.519727 -83.941109) (xy 375.562595 -83.976784) (xy 375.599812 -84.018321) (xy 375.630585 -84.064834)
			(xy 375.654257 -84.115331) (xy 375.662608 -84.143088) (xy 377.35459 -84.143088) (xy 377.358661 -84.087466)
			(xy 377.370787 -84.033029) (xy 377.39071 -83.980938) (xy 377.418006 -83.932303) (xy 377.452092 -83.88816)
			(xy 377.492241 -83.849451) (xy 377.537599 -83.817) (xy 377.587199 -83.791499) (xy 377.639983 -83.773492)
			(xy 377.694826 -83.763362) (xy 377.75056 -83.761325) (xy 377.805997 -83.767425) (xy 377.859954 -83.781531)
			(xy 377.911283 -83.803343) (xy 377.948565 -83.826096) (xy 380.785368 -83.826096) (xy 380.789439 -83.770474)
			(xy 380.801565 -83.716037) (xy 380.821488 -83.663946) (xy 380.848784 -83.615311) (xy 380.88287 -83.571168)
			(xy 380.923019 -83.532459) (xy 380.968377 -83.500008) (xy 381.017977 -83.474507) (xy 381.070761 -83.4565)
			(xy 381.125604 -83.44637) (xy 381.181338 -83.444333) (xy 381.236775 -83.450433) (xy 381.290732 -83.464539)
			(xy 381.342061 -83.486351) (xy 381.389667 -83.515405) (xy 381.432535 -83.55108) (xy 381.469752 -83.592617)
			(xy 381.500525 -83.63913) (xy 381.524197 -83.689627) (xy 381.540265 -83.743034) (xy 381.548385 -83.79821)
			(xy 381.548894 -83.826096) (xy 381.548385 -83.853982) (xy 381.540265 -83.909158) (xy 381.524197 -83.962565)
			(xy 381.500525 -84.013062) (xy 381.469752 -84.059575) (xy 381.432535 -84.101112) (xy 381.389667 -84.136787)
			(xy 381.342061 -84.165841) (xy 381.290732 -84.187653) (xy 381.236775 -84.201759) (xy 381.181338 -84.207859)
			(xy 381.125604 -84.205822) (xy 381.070761 -84.195692) (xy 381.017977 -84.177685) (xy 380.968377 -84.152184)
			(xy 380.923019 -84.119733) (xy 380.88287 -84.081024) (xy 380.848784 -84.036881) (xy 380.821488 -83.988246)
			(xy 380.801565 -83.936155) (xy 380.789439 -83.881718) (xy 380.785368 -83.826096) (xy 377.948565 -83.826096)
			(xy 377.958889 -83.832397) (xy 378.001757 -83.868072) (xy 378.038974 -83.909609) (xy 378.069747 -83.956122)
			(xy 378.093419 -84.006619) (xy 378.109487 -84.060026) (xy 378.117607 -84.115202) (xy 378.118116 -84.143088)
			(xy 378.117607 -84.170974) (xy 378.109487 -84.22615) (xy 378.093419 -84.279557) (xy 378.069747 -84.330054)
			(xy 378.038974 -84.376567) (xy 378.001757 -84.418104) (xy 377.958889 -84.453779) (xy 377.942738 -84.463636)
			(xy 379.522988 -84.463636) (xy 379.527059 -84.408014) (xy 379.539185 -84.353577) (xy 379.559108 -84.301486)
			(xy 379.586404 -84.252851) (xy 379.62049 -84.208708) (xy 379.660639 -84.169999) (xy 379.705997 -84.137548)
			(xy 379.755597 -84.112047) (xy 379.808381 -84.09404) (xy 379.863224 -84.08391) (xy 379.918958 -84.081873)
			(xy 379.974395 -84.087973) (xy 380.028352 -84.102079) (xy 380.079681 -84.123891) (xy 380.127287 -84.152945)
			(xy 380.170155 -84.18862) (xy 380.207372 -84.230157) (xy 380.238145 -84.27667) (xy 380.261817 -84.327167)
			(xy 380.277885 -84.380574) (xy 380.286005 -84.43575) (xy 380.286514 -84.463636) (xy 380.286005 -84.491522)
			(xy 380.277885 -84.546698) (xy 380.261817 -84.600105) (xy 380.238145 -84.650602) (xy 380.207372 -84.697115)
			(xy 380.170155 -84.738652) (xy 380.127287 -84.774327) (xy 380.079681 -84.803381) (xy 380.028352 -84.825193)
			(xy 379.974395 -84.839299) (xy 379.918958 -84.845399) (xy 379.863224 -84.843362) (xy 379.808381 -84.833232)
			(xy 379.755597 -84.815225) (xy 379.705997 -84.789724) (xy 379.660639 -84.757273) (xy 379.62049 -84.718564)
			(xy 379.586404 -84.674421) (xy 379.559108 -84.625786) (xy 379.539185 -84.573695) (xy 379.527059 -84.519258)
			(xy 379.522988 -84.463636) (xy 377.942738 -84.463636) (xy 377.911283 -84.482833) (xy 377.859954 -84.504645)
			(xy 377.805997 -84.518751) (xy 377.75056 -84.524851) (xy 377.694826 -84.522814) (xy 377.639983 -84.512684)
			(xy 377.587199 -84.494677) (xy 377.537599 -84.469176) (xy 377.492241 -84.436725) (xy 377.452092 -84.398016)
			(xy 377.418006 -84.353873) (xy 377.39071 -84.305238) (xy 377.370787 -84.253147) (xy 377.358661 -84.19871)
			(xy 377.35459 -84.143088) (xy 375.662608 -84.143088) (xy 375.670325 -84.168738) (xy 375.678445 -84.223914)
			(xy 375.678954 -84.2518) (xy 375.678445 -84.279686) (xy 375.670325 -84.334862) (xy 375.654257 -84.388269)
			(xy 375.630585 -84.438766) (xy 375.599812 -84.485279) (xy 375.562595 -84.526816) (xy 375.519727 -84.562491)
			(xy 375.472121 -84.591545) (xy 375.420792 -84.613357) (xy 375.366835 -84.627463) (xy 375.311398 -84.633563)
			(xy 375.255664 -84.631526) (xy 375.200821 -84.621396) (xy 375.148037 -84.603389) (xy 375.098437 -84.577888)
			(xy 375.053079 -84.545437) (xy 375.01293 -84.506728) (xy 374.978844 -84.462585) (xy 374.951548 -84.41395)
			(xy 374.931625 -84.361859) (xy 374.919499 -84.307422) (xy 374.915428 -84.2518) (xy 368.215685 -84.2518)
			(xy 368.225925 -84.267947) (xy 368.235738 -84.277454) (xy 368.254965 -84.295578) (xy 368.288682 -84.336262)
			(xy 368.316462 -84.381208) (xy 368.337775 -84.429558) (xy 368.352213 -84.480386) (xy 368.359498 -84.53272)
			(xy 368.359944 -84.55914) (xy 368.359458 -84.586391) (xy 368.351702 -84.640339) (xy 368.336347 -84.692634)
			(xy 368.313705 -84.742211) (xy 368.284239 -84.788061) (xy 368.248548 -84.829252) (xy 368.207357 -84.864943)
			(xy 368.161507 -84.894409) (xy 368.11193 -84.917051) (xy 368.075683 -84.927694) (xy 370.219222 -84.927694)
			(xy 370.223293 -84.872072) (xy 370.235419 -84.817635) (xy 370.255342 -84.765544) (xy 370.282638 -84.716909)
			(xy 370.316724 -84.672766) (xy 370.356873 -84.634057) (xy 370.402231 -84.601606) (xy 370.451831 -84.576105)
			(xy 370.504615 -84.558098) (xy 370.559458 -84.547968) (xy 370.615192 -84.545931) (xy 370.670629 -84.552031)
			(xy 370.724586 -84.566137) (xy 370.775915 -84.587949) (xy 370.823521 -84.617003) (xy 370.866389 -84.652678)
			(xy 370.903606 -84.694215) (xy 370.934379 -84.740728) (xy 370.958051 -84.791225) (xy 370.974119 -84.844632)
			(xy 370.982239 -84.899808) (xy 370.982748 -84.927694) (xy 370.982239 -84.95558) (xy 370.974119 -85.010756)
			(xy 370.958051 -85.064163) (xy 370.934379 -85.11466) (xy 370.903606 -85.161173) (xy 370.866389 -85.20271)
			(xy 370.823521 -85.238385) (xy 370.775915 -85.267439) (xy 370.724586 -85.289251) (xy 370.670629 -85.303357)
			(xy 370.615192 -85.309457) (xy 370.559458 -85.30742) (xy 370.504615 -85.29729) (xy 370.451831 -85.279283)
			(xy 370.402231 -85.253782) (xy 370.356873 -85.221331) (xy 370.316724 -85.182622) (xy 370.282638 -85.138479)
			(xy 370.255342 -85.089844) (xy 370.235419 -85.037753) (xy 370.223293 -84.983316) (xy 370.219222 -84.927694)
			(xy 368.075683 -84.927694) (xy 368.059635 -84.932406) (xy 368.005687 -84.940162) (xy 367.951185 -84.940162)
			(xy 367.897237 -84.932406) (xy 367.844942 -84.917051) (xy 367.795365 -84.894409) (xy 367.749515 -84.864943)
			(xy 367.708324 -84.829252) (xy 367.672633 -84.788061) (xy 367.643167 -84.742211) (xy 367.620525 -84.692634)
			(xy 367.60517 -84.640339) (xy 367.597414 -84.586391) (xy 367.596928 -84.55914) (xy 364.473791 -84.55914)
			(xy 364.510801 -84.58994) (xy 364.548018 -84.631477) (xy 364.578791 -84.67799) (xy 364.602463 -84.728487)
			(xy 364.618531 -84.781894) (xy 364.626651 -84.83707) (xy 364.62716 -84.864956) (xy 364.626651 -84.892842)
			(xy 364.618531 -84.948018) (xy 364.602463 -85.001425) (xy 364.578791 -85.051922) (xy 364.548018 -85.098435)
			(xy 364.510801 -85.139972) (xy 364.467933 -85.175647) (xy 364.420327 -85.204701) (xy 364.368998 -85.226513)
			(xy 364.315041 -85.240619) (xy 364.259604 -85.246719) (xy 364.20387 -85.244682) (xy 364.149027 -85.234552)
			(xy 364.096243 -85.216545) (xy 364.046643 -85.191044) (xy 364.001285 -85.158593) (xy 363.961136 -85.119884)
			(xy 363.92705 -85.075741) (xy 363.899754 -85.027106) (xy 363.879831 -84.975015) (xy 363.867705 -84.920578)
			(xy 363.863634 -84.864956) (xy 362.419141 -84.864956) (xy 362.43133 -84.950046) (xy 362.465874 -85.191092)
			(xy 362.466128 -85.193124) (xy 362.466636 -85.195156) (xy 362.563561 -85.514942) (xy 365.30483 -85.514942)
			(xy 365.308901 -85.45932) (xy 365.321027 -85.404883) (xy 365.34095 -85.352792) (xy 365.368246 -85.304157)
			(xy 365.402332 -85.260014) (xy 365.442481 -85.221305) (xy 365.487839 -85.188854) (xy 365.537439 -85.163353)
			(xy 365.590223 -85.145346) (xy 365.645066 -85.135216) (xy 365.7008 -85.133179) (xy 365.756237 -85.139279)
			(xy 365.810194 -85.153385) (xy 365.861523 -85.175197) (xy 365.909129 -85.204251) (xy 365.951997 -85.239926)
			(xy 365.989214 -85.281463) (xy 366.019987 -85.327976) (xy 366.043659 -85.378473) (xy 366.059727 -85.43188)
			(xy 366.067764 -85.486494) (xy 381.045718 -85.486494) (xy 381.049789 -85.430872) (xy 381.061915 -85.376435)
			(xy 381.081838 -85.324344) (xy 381.109134 -85.275709) (xy 381.14322 -85.231566) (xy 381.183369 -85.192857)
			(xy 381.228727 -85.160406) (xy 381.278327 -85.134905) (xy 381.331111 -85.116898) (xy 381.385954 -85.106768)
			(xy 381.441688 -85.104731) (xy 381.497125 -85.110831) (xy 381.551082 -85.124937) (xy 381.602411 -85.146749)
			(xy 381.650017 -85.175803) (xy 381.692885 -85.211478) (xy 381.730102 -85.253015) (xy 381.760875 -85.299528)
			(xy 381.784547 -85.350025) (xy 381.800615 -85.403432) (xy 381.808735 -85.458608) (xy 381.809244 -85.486494)
			(xy 381.808735 -85.51438) (xy 381.800615 -85.569556) (xy 381.784547 -85.622963) (xy 381.760875 -85.67346)
			(xy 381.730102 -85.719973) (xy 381.692885 -85.76151) (xy 381.650017 -85.797185) (xy 381.602411 -85.826239)
			(xy 381.551082 -85.848051) (xy 381.497125 -85.862157) (xy 381.441688 -85.868257) (xy 381.385954 -85.86622)
			(xy 381.331111 -85.85609) (xy 381.278327 -85.838083) (xy 381.228727 -85.812582) (xy 381.183369 -85.780131)
			(xy 381.14322 -85.741422) (xy 381.109134 -85.697279) (xy 381.081838 -85.648644) (xy 381.061915 -85.596553)
			(xy 381.049789 -85.542116) (xy 381.045718 -85.486494) (xy 366.067764 -85.486494) (xy 366.067847 -85.487056)
			(xy 366.068356 -85.514942) (xy 366.067847 -85.542828) (xy 366.059727 -85.598004) (xy 366.043659 -85.651411)
			(xy 366.019987 -85.701908) (xy 365.989214 -85.748421) (xy 365.951997 -85.789958) (xy 365.909129 -85.825633)
			(xy 365.861523 -85.854687) (xy 365.810194 -85.876499) (xy 365.756237 -85.890605) (xy 365.7008 -85.896705)
			(xy 365.645066 -85.894668) (xy 365.590223 -85.884538) (xy 365.537439 -85.866531) (xy 365.487839 -85.84103)
			(xy 365.442481 -85.808579) (xy 365.402332 -85.76987) (xy 365.368246 -85.725727) (xy 365.34095 -85.677092)
			(xy 365.321027 -85.625001) (xy 365.308901 -85.570564) (xy 365.30483 -85.514942) (xy 362.563561 -85.514942)
			(xy 362.760567 -86.164928) (xy 363.895638 -86.164928) (xy 363.899709 -86.109306) (xy 363.911835 -86.054869)
			(xy 363.931758 -86.002778) (xy 363.959054 -85.954143) (xy 363.99314 -85.91) (xy 364.033289 -85.871291)
			(xy 364.078647 -85.83884) (xy 364.128247 -85.813339) (xy 364.181031 -85.795332) (xy 364.235874 -85.785202)
			(xy 364.291608 -85.783165) (xy 364.347045 -85.789265) (xy 364.401002 -85.803371) (xy 364.452331 -85.825183)
			(xy 364.499937 -85.854237) (xy 364.542805 -85.889912) (xy 364.580022 -85.931449) (xy 364.610795 -85.977962)
			(xy 364.634467 -86.028459) (xy 364.647174 -86.070694) (xy 370.219222 -86.070694) (xy 370.223293 -86.015072)
			(xy 370.235419 -85.960635) (xy 370.255342 -85.908544) (xy 370.282638 -85.859909) (xy 370.316724 -85.815766)
			(xy 370.356873 -85.777057) (xy 370.402231 -85.744606) (xy 370.451831 -85.719105) (xy 370.504615 -85.701098)
			(xy 370.559458 -85.690968) (xy 370.615192 -85.688931) (xy 370.670629 -85.695031) (xy 370.724586 -85.709137)
			(xy 370.775915 -85.730949) (xy 370.823521 -85.760003) (xy 370.866389 -85.795678) (xy 370.903606 -85.837215)
			(xy 370.934379 -85.883728) (xy 370.958051 -85.934225) (xy 370.974119 -85.987632) (xy 370.982239 -86.042808)
			(xy 370.982748 -86.070694) (xy 370.982239 -86.09858) (xy 370.974119 -86.153756) (xy 370.958051 -86.207163)
			(xy 370.934379 -86.25766) (xy 370.903606 -86.304173) (xy 370.866389 -86.34571) (xy 370.823521 -86.381385)
			(xy 370.775915 -86.410439) (xy 370.724586 -86.432251) (xy 370.670629 -86.446357) (xy 370.615192 -86.452457)
			(xy 370.559458 -86.45042) (xy 370.504615 -86.44029) (xy 370.451831 -86.422283) (xy 370.402231 -86.396782)
			(xy 370.356873 -86.364331) (xy 370.316724 -86.325622) (xy 370.282638 -86.281479) (xy 370.255342 -86.232844)
			(xy 370.235419 -86.180753) (xy 370.223293 -86.126316) (xy 370.219222 -86.070694) (xy 364.647174 -86.070694)
			(xy 364.650535 -86.081866) (xy 364.658655 -86.137042) (xy 364.659164 -86.164928) (xy 364.658655 -86.192814)
			(xy 364.650535 -86.24799) (xy 364.634467 -86.301397) (xy 364.610795 -86.351894) (xy 364.580022 -86.398407)
			(xy 364.542805 -86.439944) (xy 364.499937 -86.475619) (xy 364.452331 -86.504673) (xy 364.449091 -86.50605)
			(xy 367.536982 -86.50605) (xy 367.541053 -86.450428) (xy 367.553179 -86.395991) (xy 367.573102 -86.3439)
			(xy 367.600398 -86.295265) (xy 367.634484 -86.251122) (xy 367.674633 -86.212413) (xy 367.719991 -86.179962)
			(xy 367.769591 -86.154461) (xy 367.822375 -86.136454) (xy 367.877218 -86.126324) (xy 367.932952 -86.124287)
			(xy 367.988389 -86.130387) (xy 368.042346 -86.144493) (xy 368.093675 -86.166305) (xy 368.141281 -86.195359)
			(xy 368.184149 -86.231034) (xy 368.221366 -86.272571) (xy 368.252139 -86.319084) (xy 368.275811 -86.369581)
			(xy 368.291879 -86.422988) (xy 368.299999 -86.478164) (xy 368.300508 -86.50605) (xy 368.299999 -86.533936)
			(xy 368.29943 -86.5378) (xy 374.915428 -86.5378) (xy 374.919499 -86.482178) (xy 374.931625 -86.427741)
			(xy 374.951548 -86.37565) (xy 374.978844 -86.327015) (xy 375.01293 -86.282872) (xy 375.053079 -86.244163)
			(xy 375.098437 -86.211712) (xy 375.148037 -86.186211) (xy 375.200821 -86.168204) (xy 375.255664 -86.158074)
			(xy 375.311398 -86.156037) (xy 375.366835 -86.162137) (xy 375.420792 -86.176243) (xy 375.472121 -86.198055)
			(xy 375.519727 -86.227109) (xy 375.562595 -86.262784) (xy 375.599812 -86.304321) (xy 375.630585 -86.350834)
			(xy 375.654257 -86.401331) (xy 375.666811 -86.443058) (xy 377.293884 -86.443058) (xy 377.297955 -86.387436)
			(xy 377.310081 -86.332999) (xy 377.330004 -86.280908) (xy 377.3573 -86.232273) (xy 377.391386 -86.18813)
			(xy 377.431535 -86.149421) (xy 377.476893 -86.11697) (xy 377.526493 -86.091469) (xy 377.579277 -86.073462)
			(xy 377.63412 -86.063332) (xy 377.689854 -86.061295) (xy 377.745291 -86.067395) (xy 377.799248 -86.081501)
			(xy 377.850577 -86.103313) (xy 377.898183 -86.132367) (xy 377.941051 -86.168042) (xy 377.978268 -86.209579)
			(xy 378.009041 -86.256092) (xy 378.032713 -86.306589) (xy 378.048781 -86.359996) (xy 378.056901 -86.415172)
			(xy 378.05741 -86.443058) (xy 378.056901 -86.470944) (xy 378.048781 -86.52612) (xy 378.045267 -86.5378)
			(xy 379.480316 -86.5378) (xy 379.484387 -86.482178) (xy 379.496513 -86.427741) (xy 379.516436 -86.37565)
			(xy 379.543732 -86.327015) (xy 379.577818 -86.282872) (xy 379.617967 -86.244163) (xy 379.663325 -86.211712)
			(xy 379.712925 -86.186211) (xy 379.765709 -86.168204) (xy 379.820552 -86.158074) (xy 379.876286 -86.156037)
			(xy 379.931723 -86.162137) (xy 379.98568 -86.176243) (xy 380.037009 -86.198055) (xy 380.084615 -86.227109)
			(xy 380.127483 -86.262784) (xy 380.1647 -86.304321) (xy 380.195473 -86.350834) (xy 380.219145 -86.401331)
			(xy 380.235213 -86.454738) (xy 380.243333 -86.509914) (xy 380.243842 -86.5378) (xy 380.243333 -86.565686)
			(xy 380.235213 -86.620862) (xy 380.219145 -86.674269) (xy 380.195473 -86.724766) (xy 380.1647 -86.771279)
			(xy 380.127483 -86.812816) (xy 380.084615 -86.848491) (xy 380.037009 -86.877545) (xy 379.98568 -86.899357)
			(xy 379.931723 -86.913463) (xy 379.876286 -86.919563) (xy 379.820552 -86.917526) (xy 379.765709 -86.907396)
			(xy 379.712925 -86.889389) (xy 379.663325 -86.863888) (xy 379.617967 -86.831437) (xy 379.577818 -86.792728)
			(xy 379.543732 -86.748585) (xy 379.516436 -86.69995) (xy 379.496513 -86.647859) (xy 379.484387 -86.593422)
			(xy 379.480316 -86.5378) (xy 378.045267 -86.5378) (xy 378.032713 -86.579527) (xy 378.009041 -86.630024)
			(xy 377.978268 -86.676537) (xy 377.941051 -86.718074) (xy 377.898183 -86.753749) (xy 377.850577 -86.782803)
			(xy 377.799248 -86.804615) (xy 377.745291 -86.818721) (xy 377.689854 -86.824821) (xy 377.63412 -86.822784)
			(xy 377.579277 -86.812654) (xy 377.526493 -86.794647) (xy 377.476893 -86.769146) (xy 377.431535 -86.736695)
			(xy 377.391386 -86.697986) (xy 377.3573 -86.653843) (xy 377.330004 -86.605208) (xy 377.310081 -86.553117)
			(xy 377.297955 -86.49868) (xy 377.293884 -86.443058) (xy 375.666811 -86.443058) (xy 375.670325 -86.454738)
			(xy 375.678445 -86.509914) (xy 375.678954 -86.5378) (xy 375.678445 -86.565686) (xy 375.670325 -86.620862)
			(xy 375.654257 -86.674269) (xy 375.630585 -86.724766) (xy 375.599812 -86.771279) (xy 375.562595 -86.812816)
			(xy 375.519727 -86.848491) (xy 375.472121 -86.877545) (xy 375.420792 -86.899357) (xy 375.366835 -86.913463)
			(xy 375.311398 -86.919563) (xy 375.255664 -86.917526) (xy 375.200821 -86.907396) (xy 375.148037 -86.889389)
			(xy 375.098437 -86.863888) (xy 375.053079 -86.831437) (xy 375.01293 -86.792728) (xy 374.978844 -86.748585)
			(xy 374.951548 -86.69995) (xy 374.931625 -86.647859) (xy 374.919499 -86.593422) (xy 374.915428 -86.5378)
			(xy 368.29943 -86.5378) (xy 368.291879 -86.589112) (xy 368.275811 -86.642519) (xy 368.252139 -86.693016)
			(xy 368.221366 -86.739529) (xy 368.184149 -86.781066) (xy 368.141281 -86.816741) (xy 368.093675 -86.845795)
			(xy 368.042346 -86.867607) (xy 367.988389 -86.881713) (xy 367.932952 -86.887813) (xy 367.877218 -86.885776)
			(xy 367.822375 -86.875646) (xy 367.769591 -86.857639) (xy 367.719991 -86.832138) (xy 367.674633 -86.799687)
			(xy 367.634484 -86.760978) (xy 367.600398 -86.716835) (xy 367.573102 -86.6682) (xy 367.553179 -86.616109)
			(xy 367.541053 -86.561672) (xy 367.536982 -86.50605) (xy 364.449091 -86.50605) (xy 364.401002 -86.526485)
			(xy 364.347045 -86.540591) (xy 364.291608 -86.546691) (xy 364.235874 -86.544654) (xy 364.181031 -86.534524)
			(xy 364.128247 -86.516517) (xy 364.078647 -86.491016) (xy 364.033289 -86.458565) (xy 363.99314 -86.419856)
			(xy 363.959054 -86.375713) (xy 363.931758 -86.327078) (xy 363.911835 -86.274987) (xy 363.899709 -86.22055)
			(xy 363.895638 -86.164928) (xy 362.760567 -86.164928) (xy 363.078441 -87.213694) (xy 370.219222 -87.213694)
			(xy 370.223293 -87.158072) (xy 370.235419 -87.103635) (xy 370.255342 -87.051544) (xy 370.282638 -87.002909)
			(xy 370.316724 -86.958766) (xy 370.356873 -86.920057) (xy 370.402231 -86.887606) (xy 370.451831 -86.862105)
			(xy 370.504615 -86.844098) (xy 370.559458 -86.833968) (xy 370.615192 -86.831931) (xy 370.670629 -86.838031)
			(xy 370.724586 -86.852137) (xy 370.775915 -86.873949) (xy 370.823521 -86.903003) (xy 370.866389 -86.938678)
			(xy 370.903606 -86.980215) (xy 370.934379 -87.026728) (xy 370.958051 -87.077225) (xy 370.974119 -87.130632)
			(xy 370.982239 -87.185808) (xy 370.982748 -87.213694) (xy 370.982239 -87.24158) (xy 370.974119 -87.296756)
			(xy 370.958051 -87.350163) (xy 370.934379 -87.40066) (xy 370.903606 -87.447173) (xy 370.866389 -87.48871)
			(xy 370.823521 -87.524385) (xy 370.775915 -87.553439) (xy 370.724586 -87.575251) (xy 370.670629 -87.589357)
			(xy 370.615192 -87.595457) (xy 370.559458 -87.59342) (xy 370.504615 -87.58329) (xy 370.451831 -87.565283)
			(xy 370.402231 -87.539782) (xy 370.356873 -87.507331) (xy 370.316724 -87.468622) (xy 370.282638 -87.424479)
			(xy 370.255342 -87.375844) (xy 370.235419 -87.323753) (xy 370.223293 -87.269316) (xy 370.219222 -87.213694)
			(xy 363.078441 -87.213694) (xy 363.229564 -87.712296) (xy 367.61877 -87.712296) (xy 367.622841 -87.656674)
			(xy 367.634967 -87.602237) (xy 367.65489 -87.550146) (xy 367.682186 -87.501511) (xy 367.716272 -87.457368)
			(xy 367.756421 -87.418659) (xy 367.801779 -87.386208) (xy 367.851379 -87.360707) (xy 367.904163 -87.3427)
			(xy 367.959006 -87.33257) (xy 368.01474 -87.330533) (xy 368.070177 -87.336633) (xy 368.124134 -87.350739)
			(xy 368.175463 -87.372551) (xy 368.223069 -87.401605) (xy 368.265937 -87.43728) (xy 368.303154 -87.478817)
			(xy 368.333927 -87.52533) (xy 368.357599 -87.575827) (xy 368.373667 -87.629234) (xy 368.381256 -87.6808)
			(xy 374.915428 -87.6808) (xy 374.919499 -87.625178) (xy 374.931625 -87.570741) (xy 374.951548 -87.51865)
			(xy 374.978844 -87.470015) (xy 375.01293 -87.425872) (xy 375.053079 -87.387163) (xy 375.098437 -87.354712)
			(xy 375.148037 -87.329211) (xy 375.200821 -87.311204) (xy 375.255664 -87.301074) (xy 375.311398 -87.299037)
			(xy 375.366835 -87.305137) (xy 375.420792 -87.319243) (xy 375.472121 -87.341055) (xy 375.519727 -87.370109)
			(xy 375.562595 -87.405784) (xy 375.599812 -87.447321) (xy 375.630585 -87.493834) (xy 375.654257 -87.544331)
			(xy 375.670325 -87.597738) (xy 375.678445 -87.652914) (xy 375.678954 -87.6808) (xy 377.153422 -87.6808)
			(xy 377.157493 -87.625178) (xy 377.169619 -87.570741) (xy 377.189542 -87.51865) (xy 377.216838 -87.470015)
			(xy 377.250924 -87.425872) (xy 377.291073 -87.387163) (xy 377.336431 -87.354712) (xy 377.386031 -87.329211)
			(xy 377.438815 -87.311204) (xy 377.493658 -87.301074) (xy 377.549392 -87.299037) (xy 377.604829 -87.305137)
			(xy 377.658786 -87.319243) (xy 377.710115 -87.341055) (xy 377.757721 -87.370109) (xy 377.800589 -87.405784)
			(xy 377.837806 -87.447321) (xy 377.868579 -87.493834) (xy 377.889784 -87.539068) (xy 380.716026 -87.539068)
			(xy 380.720097 -87.483446) (xy 380.732223 -87.429009) (xy 380.752146 -87.376918) (xy 380.779442 -87.328283)
			(xy 380.813528 -87.28414) (xy 380.853677 -87.245431) (xy 380.899035 -87.21298) (xy 380.948635 -87.187479)
			(xy 381.001419 -87.169472) (xy 381.056262 -87.159342) (xy 381.111996 -87.157305) (xy 381.167433 -87.163405)
			(xy 381.22139 -87.177511) (xy 381.272719 -87.199323) (xy 381.320325 -87.228377) (xy 381.363193 -87.264052)
			(xy 381.40041 -87.305589) (xy 381.431183 -87.352102) (xy 381.454855 -87.402599) (xy 381.470923 -87.456006)
			(xy 381.479043 -87.511182) (xy 381.479552 -87.539068) (xy 381.479043 -87.566954) (xy 381.470923 -87.62213)
			(xy 381.454855 -87.675537) (xy 381.431183 -87.726034) (xy 381.40041 -87.772547) (xy 381.363193 -87.814084)
			(xy 381.320325 -87.849759) (xy 381.272719 -87.878813) (xy 381.22139 -87.900625) (xy 381.167433 -87.914731)
			(xy 381.111996 -87.920831) (xy 381.056262 -87.918794) (xy 381.001419 -87.908664) (xy 380.948635 -87.890657)
			(xy 380.899035 -87.865156) (xy 380.853677 -87.832705) (xy 380.813528 -87.793996) (xy 380.779442 -87.749853)
			(xy 380.752146 -87.701218) (xy 380.732223 -87.649127) (xy 380.720097 -87.59469) (xy 380.716026 -87.539068)
			(xy 377.889784 -87.539068) (xy 377.892251 -87.544331) (xy 377.908319 -87.597738) (xy 377.916439 -87.652914)
			(xy 377.916948 -87.6808) (xy 377.916439 -87.708686) (xy 377.908319 -87.763862) (xy 377.892251 -87.817269)
			(xy 377.868579 -87.867766) (xy 377.837806 -87.914279) (xy 377.800589 -87.955816) (xy 377.757721 -87.991491)
			(xy 377.710115 -88.020545) (xy 377.658786 -88.042357) (xy 377.604829 -88.056463) (xy 377.549392 -88.062563)
			(xy 377.493658 -88.060526) (xy 377.438815 -88.050396) (xy 377.386031 -88.032389) (xy 377.336431 -88.006888)
			(xy 377.291073 -87.974437) (xy 377.250924 -87.935728) (xy 377.216838 -87.891585) (xy 377.189542 -87.84295)
			(xy 377.169619 -87.790859) (xy 377.157493 -87.736422) (xy 377.153422 -87.6808) (xy 375.678954 -87.6808)
			(xy 375.678445 -87.708686) (xy 375.670325 -87.763862) (xy 375.654257 -87.817269) (xy 375.630585 -87.867766)
			(xy 375.599812 -87.914279) (xy 375.562595 -87.955816) (xy 375.519727 -87.991491) (xy 375.472121 -88.020545)
			(xy 375.420792 -88.042357) (xy 375.366835 -88.056463) (xy 375.311398 -88.062563) (xy 375.255664 -88.060526)
			(xy 375.200821 -88.050396) (xy 375.148037 -88.032389) (xy 375.098437 -88.006888) (xy 375.053079 -87.974437)
			(xy 375.01293 -87.935728) (xy 374.978844 -87.891585) (xy 374.951548 -87.84295) (xy 374.931625 -87.790859)
			(xy 374.919499 -87.736422) (xy 374.915428 -87.6808) (xy 368.381256 -87.6808) (xy 368.381787 -87.68441)
			(xy 368.382296 -87.712296) (xy 368.381787 -87.740182) (xy 368.373667 -87.795358) (xy 368.357599 -87.848765)
			(xy 368.333927 -87.899262) (xy 368.303154 -87.945775) (xy 368.265937 -87.987312) (xy 368.223069 -88.022987)
			(xy 368.175463 -88.052041) (xy 368.124134 -88.073853) (xy 368.070177 -88.087959) (xy 368.01474 -88.094059)
			(xy 367.959006 -88.092022) (xy 367.904163 -88.081892) (xy 367.851379 -88.063885) (xy 367.801779 -88.038384)
			(xy 367.756421 -88.005933) (xy 367.716272 -87.967224) (xy 367.682186 -87.923081) (xy 367.65489 -87.874446)
			(xy 367.634967 -87.822355) (xy 367.622841 -87.767918) (xy 367.61877 -87.712296) (xy 363.229564 -87.712296)
			(xy 363.368215 -88.16975) (xy 364.03102 -88.16975) (xy 364.035091 -88.114128) (xy 364.047217 -88.059691)
			(xy 364.06714 -88.0076) (xy 364.094436 -87.958965) (xy 364.128522 -87.914822) (xy 364.168671 -87.876113)
			(xy 364.214029 -87.843662) (xy 364.263629 -87.818161) (xy 364.316413 -87.800154) (xy 364.371256 -87.790024)
			(xy 364.42699 -87.787987) (xy 364.482427 -87.794087) (xy 364.536384 -87.808193) (xy 364.587713 -87.830005)
			(xy 364.635319 -87.859059) (xy 364.678187 -87.894734) (xy 364.715404 -87.936271) (xy 364.746177 -87.982784)
			(xy 364.769849 -88.033281) (xy 364.785917 -88.086688) (xy 364.787226 -88.095582) (xy 365.484662 -88.095582)
			(xy 365.488733 -88.03996) (xy 365.500859 -87.985523) (xy 365.520782 -87.933432) (xy 365.548078 -87.884797)
			(xy 365.582164 -87.840654) (xy 365.622313 -87.801945) (xy 365.667671 -87.769494) (xy 365.717271 -87.743993)
			(xy 365.770055 -87.725986) (xy 365.824898 -87.715856) (xy 365.880632 -87.713819) (xy 365.936069 -87.719919)
			(xy 365.990026 -87.734025) (xy 366.041355 -87.755837) (xy 366.088961 -87.784891) (xy 366.131829 -87.820566)
			(xy 366.169046 -87.862103) (xy 366.199819 -87.908616) (xy 366.223491 -87.959113) (xy 366.239559 -88.01252)
			(xy 366.247679 -88.067696) (xy 366.248188 -88.095582) (xy 366.247679 -88.123468) (xy 366.239559 -88.178644)
			(xy 366.223491 -88.232051) (xy 366.199819 -88.282548) (xy 366.169046 -88.329061) (xy 366.144287 -88.356694)
			(xy 370.219222 -88.356694) (xy 370.223293 -88.301072) (xy 370.235419 -88.246635) (xy 370.255342 -88.194544)
			(xy 370.282638 -88.145909) (xy 370.316724 -88.101766) (xy 370.356873 -88.063057) (xy 370.402231 -88.030606)
			(xy 370.451831 -88.005105) (xy 370.504615 -87.987098) (xy 370.559458 -87.976968) (xy 370.615192 -87.974931)
			(xy 370.670629 -87.981031) (xy 370.724586 -87.995137) (xy 370.775915 -88.016949) (xy 370.823521 -88.046003)
			(xy 370.866389 -88.081678) (xy 370.903606 -88.123215) (xy 370.934379 -88.169728) (xy 370.958051 -88.220225)
			(xy 370.974119 -88.273632) (xy 370.982239 -88.328808) (xy 370.982748 -88.356694) (xy 370.982239 -88.38458)
			(xy 370.974119 -88.439756) (xy 370.958051 -88.493163) (xy 370.934379 -88.54366) (xy 370.903606 -88.590173)
			(xy 370.866389 -88.63171) (xy 370.823521 -88.667385) (xy 370.775915 -88.696439) (xy 370.724586 -88.718251)
			(xy 370.670629 -88.732357) (xy 370.615192 -88.738457) (xy 370.559458 -88.73642) (xy 370.504615 -88.72629)
			(xy 370.451831 -88.708283) (xy 370.402231 -88.682782) (xy 370.356873 -88.650331) (xy 370.316724 -88.611622)
			(xy 370.282638 -88.567479) (xy 370.255342 -88.518844) (xy 370.235419 -88.466753) (xy 370.223293 -88.412316)
			(xy 370.219222 -88.356694) (xy 366.144287 -88.356694) (xy 366.131829 -88.370598) (xy 366.088961 -88.406273)
			(xy 366.041355 -88.435327) (xy 365.990026 -88.457139) (xy 365.936069 -88.471245) (xy 365.880632 -88.477345)
			(xy 365.824898 -88.475308) (xy 365.770055 -88.465178) (xy 365.717271 -88.447171) (xy 365.667671 -88.42167)
			(xy 365.622313 -88.389219) (xy 365.582164 -88.35051) (xy 365.548078 -88.306367) (xy 365.520782 -88.257732)
			(xy 365.500859 -88.205641) (xy 365.488733 -88.151204) (xy 365.484662 -88.095582) (xy 364.787226 -88.095582)
			(xy 364.794037 -88.141864) (xy 364.794546 -88.16975) (xy 364.794037 -88.197636) (xy 364.785917 -88.252812)
			(xy 364.769849 -88.306219) (xy 364.746177 -88.356716) (xy 364.715404 -88.403229) (xy 364.678187 -88.444766)
			(xy 364.635319 -88.480441) (xy 364.587713 -88.509495) (xy 364.536384 -88.531307) (xy 364.482427 -88.545413)
			(xy 364.42699 -88.551513) (xy 364.371256 -88.549476) (xy 364.316413 -88.539346) (xy 364.263629 -88.521339)
			(xy 364.214029 -88.495838) (xy 364.168671 -88.463387) (xy 364.128522 -88.424678) (xy 364.094436 -88.380535)
			(xy 364.06714 -88.3319) (xy 364.047217 -88.279809) (xy 364.035091 -88.225372) (xy 364.03102 -88.16975)
			(xy 363.368215 -88.16975) (xy 363.619342 -88.998298) (xy 365.306608 -88.998298) (xy 365.310679 -88.942676)
			(xy 365.322805 -88.888239) (xy 365.342728 -88.836148) (xy 365.370024 -88.787513) (xy 365.40411 -88.74337)
			(xy 365.444259 -88.704661) (xy 365.489617 -88.67221) (xy 365.539217 -88.646709) (xy 365.592001 -88.628702)
			(xy 365.646844 -88.618572) (xy 365.702578 -88.616535) (xy 365.758015 -88.622635) (xy 365.811972 -88.636741)
			(xy 365.863301 -88.658553) (xy 365.910907 -88.687607) (xy 365.953775 -88.723282) (xy 365.984895 -88.758014)
			(xy 367.55578 -88.758014) (xy 367.556266 -88.730763) (xy 367.564022 -88.676815) (xy 367.579377 -88.62452)
			(xy 367.602019 -88.574943) (xy 367.631485 -88.529093) (xy 367.667176 -88.487902) (xy 367.708367 -88.452211)
			(xy 367.754217 -88.422745) (xy 367.803794 -88.400103) (xy 367.856089 -88.384748) (xy 367.910037 -88.376992)
			(xy 367.964539 -88.376992) (xy 368.018487 -88.384748) (xy 368.070782 -88.400103) (xy 368.120359 -88.422745)
			(xy 368.166209 -88.452211) (xy 368.2074 -88.487902) (xy 368.243091 -88.529093) (xy 368.272557 -88.574943)
			(xy 368.295199 -88.62452) (xy 368.310554 -88.676815) (xy 368.31831 -88.730763) (xy 368.318796 -88.758014)
			(xy 368.318796 -88.758268) (xy 368.318301 -88.785979) (xy 368.312775 -88.8238) (xy 374.915428 -88.8238)
			(xy 374.919499 -88.768178) (xy 374.931625 -88.713741) (xy 374.951548 -88.66165) (xy 374.978844 -88.613015)
			(xy 375.01293 -88.568872) (xy 375.053079 -88.530163) (xy 375.098437 -88.497712) (xy 375.148037 -88.472211)
			(xy 375.200821 -88.454204) (xy 375.255664 -88.444074) (xy 375.311398 -88.442037) (xy 375.366835 -88.448137)
			(xy 375.420792 -88.462243) (xy 375.472121 -88.484055) (xy 375.519727 -88.513109) (xy 375.562595 -88.548784)
			(xy 375.599812 -88.590321) (xy 375.630585 -88.636834) (xy 375.654257 -88.687331) (xy 375.670325 -88.740738)
			(xy 375.678445 -88.795914) (xy 375.678954 -88.8238) (xy 377.153422 -88.8238) (xy 377.157493 -88.768178)
			(xy 377.169619 -88.713741) (xy 377.189542 -88.66165) (xy 377.216838 -88.613015) (xy 377.250924 -88.568872)
			(xy 377.291073 -88.530163) (xy 377.336431 -88.497712) (xy 377.386031 -88.472211) (xy 377.438815 -88.454204)
			(xy 377.493658 -88.444074) (xy 377.549392 -88.442037) (xy 377.604829 -88.448137) (xy 377.658786 -88.462243)
			(xy 377.710115 -88.484055) (xy 377.757721 -88.513109) (xy 377.800589 -88.548784) (xy 377.837806 -88.590321)
			(xy 377.868579 -88.636834) (xy 377.892251 -88.687331) (xy 377.908319 -88.740738) (xy 377.916439 -88.795914)
			(xy 377.91686 -88.818974) (xy 379.480316 -88.818974) (xy 379.484387 -88.763352) (xy 379.496513 -88.708915)
			(xy 379.516436 -88.656824) (xy 379.543732 -88.608189) (xy 379.577818 -88.564046) (xy 379.617967 -88.525337)
			(xy 379.663325 -88.492886) (xy 379.712925 -88.467385) (xy 379.765709 -88.449378) (xy 379.820552 -88.439248)
			(xy 379.876286 -88.437211) (xy 379.931723 -88.443311) (xy 379.98568 -88.457417) (xy 380.037009 -88.479229)
			(xy 380.084615 -88.508283) (xy 380.127483 -88.543958) (xy 380.1647 -88.585495) (xy 380.195473 -88.632008)
			(xy 380.219145 -88.682505) (xy 380.235213 -88.735912) (xy 380.243333 -88.791088) (xy 380.243842 -88.818974)
			(xy 380.243333 -88.84686) (xy 380.235213 -88.902036) (xy 380.219145 -88.955443) (xy 380.195473 -89.00594)
			(xy 380.1647 -89.052453) (xy 380.127483 -89.09399) (xy 380.084615 -89.129665) (xy 380.037009 -89.158719)
			(xy 379.98568 -89.180531) (xy 379.931723 -89.194637) (xy 379.876286 -89.200737) (xy 379.820552 -89.1987)
			(xy 379.765709 -89.18857) (xy 379.712925 -89.170563) (xy 379.663325 -89.145062) (xy 379.617967 -89.112611)
			(xy 379.577818 -89.073902) (xy 379.543732 -89.029759) (xy 379.516436 -88.981124) (xy 379.496513 -88.929033)
			(xy 379.484387 -88.874596) (xy 379.480316 -88.818974) (xy 377.91686 -88.818974) (xy 377.916948 -88.8238)
			(xy 377.916439 -88.851686) (xy 377.908319 -88.906862) (xy 377.892251 -88.960269) (xy 377.868579 -89.010766)
			(xy 377.837806 -89.057279) (xy 377.800589 -89.098816) (xy 377.757721 -89.134491) (xy 377.710115 -89.163545)
			(xy 377.658786 -89.185357) (xy 377.604829 -89.199463) (xy 377.549392 -89.205563) (xy 377.493658 -89.203526)
			(xy 377.438815 -89.193396) (xy 377.386031 -89.175389) (xy 377.336431 -89.149888) (xy 377.291073 -89.117437)
			(xy 377.250924 -89.078728) (xy 377.216838 -89.034585) (xy 377.189542 -88.98595) (xy 377.169619 -88.933859)
			(xy 377.157493 -88.879422) (xy 377.153422 -88.8238) (xy 375.678954 -88.8238) (xy 375.678445 -88.851686)
			(xy 375.670325 -88.906862) (xy 375.654257 -88.960269) (xy 375.630585 -89.010766) (xy 375.599812 -89.057279)
			(xy 375.562595 -89.098816) (xy 375.519727 -89.134491) (xy 375.472121 -89.163545) (xy 375.420792 -89.185357)
			(xy 375.366835 -89.199463) (xy 375.311398 -89.205563) (xy 375.255664 -89.203526) (xy 375.200821 -89.193396)
			(xy 375.148037 -89.175389) (xy 375.098437 -89.149888) (xy 375.053079 -89.117437) (xy 375.01293 -89.078728)
			(xy 374.978844 -89.034585) (xy 374.951548 -88.98595) (xy 374.931625 -88.933859) (xy 374.919499 -88.879422)
			(xy 374.915428 -88.8238) (xy 368.312775 -88.8238) (xy 368.310288 -88.840817) (xy 368.294412 -88.893916)
			(xy 368.271008 -88.944153) (xy 368.240571 -88.990467) (xy 368.22253 -89.011506) (xy 368.214656 -89.020142)
			(xy 368.208306 -89.041986) (xy 368.223292 -89.131394) (xy 368.225638 -89.142656) (xy 368.238891 -89.161436)
			(xy 368.248692 -89.167462) (xy 368.273516 -89.182113) (xy 368.318894 -89.217652) (xy 368.358408 -89.259615)
			(xy 368.391156 -89.307046) (xy 368.416393 -89.358866) (xy 368.433545 -89.413893) (xy 368.44222 -89.470875)
			(xy 368.442748 -89.499694) (xy 370.219222 -89.499694) (xy 370.223293 -89.444072) (xy 370.235419 -89.389635)
			(xy 370.255342 -89.337544) (xy 370.282638 -89.288909) (xy 370.316724 -89.244766) (xy 370.356873 -89.206057)
			(xy 370.402231 -89.173606) (xy 370.451831 -89.148105) (xy 370.504615 -89.130098) (xy 370.559458 -89.119968)
			(xy 370.615192 -89.117931) (xy 370.670629 -89.124031) (xy 370.724586 -89.138137) (xy 370.775915 -89.159949)
			(xy 370.823521 -89.189003) (xy 370.866389 -89.224678) (xy 370.903606 -89.266215) (xy 370.934379 -89.312728)
			(xy 370.958051 -89.363225) (xy 370.974119 -89.416632) (xy 370.982239 -89.471808) (xy 370.982748 -89.499694)
			(xy 370.982239 -89.52758) (xy 370.974119 -89.582756) (xy 370.958051 -89.636163) (xy 370.934379 -89.68666)
			(xy 370.903606 -89.733173) (xy 370.866389 -89.77471) (xy 370.823521 -89.810385) (xy 370.775915 -89.839439)
			(xy 370.724586 -89.861251) (xy 370.670629 -89.875357) (xy 370.615192 -89.881457) (xy 370.559458 -89.87942)
			(xy 370.504615 -89.86929) (xy 370.451831 -89.851283) (xy 370.402231 -89.825782) (xy 370.356873 -89.793331)
			(xy 370.316724 -89.754622) (xy 370.282638 -89.710479) (xy 370.255342 -89.661844) (xy 370.235419 -89.609753)
			(xy 370.223293 -89.555316) (xy 370.219222 -89.499694) (xy 368.442748 -89.499694) (xy 368.442262 -89.526945)
			(xy 368.434506 -89.580893) (xy 368.419151 -89.633188) (xy 368.396509 -89.682765) (xy 368.367043 -89.728615)
			(xy 368.331352 -89.769806) (xy 368.290161 -89.805497) (xy 368.244311 -89.834963) (xy 368.194734 -89.857605)
			(xy 368.142439 -89.87296) (xy 368.088491 -89.880716) (xy 368.033989 -89.880716) (xy 367.980041 -89.87296)
			(xy 367.927746 -89.857605) (xy 367.878169 -89.834963) (xy 367.832319 -89.805497) (xy 367.791128 -89.769806)
			(xy 367.755437 -89.728615) (xy 367.725971 -89.682765) (xy 367.703329 -89.633188) (xy 367.687974 -89.580893)
			(xy 367.680218 -89.526945) (xy 367.679732 -89.499694) (xy 367.679732 -89.49944) (xy 367.680225 -89.471729)
			(xy 367.688237 -89.41689) (xy 367.704113 -89.363792) (xy 367.727518 -89.313555) (xy 367.757956 -89.26724)
			(xy 367.775998 -89.246202) (xy 367.783872 -89.237566) (xy 367.790222 -89.215722) (xy 367.775236 -89.126314)
			(xy 367.772874 -89.115057) (xy 367.759632 -89.096276) (xy 367.749836 -89.090246) (xy 367.724978 -89.075649)
			(xy 367.679598 -89.040103) (xy 367.640085 -88.998132) (xy 367.60734 -88.950691) (xy 367.582108 -88.898862)
			(xy 367.564965 -88.843826) (xy 367.556302 -88.786836) (xy 367.55578 -88.758014) (xy 365.984895 -88.758014)
			(xy 365.990992 -88.764819) (xy 366.021765 -88.811332) (xy 366.045437 -88.861829) (xy 366.061505 -88.915236)
			(xy 366.069625 -88.970412) (xy 366.070134 -88.998298) (xy 366.069625 -89.026184) (xy 366.061505 -89.08136)
			(xy 366.045437 -89.134767) (xy 366.021765 -89.185264) (xy 365.990992 -89.231777) (xy 365.953775 -89.273314)
			(xy 365.910907 -89.308989) (xy 365.863301 -89.338043) (xy 365.811972 -89.359855) (xy 365.758015 -89.373961)
			(xy 365.702578 -89.380061) (xy 365.646844 -89.378024) (xy 365.592001 -89.367894) (xy 365.539217 -89.349887)
			(xy 365.489617 -89.324386) (xy 365.444259 -89.291935) (xy 365.40411 -89.253226) (xy 365.370024 -89.209083)
			(xy 365.342728 -89.160448) (xy 365.322805 -89.108357) (xy 365.310679 -89.05392) (xy 365.306608 -88.998298)
			(xy 363.619342 -88.998298) (xy 363.771312 -89.499694) (xy 364.315754 -89.499694) (xy 364.319825 -89.444072)
			(xy 364.331951 -89.389635) (xy 364.351874 -89.337544) (xy 364.37917 -89.288909) (xy 364.413256 -89.244766)
			(xy 364.453405 -89.206057) (xy 364.498763 -89.173606) (xy 364.548363 -89.148105) (xy 364.601147 -89.130098)
			(xy 364.65599 -89.119968) (xy 364.711724 -89.117931) (xy 364.767161 -89.124031) (xy 364.821118 -89.138137)
			(xy 364.872447 -89.159949) (xy 364.920053 -89.189003) (xy 364.962921 -89.224678) (xy 365.000138 -89.266215)
			(xy 365.030911 -89.312728) (xy 365.054583 -89.363225) (xy 365.070651 -89.416632) (xy 365.078771 -89.471808)
			(xy 365.07928 -89.499694) (xy 365.078771 -89.52758) (xy 365.070651 -89.582756) (xy 365.054583 -89.636163)
			(xy 365.030911 -89.68666) (xy 365.000138 -89.733173) (xy 364.962921 -89.77471) (xy 364.920053 -89.810385)
			(xy 364.872447 -89.839439) (xy 364.821118 -89.861251) (xy 364.767161 -89.875357) (xy 364.711724 -89.881457)
			(xy 364.65599 -89.87942) (xy 364.601147 -89.86929) (xy 364.548363 -89.851283) (xy 364.498763 -89.825782)
			(xy 364.453405 -89.793331) (xy 364.413256 -89.754622) (xy 364.37917 -89.710479) (xy 364.351874 -89.661844)
			(xy 364.331951 -89.609753) (xy 364.319825 -89.555316) (xy 364.315754 -89.499694) (xy 363.771312 -89.499694)
			(xy 363.967472 -90.146886) (xy 365.677702 -90.146886) (xy 365.681773 -90.091264) (xy 365.693899 -90.036827)
			(xy 365.713822 -89.984736) (xy 365.741118 -89.936101) (xy 365.775204 -89.891958) (xy 365.815353 -89.853249)
			(xy 365.860711 -89.820798) (xy 365.910311 -89.795297) (xy 365.963095 -89.77729) (xy 366.017938 -89.76716)
			(xy 366.073672 -89.765123) (xy 366.129109 -89.771223) (xy 366.183066 -89.785329) (xy 366.234395 -89.807141)
			(xy 366.282001 -89.836195) (xy 366.324869 -89.87187) (xy 366.362086 -89.913407) (xy 366.392859 -89.95992)
			(xy 366.396084 -89.9668) (xy 374.915428 -89.9668) (xy 374.919499 -89.911178) (xy 374.931625 -89.856741)
			(xy 374.951548 -89.80465) (xy 374.978844 -89.756015) (xy 375.01293 -89.711872) (xy 375.053079 -89.673163)
			(xy 375.098437 -89.640712) (xy 375.148037 -89.615211) (xy 375.200821 -89.597204) (xy 375.255664 -89.587074)
			(xy 375.311398 -89.585037) (xy 375.366835 -89.591137) (xy 375.420792 -89.605243) (xy 375.472121 -89.627055)
			(xy 375.519727 -89.656109) (xy 375.562595 -89.691784) (xy 375.599812 -89.733321) (xy 375.630585 -89.779834)
			(xy 375.654257 -89.830331) (xy 375.670325 -89.883738) (xy 375.67511 -89.916254) (xy 380.577088 -89.916254)
			(xy 380.581159 -89.860632) (xy 380.593285 -89.806195) (xy 380.613208 -89.754104) (xy 380.640504 -89.705469)
			(xy 380.67459 -89.661326) (xy 380.714739 -89.622617) (xy 380.760097 -89.590166) (xy 380.809697 -89.564665)
			(xy 380.862481 -89.546658) (xy 380.917324 -89.536528) (xy 380.973058 -89.534491) (xy 381.028495 -89.540591)
			(xy 381.082452 -89.554697) (xy 381.133781 -89.576509) (xy 381.181387 -89.605563) (xy 381.224255 -89.641238)
			(xy 381.261472 -89.682775) (xy 381.292245 -89.729288) (xy 381.315917 -89.779785) (xy 381.331985 -89.833192)
			(xy 381.340105 -89.888368) (xy 381.340614 -89.916254) (xy 381.340105 -89.94414) (xy 381.331985 -89.999316)
			(xy 381.315917 -90.052723) (xy 381.308449 -90.068654) (xy 384.658868 -90.068654) (xy 384.662939 -90.013032)
			(xy 384.675065 -89.958595) (xy 384.694988 -89.906504) (xy 384.722284 -89.857869) (xy 384.75637 -89.813726)
			(xy 384.796519 -89.775017) (xy 384.841877 -89.742566) (xy 384.891477 -89.717065) (xy 384.944261 -89.699058)
			(xy 384.999104 -89.688928) (xy 385.054838 -89.686891) (xy 385.110275 -89.692991) (xy 385.164232 -89.707097)
			(xy 385.215561 -89.728909) (xy 385.263167 -89.757963) (xy 385.306035 -89.793638) (xy 385.343252 -89.835175)
			(xy 385.374025 -89.881688) (xy 385.397697 -89.932185) (xy 385.413765 -89.985592) (xy 385.421885 -90.040768)
			(xy 385.422394 -90.068654) (xy 385.421885 -90.09654) (xy 385.413765 -90.151716) (xy 385.397697 -90.205123)
			(xy 385.374025 -90.25562) (xy 385.343252 -90.302133) (xy 385.306035 -90.34367) (xy 385.263167 -90.379345)
			(xy 385.215561 -90.408399) (xy 385.164232 -90.430211) (xy 385.110275 -90.444317) (xy 385.054838 -90.450417)
			(xy 384.999104 -90.44838) (xy 384.944261 -90.43825) (xy 384.891477 -90.420243) (xy 384.841877 -90.394742)
			(xy 384.796519 -90.362291) (xy 384.75637 -90.323582) (xy 384.722284 -90.279439) (xy 384.694988 -90.230804)
			(xy 384.675065 -90.178713) (xy 384.662939 -90.124276) (xy 384.658868 -90.068654) (xy 381.308449 -90.068654)
			(xy 381.292245 -90.10322) (xy 381.261472 -90.149733) (xy 381.224255 -90.19127) (xy 381.181387 -90.226945)
			(xy 381.133781 -90.255999) (xy 381.082452 -90.277811) (xy 381.028495 -90.291917) (xy 380.973058 -90.298017)
			(xy 380.917324 -90.29598) (xy 380.862481 -90.28585) (xy 380.809697 -90.267843) (xy 380.760097 -90.242342)
			(xy 380.714739 -90.209891) (xy 380.67459 -90.171182) (xy 380.640504 -90.127039) (xy 380.613208 -90.078404)
			(xy 380.593285 -90.026313) (xy 380.581159 -89.971876) (xy 380.577088 -89.916254) (xy 375.67511 -89.916254)
			(xy 375.678445 -89.938914) (xy 375.678954 -89.9668) (xy 375.678445 -89.994686) (xy 375.670325 -90.049862)
			(xy 375.654257 -90.103269) (xy 375.630585 -90.153766) (xy 375.599812 -90.200279) (xy 375.562595 -90.241816)
			(xy 375.519727 -90.277491) (xy 375.472121 -90.306545) (xy 375.420792 -90.328357) (xy 375.366835 -90.342463)
			(xy 375.311398 -90.348563) (xy 375.255664 -90.346526) (xy 375.200821 -90.336396) (xy 375.148037 -90.318389)
			(xy 375.098437 -90.292888) (xy 375.053079 -90.260437) (xy 375.01293 -90.221728) (xy 374.978844 -90.177585)
			(xy 374.951548 -90.12895) (xy 374.931625 -90.076859) (xy 374.919499 -90.022422) (xy 374.915428 -89.9668)
			(xy 366.396084 -89.9668) (xy 366.416531 -90.010417) (xy 366.432599 -90.063824) (xy 366.440719 -90.119)
			(xy 366.441228 -90.146886) (xy 366.440719 -90.174772) (xy 366.432599 -90.229948) (xy 366.416531 -90.283355)
			(xy 366.392859 -90.333852) (xy 366.362086 -90.380365) (xy 366.324869 -90.421902) (xy 366.282001 -90.457577)
			(xy 366.234395 -90.486631) (xy 366.183066 -90.508443) (xy 366.129109 -90.522549) (xy 366.073672 -90.528649)
			(xy 366.017938 -90.526612) (xy 365.963095 -90.516482) (xy 365.910311 -90.498475) (xy 365.860711 -90.472974)
			(xy 365.815353 -90.440523) (xy 365.775204 -90.401814) (xy 365.741118 -90.357671) (xy 365.713822 -90.309036)
			(xy 365.693899 -90.256945) (xy 365.681773 -90.202508) (xy 365.677702 -90.146886) (xy 363.967472 -90.146886)
			(xy 364.117748 -90.642694) (xy 367.679222 -90.642694) (xy 367.683293 -90.587072) (xy 367.695419 -90.532635)
			(xy 367.715342 -90.480544) (xy 367.742638 -90.431909) (xy 367.776724 -90.387766) (xy 367.816873 -90.349057)
			(xy 367.862231 -90.316606) (xy 367.911831 -90.291105) (xy 367.964615 -90.273098) (xy 368.019458 -90.262968)
			(xy 368.075192 -90.260931) (xy 368.130629 -90.267031) (xy 368.184586 -90.281137) (xy 368.235915 -90.302949)
			(xy 368.283521 -90.332003) (xy 368.326389 -90.367678) (xy 368.363606 -90.409215) (xy 368.394379 -90.455728)
			(xy 368.418051 -90.506225) (xy 368.434119 -90.559632) (xy 368.442239 -90.614808) (xy 368.442748 -90.642694)
			(xy 368.442239 -90.67058) (xy 368.434119 -90.725756) (xy 368.418051 -90.779163) (xy 368.394379 -90.82966)
			(xy 368.363606 -90.876173) (xy 368.326389 -90.91771) (xy 368.283521 -90.953385) (xy 368.235915 -90.982439)
			(xy 368.184586 -91.004251) (xy 368.130629 -91.018357) (xy 368.075192 -91.024457) (xy 368.019458 -91.02242)
			(xy 367.964615 -91.01229) (xy 367.911831 -90.994283) (xy 367.862231 -90.968782) (xy 367.816873 -90.936331)
			(xy 367.776724 -90.897622) (xy 367.742638 -90.853479) (xy 367.715342 -90.804844) (xy 367.695419 -90.752753)
			(xy 367.683293 -90.698316) (xy 367.679222 -90.642694) (xy 364.117748 -90.642694) (xy 364.24616 -91.066366)
			(xy 364.259339 -91.1098) (xy 374.915428 -91.1098) (xy 374.919499 -91.054178) (xy 374.931625 -90.999741)
			(xy 374.951548 -90.94765) (xy 374.978844 -90.899015) (xy 375.01293 -90.854872) (xy 375.053079 -90.816163)
			(xy 375.098437 -90.783712) (xy 375.148037 -90.758211) (xy 375.200821 -90.740204) (xy 375.255664 -90.730074)
			(xy 375.311398 -90.728037) (xy 375.366835 -90.734137) (xy 375.420792 -90.748243) (xy 375.472121 -90.770055)
			(xy 375.519727 -90.799109) (xy 375.562595 -90.834784) (xy 375.599812 -90.876321) (xy 375.630585 -90.922834)
			(xy 375.654257 -90.973331) (xy 375.670325 -91.026738) (xy 375.678445 -91.081914) (xy 375.678954 -91.1098)
			(xy 379.582932 -91.1098) (xy 379.587003 -91.054178) (xy 379.599129 -90.999741) (xy 379.619052 -90.94765)
			(xy 379.646348 -90.899015) (xy 379.680434 -90.854872) (xy 379.720583 -90.816163) (xy 379.765941 -90.783712)
			(xy 379.815541 -90.758211) (xy 379.868325 -90.740204) (xy 379.923168 -90.730074) (xy 379.978902 -90.728037)
			(xy 380.034339 -90.734137) (xy 380.088296 -90.748243) (xy 380.139625 -90.770055) (xy 380.187231 -90.799109)
			(xy 380.230099 -90.834784) (xy 380.267316 -90.876321) (xy 380.298089 -90.922834) (xy 380.321761 -90.973331)
			(xy 380.337829 -91.026738) (xy 380.345949 -91.081914) (xy 380.346458 -91.1098) (xy 380.345949 -91.137686)
			(xy 380.337829 -91.192862) (xy 380.321761 -91.246269) (xy 380.298089 -91.296766) (xy 380.267316 -91.343279)
			(xy 380.230099 -91.384816) (xy 380.187231 -91.420491) (xy 380.139625 -91.449545) (xy 380.088296 -91.471357)
			(xy 380.034339 -91.485463) (xy 379.978902 -91.491563) (xy 379.923168 -91.489526) (xy 379.868325 -91.479396)
			(xy 379.815541 -91.461389) (xy 379.765941 -91.435888) (xy 379.720583 -91.403437) (xy 379.680434 -91.364728)
			(xy 379.646348 -91.320585) (xy 379.619052 -91.27195) (xy 379.599129 -91.219859) (xy 379.587003 -91.165422)
			(xy 379.582932 -91.1098) (xy 375.678954 -91.1098) (xy 375.678445 -91.137686) (xy 375.670325 -91.192862)
			(xy 375.654257 -91.246269) (xy 375.630585 -91.296766) (xy 375.599812 -91.343279) (xy 375.562595 -91.384816)
			(xy 375.519727 -91.420491) (xy 375.472121 -91.449545) (xy 375.420792 -91.471357) (xy 375.366835 -91.485463)
			(xy 375.311398 -91.491563) (xy 375.255664 -91.489526) (xy 375.200821 -91.479396) (xy 375.148037 -91.461389)
			(xy 375.098437 -91.435888) (xy 375.053079 -91.403437) (xy 375.01293 -91.364728) (xy 374.978844 -91.320585)
			(xy 374.951548 -91.27195) (xy 374.931625 -91.219859) (xy 374.919499 -91.165422) (xy 374.915428 -91.1098)
			(xy 364.259339 -91.1098) (xy 364.42003 -91.63939) (xy 367.28349 -91.63939) (xy 367.287561 -91.583768)
			(xy 367.299687 -91.529331) (xy 367.31961 -91.47724) (xy 367.346906 -91.428605) (xy 367.380992 -91.384462)
			(xy 367.421141 -91.345753) (xy 367.466499 -91.313302) (xy 367.516099 -91.287801) (xy 367.568883 -91.269794)
			(xy 367.623726 -91.259664) (xy 367.67946 -91.257627) (xy 367.734897 -91.263727) (xy 367.788854 -91.277833)
			(xy 367.840183 -91.299645) (xy 367.887789 -91.328699) (xy 367.930657 -91.364374) (xy 367.967874 -91.405911)
			(xy 367.998647 -91.452424) (xy 368.022319 -91.502921) (xy 368.038387 -91.556328) (xy 368.046507 -91.611504)
			(xy 368.047016 -91.63939) (xy 368.046507 -91.667276) (xy 368.038387 -91.722452) (xy 368.022319 -91.775859)
			(xy 367.998647 -91.826356) (xy 367.967874 -91.872869) (xy 367.930657 -91.914406) (xy 367.887789 -91.950081)
			(xy 367.840183 -91.979135) (xy 367.788854 -92.000947) (xy 367.734897 -92.015053) (xy 367.67946 -92.021153)
			(xy 367.623726 -92.019116) (xy 367.568883 -92.008986) (xy 367.516099 -91.990979) (xy 367.466499 -91.965478)
			(xy 367.421141 -91.933027) (xy 367.380992 -91.894318) (xy 367.346906 -91.850175) (xy 367.31961 -91.80154)
			(xy 367.299687 -91.749449) (xy 367.287561 -91.695012) (xy 367.28349 -91.63939) (xy 364.42003 -91.63939)
			(xy 364.435136 -91.689174) (xy 364.437343 -91.695673) (xy 364.444677 -91.707267) (xy 364.449614 -91.712034)
			(xy 364.454186 -91.716098) (xy 364.465362 -91.722194) (xy 364.472474 -91.723718) (xy 364.50041 -91.730396)
			(xy 364.554022 -91.751008) (xy 364.603938 -91.779425) (xy 364.64903 -91.815003) (xy 364.688278 -91.856939)
			(xy 364.720797 -91.904285) (xy 364.74585 -91.95597) (xy 364.762871 -92.010828) (xy 364.771477 -92.067617)
			(xy 364.77194 -92.096336) (xy 364.77194 -92.106496) (xy 364.770778 -92.133827) (xy 364.761602 -92.187755)
			(xy 364.744827 -92.239822) (xy 364.720796 -92.288964) (xy 364.69 -92.334175) (xy 364.671864 -92.354654)
			(xy 364.665768 -92.361258) (xy 364.663581 -92.366592) (xy 366.150396 -92.366592) (xy 366.154467 -92.31097)
			(xy 366.166593 -92.256533) (xy 366.186516 -92.204442) (xy 366.213812 -92.155807) (xy 366.247898 -92.111664)
			(xy 366.288047 -92.072955) (xy 366.333405 -92.040504) (xy 366.383005 -92.015003) (xy 366.435789 -91.996996)
			(xy 366.490632 -91.986866) (xy 366.546366 -91.984829) (xy 366.601803 -91.990929) (xy 366.65576 -92.005035)
			(xy 366.707089 -92.026847) (xy 366.754695 -92.055901) (xy 366.797563 -92.091576) (xy 366.83478 -92.133113)
			(xy 366.865553 -92.179626) (xy 366.889225 -92.230123) (xy 366.905293 -92.28353) (xy 366.913413 -92.338706)
			(xy 366.913922 -92.366592) (xy 366.913413 -92.394478) (xy 366.905293 -92.449654) (xy 366.889225 -92.503061)
			(xy 366.865553 -92.553558) (xy 366.83478 -92.600071) (xy 366.797563 -92.641608) (xy 366.754695 -92.677283)
			(xy 366.707089 -92.706337) (xy 366.65576 -92.728149) (xy 366.601803 -92.742255) (xy 366.546366 -92.748355)
			(xy 366.490632 -92.746318) (xy 366.435789 -92.736188) (xy 366.383005 -92.718181) (xy 366.333405 -92.69268)
			(xy 366.288047 -92.660229) (xy 366.247898 -92.62152) (xy 366.213812 -92.577377) (xy 366.186516 -92.528742)
			(xy 366.166593 -92.476651) (xy 366.154467 -92.422214) (xy 366.150396 -92.366592) (xy 364.663581 -92.366592)
			(xy 364.65129 -92.396564) (xy 364.652306 -92.40647) (xy 364.823663 -92.97162) (xy 366.878106 -92.97162)
			(xy 366.882177 -92.915998) (xy 366.894303 -92.861561) (xy 366.914226 -92.80947) (xy 366.941522 -92.760835)
			(xy 366.975608 -92.716692) (xy 367.015757 -92.677983) (xy 367.061115 -92.645532) (xy 367.110715 -92.620031)
			(xy 367.163499 -92.602024) (xy 367.218342 -92.591894) (xy 367.274076 -92.589857) (xy 367.329513 -92.595957)
			(xy 367.38347 -92.610063) (xy 367.434799 -92.631875) (xy 367.482405 -92.660929) (xy 367.525273 -92.696604)
			(xy 367.56249 -92.738141) (xy 367.593263 -92.784654) (xy 367.616935 -92.835151) (xy 367.633003 -92.888558)
			(xy 367.641123 -92.943734) (xy 367.641632 -92.97162) (xy 367.641123 -92.999506) (xy 367.633003 -93.054682)
			(xy 367.616935 -93.108089) (xy 367.593263 -93.158586) (xy 367.56249 -93.205099) (xy 367.525273 -93.246636)
			(xy 367.482405 -93.282311) (xy 367.434799 -93.311365) (xy 367.38347 -93.333177) (xy 367.329513 -93.347283)
			(xy 367.274076 -93.353383) (xy 367.218342 -93.351346) (xy 367.163499 -93.341216) (xy 367.110715 -93.323209)
			(xy 367.061115 -93.297708) (xy 367.015757 -93.265257) (xy 366.975608 -93.226548) (xy 366.941522 -93.182405)
			(xy 366.914226 -93.13377) (xy 366.894303 -93.081679) (xy 366.882177 -93.027242) (xy 366.878106 -92.97162)
			(xy 364.823663 -92.97162) (xy 365.01512 -93.603064) (xy 375.71629 -93.603064) (xy 375.720361 -93.547442)
			(xy 375.732487 -93.493005) (xy 375.75241 -93.440914) (xy 375.779706 -93.392279) (xy 375.813792 -93.348136)
			(xy 375.853941 -93.309427) (xy 375.899299 -93.276976) (xy 375.948899 -93.251475) (xy 376.001683 -93.233468)
			(xy 376.056526 -93.223338) (xy 376.11226 -93.221301) (xy 376.167697 -93.227401) (xy 376.221654 -93.241507)
			(xy 376.272983 -93.263319) (xy 376.320589 -93.292373) (xy 376.363457 -93.328048) (xy 376.400674 -93.369585)
			(xy 376.431447 -93.416098) (xy 376.455119 -93.466595) (xy 376.471187 -93.520002) (xy 376.479307 -93.575178)
			(xy 376.479816 -93.603064) (xy 376.479538 -93.618304) (xy 377.288042 -93.618304) (xy 377.292113 -93.562682)
			(xy 377.304239 -93.508245) (xy 377.324162 -93.456154) (xy 377.351458 -93.407519) (xy 377.385544 -93.363376)
			(xy 377.425693 -93.324667) (xy 377.471051 -93.292216) (xy 377.520651 -93.266715) (xy 377.573435 -93.248708)
			(xy 377.628278 -93.238578) (xy 377.684012 -93.236541) (xy 377.739449 -93.242641) (xy 377.793406 -93.256747)
			(xy 377.844735 -93.278559) (xy 377.892341 -93.307613) (xy 377.935209 -93.343288) (xy 377.972426 -93.384825)
			(xy 378.003199 -93.431338) (xy 378.026871 -93.481835) (xy 378.042939 -93.535242) (xy 378.051059 -93.590418)
			(xy 378.051568 -93.618304) (xy 378.051059 -93.64619) (xy 378.042939 -93.701366) (xy 378.026871 -93.754773)
			(xy 378.003199 -93.80527) (xy 377.972426 -93.851783) (xy 377.935209 -93.89332) (xy 377.892341 -93.928995)
			(xy 377.844735 -93.958049) (xy 377.793406 -93.979861) (xy 377.739449 -93.993967) (xy 377.684012 -94.000067)
			(xy 377.628278 -93.99803) (xy 377.573435 -93.9879) (xy 377.520651 -93.969893) (xy 377.471051 -93.944392)
			(xy 377.425693 -93.911941) (xy 377.385544 -93.873232) (xy 377.351458 -93.829089) (xy 377.324162 -93.780454)
			(xy 377.304239 -93.728363) (xy 377.292113 -93.673926) (xy 377.288042 -93.618304) (xy 376.479538 -93.618304)
			(xy 376.479307 -93.63095) (xy 376.471187 -93.686126) (xy 376.455119 -93.739533) (xy 376.431447 -93.79003)
			(xy 376.400674 -93.836543) (xy 376.363457 -93.87808) (xy 376.320589 -93.913755) (xy 376.272983 -93.942809)
			(xy 376.221654 -93.964621) (xy 376.167697 -93.978727) (xy 376.11226 -93.984827) (xy 376.056526 -93.98279)
			(xy 376.001683 -93.97266) (xy 375.948899 -93.954653) (xy 375.899299 -93.929152) (xy 375.853941 -93.896701)
			(xy 375.813792 -93.857992) (xy 375.779706 -93.813849) (xy 375.75241 -93.765214) (xy 375.732487 -93.713123)
			(xy 375.720361 -93.658686) (xy 375.71629 -93.603064) (xy 365.01512 -93.603064) (xy 365.144812 -94.0308)
			(xy 365.148882 -94.039719) (xy 365.162468 -94.05383) (xy 365.171228 -94.058232) (xy 365.194596 -94.067376)
			(xy 365.198823 -94.06888) (xy 365.207638 -94.070541) (xy 365.212122 -94.070678) (xy 365.248444 -94.070678)
			(xy 365.260382 -94.06763) (xy 365.26597 -94.064582) (xy 365.293973 -94.050214) (xy 365.353521 -94.029842)
			(xy 365.415604 -94.019522) (xy 365.447072 -94.018862) (xy 365.474808 -94.019365) (xy 365.529695 -94.027406)
			(xy 365.582839 -94.043309) (xy 365.63312 -94.066739) (xy 365.67948 -94.097201) (xy 365.720942 -94.134054)
			(xy 365.756631 -94.176522) (xy 365.785795 -94.223709) (xy 365.807821 -94.274621) (xy 365.822244 -94.328185)
			(xy 365.82604 -94.355666) (xy 365.826689 -94.361508) (xy 366.046764 -94.361508) (xy 366.050835 -94.305886)
			(xy 366.062961 -94.251449) (xy 366.082884 -94.199358) (xy 366.11018 -94.150723) (xy 366.144266 -94.10658)
			(xy 366.184415 -94.067871) (xy 366.229773 -94.03542) (xy 366.279373 -94.009919) (xy 366.332157 -93.991912)
			(xy 366.387 -93.981782) (xy 366.442734 -93.979745) (xy 366.498171 -93.985845) (xy 366.552128 -93.999951)
			(xy 366.603457 -94.021763) (xy 366.651063 -94.050817) (xy 366.693931 -94.086492) (xy 366.731148 -94.128029)
			(xy 366.761921 -94.174542) (xy 366.785593 -94.225039) (xy 366.801661 -94.278446) (xy 366.809781 -94.333622)
			(xy 366.81029 -94.361508) (xy 366.809781 -94.389394) (xy 366.801661 -94.44457) (xy 366.785593 -94.497977)
			(xy 366.761921 -94.548474) (xy 366.731148 -94.594987) (xy 366.693931 -94.636524) (xy 366.659057 -94.665546)
			(xy 379.166626 -94.665546) (xy 379.170697 -94.609924) (xy 379.182823 -94.555487) (xy 379.202746 -94.503396)
			(xy 379.230042 -94.454761) (xy 379.264128 -94.410618) (xy 379.304277 -94.371909) (xy 379.349635 -94.339458)
			(xy 379.399235 -94.313957) (xy 379.452019 -94.29595) (xy 379.506862 -94.28582) (xy 379.562596 -94.283783)
			(xy 379.618033 -94.289883) (xy 379.67199 -94.303989) (xy 379.723319 -94.325801) (xy 379.770925 -94.354855)
			(xy 379.813793 -94.39053) (xy 379.85101 -94.432067) (xy 379.881783 -94.47858) (xy 379.905455 -94.529077)
			(xy 379.921523 -94.582484) (xy 379.929643 -94.63766) (xy 379.930152 -94.665546) (xy 379.929643 -94.693432)
			(xy 379.921523 -94.748608) (xy 379.905455 -94.802015) (xy 379.881783 -94.852512) (xy 379.85101 -94.899025)
			(xy 379.813793 -94.940562) (xy 379.770925 -94.976237) (xy 379.723319 -95.005291) (xy 379.67199 -95.027103)
			(xy 379.618033 -95.041209) (xy 379.562596 -95.047309) (xy 379.506862 -95.045272) (xy 379.452019 -95.035142)
			(xy 379.399235 -95.017135) (xy 379.349635 -94.991634) (xy 379.304277 -94.959183) (xy 379.264128 -94.920474)
			(xy 379.230042 -94.876331) (xy 379.202746 -94.827696) (xy 379.182823 -94.775605) (xy 379.170697 -94.721168)
			(xy 379.166626 -94.665546) (xy 366.659057 -94.665546) (xy 366.651063 -94.672199) (xy 366.603457 -94.701253)
			(xy 366.552128 -94.723065) (xy 366.498171 -94.737171) (xy 366.442734 -94.743271) (xy 366.387 -94.741234)
			(xy 366.332157 -94.731104) (xy 366.279373 -94.713097) (xy 366.229773 -94.687596) (xy 366.184415 -94.655145)
			(xy 366.144266 -94.616436) (xy 366.11018 -94.572293) (xy 366.082884 -94.523658) (xy 366.062961 -94.471567)
			(xy 366.050835 -94.41713) (xy 366.046764 -94.361508) (xy 365.826689 -94.361508) (xy 365.827564 -94.369382)
			(xy 365.829292 -94.396357) (xy 365.826041 -94.450311) (xy 365.815211 -94.503268) (xy 365.797019 -94.554167)
			(xy 365.771829 -94.60199) (xy 365.740144 -94.645782) (xy 365.702599 -94.684667) (xy 365.659944 -94.717866)
			(xy 365.613032 -94.744717) (xy 365.562801 -94.764681) (xy 365.510257 -94.77736) (xy 365.483394 -94.780354)
			(xy 365.472218 -94.78137) (xy 365.438436 -94.800928) (xy 365.431832 -94.80677) (xy 365.416846 -94.827598)
			(xy 365.416846 -94.828106) (xy 365.400336 -94.851474) (xy 365.396272 -94.85757) (xy 365.39551 -94.858586)
			(xy 365.793528 -96.17202) (xy 365.991902 -96.826324) (xy 365.993795 -96.831873) (xy 365.999697 -96.842001)
			(xy 366.003586 -96.84639) (xy 366.011714 -96.855026) (xy 366.018826 -96.857566) (xy 366.04194 -96.866456)
			(xy 366.042448 -96.866456) (xy 366.067906 -96.877851) (xy 366.115492 -96.90694) (xy 366.158337 -96.942646)
			(xy 366.19553 -96.984208) (xy 366.226277 -97.030741) (xy 366.249924 -97.081253) (xy 366.265967 -97.134669)
			(xy 366.274065 -97.189851) (xy 366.274604 -97.217738) (xy 366.274604 -97.22104) (xy 366.274096 -97.228406)
			(xy 366.272771 -97.257257) (xy 366.262503 -97.314091) (xy 366.243791 -97.36873) (xy 366.217061 -97.419927)
			(xy 366.200436 -97.443544) (xy 366.200436 -97.443798) (xy 366.194138 -97.453344) (xy 366.1898 -97.475765)
			(xy 366.192054 -97.486978) (xy 366.808503 -99.520357) (xy 370.426625 -99.520357) (xy 370.426625 -99.465843)
			(xy 370.434384 -99.411884) (xy 370.449743 -99.359579) (xy 370.47239 -99.309992) (xy 370.501865 -99.264133)
			(xy 370.537566 -99.222936) (xy 370.578767 -99.18724) (xy 370.624629 -99.15777) (xy 370.674218 -99.135128)
			(xy 370.726525 -99.119775) (xy 370.780485 -99.112022) (xy 370.807742 -99.111562) (xy 370.834964 -99.112001)
			(xy 370.888857 -99.119729) (xy 370.941105 -99.135037) (xy 370.990648 -99.157614) (xy 371.036479 -99.187003)
			(xy 371.077669 -99.222605) (xy 371.113382 -99.2637) (xy 371.128544 -99.286314) (xy 371.137173 -99.298701)
			(xy 371.16016 -99.318238) (xy 371.187857 -99.330197) (xy 371.21784 -99.333532) (xy 371.247488 -99.327951)
			(xy 371.274206 -99.313941) (xy 371.295659 -99.292729) (xy 371.303296 -99.27971) (xy 371.317739 -99.254195)
			(xy 371.353158 -99.207477) (xy 371.39531 -99.16673) (xy 371.443202 -99.132915) (xy 371.495705 -99.106828)
			(xy 371.551582 -99.089084) (xy 371.609517 -99.0801) (xy 371.63883 -99.079558) (xy 371.666077 -99.080114)
			(xy 371.720017 -99.087874) (xy 371.772303 -99.10323) (xy 371.821872 -99.125871) (xy 371.867715 -99.155335)
			(xy 371.908898 -99.191023) (xy 371.944583 -99.232209) (xy 371.974044 -99.278054) (xy 371.996681 -99.327625)
			(xy 372.012033 -99.379912) (xy 372.019788 -99.433853) (xy 372.019788 -99.488347) (xy 372.012033 -99.542288)
			(xy 371.996681 -99.594575) (xy 371.974044 -99.644146) (xy 371.944583 -99.689991) (xy 371.908898 -99.731177)
			(xy 371.867715 -99.766865) (xy 371.821872 -99.796329) (xy 371.772303 -99.81897) (xy 371.720017 -99.834326)
			(xy 371.666077 -99.842086) (xy 371.63883 -99.842574) (xy 371.61161 -99.842064) (xy 371.557721 -99.834346)
			(xy 371.505476 -99.819049) (xy 371.455934 -99.796483) (xy 371.410102 -99.767107) (xy 371.368909 -99.731515)
			(xy 371.333192 -99.690431) (xy 371.318028 -99.667822) (xy 371.30944 -99.655403) (xy 371.286446 -99.635857)
			(xy 371.258739 -99.623894) (xy 371.228744 -99.620561) (xy 371.199087 -99.62615) (xy 371.172363 -99.640172)
			(xy 371.150911 -99.661399) (xy 371.143276 -99.674426) (xy 371.128868 -99.699962) (xy 371.093441 -99.746678)
			(xy 371.051282 -99.787422) (xy 371.003385 -99.821235) (xy 370.950877 -99.847318) (xy 370.894995 -99.865058)
			(xy 370.837057 -99.874038) (xy 370.807742 -99.874578) (xy 370.780485 -99.874178) (xy 370.726525 -99.866425)
			(xy 370.674218 -99.851072) (xy 370.624629 -99.82843) (xy 370.578767 -99.79896) (xy 370.537566 -99.763264)
			(xy 370.501865 -99.722067) (xy 370.47239 -99.676208) (xy 370.449743 -99.626621) (xy 370.434384 -99.574316)
			(xy 370.426625 -99.520357) (xy 366.808503 -99.520357) (xy 367.213896 -100.857558) (xy 367.555421 -101.984302)
			(xy 383.577592 -101.984302) (xy 383.577592 -101.120702) (xy 383.578082 -101.090734) (xy 383.585905 -101.031312)
			(xy 383.601418 -100.973419) (xy 383.624354 -100.918046) (xy 383.654321 -100.86614) (xy 383.690808 -100.81859)
			(xy 383.733188 -100.77621) (xy 383.780738 -100.739723) (xy 383.832644 -100.709756) (xy 383.888017 -100.68682)
			(xy 383.94591 -100.671307) (xy 384.005332 -100.663484) (xy 384.065268 -100.663484) (xy 384.12469 -100.671307)
			(xy 384.182583 -100.68682) (xy 384.237956 -100.709756) (xy 384.289862 -100.739723) (xy 384.337412 -100.77621)
			(xy 384.379792 -100.81859) (xy 384.416279 -100.86614) (xy 384.446246 -100.918046) (xy 384.469182 -100.973419)
			(xy 384.484695 -101.031312) (xy 384.492518 -101.090734) (xy 384.493008 -101.120702) (xy 384.493008 -101.984302)
			(xy 384.492518 -102.01427) (xy 384.484695 -102.073692) (xy 384.469182 -102.131585) (xy 384.446246 -102.186958)
			(xy 384.416279 -102.238864) (xy 384.379792 -102.286414) (xy 384.337412 -102.328794) (xy 384.289862 -102.365281)
			(xy 384.237956 -102.395248) (xy 384.182583 -102.418184) (xy 384.12469 -102.433697) (xy 384.065268 -102.44152)
			(xy 384.005332 -102.44152) (xy 383.94591 -102.433697) (xy 383.888017 -102.418184) (xy 383.832644 -102.395248)
			(xy 383.780738 -102.365281) (xy 383.733188 -102.328794) (xy 383.690808 -102.286414) (xy 383.654321 -102.238864)
			(xy 383.624354 -102.186958) (xy 383.601418 -102.131585) (xy 383.585905 -102.073692) (xy 383.578082 -102.01427)
			(xy 383.577592 -101.984302) (xy 367.555421 -101.984302) (xy 367.918658 -103.182674) (xy 370.004338 -103.182674)
			(xy 370.008409 -103.127052) (xy 370.020535 -103.072615) (xy 370.040458 -103.020524) (xy 370.067754 -102.971889)
			(xy 370.10184 -102.927746) (xy 370.141989 -102.889037) (xy 370.187347 -102.856586) (xy 370.236947 -102.831085)
			(xy 370.289731 -102.813078) (xy 370.344574 -102.802948) (xy 370.400308 -102.800911) (xy 370.455745 -102.807011)
			(xy 370.509702 -102.821117) (xy 370.561031 -102.842929) (xy 370.608637 -102.871983) (xy 370.651505 -102.907658)
			(xy 370.688722 -102.949195) (xy 370.719495 -102.995708) (xy 370.743167 -103.046205) (xy 370.759235 -103.099612)
			(xy 370.767355 -103.154788) (xy 370.767864 -103.182674) (xy 370.767355 -103.21056) (xy 370.759235 -103.265736)
			(xy 370.743167 -103.319143) (xy 370.719495 -103.36964) (xy 370.688722 -103.416153) (xy 370.651505 -103.45769)
			(xy 370.608637 -103.493365) (xy 370.561031 -103.522419) (xy 370.509702 -103.544231) (xy 370.455745 -103.558337)
			(xy 370.400308 -103.564437) (xy 370.344574 -103.5624) (xy 370.289731 -103.55227) (xy 370.236947 -103.534263)
			(xy 370.187347 -103.508762) (xy 370.141989 -103.476311) (xy 370.10184 -103.437602) (xy 370.067754 -103.393459)
			(xy 370.040458 -103.344824) (xy 370.020535 -103.292733) (xy 370.008409 -103.238296) (xy 370.004338 -103.182674)
			(xy 367.918658 -103.182674) (xy 368.12114 -103.850694) (xy 372.568468 -103.850694) (xy 372.572539 -103.795072)
			(xy 372.584665 -103.740635) (xy 372.604588 -103.688544) (xy 372.631884 -103.639909) (xy 372.66597 -103.595766)
			(xy 372.706119 -103.557057) (xy 372.751477 -103.524606) (xy 372.801077 -103.499105) (xy 372.853861 -103.481098)
			(xy 372.908704 -103.470968) (xy 372.964438 -103.468931) (xy 373.019875 -103.475031) (xy 373.073832 -103.489137)
			(xy 373.125161 -103.510949) (xy 373.172767 -103.540003) (xy 373.215635 -103.575678) (xy 373.252852 -103.617215)
			(xy 373.283625 -103.663728) (xy 373.307297 -103.714225) (xy 373.323365 -103.767632) (xy 373.331485 -103.822808)
			(xy 373.331994 -103.850694) (xy 373.331485 -103.87858) (xy 373.323365 -103.933756) (xy 373.307297 -103.987163)
			(xy 373.283625 -104.03766) (xy 373.252852 -104.084173) (xy 373.215635 -104.12571) (xy 373.172767 -104.161385)
			(xy 373.125161 -104.190439) (xy 373.073832 -104.212251) (xy 373.019875 -104.226357) (xy 372.964438 -104.232457)
			(xy 372.908704 -104.23042) (xy 372.853861 -104.22029) (xy 372.801077 -104.202283) (xy 372.751477 -104.176782)
			(xy 372.706119 -104.144331) (xy 372.66597 -104.105622) (xy 372.631884 -104.061479) (xy 372.604588 -104.012844)
			(xy 372.584665 -103.960753) (xy 372.572539 -103.906316) (xy 372.568468 -103.850694) (xy 368.12114 -103.850694)
			(xy 368.399919 -104.770428) (xy 374.327926 -104.770428) (xy 374.331997 -104.714806) (xy 374.344123 -104.660369)
			(xy 374.364046 -104.608278) (xy 374.391342 -104.559643) (xy 374.425428 -104.5155) (xy 374.465577 -104.476791)
			(xy 374.510935 -104.44434) (xy 374.560535 -104.418839) (xy 374.613319 -104.400832) (xy 374.668162 -104.390702)
			(xy 374.723896 -104.388665) (xy 374.779333 -104.394765) (xy 374.83329 -104.408871) (xy 374.884619 -104.430683)
			(xy 374.932225 -104.459737) (xy 374.975093 -104.495412) (xy 375.01231 -104.536949) (xy 375.043083 -104.583462)
			(xy 375.066755 -104.633959) (xy 375.082823 -104.687366) (xy 375.090943 -104.742542) (xy 375.091452 -104.770428)
			(xy 375.090943 -104.798314) (xy 375.082823 -104.85349) (xy 375.066755 -104.906897) (xy 375.043083 -104.957394)
			(xy 375.01231 -105.003907) (xy 374.975093 -105.045444) (xy 374.932225 -105.081119) (xy 374.884619 -105.110173)
			(xy 374.83329 -105.131985) (xy 374.779333 -105.146091) (xy 374.723896 -105.152191) (xy 374.668162 -105.150154)
			(xy 374.613319 -105.140024) (xy 374.560535 -105.122017) (xy 374.510935 -105.096516) (xy 374.465577 -105.064065)
			(xy 374.425428 -105.025356) (xy 374.391342 -104.981213) (xy 374.364046 -104.932578) (xy 374.344123 -104.880487)
			(xy 374.331997 -104.82605) (xy 374.327926 -104.770428) (xy 368.399919 -104.770428) (xy 368.731974 -105.86593)
			(xy 372.880634 -105.86593) (xy 372.884705 -105.810308) (xy 372.896831 -105.755871) (xy 372.916754 -105.70378)
			(xy 372.94405 -105.655145) (xy 372.978136 -105.611002) (xy 373.018285 -105.572293) (xy 373.063643 -105.539842)
			(xy 373.113243 -105.514341) (xy 373.166027 -105.496334) (xy 373.22087 -105.486204) (xy 373.276604 -105.484167)
			(xy 373.332041 -105.490267) (xy 373.385998 -105.504373) (xy 373.437327 -105.526185) (xy 373.484933 -105.555239)
			(xy 373.520091 -105.584498) (xy 382.967992 -105.584498) (xy 382.967992 -104.720898) (xy 382.968482 -104.69093)
			(xy 382.976305 -104.631508) (xy 382.991818 -104.573615) (xy 383.014754 -104.518242) (xy 383.044721 -104.466336)
			(xy 383.081208 -104.418786) (xy 383.123588 -104.376406) (xy 383.171138 -104.339919) (xy 383.223044 -104.309952)
			(xy 383.278417 -104.287016) (xy 383.33631 -104.271503) (xy 383.395732 -104.26368) (xy 383.455668 -104.26368)
			(xy 383.51509 -104.271503) (xy 383.572983 -104.287016) (xy 383.628356 -104.309952) (xy 383.680262 -104.339919)
			(xy 383.727812 -104.376406) (xy 383.770192 -104.418786) (xy 383.806679 -104.466336) (xy 383.836646 -104.518242)
			(xy 383.859582 -104.573615) (xy 383.875095 -104.631508) (xy 383.882918 -104.69093) (xy 383.883408 -104.720898)
			(xy 383.883408 -105.584498) (xy 383.882918 -105.614466) (xy 383.875095 -105.673888) (xy 383.859582 -105.731781)
			(xy 383.836646 -105.787154) (xy 383.806679 -105.83906) (xy 383.770192 -105.88661) (xy 383.727812 -105.92899)
			(xy 383.680262 -105.965477) (xy 383.628356 -105.995444) (xy 383.572983 -106.01838) (xy 383.51509 -106.033893)
			(xy 383.455668 -106.041716) (xy 383.395732 -106.041716) (xy 383.33631 -106.033893) (xy 383.278417 -106.01838)
			(xy 383.223044 -105.995444) (xy 383.171138 -105.965477) (xy 383.123588 -105.92899) (xy 383.081208 -105.88661)
			(xy 383.044721 -105.83906) (xy 383.014754 -105.787154) (xy 382.991818 -105.731781) (xy 382.976305 -105.673888)
			(xy 382.968482 -105.614466) (xy 382.967992 -105.584498) (xy 373.520091 -105.584498) (xy 373.527801 -105.590914)
			(xy 373.565018 -105.632451) (xy 373.595791 -105.678964) (xy 373.619463 -105.729461) (xy 373.635531 -105.782868)
			(xy 373.643651 -105.838044) (xy 373.64416 -105.86593) (xy 373.643651 -105.893816) (xy 373.635531 -105.948992)
			(xy 373.619463 -106.002399) (xy 373.595791 -106.052896) (xy 373.565018 -106.099409) (xy 373.527801 -106.140946)
			(xy 373.484933 -106.176621) (xy 373.437327 -106.205675) (xy 373.385998 -106.227487) (xy 373.332041 -106.241593)
			(xy 373.276604 -106.247693) (xy 373.22087 -106.245656) (xy 373.166027 -106.235526) (xy 373.113243 -106.217519)
			(xy 373.063643 -106.192018) (xy 373.018285 -106.159567) (xy 372.978136 -106.120858) (xy 372.94405 -106.076715)
			(xy 372.916754 -106.02808) (xy 372.896831 -105.975989) (xy 372.884705 -105.921552) (xy 372.880634 -105.86593)
			(xy 368.731974 -105.86593) (xy 369.261354 -107.612434) (xy 372.040656 -107.612434) (xy 372.044727 -107.556812)
			(xy 372.056853 -107.502375) (xy 372.076776 -107.450284) (xy 372.104072 -107.401649) (xy 372.138158 -107.357506)
			(xy 372.178307 -107.318797) (xy 372.223665 -107.286346) (xy 372.273265 -107.260845) (xy 372.326049 -107.242838)
			(xy 372.380892 -107.232708) (xy 372.436626 -107.230671) (xy 372.492063 -107.236771) (xy 372.54602 -107.250877)
			(xy 372.597349 -107.272689) (xy 372.644955 -107.301743) (xy 372.687823 -107.337418) (xy 372.72395 -107.377738)
			(xy 385.6101 -107.377738) (xy 385.6101 -106.514138) (xy 385.61059 -106.48417) (xy 385.618413 -106.424748)
			(xy 385.633926 -106.366855) (xy 385.656862 -106.311482) (xy 385.686829 -106.259576) (xy 385.723316 -106.212026)
			(xy 385.765696 -106.169646) (xy 385.813246 -106.133159) (xy 385.865152 -106.103192) (xy 385.920525 -106.080256)
			(xy 385.978418 -106.064743) (xy 386.03784 -106.05692) (xy 386.097776 -106.05692) (xy 386.157198 -106.064743)
			(xy 386.215091 -106.080256) (xy 386.270464 -106.103192) (xy 386.32237 -106.133159) (xy 386.36992 -106.169646)
			(xy 386.4123 -106.212026) (xy 386.448787 -106.259576) (xy 386.478754 -106.311482) (xy 386.50169 -106.366855)
			(xy 386.517203 -106.424748) (xy 386.525026 -106.48417) (xy 386.525516 -106.514138) (xy 386.525516 -107.377738)
			(xy 386.525026 -107.407706) (xy 386.517203 -107.467128) (xy 386.50169 -107.525021) (xy 386.478754 -107.580394)
			(xy 386.448787 -107.6323) (xy 386.4123 -107.67985) (xy 386.36992 -107.72223) (xy 386.32237 -107.758717)
			(xy 386.270464 -107.788684) (xy 386.215091 -107.81162) (xy 386.157198 -107.827133) (xy 386.097776 -107.834956)
			(xy 386.03784 -107.834956) (xy 385.978418 -107.827133) (xy 385.920525 -107.81162) (xy 385.865152 -107.788684)
			(xy 385.813246 -107.758717) (xy 385.765696 -107.72223) (xy 385.723316 -107.67985) (xy 385.686829 -107.6323)
			(xy 385.656862 -107.580394) (xy 385.633926 -107.525021) (xy 385.618413 -107.467128) (xy 385.61059 -107.407706)
			(xy 385.6101 -107.377738) (xy 372.72395 -107.377738) (xy 372.72504 -107.378955) (xy 372.755813 -107.425468)
			(xy 372.779485 -107.475965) (xy 372.795553 -107.529372) (xy 372.803673 -107.584548) (xy 372.804182 -107.612434)
			(xy 372.803673 -107.64032) (xy 372.795553 -107.695496) (xy 372.779485 -107.748903) (xy 372.755813 -107.7994)
			(xy 372.72504 -107.845913) (xy 372.687823 -107.88745) (xy 372.644955 -107.923125) (xy 372.597349 -107.952179)
			(xy 372.54602 -107.973991) (xy 372.492063 -107.988097) (xy 372.436626 -107.994197) (xy 372.380892 -107.99216)
			(xy 372.326049 -107.98203) (xy 372.273265 -107.964023) (xy 372.223665 -107.938522) (xy 372.178307 -107.906071)
			(xy 372.138158 -107.867362) (xy 372.104072 -107.823219) (xy 372.076776 -107.774584) (xy 372.056853 -107.722493)
			(xy 372.044727 -107.668056) (xy 372.040656 -107.612434) (xy 369.261354 -107.612434) (xy 369.490244 -108.367576)
			(xy 369.640533 -108.859828) (xy 372.147844 -108.859828) (xy 372.151915 -108.804206) (xy 372.164041 -108.749769)
			(xy 372.183964 -108.697678) (xy 372.21126 -108.649043) (xy 372.245346 -108.6049) (xy 372.285495 -108.566191)
			(xy 372.330853 -108.53374) (xy 372.380453 -108.508239) (xy 372.433237 -108.490232) (xy 372.48808 -108.480102)
			(xy 372.543814 -108.478065) (xy 372.599251 -108.484165) (xy 372.653208 -108.498271) (xy 372.704537 -108.520083)
			(xy 372.752143 -108.549137) (xy 372.795011 -108.584812) (xy 372.832228 -108.626349) (xy 372.863001 -108.672862)
			(xy 372.886673 -108.723359) (xy 372.902741 -108.776766) (xy 372.910861 -108.831942) (xy 372.91137 -108.859828)
			(xy 372.910861 -108.887714) (xy 372.902741 -108.94289) (xy 372.886673 -108.996297) (xy 372.863001 -109.046794)
			(xy 372.832228 -109.093307) (xy 372.795011 -109.134844) (xy 372.752143 -109.170519) (xy 372.729333 -109.18444)
			(xy 382.967992 -109.18444) (xy 382.967992 -108.32084) (xy 382.968482 -108.290872) (xy 382.976305 -108.23145)
			(xy 382.991818 -108.173557) (xy 383.014754 -108.118184) (xy 383.044721 -108.066278) (xy 383.081208 -108.018728)
			(xy 383.123588 -107.976348) (xy 383.171138 -107.939861) (xy 383.223044 -107.909894) (xy 383.278417 -107.886958)
			(xy 383.33631 -107.871445) (xy 383.395732 -107.863622) (xy 383.455668 -107.863622) (xy 383.51509 -107.871445)
			(xy 383.572983 -107.886958) (xy 383.628356 -107.909894) (xy 383.680262 -107.939861) (xy 383.727812 -107.976348)
			(xy 383.770192 -108.018728) (xy 383.806679 -108.066278) (xy 383.836646 -108.118184) (xy 383.859582 -108.173557)
			(xy 383.875095 -108.23145) (xy 383.882918 -108.290872) (xy 383.883408 -108.32084) (xy 383.883408 -109.18444)
			(xy 383.882918 -109.214408) (xy 383.875095 -109.27383) (xy 383.859582 -109.331723) (xy 383.836646 -109.387096)
			(xy 383.806679 -109.439002) (xy 383.770192 -109.486552) (xy 383.727812 -109.528932) (xy 383.680262 -109.565419)
			(xy 383.628356 -109.595386) (xy 383.572983 -109.618322) (xy 383.51509 -109.633835) (xy 383.455668 -109.641658)
			(xy 383.395732 -109.641658) (xy 383.33631 -109.633835) (xy 383.278417 -109.618322) (xy 383.223044 -109.595386)
			(xy 383.171138 -109.565419) (xy 383.123588 -109.528932) (xy 383.081208 -109.486552) (xy 383.044721 -109.439002)
			(xy 383.014754 -109.387096) (xy 382.991818 -109.331723) (xy 382.976305 -109.27383) (xy 382.968482 -109.214408)
			(xy 382.967992 -109.18444) (xy 372.729333 -109.18444) (xy 372.704537 -109.199573) (xy 372.653208 -109.221385)
			(xy 372.599251 -109.235491) (xy 372.543814 -109.241591) (xy 372.48808 -109.239554) (xy 372.433237 -109.229424)
			(xy 372.380453 -109.211417) (xy 372.330853 -109.185916) (xy 372.285495 -109.153465) (xy 372.245346 -109.114756)
			(xy 372.21126 -109.070613) (xy 372.183964 -109.021978) (xy 372.164041 -108.969887) (xy 372.151915 -108.91545)
			(xy 372.147844 -108.859828) (xy 369.640533 -108.859828) (xy 369.991982 -110.010956) (xy 371.610126 -110.010956)
			(xy 371.614197 -109.955334) (xy 371.626323 -109.900897) (xy 371.646246 -109.848806) (xy 371.673542 -109.800171)
			(xy 371.707628 -109.756028) (xy 371.747777 -109.717319) (xy 371.793135 -109.684868) (xy 371.842735 -109.659367)
			(xy 371.895519 -109.64136) (xy 371.950362 -109.63123) (xy 372.006096 -109.629193) (xy 372.061533 -109.635293)
			(xy 372.11549 -109.649399) (xy 372.166819 -109.671211) (xy 372.214425 -109.700265) (xy 372.257293 -109.73594)
			(xy 372.29451 -109.777477) (xy 372.325283 -109.82399) (xy 372.348955 -109.874487) (xy 372.365023 -109.927894)
			(xy 372.373143 -109.98307) (xy 372.373652 -110.010956) (xy 372.373647 -110.01121) (xy 373.347232 -110.01121)
			(xy 373.351303 -109.955588) (xy 373.363429 -109.901151) (xy 373.383352 -109.84906) (xy 373.410648 -109.800425)
			(xy 373.444734 -109.756282) (xy 373.484883 -109.717573) (xy 373.530241 -109.685122) (xy 373.579841 -109.659621)
			(xy 373.632625 -109.641614) (xy 373.687468 -109.631484) (xy 373.743202 -109.629447) (xy 373.798639 -109.635547)
			(xy 373.852596 -109.649653) (xy 373.903925 -109.671465) (xy 373.951531 -109.700519) (xy 373.994399 -109.736194)
			(xy 374.031616 -109.777731) (xy 374.062389 -109.824244) (xy 374.086061 -109.874741) (xy 374.102129 -109.928148)
			(xy 374.110249 -109.983324) (xy 374.110758 -110.01121) (xy 374.110249 -110.039096) (xy 374.102129 -110.094272)
			(xy 374.086061 -110.147679) (xy 374.062389 -110.198176) (xy 374.031616 -110.244689) (xy 373.994399 -110.286226)
			(xy 373.951531 -110.321901) (xy 373.903925 -110.350955) (xy 373.852596 -110.372767) (xy 373.798639 -110.386873)
			(xy 373.743202 -110.392973) (xy 373.687468 -110.390936) (xy 373.632625 -110.380806) (xy 373.579841 -110.362799)
			(xy 373.530241 -110.337298) (xy 373.484883 -110.304847) (xy 373.444734 -110.266138) (xy 373.410648 -110.221995)
			(xy 373.383352 -110.17336) (xy 373.363429 -110.121269) (xy 373.351303 -110.066832) (xy 373.347232 -110.01121)
			(xy 372.373647 -110.01121) (xy 372.373143 -110.038842) (xy 372.365023 -110.094018) (xy 372.348955 -110.147425)
			(xy 372.325283 -110.197922) (xy 372.29451 -110.244435) (xy 372.257293 -110.285972) (xy 372.214425 -110.321647)
			(xy 372.166819 -110.350701) (xy 372.11549 -110.372513) (xy 372.061533 -110.386619) (xy 372.006096 -110.392719)
			(xy 371.950362 -110.390682) (xy 371.895519 -110.380552) (xy 371.842735 -110.362545) (xy 371.793135 -110.337044)
			(xy 371.747777 -110.304593) (xy 371.707628 -110.265884) (xy 371.673542 -110.221741) (xy 371.646246 -110.173106)
			(xy 371.626323 -110.121015) (xy 371.614197 -110.066578) (xy 371.610126 -110.010956) (xy 369.991982 -110.010956)
			(xy 370.287208 -110.977934) (xy 385.6101 -110.977934) (xy 385.6101 -110.114334) (xy 385.61059 -110.084366)
			(xy 385.618413 -110.024944) (xy 385.633926 -109.967051) (xy 385.656862 -109.911678) (xy 385.686829 -109.859772)
			(xy 385.723316 -109.812222) (xy 385.765696 -109.769842) (xy 385.813246 -109.733355) (xy 385.865152 -109.703388)
			(xy 385.920525 -109.680452) (xy 385.978418 -109.664939) (xy 386.03784 -109.657116) (xy 386.097776 -109.657116)
			(xy 386.157198 -109.664939) (xy 386.215091 -109.680452) (xy 386.270464 -109.703388) (xy 386.32237 -109.733355)
			(xy 386.36992 -109.769842) (xy 386.4123 -109.812222) (xy 386.448787 -109.859772) (xy 386.478754 -109.911678)
			(xy 386.50169 -109.967051) (xy 386.517203 -110.024944) (xy 386.525026 -110.084366) (xy 386.525516 -110.114334)
			(xy 386.525516 -110.977934) (xy 386.525026 -111.007902) (xy 386.517203 -111.067324) (xy 386.50169 -111.125217)
			(xy 386.478754 -111.18059) (xy 386.448787 -111.232496) (xy 386.4123 -111.280046) (xy 386.36992 -111.322426)
			(xy 386.32237 -111.358913) (xy 386.270464 -111.38888) (xy 386.215091 -111.411816) (xy 386.157198 -111.427329)
			(xy 386.097776 -111.435152) (xy 386.03784 -111.435152) (xy 385.978418 -111.427329) (xy 385.920525 -111.411816)
			(xy 385.865152 -111.38888) (xy 385.813246 -111.358913) (xy 385.765696 -111.322426) (xy 385.723316 -111.280046)
			(xy 385.686829 -111.232496) (xy 385.656862 -111.18059) (xy 385.633926 -111.125217) (xy 385.618413 -111.067324)
			(xy 385.61059 -111.007902) (xy 385.6101 -110.977934) (xy 370.287208 -110.977934) (xy 370.838732 -112.784382)
			(xy 382.967992 -112.784382) (xy 382.967992 -111.920782) (xy 382.968482 -111.890814) (xy 382.976305 -111.831392)
			(xy 382.991818 -111.773499) (xy 383.014754 -111.718126) (xy 383.044721 -111.66622) (xy 383.081208 -111.61867)
			(xy 383.123588 -111.57629) (xy 383.171138 -111.539803) (xy 383.223044 -111.509836) (xy 383.278417 -111.4869)
			(xy 383.33631 -111.471387) (xy 383.395732 -111.463564) (xy 383.455668 -111.463564) (xy 383.51509 -111.471387)
			(xy 383.572983 -111.4869) (xy 383.628356 -111.509836) (xy 383.680262 -111.539803) (xy 383.727812 -111.57629)
			(xy 383.770192 -111.61867) (xy 383.806679 -111.66622) (xy 383.836646 -111.718126) (xy 383.859582 -111.773499)
			(xy 383.875095 -111.831392) (xy 383.882918 -111.890814) (xy 383.883408 -111.920782) (xy 383.883408 -112.784382)
			(xy 383.882918 -112.81435) (xy 383.875095 -112.873772) (xy 383.859582 -112.931665) (xy 383.836646 -112.987038)
			(xy 383.806679 -113.038944) (xy 383.770192 -113.086494) (xy 383.727812 -113.128874) (xy 383.680262 -113.165361)
			(xy 383.628356 -113.195328) (xy 383.572983 -113.218264) (xy 383.51509 -113.233777) (xy 383.455668 -113.2416)
			(xy 383.395732 -113.2416) (xy 383.33631 -113.233777) (xy 383.278417 -113.218264) (xy 383.223044 -113.195328)
			(xy 383.171138 -113.165361) (xy 383.123588 -113.128874) (xy 383.081208 -113.086494) (xy 383.044721 -113.038944)
			(xy 383.014754 -112.987038) (xy 382.991818 -112.931665) (xy 382.976305 -112.873772) (xy 382.968482 -112.81435)
			(xy 382.967992 -112.784382) (xy 370.838732 -112.784382) (xy 371.98531 -116.539855) (xy 384.844449 -116.539855)
			(xy 384.844449 -116.485345) (xy 384.852208 -116.431389) (xy 384.867566 -116.379087) (xy 384.890212 -116.329503)
			(xy 384.919685 -116.283647) (xy 384.955384 -116.242453) (xy 384.996582 -116.206758) (xy 385.042442 -116.177291)
			(xy 385.092028 -116.154651) (xy 385.144332 -116.139298) (xy 385.198289 -116.131546) (xy 385.225544 -116.131086)
			(xy 385.251859 -116.131529) (xy 385.303988 -116.138769) (xy 385.354631 -116.153093) (xy 385.40283 -116.174231)
			(xy 385.447673 -116.201781) (xy 385.488312 -116.235223) (xy 385.506468 -116.254276) (xy 385.514003 -116.261662)
			(xy 385.533273 -116.270196) (xy 385.543806 -116.270786) (xy 385.618482 -116.270786) (xy 385.629033 -116.270265)
			(xy 385.648328 -116.261724) (xy 385.65582 -116.254276) (xy 385.672828 -116.236404) (xy 385.71066 -116.204739)
			(xy 385.752264 -116.178223) (xy 385.774438 -116.167408) (xy 385.784598 -116.162582) (xy 385.798822 -116.145818)
			(xy 385.825238 -116.049044) (xy 385.821682 -116.027708) (xy 385.815332 -116.018564) (xy 385.815332 -116.01831)
			(xy 385.799759 -115.994468) (xy 385.775105 -115.943136) (xy 385.758343 -115.888714) (xy 385.749842 -115.832406)
			(xy 385.749292 -115.803934) (xy 385.749829 -115.775041) (xy 385.758512 -115.717911) (xy 385.775713 -115.662745)
			(xy 385.80104 -115.610806) (xy 385.833913 -115.563281) (xy 385.873578 -115.52126) (xy 385.91913 -115.485704)
			(xy 385.969523 -115.457426) (xy 386.023606 -115.437074) (xy 386.080141 -115.425114) (xy 386.108956 -115.422934)
			(xy 386.119878 -115.422426) (xy 386.139182 -115.412266) (xy 386.199888 -115.335304) (xy 386.205222 -115.314222)
			(xy 386.20319 -115.303554) (xy 386.200347 -115.286807) (xy 386.197292 -115.252975) (xy 386.197094 -115.23599)
			(xy 386.197094 -115.235228) (xy 386.19758 -115.207977) (xy 386.205336 -115.154029) (xy 386.220691 -115.101734)
			(xy 386.243333 -115.052157) (xy 386.272799 -115.006307) (xy 386.30849 -114.965116) (xy 386.349681 -114.929425)
			(xy 386.395531 -114.899959) (xy 386.445108 -114.877317) (xy 386.497403 -114.861962) (xy 386.551351 -114.854206)
			(xy 386.605853 -114.854206) (xy 386.659801 -114.861962) (xy 386.712096 -114.877317) (xy 386.761673 -114.899959)
			(xy 386.807523 -114.929425) (xy 386.848714 -114.965116) (xy 386.884405 -115.006307) (xy 386.913871 -115.052157)
			(xy 386.936513 -115.101734) (xy 386.951868 -115.154029) (xy 386.959624 -115.207977) (xy 386.96011 -115.235228)
			(xy 386.959629 -115.264123) (xy 386.950937 -115.321254) (xy 386.933728 -115.376421) (xy 386.908393 -115.428361)
			(xy 386.875514 -115.475885) (xy 386.835842 -115.517905) (xy 386.790286 -115.553461) (xy 386.739888 -115.581738)
			(xy 386.685801 -115.602089) (xy 386.629263 -115.614049) (xy 386.600446 -115.616228) (xy 386.589524 -115.616736)
			(xy 386.57022 -115.626896) (xy 386.509514 -115.703858) (xy 386.50418 -115.72494) (xy 386.506212 -115.735608)
			(xy 386.509063 -115.752353) (xy 386.512113 -115.786187) (xy 386.512308 -115.803172) (xy 386.512308 -115.803934)
			(xy 386.511771 -115.830914) (xy 386.504152 -115.884333) (xy 386.489084 -115.936147) (xy 386.466868 -115.985321)
			(xy 386.437948 -116.030877) (xy 386.402899 -116.071904) (xy 386.36242 -116.107586) (xy 386.317319 -116.13721)
			(xy 386.293106 -116.14912) (xy 386.282946 -116.153946) (xy 386.268722 -116.17071) (xy 386.242306 -116.267484)
			(xy 386.245862 -116.28882) (xy 386.252212 -116.297964) (xy 386.252212 -116.298218) (xy 386.26779 -116.322057)
			(xy 386.292444 -116.373389) (xy 386.309206 -116.427813) (xy 386.317704 -116.484121) (xy 386.318252 -116.512594)
			(xy 386.317717 -116.539843) (xy 386.309962 -116.593787) (xy 386.29461 -116.646078) (xy 386.271973 -116.695652)
			(xy 386.242511 -116.741501) (xy 386.206825 -116.78269) (xy 386.165641 -116.818381) (xy 386.119796 -116.847849)
			(xy 386.070225 -116.870493) (xy 386.017936 -116.885852) (xy 385.963993 -116.893613) (xy 385.936744 -116.894102)
			(xy 385.910429 -116.893671) (xy 385.858299 -116.886429) (xy 385.807655 -116.872102) (xy 385.759457 -116.850963)
			(xy 385.714614 -116.823411) (xy 385.673976 -116.789966) (xy 385.65582 -116.770912) (xy 385.648291 -116.763519)
			(xy 385.629017 -116.754989) (xy 385.618482 -116.754402) (xy 385.543806 -116.754402) (xy 385.533255 -116.75492)
			(xy 385.51396 -116.763463) (xy 385.506468 -116.770912) (xy 385.488323 -116.789978) (xy 385.447691 -116.823434)
			(xy 385.402848 -116.850991) (xy 385.354646 -116.872128) (xy 385.303996 -116.886443) (xy 385.251861 -116.893665)
			(xy 385.225544 -116.894102) (xy 385.198289 -116.893654) (xy 385.144332 -116.885902) (xy 385.092028 -116.870549)
			(xy 385.042442 -116.847909) (xy 384.996582 -116.818442) (xy 384.955384 -116.782747) (xy 384.919685 -116.741553)
			(xy 384.890212 -116.695697) (xy 384.867566 -116.646113) (xy 384.852208 -116.593811) (xy 384.844449 -116.539855)
			(xy 371.98531 -116.539855) (xy 372.356121 -117.7544) (xy 385.388102 -117.7544) (xy 385.392173 -117.698778)
			(xy 385.404299 -117.644341) (xy 385.424222 -117.59225) (xy 385.451518 -117.543615) (xy 385.485604 -117.499472)
			(xy 385.525753 -117.460763) (xy 385.571111 -117.428312) (xy 385.620711 -117.402811) (xy 385.673495 -117.384804)
			(xy 385.728338 -117.374674) (xy 385.784072 -117.372637) (xy 385.839509 -117.378737) (xy 385.893466 -117.392843)
			(xy 385.944795 -117.414655) (xy 385.992401 -117.443709) (xy 386.035269 -117.479384) (xy 386.072486 -117.520921)
			(xy 386.103259 -117.567434) (xy 386.126931 -117.617931) (xy 386.142999 -117.671338) (xy 386.151119 -117.726514)
			(xy 386.151628 -117.7544) (xy 386.151119 -117.782286) (xy 386.142999 -117.837462) (xy 386.126931 -117.890869)
			(xy 386.103259 -117.941366) (xy 386.072486 -117.987879) (xy 386.035269 -118.029416) (xy 385.992401 -118.065091)
			(xy 385.944795 -118.094145) (xy 385.893466 -118.115957) (xy 385.839509 -118.130063) (xy 385.784072 -118.136163)
			(xy 385.728338 -118.134126) (xy 385.673495 -118.123996) (xy 385.620711 -118.105989) (xy 385.571111 -118.080488)
			(xy 385.525753 -118.048037) (xy 385.485604 -118.009328) (xy 385.451518 -117.965185) (xy 385.424222 -117.91655)
			(xy 385.404299 -117.864459) (xy 385.392173 -117.810022) (xy 385.388102 -117.7544) (xy 372.356121 -117.7544)
			(xy 372.610634 -118.588028) (xy 372.624306 -118.634363) (xy 372.64364 -118.72902) (xy 372.649242 -118.777004)
			(xy 372.649242 -118.777766) (xy 372.650004 -118.783608) (xy 372.651528 -118.795038) (xy 372.653306 -118.803166)
			(xy 372.731284 -119.060214) (xy 372.742704 -119.099363) (xy 372.759874 -119.179092) (xy 372.765574 -119.219472)
			(xy 372.87981 -120.087898) (xy 382.967992 -120.087898) (xy 382.967992 -119.224298) (xy 382.968482 -119.19433)
			(xy 382.976305 -119.134908) (xy 382.991818 -119.077015) (xy 383.014754 -119.021642) (xy 383.044721 -118.969736)
			(xy 383.081208 -118.922186) (xy 383.123588 -118.879806) (xy 383.171138 -118.843319) (xy 383.223044 -118.813352)
			(xy 383.278417 -118.790416) (xy 383.33631 -118.774903) (xy 383.395732 -118.76708) (xy 383.455668 -118.76708)
			(xy 383.51509 -118.774903) (xy 383.572983 -118.790416) (xy 383.628356 -118.813352) (xy 383.680262 -118.843319)
			(xy 383.727812 -118.879806) (xy 383.770192 -118.922186) (xy 383.806679 -118.969736) (xy 383.836646 -119.021642)
			(xy 383.859582 -119.077015) (xy 383.875095 -119.134908) (xy 383.882918 -119.19433) (xy 383.883408 -119.224298)
			(xy 383.883408 -120.087898) (xy 383.882918 -120.117866) (xy 383.875095 -120.177288) (xy 383.859582 -120.235181)
			(xy 383.836646 -120.290554) (xy 383.806679 -120.34246) (xy 383.770192 -120.39001) (xy 383.727812 -120.43239)
			(xy 383.680262 -120.468877) (xy 383.628356 -120.498844) (xy 383.572983 -120.52178) (xy 383.51509 -120.537293)
			(xy 383.455668 -120.545116) (xy 383.395732 -120.545116) (xy 383.33631 -120.537293) (xy 383.278417 -120.52178)
			(xy 383.223044 -120.498844) (xy 383.171138 -120.468877) (xy 383.123588 -120.43239) (xy 383.081208 -120.39001)
			(xy 383.044721 -120.34246) (xy 383.014754 -120.290554) (xy 382.991818 -120.235181) (xy 382.976305 -120.177288)
			(xy 382.968482 -120.117866) (xy 382.967992 -120.087898) (xy 372.87981 -120.087898) (xy 373.117438 -121.894346)
			(xy 385.6101 -121.894346) (xy 385.6101 -121.030746) (xy 385.61059 -121.000778) (xy 385.618413 -120.941356)
			(xy 385.633926 -120.883463) (xy 385.656862 -120.82809) (xy 385.686829 -120.776184) (xy 385.723316 -120.728634)
			(xy 385.765696 -120.686254) (xy 385.813246 -120.649767) (xy 385.865152 -120.6198) (xy 385.920525 -120.596864)
			(xy 385.978418 -120.581351) (xy 386.03784 -120.573528) (xy 386.097776 -120.573528) (xy 386.157198 -120.581351)
			(xy 386.215091 -120.596864) (xy 386.270464 -120.6198) (xy 386.32237 -120.649767) (xy 386.36992 -120.686254)
			(xy 386.4123 -120.728634) (xy 386.448787 -120.776184) (xy 386.478754 -120.82809) (xy 386.50169 -120.883463)
			(xy 386.517203 -120.941356) (xy 386.525026 -121.000778) (xy 386.525516 -121.030746) (xy 386.525516 -121.894346)
			(xy 386.525026 -121.924314) (xy 386.517203 -121.983736) (xy 386.50169 -122.041629) (xy 386.478754 -122.097002)
			(xy 386.448787 -122.148908) (xy 386.4123 -122.196458) (xy 386.36992 -122.238838) (xy 386.32237 -122.275325)
			(xy 386.270464 -122.305292) (xy 386.215091 -122.328228) (xy 386.157198 -122.343741) (xy 386.097776 -122.351564)
			(xy 386.03784 -122.351564) (xy 385.978418 -122.343741) (xy 385.920525 -122.328228) (xy 385.865152 -122.305292)
			(xy 385.813246 -122.275325) (xy 385.765696 -122.238838) (xy 385.723316 -122.196458) (xy 385.686829 -122.148908)
			(xy 385.656862 -122.097002) (xy 385.633926 -122.041629) (xy 385.618413 -121.983736) (xy 385.61059 -121.924314)
			(xy 385.6101 -121.894346) (xy 373.117438 -121.894346) (xy 373.353362 -123.68784) (xy 382.967992 -123.68784)
			(xy 382.967992 -122.82424) (xy 382.968482 -122.794272) (xy 382.976305 -122.73485) (xy 382.991818 -122.676957)
			(xy 383.014754 -122.621584) (xy 383.044721 -122.569678) (xy 383.081208 -122.522128) (xy 383.123588 -122.479748)
			(xy 383.171138 -122.443261) (xy 383.223044 -122.413294) (xy 383.278417 -122.390358) (xy 383.33631 -122.374845)
			(xy 383.395732 -122.367022) (xy 383.455668 -122.367022) (xy 383.51509 -122.374845) (xy 383.572983 -122.390358)
			(xy 383.628356 -122.413294) (xy 383.680262 -122.443261) (xy 383.727812 -122.479748) (xy 383.770192 -122.522128)
			(xy 383.806679 -122.569678) (xy 383.836646 -122.621584) (xy 383.859582 -122.676957) (xy 383.875095 -122.73485)
			(xy 383.882918 -122.794272) (xy 383.883408 -122.82424) (xy 383.883408 -123.68784) (xy 383.882918 -123.717808)
			(xy 383.875095 -123.77723) (xy 383.859582 -123.835123) (xy 383.836646 -123.890496) (xy 383.806679 -123.942402)
			(xy 383.770192 -123.989952) (xy 383.727812 -124.032332) (xy 383.680262 -124.068819) (xy 383.628356 -124.098786)
			(xy 383.572983 -124.121722) (xy 383.51509 -124.137235) (xy 383.455668 -124.145058) (xy 383.395732 -124.145058)
			(xy 383.33631 -124.137235) (xy 383.278417 -124.121722) (xy 383.223044 -124.098786) (xy 383.171138 -124.068819)
			(xy 383.123588 -124.032332) (xy 383.081208 -123.989952) (xy 383.044721 -123.942402) (xy 383.014754 -123.890496)
			(xy 382.991818 -123.835123) (xy 382.976305 -123.77723) (xy 382.968482 -123.717808) (xy 382.967992 -123.68784)
			(xy 373.353362 -123.68784) (xy 373.591023 -125.494542) (xy 385.6101 -125.494542) (xy 385.6101 -124.630942)
			(xy 385.61059 -124.600974) (xy 385.618413 -124.541552) (xy 385.633926 -124.483659) (xy 385.656862 -124.428286)
			(xy 385.686829 -124.37638) (xy 385.723316 -124.32883) (xy 385.765696 -124.28645) (xy 385.813246 -124.249963)
			(xy 385.865152 -124.219996) (xy 385.920525 -124.19706) (xy 385.978418 -124.181547) (xy 386.03784 -124.173724)
			(xy 386.097776 -124.173724) (xy 386.157198 -124.181547) (xy 386.215091 -124.19706) (xy 386.270464 -124.219996)
			(xy 386.32237 -124.249963) (xy 386.36992 -124.28645) (xy 386.4123 -124.32883) (xy 386.448787 -124.37638)
			(xy 386.478754 -124.428286) (xy 386.50169 -124.483659) (xy 386.517203 -124.541552) (xy 386.525026 -124.600974)
			(xy 386.525516 -124.630942) (xy 386.525516 -125.494542) (xy 386.525026 -125.52451) (xy 386.517203 -125.583932)
			(xy 386.50169 -125.641825) (xy 386.478754 -125.697198) (xy 386.448787 -125.749104) (xy 386.4123 -125.796654)
			(xy 386.36992 -125.839034) (xy 386.32237 -125.875521) (xy 386.270464 -125.905488) (xy 386.215091 -125.928424)
			(xy 386.157198 -125.943937) (xy 386.097776 -125.95176) (xy 386.03784 -125.95176) (xy 385.978418 -125.943937)
			(xy 385.920525 -125.928424) (xy 385.865152 -125.905488) (xy 385.813246 -125.875521) (xy 385.765696 -125.839034)
			(xy 385.723316 -125.796654) (xy 385.686829 -125.749104) (xy 385.656862 -125.697198) (xy 385.633926 -125.641825)
			(xy 385.618413 -125.583932) (xy 385.61059 -125.52451) (xy 385.6101 -125.494542) (xy 373.591023 -125.494542)
			(xy 374.354425 -131.297934) (xy 382.967992 -131.297934) (xy 382.967992 -130.434334) (xy 382.968482 -130.404366)
			(xy 382.976305 -130.344944) (xy 382.991818 -130.287051) (xy 383.014754 -130.231678) (xy 383.044721 -130.179772)
			(xy 383.081208 -130.132222) (xy 383.123588 -130.089842) (xy 383.171138 -130.053355) (xy 383.223044 -130.023388)
			(xy 383.278417 -130.000452) (xy 383.33631 -129.984939) (xy 383.395732 -129.977116) (xy 383.455668 -129.977116)
			(xy 383.51509 -129.984939) (xy 383.572983 -130.000452) (xy 383.628356 -130.023388) (xy 383.680262 -130.053355)
			(xy 383.727812 -130.089842) (xy 383.770192 -130.132222) (xy 383.806679 -130.179772) (xy 383.836646 -130.231678)
			(xy 383.859582 -130.287051) (xy 383.875095 -130.344944) (xy 383.882918 -130.404366) (xy 383.883408 -130.434334)
			(xy 383.883408 -131.297934) (xy 383.882918 -131.327902) (xy 383.875095 -131.387324) (xy 383.859582 -131.445217)
			(xy 383.836646 -131.50059) (xy 383.806679 -131.552496) (xy 383.770192 -131.600046) (xy 383.727812 -131.642426)
			(xy 383.680262 -131.678913) (xy 383.628356 -131.70888) (xy 383.572983 -131.731816) (xy 383.51509 -131.747329)
			(xy 383.455668 -131.755152) (xy 383.395732 -131.755152) (xy 383.33631 -131.747329) (xy 383.278417 -131.731816)
			(xy 383.223044 -131.70888) (xy 383.171138 -131.678913) (xy 383.123588 -131.642426) (xy 383.081208 -131.600046)
			(xy 383.044721 -131.552496) (xy 383.014754 -131.50059) (xy 382.991818 -131.445217) (xy 382.976305 -131.387324)
			(xy 382.968482 -131.327902) (xy 382.967992 -131.297934) (xy 374.354425 -131.297934) (xy 374.592053 -133.104382)
			(xy 385.6101 -133.104382) (xy 385.6101 -132.240782) (xy 385.61059 -132.210814) (xy 385.618413 -132.151392)
			(xy 385.633926 -132.093499) (xy 385.656862 -132.038126) (xy 385.686829 -131.98622) (xy 385.723316 -131.93867)
			(xy 385.765696 -131.89629) (xy 385.813246 -131.859803) (xy 385.865152 -131.829836) (xy 385.920525 -131.8069)
			(xy 385.978418 -131.791387) (xy 386.03784 -131.783564) (xy 386.097776 -131.783564) (xy 386.157198 -131.791387)
			(xy 386.215091 -131.8069) (xy 386.270464 -131.829836) (xy 386.32237 -131.859803) (xy 386.36992 -131.89629)
			(xy 386.4123 -131.93867) (xy 386.448787 -131.98622) (xy 386.478754 -132.038126) (xy 386.50169 -132.093499)
			(xy 386.517203 -132.151392) (xy 386.525026 -132.210814) (xy 386.525516 -132.240782) (xy 386.525516 -133.104382)
			(xy 386.525026 -133.13435) (xy 386.517203 -133.193772) (xy 386.50169 -133.251665) (xy 386.478754 -133.307038)
			(xy 386.448787 -133.358944) (xy 386.4123 -133.406494) (xy 386.36992 -133.448874) (xy 386.32237 -133.485361)
			(xy 386.270464 -133.515328) (xy 386.215091 -133.538264) (xy 386.157198 -133.553777) (xy 386.097776 -133.5616)
			(xy 386.03784 -133.5616) (xy 385.978418 -133.553777) (xy 385.920525 -133.538264) (xy 385.865152 -133.515328)
			(xy 385.813246 -133.485361) (xy 385.765696 -133.448874) (xy 385.723316 -133.406494) (xy 385.686829 -133.358944)
			(xy 385.656862 -133.307038) (xy 385.633926 -133.251665) (xy 385.618413 -133.193772) (xy 385.61059 -133.13435)
			(xy 385.6101 -133.104382) (xy 374.592053 -133.104382) (xy 374.827976 -134.897876) (xy 382.967992 -134.897876)
			(xy 382.967992 -134.034276) (xy 382.968482 -134.004308) (xy 382.976305 -133.944886) (xy 382.991818 -133.886993)
			(xy 383.014754 -133.83162) (xy 383.044721 -133.779714) (xy 383.081208 -133.732164) (xy 383.123588 -133.689784)
			(xy 383.171138 -133.653297) (xy 383.223044 -133.62333) (xy 383.278417 -133.600394) (xy 383.33631 -133.584881)
			(xy 383.395732 -133.577058) (xy 383.455668 -133.577058) (xy 383.51509 -133.584881) (xy 383.572983 -133.600394)
			(xy 383.628356 -133.62333) (xy 383.680262 -133.653297) (xy 383.727812 -133.689784) (xy 383.770192 -133.732164)
			(xy 383.806679 -133.779714) (xy 383.836646 -133.83162) (xy 383.859582 -133.886993) (xy 383.875095 -133.944886)
			(xy 383.882918 -134.004308) (xy 383.883408 -134.034276) (xy 383.883408 -134.897876) (xy 383.882918 -134.927844)
			(xy 383.875095 -134.987266) (xy 383.859582 -135.045159) (xy 383.836646 -135.100532) (xy 383.806679 -135.152438)
			(xy 383.770192 -135.199988) (xy 383.727812 -135.242368) (xy 383.680262 -135.278855) (xy 383.628356 -135.308822)
			(xy 383.572983 -135.331758) (xy 383.51509 -135.347271) (xy 383.455668 -135.355094) (xy 383.395732 -135.355094)
			(xy 383.33631 -135.347271) (xy 383.278417 -135.331758) (xy 383.223044 -135.308822) (xy 383.171138 -135.278855)
			(xy 383.123588 -135.242368) (xy 383.081208 -135.199988) (xy 383.044721 -135.152438) (xy 383.014754 -135.100532)
			(xy 382.991818 -135.045159) (xy 382.976305 -134.987266) (xy 382.968482 -134.927844) (xy 382.967992 -134.897876)
			(xy 374.827976 -134.897876) (xy 375.542062 -140.326364) (xy 383.992118 -140.326364) (xy 383.996189 -140.270742)
			(xy 384.008315 -140.216305) (xy 384.028238 -140.164214) (xy 384.055534 -140.115579) (xy 384.08962 -140.071436)
			(xy 384.129769 -140.032727) (xy 384.175127 -140.000276) (xy 384.224727 -139.974775) (xy 384.277511 -139.956768)
			(xy 384.332354 -139.946638) (xy 384.388088 -139.944601) (xy 384.443525 -139.950701) (xy 384.497482 -139.964807)
			(xy 384.548811 -139.986619) (xy 384.596417 -140.015673) (xy 384.639285 -140.051348) (xy 384.676502 -140.092885)
			(xy 384.707275 -140.139398) (xy 384.730947 -140.189895) (xy 384.747015 -140.243302) (xy 384.755135 -140.298478)
			(xy 384.755644 -140.326364) (xy 384.755135 -140.35425) (xy 384.747015 -140.409426) (xy 384.730947 -140.462833)
			(xy 384.707275 -140.51333) (xy 384.676502 -140.559843) (xy 384.639285 -140.60138) (xy 384.596417 -140.637055)
			(xy 384.548811 -140.666109) (xy 384.497482 -140.687921) (xy 384.443525 -140.702027) (xy 384.388088 -140.708127)
			(xy 384.332354 -140.70609) (xy 384.277511 -140.69596) (xy 384.224727 -140.677953) (xy 384.175127 -140.652452)
			(xy 384.129769 -140.620001) (xy 384.08962 -140.581292) (xy 384.055534 -140.537149) (xy 384.028238 -140.488514)
			(xy 384.008315 -140.436423) (xy 383.996189 -140.381986) (xy 383.992118 -140.326364) (xy 375.542062 -140.326364)
			(xy 376.051064 -144.1958) (xy 376.051318 -144.197324) (xy 377.775355 -153.3144) (xy 385.490972 -153.3144)
			(xy 385.495043 -153.258778) (xy 385.507169 -153.204341) (xy 385.527092 -153.15225) (xy 385.554388 -153.103615)
			(xy 385.588474 -153.059472) (xy 385.628623 -153.020763) (xy 385.673981 -152.988312) (xy 385.723581 -152.962811)
			(xy 385.776365 -152.944804) (xy 385.831208 -152.934674) (xy 385.886942 -152.932637) (xy 385.942379 -152.938737)
			(xy 385.996336 -152.952843) (xy 386.047665 -152.974655) (xy 386.095271 -153.003709) (xy 386.138139 -153.039384)
			(xy 386.175356 -153.080921) (xy 386.206129 -153.127434) (xy 386.229801 -153.177931) (xy 386.245869 -153.231338)
			(xy 386.253989 -153.286514) (xy 386.254498 -153.3144) (xy 386.253989 -153.342286) (xy 386.245869 -153.397462)
			(xy 386.229801 -153.450869) (xy 386.206129 -153.501366) (xy 386.175356 -153.547879) (xy 386.138139 -153.589416)
			(xy 386.095271 -153.625091) (xy 386.047665 -153.654145) (xy 385.996336 -153.675957) (xy 385.942379 -153.690063)
			(xy 385.886942 -153.696163) (xy 385.831208 -153.694126) (xy 385.776365 -153.683996) (xy 385.723581 -153.665989)
			(xy 385.673981 -153.640488) (xy 385.628623 -153.608037) (xy 385.588474 -153.569328) (xy 385.554388 -153.525185)
			(xy 385.527092 -153.47655) (xy 385.507169 -153.424459) (xy 385.495043 -153.370022) (xy 385.490972 -153.3144)
			(xy 377.775355 -153.3144) (xy 378.543857 -157.3784) (xy 385.490972 -157.3784) (xy 385.495043 -157.322778)
			(xy 385.507169 -157.268341) (xy 385.527092 -157.21625) (xy 385.554388 -157.167615) (xy 385.588474 -157.123472)
			(xy 385.628623 -157.084763) (xy 385.673981 -157.052312) (xy 385.723581 -157.026811) (xy 385.776365 -157.008804)
			(xy 385.831208 -156.998674) (xy 385.886942 -156.996637) (xy 385.942379 -157.002737) (xy 385.996336 -157.016843)
			(xy 386.047665 -157.038655) (xy 386.095271 -157.067709) (xy 386.138139 -157.103384) (xy 386.175356 -157.144921)
			(xy 386.206129 -157.191434) (xy 386.229801 -157.241931) (xy 386.245869 -157.295338) (xy 386.253989 -157.350514)
			(xy 386.254498 -157.3784) (xy 386.253989 -157.406286) (xy 386.245869 -157.461462) (xy 386.229801 -157.514869)
			(xy 386.206129 -157.565366) (xy 386.175356 -157.611879) (xy 386.138139 -157.653416) (xy 386.095271 -157.689091)
			(xy 386.047665 -157.718145) (xy 385.996336 -157.739957) (xy 385.942379 -157.754063) (xy 385.886942 -157.760163)
			(xy 385.831208 -157.758126) (xy 385.776365 -157.747996) (xy 385.723581 -157.729989) (xy 385.673981 -157.704488)
			(xy 385.628623 -157.672037) (xy 385.588474 -157.633328) (xy 385.554388 -157.589185) (xy 385.527092 -157.54055)
			(xy 385.507169 -157.488459) (xy 385.495043 -157.434022) (xy 385.490972 -157.3784) (xy 378.543857 -157.3784)
			(xy 378.735982 -158.3944) (xy 385.490972 -158.3944) (xy 385.495043 -158.338778) (xy 385.507169 -158.284341)
			(xy 385.527092 -158.23225) (xy 385.554388 -158.183615) (xy 385.588474 -158.139472) (xy 385.628623 -158.100763)
			(xy 385.673981 -158.068312) (xy 385.723581 -158.042811) (xy 385.776365 -158.024804) (xy 385.831208 -158.014674)
			(xy 385.886942 -158.012637) (xy 385.942379 -158.018737) (xy 385.996336 -158.032843) (xy 386.047665 -158.054655)
			(xy 386.095271 -158.083709) (xy 386.138139 -158.119384) (xy 386.175356 -158.160921) (xy 386.206129 -158.207434)
			(xy 386.229801 -158.257931) (xy 386.245869 -158.311338) (xy 386.253989 -158.366514) (xy 386.254498 -158.3944)
			(xy 386.253989 -158.422286) (xy 386.245869 -158.477462) (xy 386.229801 -158.530869) (xy 386.206129 -158.581366)
			(xy 386.175356 -158.627879) (xy 386.138139 -158.669416) (xy 386.095271 -158.705091) (xy 386.047665 -158.734145)
			(xy 385.996336 -158.755957) (xy 385.942379 -158.770063) (xy 385.886942 -158.776163) (xy 385.831208 -158.774126)
			(xy 385.776365 -158.763996) (xy 385.723581 -158.745989) (xy 385.673981 -158.720488) (xy 385.628623 -158.688037)
			(xy 385.588474 -158.649328) (xy 385.554388 -158.605185) (xy 385.527092 -158.55655) (xy 385.507169 -158.504459)
			(xy 385.495043 -158.450022) (xy 385.490972 -158.3944) (xy 378.735982 -158.3944) (xy 379.244634 -161.08426)
			(xy 385.883148 -161.08426) (xy 385.887219 -161.028638) (xy 385.899345 -160.974201) (xy 385.919268 -160.92211)
			(xy 385.946564 -160.873475) (xy 385.98065 -160.829332) (xy 386.020799 -160.790623) (xy 386.066157 -160.758172)
			(xy 386.115757 -160.732671) (xy 386.168541 -160.714664) (xy 386.223384 -160.704534) (xy 386.279118 -160.702497)
			(xy 386.334555 -160.708597) (xy 386.388512 -160.722703) (xy 386.439841 -160.744515) (xy 386.487447 -160.773569)
			(xy 386.530315 -160.809244) (xy 386.567532 -160.850781) (xy 386.598305 -160.897294) (xy 386.621977 -160.947791)
			(xy 386.638045 -161.001198) (xy 386.646165 -161.056374) (xy 386.646674 -161.08426) (xy 386.646165 -161.112146)
			(xy 386.638045 -161.167322) (xy 386.621977 -161.220729) (xy 386.598305 -161.271226) (xy 386.567532 -161.317739)
			(xy 386.530315 -161.359276) (xy 386.487447 -161.394951) (xy 386.439841 -161.424005) (xy 386.388512 -161.445817)
			(xy 386.334555 -161.459923) (xy 386.279118 -161.466023) (xy 386.223384 -161.463986) (xy 386.168541 -161.453856)
			(xy 386.115757 -161.435849) (xy 386.066157 -161.410348) (xy 386.020799 -161.377897) (xy 385.98065 -161.339188)
			(xy 385.946564 -161.295045) (xy 385.919268 -161.24641) (xy 385.899345 -161.194319) (xy 385.887219 -161.139882)
			(xy 385.883148 -161.08426) (xy 379.244634 -161.08426) (xy 379.816591 -164.108892) (xy 386.764782 -164.108892)
			(xy 386.768853 -164.05327) (xy 386.780979 -163.998833) (xy 386.800902 -163.946742) (xy 386.828198 -163.898107)
			(xy 386.862284 -163.853964) (xy 386.902433 -163.815255) (xy 386.947791 -163.782804) (xy 386.997391 -163.757303)
			(xy 387.050175 -163.739296) (xy 387.105018 -163.729166) (xy 387.160752 -163.727129) (xy 387.216189 -163.733229)
			(xy 387.270146 -163.747335) (xy 387.321475 -163.769147) (xy 387.369081 -163.798201) (xy 387.411949 -163.833876)
			(xy 387.449166 -163.875413) (xy 387.479939 -163.921926) (xy 387.503611 -163.972423) (xy 387.519679 -164.02583)
			(xy 387.527799 -164.081006) (xy 387.528308 -164.108892) (xy 387.527799 -164.136778) (xy 387.519679 -164.191954)
			(xy 387.503611 -164.245361) (xy 387.479939 -164.295858) (xy 387.449166 -164.342371) (xy 387.411949 -164.383908)
			(xy 387.369081 -164.419583) (xy 387.321475 -164.448637) (xy 387.270146 -164.470449) (xy 387.216189 -164.484555)
			(xy 387.160752 -164.490655) (xy 387.105018 -164.488618) (xy 387.050175 -164.478488) (xy 386.997391 -164.460481)
			(xy 386.947791 -164.43498) (xy 386.902433 -164.402529) (xy 386.862284 -164.36382) (xy 386.828198 -164.319677)
			(xy 386.800902 -164.271042) (xy 386.780979 -164.218951) (xy 386.768853 -164.164514) (xy 386.764782 -164.108892)
			(xy 379.816591 -164.108892) (xy 386.736082 -200.70064) (xy 390.696196 -221.608142) (xy 390.699498 -221.61754)
			(xy 390.704495 -221.626911) (xy 390.720509 -221.640824) (xy 390.730486 -221.644464) (xy 390.738868 -221.64675)
			(xy 392.48969 -221.64675) (xy 392.503677 -221.646272) (xy 392.530586 -221.638614) (xy 392.554413 -221.623951)
			(xy 392.573374 -221.603379) (xy 392.586052 -221.57844) (xy 392.591497 -221.550998) (xy 392.590782 -221.537022)
			(xy 392.278108 -217.66403) (xy 391.058908 -202.56881) (xy 390.541764 -196.167502) (xy 390.369298 -194.031616)
			(xy 390.186164 -191.765428) (xy 388.797292 -174.570136) (xy 388.797292 -174.568866) (xy 388.796784 -174.564802)
			(xy 388.79653 -174.562516) (xy 388.796276 -174.559468) (xy 388.796276 -174.558706) (xy 388.796022 -174.55642)
			(xy 388.795514 -174.55007) (xy 388.729982 -173.739302) (xy 388.561834 -171.656502) (xy 388.420356 -169.905426)
			(xy 388.369302 -169.272204) (xy 388.145782 -166.503604) (xy 387.919976 -163.70554) (xy 387.918706 -163.686744)
			(xy 387.551422 -157.708854) (xy 387.328664 -154.084528) (xy 387.328664 -154.083766) (xy 387.299962 -153.71826)
			(xy 386.53085 -143.940784) (xy 386.53085 -143.93926) (xy 386.240528 -141.181328) (xy 386.238059 -141.156127)
			(xy 386.235391 -141.105556) (xy 386.235194 -141.080236) (xy 386.229352 -138.52398) (xy 386.229352 -138.521694)
			(xy 386.229443 -138.4981) (xy 386.231605 -138.450963) (xy 386.23367 -138.42746) (xy 386.238242 -138.38809)
			(xy 386.344668 -137.608056) (xy 386.396484 -137.226802) (xy 386.396749 -137.221308) (xy 386.395215 -137.210417)
			(xy 386.393436 -137.205212) (xy 386.391404 -137.199878) (xy 386.389497 -137.19634) (xy 386.384777 -137.189835)
			(xy 386.382006 -137.186924) (xy 386.377942 -137.18286) (xy 386.370068 -137.176764) (xy 386.337048 -137.151618)
			(xy 386.336286 -137.15111) (xy 386.309616 -137.13206) (xy 386.303043 -137.127682) (xy 386.288042 -137.12277)
			(xy 386.280152 -137.122408) (xy 386.265674 -137.122408) (xy 386.246878 -137.126218) (xy 386.24256 -137.127996)
			(xy 386.210671 -137.140358) (xy 386.144226 -137.156548) (xy 386.110226 -137.160254) (xy 386.067808 -137.162032)
			(xy 386.037839 -137.161542) (xy 385.978415 -137.15372) (xy 385.92052 -137.138209) (xy 385.865145 -137.115273)
			(xy 385.813237 -137.085306) (xy 385.765684 -137.04882) (xy 385.723301 -137.00644) (xy 385.686812 -136.95889)
			(xy 385.656841 -136.906984) (xy 385.633901 -136.851611) (xy 385.618386 -136.793716) (xy 385.61056 -136.734293)
			(xy 385.6101 -136.704324) (xy 385.6101 -135.840724) (xy 385.610568 -135.810754) (xy 385.618389 -135.751327)
			(xy 385.6339 -135.693429) (xy 385.656836 -135.638051) (xy 385.686804 -135.586141) (xy 385.723292 -135.538587)
			(xy 385.765675 -135.496202) (xy 385.813228 -135.459713) (xy 385.865137 -135.429743) (xy 385.920514 -135.406805)
			(xy 385.978411 -135.391292) (xy 386.037838 -135.383469) (xy 386.067808 -135.383016) (xy 386.098403 -135.383434)
			(xy 386.159062 -135.391463) (xy 386.188712 -135.399018) (xy 386.199134 -135.401957) (xy 386.219717 -135.40869)
			(xy 386.22986 -135.41248) (xy 386.24514 -135.418387) (xy 386.274888 -135.432115) (xy 386.289296 -135.439912)
			(xy 386.294884 -135.44296) (xy 386.304536 -135.4455) (xy 386.307584 -135.446262) (xy 386.313934 -135.448294)
			(xy 386.32765 -135.449056) (xy 386.352034 -135.443468) (xy 386.361686 -135.441436) (xy 386.390896 -135.421624)
			(xy 386.39623 -135.414512) (xy 386.40385 -135.404606) (xy 386.404866 -135.403336) (xy 386.40512 -135.403082)
			(xy 386.421594 -135.38342) (xy 386.458929 -135.348245) (xy 386.479542 -135.332978) (xy 386.489448 -135.32612)
			(xy 386.489702 -135.325866) (xy 386.493512 -135.32358) (xy 386.495036 -135.322564) (xy 386.500116 -135.319262)
			(xy 386.501132 -135.318754) (xy 386.501386 -135.3185) (xy 386.50164 -135.318246) (xy 386.504434 -135.316722)
			(xy 386.506212 -135.315452) (xy 386.51053 -135.312912) (xy 386.511546 -135.312404) (xy 386.5118 -135.31215)
			(xy 386.526786 -135.304022) (xy 386.527548 -135.303514) (xy 386.529072 -135.302752) (xy 386.531612 -135.301482)
			(xy 386.532882 -135.300974) (xy 386.535168 -135.299704) (xy 386.535422 -135.29945) (xy 386.535676 -135.29945)
			(xy 386.545836 -135.294878) (xy 386.560822 -135.288528) (xy 386.574057 -135.283398) (xy 386.601136 -135.274883)
			(xy 386.614924 -135.27151) (xy 386.615178 -135.27151) (xy 386.616194 -135.271256) (xy 386.62102 -135.269986)
			(xy 386.62483 -135.268716) (xy 386.631688 -135.266176) (xy 386.636514 -135.264398) (xy 386.64515 -135.259318)
			(xy 386.653144 -135.254208) (xy 386.664883 -135.239321) (xy 386.66801 -135.230362) (xy 386.669534 -135.225028)
			(xy 386.812028 -134.179818) (xy 386.876544 -133.70687) (xy 386.899912 -133.534912) (xy 386.998464 -132.81152)
			(xy 386.998718 -132.809996) (xy 386.998718 -132.808726) (xy 387.082538 -132.03428) (xy 387.095746 -131.911344)
			(xy 387.096 -131.90728) (xy 387.190742 -123.120658) (xy 387.228588 -119.60606) (xy 387.228588 -119.604028)
			(xy 387.089142 -115.000786) (xy 386.841238 -106.81335) (xy 386.799836 -105.5497) (xy 386.785612 -105.121456)
			(xy 386.785612 -105.118916) (xy 386.728208 -104.40289) (xy 386.727101 -104.3938) (xy 386.719294 -104.377252)
			(xy 386.712968 -104.370632) (xy 386.706364 -104.364028) (xy 386.689854 -104.356916) (xy 386.680456 -104.356408)
			(xy 386.652259 -104.354296) (xy 386.596896 -104.342803) (xy 386.543833 -104.323274) (xy 386.494229 -104.296134)
			(xy 386.449168 -104.261978) (xy 386.409636 -104.221551) (xy 386.392674 -104.198928) (xy 386.390896 -104.196642)
			(xy 386.36829 -104.18191) (xy 386.364457 -104.179512) (xy 386.356157 -104.175931) (xy 386.35178 -104.174798)
			(xy 386.330952 -104.169972) (xy 386.327441 -104.169276) (xy 386.320302 -104.16876) (xy 386.316728 -104.168956)
			(xy 386.311794 -104.169346) (xy 386.302202 -104.171776) (xy 386.297678 -104.173782) (xy 386.29463 -104.17556)
			(xy 386.268705 -104.189797) (xy 386.213967 -104.212208) (xy 386.156794 -104.227367) (xy 386.098144 -104.235021)
			(xy 386.06857 -104.235504) (xy 386.067808 -104.235504) (xy 386.037839 -104.235035) (xy 385.978413 -104.227213)
			(xy 385.920517 -104.2117) (xy 385.86514 -104.188763) (xy 385.813232 -104.158795) (xy 385.765679 -104.122307)
			(xy 385.723296 -104.079924) (xy 385.686808 -104.032372) (xy 385.656838 -103.980463) (xy 385.633901 -103.925087)
			(xy 385.618388 -103.867191) (xy 385.610565 -103.807765) (xy 385.6101 -103.777796) (xy 385.6101 -102.914196)
			(xy 385.610569 -102.884227) (xy 385.618393 -102.824803) (xy 385.633907 -102.766908) (xy 385.656844 -102.711533)
			(xy 385.686814 -102.659626) (xy 385.723302 -102.612075) (xy 385.765684 -102.569694) (xy 385.813236 -102.533207)
			(xy 385.865144 -102.503239) (xy 385.920519 -102.480303) (xy 385.978415 -102.464791) (xy 386.037839 -102.456969)
			(xy 386.067808 -102.456488) (xy 386.07111 -102.456488) (xy 386.099524 -102.457089) (xy 386.155877 -102.464472)
			(xy 386.210879 -102.478787) (xy 386.26368 -102.499813) (xy 386.288788 -102.51313) (xy 386.28955 -102.513638)
			(xy 386.294376 -102.516178) (xy 386.317236 -102.522528) (xy 386.330698 -102.52202) (xy 386.351526 -102.517194)
			(xy 386.36067 -102.515162) (xy 386.390896 -102.49535) (xy 386.39623 -102.488238) (xy 386.414636 -102.464588)
			(xy 386.457573 -102.422787) (xy 386.506519 -102.388217) (xy 386.533136 -102.374446) (xy 386.540817 -102.370295)
			(xy 386.553023 -102.357828) (xy 386.557012 -102.350062) (xy 386.559533 -102.344041) (xy 386.561726 -102.331177)
			(xy 386.56133 -102.324662) (xy 386.561076 -102.322376) (xy 386.561076 -102.321868) (xy 386.50037 -101.567742)
			(xy 386.4356 -100.759514) (xy 386.427218 -100.65639) (xy 386.426299 -100.64861) (xy 386.420338 -100.634132)
			(xy 386.415534 -100.627942) (xy 386.410454 -100.621846) (xy 386.407914 -100.618798) (xy 386.406898 -100.617528)
			(xy 386.404612 -100.614734) (xy 386.40385 -100.613972) (xy 386.399024 -100.607622) (xy 386.398516 -100.607114)
			(xy 386.397246 -100.605336) (xy 386.391912 -100.597716) (xy 386.381498 -100.590604) (xy 386.377942 -100.588318)
			(xy 386.3721 -100.579682) (xy 386.345938 -100.57384) (xy 386.34543 -100.57384) (xy 386.33527 -100.571554)
			(xy 386.326888 -100.570792) (xy 386.316728 -100.570792) (xy 386.311838 -100.570931) (xy 386.302247 -100.572852)
			(xy 386.297678 -100.574602) (xy 386.29336 -100.576634) (xy 386.29082 -100.577904) (xy 386.265053 -100.591728)
			(xy 386.210766 -100.613462) (xy 386.15416 -100.628129) (xy 386.125212 -100.63226) (xy 386.101878 -100.634934)
			(xy 386.054922 -100.63608) (xy 386.031486 -100.634546) (xy 386.028184 -100.634292) (xy 385.998788 -100.631274)
			(xy 385.941062 -100.618624) (xy 385.885445 -100.598651) (xy 385.832862 -100.571685) (xy 385.784186 -100.538176)
			(xy 385.740227 -100.498681) (xy 385.701718 -100.453857) (xy 385.669297 -100.404449) (xy 385.643506 -100.35128)
			(xy 385.633722 -100.323396) (xy 385.622744 -100.288209) (xy 385.610869 -100.215467) (xy 385.6101 -100.178616)
			(xy 385.6101 -99.746308) (xy 385.609846 -99.314254) (xy 385.610338 -99.284282) (xy 385.618165 -99.224852)
			(xy 385.633679 -99.166952) (xy 385.656615 -99.11157) (xy 385.686581 -99.059654) (xy 385.723064 -99.012092)
			(xy 385.765441 -98.969696) (xy 385.812988 -98.933192) (xy 385.86489 -98.903204) (xy 385.920262 -98.880244)
			(xy 385.978156 -98.864704) (xy 386.037583 -98.856851) (xy 386.067554 -98.856292) (xy 386.067808 -98.856292)
			(xy 386.11048 -98.858324) (xy 386.112258 -98.858578) (xy 386.113274 -98.858578) (xy 386.121148 -98.859594)
			(xy 386.122418 -98.859594) (xy 386.131054 -98.860864) (xy 386.132578 -98.860864) (xy 386.134102 -98.861118)
			(xy 386.135118 -98.861372) (xy 386.137404 -98.861626) (xy 386.13842 -98.86188) (xy 386.141468 -98.862134)
			(xy 386.154821 -98.864435) (xy 386.181255 -98.870408) (xy 386.1943 -98.874072) (xy 386.197856 -98.875088)
			(xy 386.206238 -98.876358) (xy 386.21589 -98.876358) (xy 386.223115 -98.875501) (xy 386.23666 -98.870203)
			(xy 386.24256 -98.865944) (xy 386.260848 -98.850958) (xy 386.265325 -98.847031) (xy 386.272505 -98.837535)
			(xy 386.275072 -98.832162) (xy 386.277167 -98.827085) (xy 386.279336 -98.816319) (xy 386.27939 -98.810826)
			(xy 386.17906 -97.565972) (xy 386.176814 -97.554513) (xy 386.163576 -97.535309) (xy 386.15366 -97.529142)
			(xy 386.145532 -97.52457) (xy 386.139766 -97.52152) (xy 386.12716 -97.518186) (xy 386.12064 -97.517966)
			(xy 386.103114 -97.517966) (xy 386.091938 -97.519236) (xy 386.079492 -97.52203) (xy 386.072634 -97.52457)
			(xy 386.071364 -97.525078) (xy 386.06603 -97.527618) (xy 386.042288 -97.53796) (xy 385.992694 -97.552865)
			(xy 385.94154 -97.560932) (xy 385.915662 -97.561908) (xy 385.905248 -97.561908) (xy 385.878263 -97.561282)
			(xy 385.82487 -97.553358) (xy 385.773127 -97.537988) (xy 385.724067 -97.515479) (xy 385.678669 -97.486279)
			(xy 385.637841 -97.450972) (xy 385.602396 -97.410263) (xy 385.573043 -97.364965) (xy 385.550368 -97.315981)
			(xy 385.534823 -97.26429) (xy 385.526719 -97.210924) (xy 385.526218 -97.156949) (xy 385.53333 -97.103443)
			(xy 385.547912 -97.051472) (xy 385.569674 -97.002076) (xy 385.598181 -96.95624) (xy 385.632864 -96.91488)
			(xy 385.67303 -96.878821) (xy 385.69519 -96.863408) (xy 385.718674 -96.848261) (xy 385.769141 -96.824264)
			(xy 385.82257 -96.807892) (xy 385.877818 -96.799496) (xy 385.905756 -96.798892) (xy 385.909058 -96.798892)
			(xy 385.939844 -96.799619) (xy 386.00059 -96.809705) (xy 386.029962 -96.818958) (xy 386.037836 -96.819974)
			(xy 386.047488 -96.819974) (xy 386.053353 -96.819805) (xy 386.064768 -96.817104) (xy 386.070094 -96.81464)
			(xy 386.074158 -96.812608) (xy 386.078984 -96.810322) (xy 386.09524 -96.797114) (xy 386.099347 -96.79365)
			(xy 386.106137 -96.785325) (xy 386.108702 -96.780604) (xy 386.111312 -96.775118) (xy 386.114147 -96.763309)
			(xy 386.11429 -96.757236) (xy 386.099812 -96.576388) (xy 386.0979 -96.566146) (xy 386.08714 -96.548329)
			(xy 386.078984 -96.541844) (xy 386.068062 -96.534732) (xy 386.062203 -96.531517) (xy 386.049338 -96.52792)
			(xy 386.042662 -96.52762) (xy 386.024374 -96.52762) (xy 386.017262 -96.529652) (xy 385.990466 -96.537236)
			(xy 385.935378 -96.545396) (xy 385.907534 -96.545908) (xy 385.88028 -96.545447) (xy 385.826325 -96.537694)
			(xy 385.774023 -96.522341) (xy 385.724439 -96.4997) (xy 385.678581 -96.470233) (xy 385.637385 -96.43454)
			(xy 385.601687 -96.393346) (xy 385.572216 -96.347491) (xy 385.549571 -96.297909) (xy 385.534213 -96.245608)
			(xy 385.526455 -96.191654) (xy 385.526026 -96.1644) (xy 385.526507 -96.137219) (xy 385.534225 -96.083407)
			(xy 385.549503 -96.031236) (xy 385.572034 -95.981762) (xy 385.601359 -95.935988) (xy 385.636886 -95.894841)
			(xy 385.677894 -95.859154) (xy 385.723554 -95.829649) (xy 385.772939 -95.806926) (xy 385.82505 -95.791444)
			(xy 385.878831 -95.783516) (xy 385.90601 -95.782892) (xy 385.908296 -95.782892) (xy 385.921677 -95.783029)
			(xy 385.948371 -95.784937) (xy 385.961636 -95.786702) (xy 385.965192 -95.78721) (xy 385.974336 -95.787464)
			(xy 385.983584 -95.786867) (xy 386.000767 -95.779962) (xy 386.007864 -95.774002) (xy 386.017516 -95.764858)
			(xy 386.018024 -95.76435) (xy 386.022596 -95.760286) (xy 386.023866 -95.759016) (xy 386.028184 -95.748094)
			(xy 386.030148 -95.742667) (xy 386.03181 -95.73125) (xy 386.031486 -95.725488) (xy 385.774946 -92.531692)
			(xy 385.611624 -90.496644) (xy 385.463542 -88.65235) (xy 385.462888 -88.646584) (xy 385.459289 -88.635556)
			(xy 385.45643 -88.630506) (xy 385.450588 -88.6206) (xy 385.442968 -88.61552) (xy 385.43103 -88.610186)
			(xy 385.427434 -88.609152) (xy 385.420039 -88.608009) (xy 385.416298 -88.6079) (xy 385.395978 -88.6079)
			(xy 385.388612 -88.610186) (xy 385.36145 -88.617909) (xy 385.305594 -88.626191) (xy 385.27736 -88.626696)
			(xy 385.275328 -88.626696) (xy 385.248163 -88.626104) (xy 385.194409 -88.618173) (xy 385.142325 -88.602695)
			(xy 385.092963 -88.579985) (xy 385.047323 -88.5505) (xy 385.006329 -88.514838) (xy 384.970809 -88.47372)
			(xy 384.941482 -88.427979) (xy 384.918942 -88.378539) (xy 384.903644 -88.326402) (xy 384.895899 -88.272621)
			(xy 384.895863 -88.218286) (xy 384.903537 -88.164495) (xy 384.918765 -88.112337) (xy 384.941239 -88.062868)
			(xy 384.970505 -88.017087) (xy 385.00597 -87.975922) (xy 385.046917 -87.940206) (xy 385.092518 -87.910661)
			(xy 385.141849 -87.887884) (xy 385.193913 -87.872337) (xy 385.247655 -87.864335) (xy 385.27482 -87.86368)
			(xy 385.277614 -87.86368) (xy 385.31546 -87.865712) (xy 385.326269 -87.866297) (xy 385.346787 -87.859456)
			(xy 385.355084 -87.852504) (xy 385.377944 -87.831168) (xy 385.386093 -87.822919) (xy 385.394555 -87.801356)
			(xy 385.3942 -87.789766) (xy 383.592578 -65.347088) (xy 383.59207 -65.34023) (xy 383.590292 -65.30721)
			(xy 383.41935 -61.041534) (xy 383.418075 -61.032567) (xy 383.410121 -61.016309) (xy 383.397028 -61.003812)
			(xy 383.38887 -60.999878) (xy 383.383536 -60.998354) (xy 383.357838 -60.989989) (xy 383.308917 -60.967028)
			(xy 383.263722 -60.937399) (xy 383.223157 -60.901692) (xy 383.188032 -60.860623) (xy 383.159049 -60.815011)
			(xy 383.136788 -60.765767) (xy 383.121692 -60.713877) (xy 383.114064 -60.660377) (xy 383.113534 -60.633356)
			(xy 383.114066 -60.604862) (xy 383.122549 -60.548507) (xy 383.139319 -60.494042) (xy 383.164003 -60.442676)
			(xy 383.196052 -60.395553) (xy 383.234753 -60.353721) (xy 383.279246 -60.31811) (xy 383.32854 -60.289512)
			(xy 383.354834 -60.278518) (xy 383.355342 -60.278264) (xy 383.362514 -60.275146) (xy 383.374678 -60.265327)
			(xy 383.379218 -60.25896) (xy 383.383028 -60.252864) (xy 383.387346 -60.237878) (xy 383.342896 -59.129168)
			(xy 383.330704 -58.824876) (xy 383.330257 -58.818442) (xy 383.326525 -58.806099) (xy 383.323338 -58.800492)
			(xy 383.32029 -58.795158) (xy 383.310892 -58.786268) (xy 383.304796 -58.782966) (xy 383.279783 -58.768374)
			(xy 383.234079 -58.732817) (xy 383.194267 -58.690767) (xy 383.161259 -58.643189) (xy 383.135813 -58.591173)
			(xy 383.118512 -58.535911) (xy 383.109752 -58.478671) (xy 383.109216 -58.449718) (xy 383.110486 -58.419492)
			(xy 383.11201 -58.40476) (xy 383.115704 -58.377545) (xy 383.129894 -58.324489) (xy 383.151544 -58.274016)
			(xy 383.180206 -58.227167) (xy 383.215287 -58.184911) (xy 383.256064 -58.14812) (xy 383.278634 -58.132472)
			(xy 383.279142 -58.132218) (xy 383.284418 -58.128476) (xy 383.29302 -58.118824) (xy 383.29616 -58.113168)
			(xy 383.2987 -58.107834) (xy 383.301494 -58.095388) (xy 383.29616 -57.960006) (xy 383.198624 -55.523384)
			(xy 383.198624 -55.522876) (xy 383.197862 -55.505858) (xy 383.197862 -55.50535) (xy 383.197608 -55.484014)
			(xy 383.197608 -55.483506) (xy 383.197608 -55.482744) (xy 383.197862 -55.468012) (xy 383.197862 -55.467758)
			(xy 383.204212 -55.056024) (xy 383.240788 -52.72151) (xy 383.240788 -52.71897) (xy 383.216912 -52.033932)
			(xy 383.142744 -49.91227) (xy 383.141944 -49.901864) (xy 383.1331 -49.882983) (xy 383.117466 -49.86919)
			(xy 383.107692 -49.865534) (xy 383.055622 -49.844706) (xy 383.055114 -49.844706) (xy 383.030984 -49.835562)
			(xy 383.022856 -49.833784) (xy 383.012302 -49.832739) (xy 382.991918 -49.838527) (xy 382.983486 -49.84496)
			(xy 382.980438 -49.847754) (xy 382.978406 -49.849786) (xy 382.959922 -49.867976) (xy 382.918996 -49.899824)
			(xy 382.874226 -49.925998) (xy 382.826396 -49.946039) (xy 382.776341 -49.959598) (xy 382.724935 -49.966437)
			(xy 382.699006 -49.96688) (xy 382.6715 -49.966417) (xy 382.617026 -49.958732) (xy 382.564161 -49.943511)
			(xy 382.513941 -49.921053) (xy 382.467351 -49.8918) (xy 382.446022 -49.874424) (xy 382.445768 -49.87417)
			(xy 382.442974 -49.871884) (xy 382.436343 -49.867481) (xy 382.421209 -49.862577) (xy 382.413256 -49.862232)
			(xy 382.408176 -49.862232) (xy 382.402737 -49.862089) (xy 382.392105 -49.85978) (xy 382.387094 -49.85766)
			(xy 382.376934 -49.852834) (xy 382.370905 -49.850343) (xy 382.358048 -49.848162) (xy 382.351534 -49.848516)
			(xy 382.347879 -49.848949) (xy 382.340739 -49.850734) (xy 382.33731 -49.852072) (xy 382.33096 -49.854612)
			(xy 382.309253 -49.874568) (xy 382.260916 -49.908333) (xy 382.208012 -49.934364) (xy 382.151767 -49.952056)
			(xy 382.093487 -49.960998) (xy 382.064006 -49.961546) (xy 382.063752 -49.961546) (xy 382.036529 -49.961059)
			(xy 381.982626 -49.953384) (xy 381.93033 -49.938234) (xy 381.880671 -49.915909) (xy 381.834629 -49.886847)
			(xy 381.813562 -49.869598) (xy 381.805942 -49.863502) (xy 381.800354 -49.862232) (xy 381.773176 -49.862232)
			(xy 381.767737 -49.862089) (xy 381.757105 -49.85978) (xy 381.752094 -49.85766) (xy 381.741934 -49.852834)
			(xy 381.735905 -49.850343) (xy 381.723048 -49.848162) (xy 381.716534 -49.848516) (xy 381.712879 -49.848949)
			(xy 381.705739 -49.850734) (xy 381.70231 -49.852072) (xy 381.69596 -49.854612) (xy 381.674253 -49.874568)
			(xy 381.625916 -49.908333) (xy 381.573012 -49.934364) (xy 381.516767 -49.952056) (xy 381.458487 -49.960998)
			(xy 381.429006 -49.961546) (xy 381.428752 -49.961546) (xy 381.401529 -49.961059) (xy 381.347626 -49.953384)
			(xy 381.29533 -49.938234) (xy 381.245671 -49.915909) (xy 381.199629 -49.886847) (xy 381.178562 -49.869598)
			(xy 381.170942 -49.863502) (xy 381.165354 -49.862232) (xy 381.138176 -49.862232) (xy 381.132737 -49.862089)
			(xy 381.122105 -49.85978) (xy 381.117094 -49.85766) (xy 381.103124 -49.85131) (xy 381.093958 -49.847636)
			(xy 381.074247 -49.846815) (xy 381.055674 -49.853469) (xy 381.048006 -49.859692) (xy 381.037592 -49.868836)
			(xy 381.016974 -49.885266) (xy 380.972078 -49.912901) (xy 380.923811 -49.934107) (xy 380.873089 -49.948482)
			(xy 380.820874 -49.955753) (xy 380.794514 -49.956212) (xy 380.794006 -49.956212) (xy 380.766753 -49.955749)
			(xy 380.7128 -49.947993) (xy 380.660501 -49.932637) (xy 380.61092 -49.909995) (xy 380.565066 -49.880526)
			(xy 380.523872 -49.844832) (xy 380.488177 -49.803639) (xy 380.458708 -49.757785) (xy 380.436065 -49.708204)
			(xy 380.420709 -49.655905) (xy 380.412951 -49.601953) (xy 380.412951 -49.547447) (xy 380.420709 -49.493495)
			(xy 380.436065 -49.441196) (xy 380.458708 -49.391615) (xy 380.488177 -49.345761) (xy 380.523872 -49.304568)
			(xy 380.565066 -49.268874) (xy 380.61092 -49.239405) (xy 380.660501 -49.216763) (xy 380.7128 -49.201407)
			(xy 380.766753 -49.193651) (xy 380.794006 -49.193196) (xy 380.79426 -49.193196) (xy 380.819771 -49.193619)
			(xy 380.870338 -49.200413) (xy 380.919549 -49.213884) (xy 380.966526 -49.233793) (xy 381.010432 -49.259784)
			(xy 381.030734 -49.275238) (xy 381.036068 -49.279556) (xy 381.04445 -49.283112) (xy 381.04699 -49.284128)
			(xy 381.051109 -49.285513) (xy 381.059664 -49.287037) (xy 381.064008 -49.287176) (xy 381.084836 -49.287176)
			(xy 381.090275 -49.287319) (xy 381.100907 -49.289626) (xy 381.105918 -49.291748) (xy 381.119888 -49.298098)
			(xy 381.125979 -49.300604) (xy 381.138965 -49.30278) (xy 381.145542 -49.302416) (xy 381.155194 -49.300638)
			(xy 381.164592 -49.292256) (xy 381.165354 -49.291748) (xy 381.165608 -49.291494) (xy 381.166878 -49.290224)
			(xy 381.18843 -49.271093) (xy 381.236138 -49.238771) (xy 381.288113 -49.213881) (xy 381.343204 -49.196977)
			(xy 381.400193 -49.18843) (xy 381.429006 -49.187862) (xy 381.456174 -49.188327) (xy 381.509971 -49.195952)
			(xy 381.562166 -49.211052) (xy 381.611725 -49.233327) (xy 381.657669 -49.262337) (xy 381.678688 -49.279556)
			(xy 381.683768 -49.28362) (xy 381.686054 -49.285398) (xy 381.698754 -49.287176) (xy 381.719836 -49.287176)
			(xy 381.725275 -49.287319) (xy 381.735907 -49.289626) (xy 381.740918 -49.291748) (xy 381.754888 -49.298098)
			(xy 381.760979 -49.300604) (xy 381.773965 -49.30278) (xy 381.780542 -49.302416) (xy 381.790194 -49.300638)
			(xy 381.799592 -49.292256) (xy 381.800354 -49.291748) (xy 381.800608 -49.291494) (xy 381.801878 -49.290224)
			(xy 381.82343 -49.271093) (xy 381.871138 -49.238771) (xy 381.923113 -49.213881) (xy 381.978204 -49.196977)
			(xy 382.035193 -49.18843) (xy 382.064006 -49.187862) (xy 382.091174 -49.188327) (xy 382.144971 -49.195952)
			(xy 382.197166 -49.211052) (xy 382.246725 -49.233327) (xy 382.292669 -49.262337) (xy 382.313688 -49.279556)
			(xy 382.318768 -49.28362) (xy 382.321054 -49.285398) (xy 382.333754 -49.287176) (xy 382.43002 -49.287176)
			(xy 382.437826 -49.286847) (xy 382.45269 -49.282054) (xy 382.45923 -49.277778) (xy 382.462532 -49.275238)
			(xy 382.46558 -49.272952) (xy 382.470406 -49.268126) (xy 382.478534 -49.257204) (xy 382.484122 -49.246536)
			(xy 382.508198 -49.231398) (xy 382.55979 -49.207469) (xy 382.614294 -49.191234) (xy 382.670571 -49.18303)
			(xy 382.699006 -49.182528) (xy 382.699514 -49.182528) (xy 382.72743 -49.183023) (xy 382.782695 -49.190951)
			(xy 382.836276 -49.206645) (xy 382.887085 -49.229787) (xy 382.934095 -49.259907) (xy 382.955546 -49.277778)
			(xy 382.961388 -49.282858) (xy 382.974596 -49.2887) (xy 382.978152 -49.28997) (xy 382.981962 -49.29124)
			(xy 382.994662 -49.29378) (xy 382.998787 -49.294229) (xy 383.007081 -49.293968) (xy 383.011172 -49.293272)
			(xy 383.020062 -49.291494) (xy 383.03708 -49.280572) (xy 383.037588 -49.280318) (xy 383.039874 -49.278794)
			(xy 383.047494 -49.27473) (xy 383.048764 -49.274222) (xy 383.06883 -49.26457) (xy 383.089658 -49.254664)
			(xy 383.094166 -49.252346) (xy 383.10222 -49.246196) (xy 383.10566 -49.242472) (xy 383.111707 -49.234956)
			(xy 383.118221 -49.216813) (xy 383.11836 -49.207166) (xy 383.081022 -48.13935) (xy 383.07518 -47.981108)
			(xy 383.074926 -47.976028) (xy 381.986536 -39.919656) (xy 381.982774 -39.890264) (xy 381.978326 -39.83117)
			(xy 381.977646 -39.801546) (xy 381.960882 -38.725856) (xy 381.960374 -38.71849) (xy 381.87122 -38.17239)
			(xy 381.86522 -38.13285) (xy 381.858865 -38.053123) (xy 381.85852 -38.013132) (xy 381.85852 -37.991542)
			(xy 381.85852 -37.99078) (xy 381.85979 -37.92728) (xy 381.85979 -37.926264) (xy 381.859282 -37.906452)
			(xy 381.851408 -37.412168) (xy 381.851408 -37.395404) (xy 381.852069 -37.341641) (xy 381.863521 -37.234727)
			(xy 381.874268 -37.182044) (xy 381.874522 -37.181282) (xy 381.875284 -37.177218) (xy 381.875792 -37.14877)
			(xy 381.876554 -37.113972) (xy 381.876554 -37.113464) (xy 381.877062 -37.086032) (xy 381.877074 -37.081098)
			(xy 381.875419 -37.071374) (xy 381.87376 -37.066728) (xy 381.872236 -37.063426) (xy 381.869188 -37.057584)
			(xy 381.867664 -37.055044) (xy 381.86741 -37.054536) (xy 381.845566 -37.008308) (xy 381.845566 -37.008054)
			(xy 381.842772 -37.001704) (xy 381.84074 -36.997132) (xy 381.840486 -36.996878) (xy 381.838708 -36.992814)
			(xy 381.837692 -36.990274) (xy 381.836422 -36.98748) (xy 381.82931 -36.9697) (xy 381.825246 -36.958778)
			(xy 381.822706 -36.95192) (xy 381.819912 -36.944554) (xy 381.819912 -36.944046) (xy 381.81661 -36.935664)
			(xy 381.8128 -36.92525) (xy 381.81026 -36.919408) (xy 381.80672 -36.913018) (xy 381.796647 -36.902447)
			(xy 381.790448 -36.89858) (xy 381.767381 -36.903894) (xy 381.72039 -36.909624) (xy 381.696722 -36.91001)
			(xy 381.696214 -36.91001) (xy 381.668032 -36.909532) (xy 381.612241 -36.901512) (xy 381.558159 -36.885634)
			(xy 381.506887 -36.862221) (xy 381.459469 -36.831749) (xy 381.416871 -36.794839) (xy 381.37996 -36.752242)
			(xy 381.349486 -36.704825) (xy 381.326071 -36.653554) (xy 381.310191 -36.599473) (xy 381.302169 -36.543682)
			(xy 381.302169 -36.487318) (xy 381.310191 -36.431527) (xy 381.326071 -36.377446) (xy 381.349486 -36.326175)
			(xy 381.37996 -36.278758) (xy 381.416871 -36.236161) (xy 381.459469 -36.199251) (xy 381.506887 -36.168779)
			(xy 381.558159 -36.145366) (xy 381.612241 -36.129488) (xy 381.668032 -36.121468) (xy 381.696214 -36.121086)
			(xy 381.731774 -36.12261) (xy 381.734568 -36.120578) (xy 381.745744 -36.11118) (xy 381.749808 -36.107624)
			(xy 381.757936 -36.100766) (xy 381.768096 -36.079938) (xy 381.771144 -36.072064) (xy 381.775208 -36.058856)
			(xy 381.775716 -36.05403) (xy 381.781468 -36.007617) (xy 381.800624 -35.916071) (xy 381.828351 -35.826746)
			(xy 381.8644 -35.740443) (xy 381.885952 -35.698938) (xy 381.89027 -35.69081) (xy 381.89154 -35.682174)
			(xy 381.892028 -35.677986) (xy 381.891774 -35.66956) (xy 381.891032 -35.66541) (xy 381.888492 -35.655504)
			(xy 381.866648 -35.574732) (xy 381.866648 -35.574224) (xy 381.862076 -35.556698) (xy 381.861314 -35.55365)
			(xy 381.858308 -35.545417) (xy 381.847651 -35.531521) (xy 381.840486 -35.526472) (xy 381.775716 -35.488372)
			(xy 381.769366 -35.485578) (xy 381.75057 -35.490404) (xy 381.716534 -35.498278) (xy 381.667007 -35.508106)
			(xy 381.566611 -35.518917) (xy 381.516128 -35.519868) (xy 381.503174 -35.519868) (xy 381.456779 -35.518986)
			(xy 381.364447 -35.509662) (xy 381.273382 -35.491796) (xy 381.184372 -35.465542) (xy 381.098188 -35.431127)
			(xy 381.015576 -35.38885) (xy 380.976124 -35.36442) (xy 380.971806 -35.365182) (xy 380.969774 -35.36569)
			(xy 380.95353 -35.36846) (xy 380.920718 -35.371513) (xy 380.904242 -35.371786) (xy 380.90094 -35.371786)
			(xy 380.873862 -35.371309) (xy 380.820253 -35.363643) (xy 380.768265 -35.348476) (xy 380.718944 -35.32611)
			(xy 380.67328 -35.296996) (xy 380.632192 -35.261719) (xy 380.596504 -35.220986) (xy 380.566933 -35.175617)
			(xy 380.544074 -35.126523) (xy 380.528385 -35.07469) (xy 380.520183 -35.021159) (xy 380.519432 -34.994088)
			(xy 380.519432 -34.990024) (xy 380.519941 -34.96277) (xy 380.527731 -34.908821) (xy 380.5431 -34.856523)
			(xy 380.553976 -34.831528) (xy 380.556262 -34.826448) (xy 380.55804 -34.81832) (xy 380.552716 -34.800887)
			(xy 380.543191 -34.765699) (xy 380.53899 -34.747962) (xy 380.530862 -34.709608) (xy 380.522609 -34.663251)
			(xy 380.513836 -34.569494) (xy 380.513336 -34.52241) (xy 380.51377 -34.479823) (xy 380.521009 -34.394958)
			(xy 380.53546 -34.31102) (xy 380.557018 -34.22862) (xy 380.585527 -34.14836) (xy 380.602744 -34.109406)
			(xy 380.605928 -34.100273) (xy 380.605932 -34.080946) (xy 380.602744 -34.071814) (xy 380.585535 -34.032858)
			(xy 380.55704 -33.952594) (xy 380.535488 -33.870195) (xy 380.521034 -33.786258) (xy 380.513785 -33.701396)
			(xy 380.513336 -33.65881) (xy 380.513336 -33.657794) (xy 380.513964 -33.607927) (xy 380.523971 -33.508696)
			(xy 380.543844 -33.410962) (xy 380.55804 -33.363154) (xy 380.557024 -33.358582) (xy 380.553468 -33.348168)
			(xy 380.549658 -33.339532) (xy 380.549658 -33.339278) (xy 380.547626 -33.333944) (xy 380.536704 -33.304226)
			(xy 380.536704 -33.303972) (xy 380.535688 -33.301178) (xy 380.53518 -33.299146) (xy 380.534926 -33.298384)
			(xy 380.534926 -33.29813) (xy 380.530066 -33.280914) (xy 380.523195 -33.245804) (xy 380.52121 -33.228026)
			(xy 380.519432 -33.1978) (xy 380.519432 -33.188402) (xy 380.520041 -33.161236) (xy 380.528004 -33.107485)
			(xy 380.543515 -33.055408) (xy 380.566259 -33.006059) (xy 380.595774 -32.960437) (xy 380.631465 -32.919464)
			(xy 380.672609 -32.883971) (xy 380.718373 -32.854675) (xy 380.767831 -32.83217) (xy 380.819982 -32.81691)
			(xy 380.873771 -32.809205) (xy 380.90094 -32.808672) (xy 380.905512 -32.808672) (xy 380.921605 -32.809012)
			(xy 380.953652 -32.812066) (xy 380.96952 -32.814768) (xy 380.976886 -32.816038) (xy 381.016226 -32.791744)
			(xy 381.098591 -32.749717) (xy 381.184493 -32.715495) (xy 381.273195 -32.689373) (xy 381.363933 -32.671575)
			(xy 381.45593 -32.662254) (xy 381.502158 -32.661352) (xy 381.51435 -32.661352) (xy 381.560967 -32.662083)
			(xy 381.653763 -32.671164) (xy 381.745306 -32.688868) (xy 381.834797 -32.71504) (xy 381.921454 -32.749453)
			(xy 382.00452 -32.791804) (xy 382.044194 -32.816292) (xy 382.050544 -32.815022) (xy 382.053338 -32.814514)
			(xy 382.053846 -32.814514) (xy 382.059688 -32.813498) (xy 382.06172 -32.81299) (xy 382.065784 -32.812482)
			(xy 382.0668 -32.812482) (xy 382.080879 -32.810536) (xy 382.10923 -32.808502) (xy 382.123442 -32.808418)
			(xy 382.12522 -32.808418) (xy 382.162304 -32.810704) (xy 382.181219 -32.813008) (xy 382.2185 -32.820894)
			(xy 382.236726 -32.826452) (xy 382.237234 -32.826452) (xy 382.237742 -32.826706) (xy 382.240028 -32.827468)
			(xy 382.244854 -32.828992) (xy 382.25476 -32.830262) (xy 382.263187 -32.830591) (xy 382.279525 -32.826457)
			(xy 382.286764 -32.822134) (xy 382.326134 -32.79394) (xy 382.326642 -32.79394) (xy 382.355852 -32.772604)
			(xy 382.355852 -32.77235) (xy 382.359383 -32.769602) (xy 382.365512 -32.763085) (xy 382.368044 -32.759396)
			(xy 382.367536 -32.741108) (xy 382.367536 -32.722312) (xy 382.36797 -32.679725) (xy 382.375209 -32.59486)
			(xy 382.38966 -32.510922) (xy 382.411218 -32.428522) (xy 382.439726 -32.348261) (xy 382.456944 -32.309308)
			(xy 382.460128 -32.300175) (xy 382.460133 -32.280848) (xy 382.456944 -32.271716) (xy 382.439735 -32.23276)
			(xy 382.41124 -32.152496) (xy 382.389687 -32.070097) (xy 382.375234 -31.98616) (xy 382.367984 -31.901298)
			(xy 382.367536 -31.858712) (xy 382.367536 -31.85795) (xy 382.367633 -31.83939) (xy 382.369032 -31.802297)
			(xy 382.37033 -31.783782) (xy 382.3716 -31.765748) (xy 382.371092 -31.764732) (xy 382.369314 -31.761938)
			(xy 382.355852 -31.743904) (xy 382.351205 -31.738558) (xy 382.339607 -31.730435) (xy 382.332992 -31.727902)
			(xy 382.325372 -31.725362) (xy 382.311402 -31.724854) (xy 382.297432 -31.728664) (xy 382.29286 -31.73095)
			(xy 382.272794 -31.740094) (xy 382.266698 -31.742634) (xy 382.243419 -31.751853) (xy 382.195065 -31.764846)
			(xy 382.145428 -31.771418) (xy 382.120394 -31.771844) (xy 382.110234 -31.771844) (xy 382.08839 -31.770574)
			(xy 382.085596 -31.77032) (xy 382.050544 -31.767272) (xy 382.03505 -31.770828) (xy 382.027938 -31.775146)
			(xy 381.98891 -31.79822) (xy 381.907437 -31.838012) (xy 381.822686 -31.870238) (xy 381.735358 -31.894634)
			(xy 381.646176 -31.910996) (xy 381.555876 -31.91919) (xy 381.51054 -31.919672) (xy 381.470441 -31.919304)
			(xy 381.390498 -31.912924) (xy 381.311326 -31.90014) (xy 381.272288 -31.89097) (xy 381.243395 -31.883647)
			(xy 381.18646 -31.865983) (xy 381.158496 -31.855664) (xy 381.110951 -31.837072) (xy 381.019583 -31.791518)
			(xy 380.976124 -31.764732) (xy 380.965456 -31.76651) (xy 380.964948 -31.76651) (xy 380.926594 -31.771082)
			(xy 380.926086 -31.771082) (xy 380.92126 -31.771336) (xy 380.920752 -31.771336) (xy 380.906782 -31.771844)
			(xy 380.899924 -31.771844) (xy 380.872821 -31.771299) (xy 380.819178 -31.76349) (xy 380.767181 -31.748166)
			(xy 380.717876 -31.725637) (xy 380.672256 -31.696357) (xy 380.631239 -31.660914) (xy 380.595652 -31.620023)
			(xy 380.566211 -31.574506) (xy 380.543508 -31.525281) (xy 380.528001 -31.473338) (xy 380.520002 -31.419723)
			(xy 380.519432 -31.392622) (xy 380.519432 -31.389828) (xy 380.519924 -31.361597) (xy 380.528211 -31.305748)
			(xy 380.544637 -31.251729) (xy 380.556262 -31.225998) (xy 380.55804 -31.218632) (xy 380.544002 -31.171265)
			(xy 380.524239 -31.074463) (xy 380.514126 -30.976183) (xy 380.513336 -30.926786) (xy 380.513336 -30.922468)
			(xy 380.513772 -30.879882) (xy 380.521014 -30.795018) (xy 380.535469 -30.711081) (xy 380.55703 -30.628682)
			(xy 380.585541 -30.548424) (xy 380.602744 -30.509464) (xy 380.60592 -30.500331) (xy 380.605909 -30.48101)
			(xy 380.602744 -30.471872) (xy 380.585533 -30.432916) (xy 380.557033 -30.352653) (xy 380.535476 -30.270254)
			(xy 380.521018 -30.186317) (xy 380.513763 -30.101454) (xy 380.513336 -30.058868) (xy 380.513336 -30.05836)
			(xy 380.51398 -30.008319) (xy 380.524054 -29.908744) (xy 380.544036 -29.810675) (xy 380.558294 -29.762704)
			(xy 380.556516 -29.755084) (xy 380.55423 -29.750258) (xy 380.543222 -29.725168) (xy 380.527711 -29.672622)
			(xy 380.519889 -29.618394) (xy 380.519432 -29.591) (xy 380.519432 -29.590238) (xy 380.519893 -29.562984)
			(xy 380.527646 -29.509032) (xy 380.542999 -29.456731) (xy 380.56564 -29.407149) (xy 380.595107 -29.361294)
			(xy 380.630801 -29.3201) (xy 380.671996 -29.284406) (xy 380.717851 -29.254939) (xy 380.767433 -29.232298)
			(xy 380.819733 -29.216945) (xy 380.873686 -29.209193) (xy 380.90094 -29.20873) (xy 380.901956 -29.20873)
			(xy 380.918808 -29.208894) (xy 380.952385 -29.211821) (xy 380.969012 -29.214572) (xy 380.97714 -29.216096)
			(xy 381.017068 -29.191468) (xy 381.100706 -29.148965) (xy 381.187963 -29.114497) (xy 381.278069 -29.088367)
			(xy 381.37023 -29.070807) (xy 381.463631 -29.061971) (xy 381.51054 -29.06141) (xy 381.510794 -29.06141)
			(xy 381.557703 -29.061965) (xy 381.651104 -29.070804) (xy 381.743263 -29.088367) (xy 381.833369 -29.114499)
			(xy 381.920625 -29.14897) (xy 382.004262 -29.191475) (xy 382.044194 -29.216096) (xy 382.04521 -29.215842)
			(xy 382.05029 -29.214826) (xy 382.052068 -29.214572) (xy 382.068945 -29.211773) (xy 382.103033 -29.208852)
			(xy 382.12014 -29.20873) (xy 382.120902 -29.20873) (xy 382.149343 -29.209316) (xy 382.205582 -29.217866)
			(xy 382.232916 -29.225748) (xy 382.240282 -29.228034) (xy 382.263396 -29.228034) (xy 382.269135 -29.227832)
			(xy 382.280298 -29.225145) (xy 382.285494 -29.2227) (xy 382.286764 -29.222192) (xy 382.288034 -29.22143)
			(xy 382.289304 -29.220668) (xy 382.29159 -29.219398) (xy 382.312926 -29.20365) (xy 382.313688 -29.203142)
			(xy 382.336802 -29.186378) (xy 382.354074 -29.173932) (xy 382.356106 -29.172408) (xy 382.357122 -29.171646)
			(xy 382.360284 -29.169014) (xy 382.365766 -29.16288) (xy 382.368044 -29.159454) (xy 382.367536 -29.137356)
			(xy 382.367536 -29.12237) (xy 382.367972 -29.079784) (xy 382.375214 -28.99492) (xy 382.389668 -28.910983)
			(xy 382.411229 -28.828584) (xy 382.43974 -28.748325) (xy 382.456944 -28.709366) (xy 382.460121 -28.700233)
			(xy 382.46011 -28.680912) (xy 382.456944 -28.671774) (xy 382.439733 -28.632818) (xy 382.411233 -28.552555)
			(xy 382.389675 -28.470156) (xy 382.375217 -28.386219) (xy 382.367963 -28.301356) (xy 382.367536 -28.25877)
			(xy 382.368024 -28.211623) (xy 382.376798 -28.117738) (xy 382.385062 -28.071318) (xy 382.38871 -28.052831)
			(xy 382.39722 -28.016118) (xy 382.40208 -27.997912) (xy 382.41224 -27.96286) (xy 382.41224 -27.962606)
			(xy 382.410462 -27.954224) (xy 382.408176 -27.949144) (xy 382.407922 -27.948636) (xy 382.397379 -27.924428)
			(xy 382.382323 -27.873818) (xy 382.374405 -27.821613) (xy 382.373632 -27.79522) (xy 382.373632 -27.789886)
			(xy 382.374133 -27.762646) (xy 382.381914 -27.708723) (xy 382.397288 -27.656457) (xy 382.419942 -27.606909)
			(xy 382.449415 -27.561088) (xy 382.485107 -27.519927) (xy 382.526292 -27.484263) (xy 382.572132 -27.45482)
			(xy 382.621695 -27.432199) (xy 382.673972 -27.41686) (xy 382.727899 -27.409115) (xy 382.75514 -27.408632)
			(xy 382.771865 -27.408812) (xy 382.805187 -27.411738) (xy 382.821688 -27.414474) (xy 382.83134 -27.415998)
			(xy 382.883156 -27.385264) (xy 382.883664 -27.385264) (xy 382.89611 -27.378152) (xy 382.89992 -27.368754)
			(xy 382.919732 -27.295348) (xy 382.919478 -27.281632) (xy 382.9177 -27.275028) (xy 382.913382 -27.259534)
			(xy 382.910334 -27.2542) (xy 382.89864 -27.232664) (xy 382.880224 -27.187249) (xy 382.867765 -27.139852)
			(xy 382.861468 -27.091251) (xy 382.861058 -27.066748) (xy 382.861058 -27.057604) (xy 382.861312 -27.05354)
			(xy 382.861312 -27.052778) (xy 382.863598 -27.022552) (xy 382.866703 -26.998918) (xy 382.878051 -26.952621)
			(xy 382.895098 -26.908105) (xy 382.906016 -26.886916) (xy 382.918846 -26.8638) (xy 382.949918 -26.821025)
			(xy 382.9866 -26.782951) (xy 383.007108 -26.766266) (xy 383.00914 -26.764742) (xy 383.016252 -26.757884)
			(xy 383.029206 -26.742136) (xy 383.031746 -26.736802) (xy 383.034286 -26.725118) (xy 383.030222 -26.647394)
			(xy 383.029714 -26.634948) (xy 383.011426 -26.603452) (xy 383.006854 -26.59888) (xy 382.995678 -26.58745)
			(xy 382.989328 -26.583132) (xy 382.967431 -26.567858) (xy 382.927725 -26.532168) (xy 382.893378 -26.491295)
			(xy 382.865061 -26.446035) (xy 382.843325 -26.397272) (xy 382.828595 -26.345956) (xy 382.821158 -26.293088)
			(xy 382.820672 -26.266394) (xy 382.821158 -26.239143) (xy 382.828914 -26.185195) (xy 382.844269 -26.1329)
			(xy 382.866911 -26.083323) (xy 382.896377 -26.037473) (xy 382.932068 -25.996282) (xy 382.973259 -25.960591)
			(xy 383.019109 -25.931125) (xy 383.068686 -25.908483) (xy 383.120981 -25.893128) (xy 383.174929 -25.885372)
			(xy 383.229431 -25.885372) (xy 383.283379 -25.893128) (xy 383.335674 -25.908483) (xy 383.385251 -25.931125)
			(xy 383.431101 -25.960591) (xy 383.472292 -25.996282) (xy 383.507983 -26.037473) (xy 383.537449 -26.083323)
			(xy 383.560091 -26.1329) (xy 383.575446 -26.185195) (xy 383.583202 -26.239143) (xy 383.583688 -26.266394)
			(xy 383.583136 -26.295552) (xy 383.574264 -26.353188) (xy 383.556726 -26.408804) (xy 383.530929 -26.461104)
			(xy 383.497476 -26.508869) (xy 383.457144 -26.550989) (xy 383.434336 -26.569162) (xy 383.431542 -26.571194)
			(xy 383.424938 -26.577798) (xy 383.420366 -26.58364) (xy 383.416292 -26.589981) (xy 383.411641 -26.604309)
			(xy 383.411222 -26.611834) (xy 383.415032 -26.69667) (xy 383.419858 -26.706068) (xy 383.420874 -26.708354)
			(xy 383.429764 -26.72334) (xy 383.43332 -26.729182) (xy 383.449068 -26.745438) (xy 383.455418 -26.749756)
			(xy 383.477276 -26.764969) (xy 383.516923 -26.800524) (xy 383.551235 -26.841252) (xy 383.579544 -26.886358)
			(xy 383.601299 -26.934967) (xy 383.616077 -26.98613) (xy 383.623589 -27.038852) (xy 383.624074 -27.065478)
			(xy 383.624074 -27.072082) (xy 383.62317 -27.101233) (xy 383.6136 -27.158761) (xy 383.605024 -27.186636)
			(xy 383.603246 -27.191716) (xy 383.601976 -27.204162) (xy 383.60185 -27.207943) (xy 383.602621 -27.215468)
			(xy 383.6035 -27.219148) (xy 383.605532 -27.225244) (xy 383.640838 -27.29611) (xy 383.641854 -27.297634)
			(xy 383.644648 -27.30119) (xy 383.663698 -27.307286) (xy 383.701007 -27.319399) (xy 383.759194 -27.342846)
			(xy 390.823704 -27.342846) (xy 390.823704 -26.479246) (xy 390.824194 -26.449278) (xy 390.832017 -26.389856)
			(xy 390.84753 -26.331963) (xy 390.870466 -26.27659) (xy 390.900433 -26.224684) (xy 390.93692 -26.177134)
			(xy 390.9793 -26.134754) (xy 391.02685 -26.098267) (xy 391.078756 -26.0683) (xy 391.134129 -26.045364)
			(xy 391.192022 -26.029851) (xy 391.251444 -26.022028) (xy 391.31138 -26.022028) (xy 391.370802 -26.029851)
			(xy 391.428695 -26.045364) (xy 391.484068 -26.0683) (xy 391.535974 -26.098267) (xy 391.583524 -26.134754)
			(xy 391.625904 -26.177134) (xy 391.662391 -26.224684) (xy 391.692358 -26.27659) (xy 391.715294 -26.331963)
			(xy 391.723043 -26.360882) (xy 393.38961 -26.360882) (xy 393.393681 -26.30526) (xy 393.405807 -26.250823)
			(xy 393.42573 -26.198732) (xy 393.453026 -26.150097) (xy 393.487112 -26.105954) (xy 393.527261 -26.067245)
			(xy 393.572619 -26.034794) (xy 393.622219 -26.009293) (xy 393.675003 -25.991286) (xy 393.729846 -25.981156)
			(xy 393.78558 -25.979119) (xy 393.841017 -25.985219) (xy 393.894974 -25.999325) (xy 393.946303 -26.021137)
			(xy 393.993909 -26.050191) (xy 394.036777 -26.085866) (xy 394.073994 -26.127403) (xy 394.104767 -26.173916)
			(xy 394.128439 -26.224413) (xy 394.144507 -26.27782) (xy 394.150675 -26.319734) (xy 399.141948 -26.319734)
			(xy 399.146019 -26.264112) (xy 399.158145 -26.209675) (xy 399.178068 -26.157584) (xy 399.205364 -26.108949)
			(xy 399.23945 -26.064806) (xy 399.279599 -26.026097) (xy 399.324957 -25.993646) (xy 399.374557 -25.968145)
			(xy 399.427341 -25.950138) (xy 399.482184 -25.940008) (xy 399.537918 -25.937971) (xy 399.593355 -25.944071)
			(xy 399.647312 -25.958177) (xy 399.698641 -25.979989) (xy 399.746247 -26.009043) (xy 399.775912 -26.03373)
			(xy 405.567894 -26.03373) (xy 405.571965 -25.978108) (xy 405.584091 -25.923671) (xy 405.604014 -25.87158)
			(xy 405.63131 -25.822945) (xy 405.665396 -25.778802) (xy 405.705545 -25.740093) (xy 405.750903 -25.707642)
			(xy 405.800503 -25.682141) (xy 405.853287 -25.664134) (xy 405.90813 -25.654004) (xy 405.963864 -25.651967)
			(xy 406.019301 -25.658067) (xy 406.073258 -25.672173) (xy 406.124587 -25.693985) (xy 406.172193 -25.723039)
			(xy 406.215061 -25.758714) (xy 406.252278 -25.800251) (xy 406.283051 -25.846764) (xy 406.306723 -25.897261)
			(xy 406.322791 -25.950668) (xy 406.330911 -26.005844) (xy 406.33142 -26.03373) (xy 406.330911 -26.061616)
			(xy 406.322791 -26.116792) (xy 406.306723 -26.170199) (xy 406.283051 -26.220696) (xy 406.252278 -26.267209)
			(xy 406.215061 -26.308746) (xy 406.172193 -26.344421) (xy 406.124587 -26.373475) (xy 406.073258 -26.395287)
			(xy 406.019301 -26.409393) (xy 405.963864 -26.415493) (xy 405.90813 -26.413456) (xy 405.853287 -26.403326)
			(xy 405.800503 -26.385319) (xy 405.750903 -26.359818) (xy 405.705545 -26.327367) (xy 405.665396 -26.288658)
			(xy 405.63131 -26.244515) (xy 405.604014 -26.19588) (xy 405.584091 -26.143789) (xy 405.571965 -26.089352)
			(xy 405.567894 -26.03373) (xy 399.775912 -26.03373) (xy 399.789115 -26.044718) (xy 399.826332 -26.086255)
			(xy 399.857105 -26.132768) (xy 399.880777 -26.183265) (xy 399.896845 -26.236672) (xy 399.904965 -26.291848)
			(xy 399.905474 -26.319734) (xy 399.904965 -26.34762) (xy 399.896845 -26.402796) (xy 399.880777 -26.456203)
			(xy 399.857105 -26.5067) (xy 399.826332 -26.553213) (xy 399.789115 -26.59475) (xy 399.746247 -26.630425)
			(xy 399.698641 -26.659479) (xy 399.647312 -26.681291) (xy 399.593355 -26.695397) (xy 399.537918 -26.701497)
			(xy 399.482184 -26.69946) (xy 399.427341 -26.68933) (xy 399.374557 -26.671323) (xy 399.324957 -26.645822)
			(xy 399.279599 -26.613371) (xy 399.23945 -26.574662) (xy 399.205364 -26.530519) (xy 399.178068 -26.481884)
			(xy 399.158145 -26.429793) (xy 399.146019 -26.375356) (xy 399.141948 -26.319734) (xy 394.150675 -26.319734)
			(xy 394.152627 -26.332996) (xy 394.153136 -26.360882) (xy 394.152627 -26.388768) (xy 394.144507 -26.443944)
			(xy 394.128439 -26.497351) (xy 394.104767 -26.547848) (xy 394.073994 -26.594361) (xy 394.036777 -26.635898)
			(xy 393.993909 -26.671573) (xy 393.946303 -26.700627) (xy 393.894974 -26.722439) (xy 393.841017 -26.736545)
			(xy 393.78558 -26.742645) (xy 393.729846 -26.740608) (xy 393.675003 -26.730478) (xy 393.622219 -26.712471)
			(xy 393.572619 -26.68697) (xy 393.527261 -26.654519) (xy 393.487112 -26.61581) (xy 393.453026 -26.571667)
			(xy 393.42573 -26.523032) (xy 393.405807 -26.470941) (xy 393.393681 -26.416504) (xy 393.38961 -26.360882)
			(xy 391.723043 -26.360882) (xy 391.730807 -26.389856) (xy 391.73863 -26.449278) (xy 391.73912 -26.479246)
			(xy 391.73912 -26.971244) (xy 395.1511 -26.971244) (xy 395.155171 -26.915622) (xy 395.167297 -26.861185)
			(xy 395.18722 -26.809094) (xy 395.214516 -26.760459) (xy 395.248602 -26.716316) (xy 395.288751 -26.677607)
			(xy 395.334109 -26.645156) (xy 395.383709 -26.619655) (xy 395.436493 -26.601648) (xy 395.491336 -26.591518)
			(xy 395.54707 -26.589481) (xy 395.602507 -26.595581) (xy 395.656464 -26.609687) (xy 395.707793 -26.631499)
			(xy 395.755399 -26.660553) (xy 395.798267 -26.696228) (xy 395.835484 -26.737765) (xy 395.866257 -26.784278)
			(xy 395.889929 -26.834775) (xy 395.905997 -26.888182) (xy 395.914117 -26.943358) (xy 395.914626 -26.971244)
			(xy 395.914117 -26.99913) (xy 395.905997 -27.054306) (xy 395.889929 -27.107713) (xy 395.866257 -27.15821)
			(xy 395.835484 -27.204723) (xy 395.798267 -27.24626) (xy 395.755399 -27.281935) (xy 395.707793 -27.310989)
			(xy 395.656464 -27.332801) (xy 395.602507 -27.346907) (xy 395.54707 -27.353007) (xy 395.491336 -27.35097)
			(xy 395.436493 -27.34084) (xy 395.383709 -27.322833) (xy 395.334109 -27.297332) (xy 395.288751 -27.264881)
			(xy 395.248602 -27.226172) (xy 395.214516 -27.182029) (xy 395.18722 -27.133394) (xy 395.167297 -27.081303)
			(xy 395.155171 -27.026866) (xy 395.1511 -26.971244) (xy 391.73912 -26.971244) (xy 391.73912 -27.342846)
			(xy 391.73863 -27.372814) (xy 391.730807 -27.432236) (xy 391.715294 -27.490129) (xy 391.692358 -27.545502)
			(xy 391.662391 -27.597408) (xy 391.625904 -27.644958) (xy 391.583524 -27.687338) (xy 391.535974 -27.723825)
			(xy 391.484068 -27.753792) (xy 391.428695 -27.776728) (xy 391.370802 -27.792241) (xy 391.31138 -27.800064)
			(xy 391.251444 -27.800064) (xy 391.192022 -27.792241) (xy 391.134129 -27.776728) (xy 391.078756 -27.753792)
			(xy 391.02685 -27.723825) (xy 390.9793 -27.687338) (xy 390.93692 -27.644958) (xy 390.900433 -27.597408)
			(xy 390.870466 -27.545502) (xy 390.84753 -27.490129) (xy 390.832017 -27.432236) (xy 390.824194 -27.372814)
			(xy 390.823704 -27.342846) (xy 383.759194 -27.342846) (xy 383.773771 -27.34872) (xy 383.844002 -27.383676)
			(xy 383.87782 -27.403552) (xy 383.883649 -27.406866) (xy 383.896522 -27.410606) (xy 383.90322 -27.410918)
			(xy 383.909824 -27.410664) (xy 383.919509 -27.409654) (xy 383.93895 -27.408508) (xy 383.948686 -27.408378)
			(xy 383.949194 -27.408378) (xy 383.968244 -27.408886) (xy 383.977896 -27.409648) (xy 384.004903 -27.412183)
			(xy 384.057861 -27.423921) (xy 384.108623 -27.443038) (xy 384.156168 -27.46915) (xy 384.199536 -27.501731)
			(xy 384.237854 -27.540123) (xy 384.254502 -27.56154) (xy 384.256534 -27.56408) (xy 384.30093 -27.571475)
			(xy 384.388268 -27.593239) (xy 384.473291 -27.622782) (xy 384.555306 -27.659864) (xy 384.633648 -27.704183)
			(xy 384.707678 -27.75538) (xy 384.776796 -27.813038) (xy 384.808984 -27.844496) (xy 386.07896 -29.114242)
			(xy 393.147296 -29.114242) (xy 393.147296 -28.250642) (xy 393.147786 -28.220658) (xy 393.155614 -28.161202)
			(xy 393.171135 -28.103277) (xy 393.194084 -28.047873) (xy 393.224068 -27.995939) (xy 393.260574 -27.948363)
			(xy 393.302979 -27.905958) (xy 393.350555 -27.869452) (xy 393.402489 -27.839468) (xy 393.457893 -27.816519)
			(xy 393.515818 -27.800998) (xy 393.575274 -27.79317) (xy 393.635242 -27.79317) (xy 393.694698 -27.800998)
			(xy 393.752623 -27.816519) (xy 393.808027 -27.839468) (xy 393.859961 -27.869452) (xy 393.907537 -27.905958)
			(xy 393.949942 -27.948363) (xy 393.986448 -27.995939) (xy 394.016432 -28.047873) (xy 394.039381 -28.103277)
			(xy 394.054902 -28.161202) (xy 394.06273 -28.220658) (xy 394.06322 -28.250642) (xy 394.06322 -28.469082)
			(xy 398.052542 -28.469082) (xy 398.056613 -28.41346) (xy 398.068739 -28.359023) (xy 398.088662 -28.306932)
			(xy 398.115958 -28.258297) (xy 398.150044 -28.214154) (xy 398.190193 -28.175445) (xy 398.235551 -28.142994)
			(xy 398.285151 -28.117493) (xy 398.337935 -28.099486) (xy 398.392778 -28.089356) (xy 398.448512 -28.087319)
			(xy 398.503949 -28.093419) (xy 398.557906 -28.107525) (xy 398.609235 -28.129337) (xy 398.625291 -28.139136)
			(xy 402.697948 -28.139136) (xy 402.702019 -28.083514) (xy 402.714145 -28.029077) (xy 402.734068 -27.976986)
			(xy 402.761364 -27.928351) (xy 402.79545 -27.884208) (xy 402.835599 -27.845499) (xy 402.880957 -27.813048)
			(xy 402.930557 -27.787547) (xy 402.983341 -27.76954) (xy 403.038184 -27.75941) (xy 403.093918 -27.757373)
			(xy 403.149355 -27.763473) (xy 403.203312 -27.777579) (xy 403.254641 -27.799391) (xy 403.302247 -27.828445)
			(xy 403.345115 -27.86412) (xy 403.382332 -27.905657) (xy 403.413105 -27.95217) (xy 403.436777 -28.002667)
			(xy 403.452845 -28.056074) (xy 403.460965 -28.11125) (xy 403.461474 -28.139136) (xy 403.967948 -28.139136)
			(xy 403.972019 -28.083514) (xy 403.984145 -28.029077) (xy 404.004068 -27.976986) (xy 404.031364 -27.928351)
			(xy 404.06545 -27.884208) (xy 404.105599 -27.845499) (xy 404.150957 -27.813048) (xy 404.200557 -27.787547)
			(xy 404.253341 -27.76954) (xy 404.308184 -27.75941) (xy 404.363918 -27.757373) (xy 404.419355 -27.763473)
			(xy 404.473312 -27.777579) (xy 404.524641 -27.799391) (xy 404.572247 -27.828445) (xy 404.615115 -27.86412)
			(xy 404.652332 -27.905657) (xy 404.683105 -27.95217) (xy 404.706777 -28.002667) (xy 404.722845 -28.056074)
			(xy 404.730965 -28.11125) (xy 404.731474 -28.139136) (xy 404.730965 -28.167022) (xy 404.722845 -28.222198)
			(xy 404.706777 -28.275605) (xy 404.683105 -28.326102) (xy 404.652332 -28.372615) (xy 404.615115 -28.414152)
			(xy 404.572247 -28.449827) (xy 404.524641 -28.478881) (xy 404.473312 -28.500693) (xy 404.419355 -28.514799)
			(xy 404.363918 -28.520899) (xy 404.308184 -28.518862) (xy 404.253341 -28.508732) (xy 404.200557 -28.490725)
			(xy 404.150957 -28.465224) (xy 404.105599 -28.432773) (xy 404.06545 -28.394064) (xy 404.031364 -28.349921)
			(xy 404.004068 -28.301286) (xy 403.984145 -28.249195) (xy 403.972019 -28.194758) (xy 403.967948 -28.139136)
			(xy 403.461474 -28.139136) (xy 403.460965 -28.167022) (xy 403.452845 -28.222198) (xy 403.436777 -28.275605)
			(xy 403.413105 -28.326102) (xy 403.382332 -28.372615) (xy 403.345115 -28.414152) (xy 403.302247 -28.449827)
			(xy 403.254641 -28.478881) (xy 403.203312 -28.500693) (xy 403.149355 -28.514799) (xy 403.093918 -28.520899)
			(xy 403.038184 -28.518862) (xy 402.983341 -28.508732) (xy 402.930557 -28.490725) (xy 402.880957 -28.465224)
			(xy 402.835599 -28.432773) (xy 402.79545 -28.394064) (xy 402.761364 -28.349921) (xy 402.734068 -28.301286)
			(xy 402.714145 -28.249195) (xy 402.702019 -28.194758) (xy 402.697948 -28.139136) (xy 398.625291 -28.139136)
			(xy 398.656841 -28.158391) (xy 398.699709 -28.194066) (xy 398.736926 -28.235603) (xy 398.767699 -28.282116)
			(xy 398.791371 -28.332613) (xy 398.807439 -28.38602) (xy 398.815559 -28.441196) (xy 398.816068 -28.469082)
			(xy 398.815559 -28.496968) (xy 398.807439 -28.552144) (xy 398.791371 -28.605551) (xy 398.767699 -28.656048)
			(xy 398.736926 -28.702561) (xy 398.699709 -28.744098) (xy 398.656841 -28.779773) (xy 398.609235 -28.808827)
			(xy 398.557906 -28.830639) (xy 398.503949 -28.844745) (xy 398.448512 -28.850845) (xy 398.392778 -28.848808)
			(xy 398.337935 -28.838678) (xy 398.285151 -28.820671) (xy 398.235551 -28.79517) (xy 398.190193 -28.762719)
			(xy 398.150044 -28.72401) (xy 398.115958 -28.679867) (xy 398.088662 -28.631232) (xy 398.068739 -28.579141)
			(xy 398.056613 -28.524704) (xy 398.052542 -28.469082) (xy 394.06322 -28.469082) (xy 394.06322 -29.114242)
			(xy 394.06273 -29.144226) (xy 394.054902 -29.203682) (xy 394.039381 -29.261607) (xy 394.016432 -29.317011)
			(xy 393.986448 -29.368945) (xy 393.949942 -29.416521) (xy 393.907537 -29.458926) (xy 393.859961 -29.495432)
			(xy 393.808027 -29.525416) (xy 393.752623 -29.548365) (xy 393.694698 -29.563886) (xy 393.635242 -29.571714)
			(xy 393.575274 -29.571714) (xy 393.515818 -29.563886) (xy 393.457893 -29.548365) (xy 393.402489 -29.525416)
			(xy 393.350555 -29.495432) (xy 393.302979 -29.458926) (xy 393.260574 -29.416521) (xy 393.224068 -29.368945)
			(xy 393.194084 -29.317011) (xy 393.171135 -29.261607) (xy 393.155614 -29.203682) (xy 393.147786 -29.144226)
			(xy 393.147296 -29.114242) (xy 386.07896 -29.114242) (xy 386.211064 -29.246322) (xy 386.214112 -29.247846)
			(xy 386.21716 -29.24937) (xy 386.218176 -29.249878) (xy 386.244666 -29.263993) (xy 386.293232 -29.299262)
			(xy 386.335678 -29.341699) (xy 386.370959 -29.390256) (xy 386.385054 -29.416756) (xy 386.385562 -29.417772)
			(xy 386.387086 -29.42082) (xy 386.38861 -29.423868) (xy 386.50799 -29.543248) (xy 387.707886 -30.743398)
			(xy 387.732546 -30.768434) (xy 387.778688 -30.821443) (xy 387.800088 -30.849316) (xy 387.815237 -30.869694)
			(xy 387.843699 -30.911751) (xy 387.849187 -30.92069) (xy 395.789404 -30.92069) (xy 395.789404 -30.05709)
			(xy 395.789894 -30.027106) (xy 395.797722 -29.96765) (xy 395.813243 -29.909725) (xy 395.836192 -29.854321)
			(xy 395.866176 -29.802387) (xy 395.902682 -29.754811) (xy 395.945087 -29.712406) (xy 395.992663 -29.6759)
			(xy 396.044597 -29.645916) (xy 396.100001 -29.622967) (xy 396.157926 -29.607446) (xy 396.217382 -29.599618)
			(xy 396.27735 -29.599618) (xy 396.336806 -29.607446) (xy 396.394731 -29.622967) (xy 396.450135 -29.645916)
			(xy 396.502069 -29.6759) (xy 396.549645 -29.712406) (xy 396.59205 -29.754811) (xy 396.628556 -29.802387)
			(xy 396.65854 -29.854321) (xy 396.681489 -29.909725) (xy 396.69701 -29.96765) (xy 396.704838 -30.027106)
			(xy 396.705328 -30.05709) (xy 396.705328 -30.376876) (xy 401.188936 -30.376876) (xy 401.189496 -30.34796)
			(xy 401.198214 -30.290791) (xy 401.215463 -30.235592) (xy 401.240847 -30.18363) (xy 401.273784 -30.136095)
			(xy 401.313519 -30.094077) (xy 401.336002 -30.075886) (xy 401.344806 -30.068275) (xy 401.354991 -30.047377)
			(xy 401.35556 -30.035754) (xy 401.35556 -29.955998) (xy 401.355022 -29.944366) (xy 401.344834 -29.923455)
			(xy 401.336002 -29.915866) (xy 401.313503 -29.897694) (xy 401.273768 -29.85567) (xy 401.240831 -29.808131)
			(xy 401.215445 -29.756166) (xy 401.198193 -29.700965) (xy 401.189468 -29.643793) (xy 401.188936 -29.614876)
			(xy 401.189422 -29.587625) (xy 401.197178 -29.533677) (xy 401.212533 -29.481382) (xy 401.235175 -29.431805)
			(xy 401.264641 -29.385955) (xy 401.300332 -29.344764) (xy 401.341523 -29.309073) (xy 401.387373 -29.279607)
			(xy 401.43695 -29.256965) (xy 401.489245 -29.24161) (xy 401.543193 -29.233854) (xy 401.597695 -29.233854)
			(xy 401.651643 -29.24161) (xy 401.703938 -29.256965) (xy 401.753515 -29.279607) (xy 401.799365 -29.309073)
			(xy 401.840556 -29.344764) (xy 401.876247 -29.385955) (xy 401.905713 -29.431805) (xy 401.928355 -29.481382)
			(xy 401.94371 -29.533677) (xy 401.951466 -29.587625) (xy 401.951952 -29.614876) (xy 401.951435 -29.643793)
			(xy 401.942708 -29.700965) (xy 401.925451 -29.756165) (xy 401.900059 -29.808127) (xy 401.867115 -29.855661)
			(xy 401.827372 -29.897677) (xy 401.804886 -29.915866) (xy 401.796102 -29.923496) (xy 401.785906 -29.944379)
			(xy 401.785328 -29.955998) (xy 401.785328 -30.035754) (xy 401.785841 -30.047389) (xy 401.796047 -30.068299)
			(xy 401.804886 -30.075886) (xy 401.82736 -30.094088) (xy 401.867096 -30.136105) (xy 401.900037 -30.183638)
			(xy 401.925427 -30.235597) (xy 401.942685 -30.290793) (xy 401.951416 -30.347961) (xy 401.951952 -30.376876)
			(xy 404.229062 -30.376876) (xy 404.229612 -30.34796) (xy 404.238331 -30.290789) (xy 404.255581 -30.23559)
			(xy 404.280967 -30.183628) (xy 404.313906 -30.136093) (xy 404.353644 -30.094076) (xy 404.376128 -30.075886)
			(xy 404.384936 -30.06828) (xy 404.395118 -30.047378) (xy 404.395686 -30.035754) (xy 404.395686 -29.955998)
			(xy 404.395138 -29.944367) (xy 404.384956 -29.923457) (xy 404.376128 -29.915866) (xy 404.353634 -29.897687)
			(xy 404.313898 -29.855666) (xy 404.28096 -29.808129) (xy 404.255573 -29.756165) (xy 404.238319 -29.700965)
			(xy 404.229594 -29.643793) (xy 404.229062 -29.614876) (xy 404.229548 -29.587625) (xy 404.237304 -29.533677)
			(xy 404.252659 -29.481382) (xy 404.275301 -29.431805) (xy 404.304767 -29.385955) (xy 404.340458 -29.344764)
			(xy 404.381649 -29.309073) (xy 404.427499 -29.279607) (xy 404.477076 -29.256965) (xy 404.529371 -29.24161)
			(xy 404.583319 -29.233854) (xy 404.637821 -29.233854) (xy 404.691769 -29.24161) (xy 404.744064 -29.256965)
			(xy 404.793641 -29.279607) (xy 404.839491 -29.309073) (xy 404.880682 -29.344764) (xy 404.916373 -29.385955)
			(xy 404.945839 -29.431805) (xy 404.968481 -29.481382) (xy 404.983836 -29.533677) (xy 404.991592 -29.587625)
			(xy 404.992078 -29.614876) (xy 404.991551 -29.643793) (xy 404.982825 -29.700964) (xy 404.965569 -29.756163)
			(xy 404.940179 -29.808125) (xy 404.907237 -29.855659) (xy 404.867497 -29.897676) (xy 404.845012 -29.915866)
			(xy 404.836232 -29.9235) (xy 404.826033 -29.94438) (xy 404.825454 -29.955998) (xy 404.825454 -30.035754)
			(xy 404.825957 -30.047391) (xy 404.83617 -30.068301) (xy 404.845012 -30.075886) (xy 404.867491 -30.094082)
			(xy 404.907226 -30.136101) (xy 404.940165 -30.183635) (xy 404.965554 -30.235595) (xy 404.982812 -30.290792)
			(xy 404.991542 -30.34796) (xy 404.992078 -30.376876) (xy 404.991592 -30.404127) (xy 404.983836 -30.458075)
			(xy 404.968481 -30.51037) (xy 404.945839 -30.559947) (xy 404.916373 -30.605797) (xy 404.880682 -30.646988)
			(xy 404.839491 -30.682679) (xy 404.793641 -30.712145) (xy 404.744064 -30.734787) (xy 404.691769 -30.750142)
			(xy 404.637821 -30.757898) (xy 404.583319 -30.757898) (xy 404.529371 -30.750142) (xy 404.477076 -30.734787)
			(xy 404.427499 -30.712145) (xy 404.381649 -30.682679) (xy 404.340458 -30.646988) (xy 404.304767 -30.605797)
			(xy 404.275301 -30.559947) (xy 404.252659 -30.51037) (xy 404.237304 -30.458075) (xy 404.229548 -30.404127)
			(xy 404.229062 -30.376876) (xy 401.951952 -30.376876) (xy 401.951466 -30.404127) (xy 401.94371 -30.458075)
			(xy 401.928355 -30.51037) (xy 401.905713 -30.559947) (xy 401.876247 -30.605797) (xy 401.840556 -30.646988)
			(xy 401.799365 -30.682679) (xy 401.753515 -30.712145) (xy 401.703938 -30.734787) (xy 401.651643 -30.750142)
			(xy 401.597695 -30.757898) (xy 401.543193 -30.757898) (xy 401.489245 -30.750142) (xy 401.43695 -30.734787)
			(xy 401.387373 -30.712145) (xy 401.341523 -30.682679) (xy 401.300332 -30.646988) (xy 401.264641 -30.605797)
			(xy 401.235175 -30.559947) (xy 401.212533 -30.51037) (xy 401.197178 -30.458075) (xy 401.189422 -30.404127)
			(xy 401.188936 -30.376876) (xy 396.705328 -30.376876) (xy 396.705328 -30.92069) (xy 396.704838 -30.950674)
			(xy 396.69701 -31.01013) (xy 396.681489 -31.068055) (xy 396.65854 -31.123459) (xy 396.628556 -31.175393)
			(xy 396.59205 -31.222969) (xy 396.549645 -31.265374) (xy 396.502069 -31.30188) (xy 396.450135 -31.331864)
			(xy 396.394731 -31.354813) (xy 396.336806 -31.370334) (xy 396.27735 -31.378162) (xy 396.217382 -31.378162)
			(xy 396.157926 -31.370334) (xy 396.100001 -31.354813) (xy 396.044597 -31.331864) (xy 395.992663 -31.30188)
			(xy 395.945087 -31.265374) (xy 395.902682 -31.222969) (xy 395.866176 -31.175393) (xy 395.836192 -31.123459)
			(xy 395.813243 -31.068055) (xy 395.797722 -31.01013) (xy 395.789894 -30.950674) (xy 395.789404 -30.92069)
			(xy 387.849187 -30.92069) (xy 387.856984 -30.93339) (xy 387.858 -30.935168) (xy 387.864096 -30.94355)
			(xy 387.877932 -30.958748) (xy 387.904482 -30.990128) (xy 387.917182 -31.006288) (xy 387.930285 -31.023208)
			(xy 387.955187 -31.058017) (xy 387.966966 -31.075884) (xy 387.983476 -31.1023) (xy 387.984492 -31.104332)
			(xy 387.986016 -31.106618) (xy 387.992112 -31.116778) (xy 388.00024 -31.130748) (xy 388.00024 -31.131002)
			(xy 388.006336 -31.142178) (xy 388.007352 -31.14421) (xy 388.019309 -31.166691) (xy 388.041163 -31.212688)
			(xy 388.05104 -31.236158) (xy 388.65683 -32.69869) (xy 388.663283 -32.714184) (xy 393.147296 -32.714184)
			(xy 393.147296 -31.850584) (xy 393.147786 -31.8206) (xy 393.155614 -31.761144) (xy 393.171135 -31.703219)
			(xy 393.194084 -31.647815) (xy 393.224068 -31.595881) (xy 393.260574 -31.548305) (xy 393.302979 -31.5059)
			(xy 393.350555 -31.469394) (xy 393.402489 -31.43941) (xy 393.457893 -31.416461) (xy 393.515818 -31.40094)
			(xy 393.575274 -31.393112) (xy 393.635242 -31.393112) (xy 393.694698 -31.40094) (xy 393.752623 -31.416461)
			(xy 393.808027 -31.43941) (xy 393.859961 -31.469394) (xy 393.907537 -31.5059) (xy 393.949942 -31.548305)
			(xy 393.964964 -31.567882) (xy 401.298662 -31.567882) (xy 401.302733 -31.51226) (xy 401.314859 -31.457823)
			(xy 401.334782 -31.405732) (xy 401.362078 -31.357097) (xy 401.396164 -31.312954) (xy 401.436313 -31.274245)
			(xy 401.481671 -31.241794) (xy 401.531271 -31.216293) (xy 401.584055 -31.198286) (xy 401.638898 -31.188156)
			(xy 401.694632 -31.186119) (xy 401.750069 -31.192219) (xy 401.804026 -31.206325) (xy 401.855355 -31.228137)
			(xy 401.902961 -31.257191) (xy 401.945829 -31.292866) (xy 401.983046 -31.334403) (xy 402.013819 -31.380916)
			(xy 402.037491 -31.431413) (xy 402.053559 -31.48482) (xy 402.061679 -31.539996) (xy 402.062188 -31.567882)
			(xy 402.061679 -31.595768) (xy 402.053559 -31.650944) (xy 402.037491 -31.704351) (xy 402.030499 -31.719266)
			(xy 402.585426 -31.719266) (xy 402.589497 -31.663644) (xy 402.601623 -31.609207) (xy 402.621546 -31.557116)
			(xy 402.648842 -31.508481) (xy 402.682928 -31.464338) (xy 402.723077 -31.425629) (xy 402.768435 -31.393178)
			(xy 402.818035 -31.367677) (xy 402.870819 -31.34967) (xy 402.925662 -31.33954) (xy 402.981396 -31.337503)
			(xy 403.036833 -31.343603) (xy 403.09079 -31.357709) (xy 403.142119 -31.379521) (xy 403.189725 -31.408575)
			(xy 403.232593 -31.44425) (xy 403.26981 -31.485787) (xy 403.300583 -31.5323) (xy 403.324255 -31.582797)
			(xy 403.340323 -31.636204) (xy 403.344473 -31.664402) (xy 403.861014 -31.664402) (xy 403.865085 -31.60878)
			(xy 403.877211 -31.554343) (xy 403.897134 -31.502252) (xy 403.92443 -31.453617) (xy 403.958516 -31.409474)
			(xy 403.998665 -31.370765) (xy 404.044023 -31.338314) (xy 404.093623 -31.312813) (xy 404.146407 -31.294806)
			(xy 404.20125 -31.284676) (xy 404.256984 -31.282639) (xy 404.312421 -31.288739) (xy 404.366378 -31.302845)
			(xy 404.417707 -31.324657) (xy 404.465313 -31.353711) (xy 404.508181 -31.389386) (xy 404.545398 -31.430923)
			(xy 404.576171 -31.477436) (xy 404.599843 -31.527933) (xy 404.615911 -31.58134) (xy 404.624031 -31.636516)
			(xy 404.62454 -31.664402) (xy 404.624031 -31.692288) (xy 404.615911 -31.747464) (xy 404.606971 -31.777178)
			(xy 405.126188 -31.777178) (xy 405.130259 -31.721556) (xy 405.142385 -31.667119) (xy 405.162308 -31.615028)
			(xy 405.189604 -31.566393) (xy 405.22369 -31.52225) (xy 405.263839 -31.483541) (xy 405.309197 -31.45109)
			(xy 405.358797 -31.425589) (xy 405.411581 -31.407582) (xy 405.466424 -31.397452) (xy 405.522158 -31.395415)
			(xy 405.577595 -31.401515) (xy 405.631552 -31.415621) (xy 405.682881 -31.437433) (xy 405.730487 -31.466487)
			(xy 405.773355 -31.502162) (xy 405.810572 -31.543699) (xy 405.841345 -31.590212) (xy 405.865017 -31.640709)
			(xy 405.881085 -31.694116) (xy 405.889205 -31.749292) (xy 405.889714 -31.777178) (xy 405.889205 -31.805064)
			(xy 405.881085 -31.86024) (xy 405.865017 -31.913647) (xy 405.841345 -31.964144) (xy 405.810572 -32.010657)
			(xy 405.773355 -32.052194) (xy 405.730487 -32.087869) (xy 405.682881 -32.116923) (xy 405.631552 -32.138735)
			(xy 405.577595 -32.152841) (xy 405.522158 -32.158941) (xy 405.466424 -32.156904) (xy 405.411581 -32.146774)
			(xy 405.358797 -32.128767) (xy 405.309197 -32.103266) (xy 405.263839 -32.070815) (xy 405.22369 -32.032106)
			(xy 405.189604 -31.987963) (xy 405.162308 -31.939328) (xy 405.142385 -31.887237) (xy 405.130259 -31.8328)
			(xy 405.126188 -31.777178) (xy 404.606971 -31.777178) (xy 404.599843 -31.800871) (xy 404.576171 -31.851368)
			(xy 404.545398 -31.897881) (xy 404.508181 -31.939418) (xy 404.465313 -31.975093) (xy 404.417707 -32.004147)
			(xy 404.366378 -32.025959) (xy 404.312421 -32.040065) (xy 404.256984 -32.046165) (xy 404.20125 -32.044128)
			(xy 404.146407 -32.033998) (xy 404.093623 -32.015991) (xy 404.044023 -31.99049) (xy 403.998665 -31.958039)
			(xy 403.958516 -31.91933) (xy 403.92443 -31.875187) (xy 403.897134 -31.826552) (xy 403.877211 -31.774461)
			(xy 403.865085 -31.720024) (xy 403.861014 -31.664402) (xy 403.344473 -31.664402) (xy 403.348443 -31.69138)
			(xy 403.348952 -31.719266) (xy 403.348443 -31.747152) (xy 403.340323 -31.802328) (xy 403.324255 -31.855735)
			(xy 403.300583 -31.906232) (xy 403.26981 -31.952745) (xy 403.232593 -31.994282) (xy 403.189725 -32.029957)
			(xy 403.142119 -32.059011) (xy 403.09079 -32.080823) (xy 403.036833 -32.094929) (xy 402.981396 -32.101029)
			(xy 402.925662 -32.098992) (xy 402.870819 -32.088862) (xy 402.818035 -32.070855) (xy 402.768435 -32.045354)
			(xy 402.723077 -32.012903) (xy 402.682928 -31.974194) (xy 402.648842 -31.930051) (xy 402.621546 -31.881416)
			(xy 402.601623 -31.829325) (xy 402.589497 -31.774888) (xy 402.585426 -31.719266) (xy 402.030499 -31.719266)
			(xy 402.013819 -31.754848) (xy 401.983046 -31.801361) (xy 401.945829 -31.842898) (xy 401.902961 -31.878573)
			(xy 401.855355 -31.907627) (xy 401.804026 -31.929439) (xy 401.750069 -31.943545) (xy 401.694632 -31.949645)
			(xy 401.638898 -31.947608) (xy 401.584055 -31.937478) (xy 401.531271 -31.919471) (xy 401.481671 -31.89397)
			(xy 401.436313 -31.861519) (xy 401.396164 -31.82281) (xy 401.362078 -31.778667) (xy 401.334782 -31.730032)
			(xy 401.314859 -31.677941) (xy 401.302733 -31.623504) (xy 401.298662 -31.567882) (xy 393.964964 -31.567882)
			(xy 393.986448 -31.595881) (xy 394.016432 -31.647815) (xy 394.039381 -31.703219) (xy 394.054902 -31.761144)
			(xy 394.06273 -31.8206) (xy 394.06322 -31.850584) (xy 394.06322 -32.714184) (xy 394.06273 -32.744168)
			(xy 394.054902 -32.803624) (xy 394.039381 -32.861549) (xy 394.016432 -32.916953) (xy 393.986448 -32.968887)
			(xy 393.949942 -33.016463) (xy 393.907537 -33.058868) (xy 393.859961 -33.095374) (xy 393.808027 -33.125358)
			(xy 393.752623 -33.148307) (xy 393.694698 -33.163828) (xy 393.635242 -33.171656) (xy 393.575274 -33.171656)
			(xy 393.515818 -33.163828) (xy 393.457893 -33.148307) (xy 393.402489 -33.125358) (xy 393.350555 -33.095374)
			(xy 393.302979 -33.058868) (xy 393.260574 -33.016463) (xy 393.224068 -32.968887) (xy 393.194084 -32.916953)
			(xy 393.171135 -32.861549) (xy 393.155614 -32.803624) (xy 393.147786 -32.744168) (xy 393.147296 -32.714184)
			(xy 388.663283 -32.714184) (xy 388.700518 -32.803592) (xy 388.700518 -32.8041) (xy 388.714234 -32.836104)
			(xy 388.721346 -32.846518) (xy 388.726426 -32.85236) (xy 388.734554 -32.856932) (xy 388.759592 -32.871503)
			(xy 388.805347 -32.907031) (xy 388.845205 -32.949067) (xy 388.878251 -32.996646) (xy 388.903724 -33.048673)
			(xy 388.92104 -33.103953) (xy 388.9298 -33.161216) (xy 388.930388 -33.19018) (xy 388.930076 -33.216082)
			(xy 388.923325 -33.267441) (xy 388.916926 -33.292542) (xy 388.915656 -33.297114) (xy 388.914894 -33.306004)
			(xy 388.914894 -33.306766) (xy 388.913878 -33.318704) (xy 389.022844 -33.581594) (xy 389.411766 -34.520886)
			(xy 395.789404 -34.520886) (xy 395.789404 -33.657286) (xy 395.789894 -33.627302) (xy 395.797722 -33.567846)
			(xy 395.813243 -33.509921) (xy 395.836192 -33.454517) (xy 395.866176 -33.402583) (xy 395.902682 -33.355007)
			(xy 395.945087 -33.312602) (xy 395.992663 -33.276096) (xy 396.044597 -33.246112) (xy 396.100001 -33.223163)
			(xy 396.157926 -33.207642) (xy 396.217382 -33.199814) (xy 396.27735 -33.199814) (xy 396.336806 -33.207642)
			(xy 396.394731 -33.223163) (xy 396.450135 -33.246112) (xy 396.502069 -33.276096) (xy 396.549645 -33.312602)
			(xy 396.59205 -33.355007) (xy 396.628556 -33.402583) (xy 396.65854 -33.454517) (xy 396.681489 -33.509921)
			(xy 396.69701 -33.567846) (xy 396.704838 -33.627302) (xy 396.705328 -33.657286) (xy 396.705328 -34.520886)
			(xy 396.704838 -34.55087) (xy 396.69701 -34.610326) (xy 396.681489 -34.668251) (xy 396.65854 -34.723655)
			(xy 396.628556 -34.775589) (xy 396.59205 -34.823165) (xy 396.549645 -34.86557) (xy 396.502069 -34.902076)
			(xy 396.450135 -34.93206) (xy 396.394731 -34.955009) (xy 396.336806 -34.97053) (xy 396.27735 -34.978358)
			(xy 396.217382 -34.978358) (xy 396.157926 -34.97053) (xy 396.100001 -34.955009) (xy 396.044597 -34.93206)
			(xy 395.992663 -34.902076) (xy 395.945087 -34.86557) (xy 395.902682 -34.823165) (xy 395.866176 -34.775589)
			(xy 395.836192 -34.723655) (xy 395.813243 -34.668251) (xy 395.797722 -34.610326) (xy 395.789894 -34.55087)
			(xy 395.789404 -34.520886) (xy 389.411766 -34.520886) (xy 389.4328 -34.571686) (xy 389.719936 -35.264852)
			(xy 404.20239 -35.264852) (xy 404.206461 -35.20923) (xy 404.218587 -35.154793) (xy 404.23851 -35.102702)
			(xy 404.265806 -35.054067) (xy 404.299892 -35.009924) (xy 404.340041 -34.971215) (xy 404.385399 -34.938764)
			(xy 404.434999 -34.913263) (xy 404.487783 -34.895256) (xy 404.542626 -34.885126) (xy 404.59836 -34.883089)
			(xy 404.653797 -34.889189) (xy 404.707754 -34.903295) (xy 404.759083 -34.925107) (xy 404.806689 -34.954161)
			(xy 404.849557 -34.989836) (xy 404.886774 -35.031373) (xy 404.917547 -35.077886) (xy 404.941219 -35.128383)
			(xy 404.957287 -35.18179) (xy 404.965407 -35.236966) (xy 404.965916 -35.264852) (xy 404.965407 -35.292738)
			(xy 404.957287 -35.347914) (xy 404.941219 -35.401321) (xy 404.917547 -35.451818) (xy 404.886774 -35.498331)
			(xy 404.849557 -35.539868) (xy 404.806689 -35.575543) (xy 404.759083 -35.604597) (xy 404.707754 -35.626409)
			(xy 404.653797 -35.640515) (xy 404.59836 -35.646615) (xy 404.542626 -35.644578) (xy 404.487783 -35.634448)
			(xy 404.434999 -35.616441) (xy 404.385399 -35.59094) (xy 404.340041 -35.558489) (xy 404.299892 -35.51978)
			(xy 404.265806 -35.475637) (xy 404.23851 -35.427002) (xy 404.218587 -35.374911) (xy 404.206461 -35.320474)
			(xy 404.20239 -35.264852) (xy 389.719936 -35.264852) (xy 389.973402 -35.876738) (xy 393.017246 -35.876738)
			(xy 393.021317 -35.821116) (xy 393.033443 -35.766679) (xy 393.053366 -35.714588) (xy 393.080662 -35.665953)
			(xy 393.114748 -35.62181) (xy 393.154897 -35.583101) (xy 393.200255 -35.55065) (xy 393.249855 -35.525149)
			(xy 393.302639 -35.507142) (xy 393.357482 -35.497012) (xy 393.413216 -35.494975) (xy 393.468653 -35.501075)
			(xy 393.52261 -35.515181) (xy 393.573939 -35.536993) (xy 393.621545 -35.566047) (xy 393.664413 -35.601722)
			(xy 393.70163 -35.643259) (xy 393.732403 -35.689772) (xy 393.756075 -35.740269) (xy 393.772143 -35.793676)
			(xy 393.780263 -35.848852) (xy 393.780772 -35.876738) (xy 397.088866 -35.876738) (xy 397.092937 -35.821116)
			(xy 397.105063 -35.766679) (xy 397.124986 -35.714588) (xy 397.152282 -35.665953) (xy 397.186368 -35.62181)
			(xy 397.226517 -35.583101) (xy 397.271875 -35.55065) (xy 397.321475 -35.525149) (xy 397.374259 -35.507142)
			(xy 397.429102 -35.497012) (xy 397.484836 -35.494975) (xy 397.540273 -35.501075) (xy 397.59423 -35.515181)
			(xy 397.645559 -35.536993) (xy 397.693165 -35.566047) (xy 397.736033 -35.601722) (xy 397.77325 -35.643259)
			(xy 397.804023 -35.689772) (xy 397.827695 -35.740269) (xy 397.843763 -35.793676) (xy 397.851883 -35.848852)
			(xy 397.852392 -35.876738) (xy 397.851883 -35.904624) (xy 397.843763 -35.9598) (xy 397.827695 -36.013207)
			(xy 397.804023 -36.063704) (xy 397.77325 -36.110217) (xy 397.736033 -36.151754) (xy 397.693165 -36.187429)
			(xy 397.645559 -36.216483) (xy 397.59423 -36.238295) (xy 397.540273 -36.252401) (xy 397.484836 -36.258501)
			(xy 397.429102 -36.256464) (xy 397.374259 -36.246334) (xy 397.321475 -36.228327) (xy 397.271875 -36.202826)
			(xy 397.226517 -36.170375) (xy 397.186368 -36.131666) (xy 397.152282 -36.087523) (xy 397.124986 -36.038888)
			(xy 397.105063 -35.986797) (xy 397.092937 -35.93236) (xy 397.088866 -35.876738) (xy 393.780772 -35.876738)
			(xy 393.780263 -35.904624) (xy 393.772143 -35.9598) (xy 393.756075 -36.013207) (xy 393.732403 -36.063704)
			(xy 393.70163 -36.110217) (xy 393.664413 -36.151754) (xy 393.621545 -36.187429) (xy 393.573939 -36.216483)
			(xy 393.52261 -36.238295) (xy 393.468653 -36.252401) (xy 393.413216 -36.258501) (xy 393.357482 -36.256464)
			(xy 393.302639 -36.246334) (xy 393.249855 -36.228327) (xy 393.200255 -36.202826) (xy 393.154897 -36.170375)
			(xy 393.114748 -36.131666) (xy 393.080662 -36.087523) (xy 393.053366 -36.038888) (xy 393.033443 -35.986797)
			(xy 393.021317 -35.93236) (xy 393.017246 -35.876738) (xy 389.973402 -35.876738) (xy 390.235707 -36.50996)
			(xy 394.913864 -36.50996) (xy 394.917935 -36.454338) (xy 394.930061 -36.399901) (xy 394.949984 -36.34781)
			(xy 394.97728 -36.299175) (xy 395.011366 -36.255032) (xy 395.051515 -36.216323) (xy 395.096873 -36.183872)
			(xy 395.146473 -36.158371) (xy 395.199257 -36.140364) (xy 395.2541 -36.130234) (xy 395.309834 -36.128197)
			(xy 395.365271 -36.134297) (xy 395.419228 -36.148403) (xy 395.470557 -36.170215) (xy 395.518163 -36.199269)
			(xy 395.561031 -36.234944) (xy 395.598248 -36.276481) (xy 395.629021 -36.322994) (xy 395.652693 -36.373491)
			(xy 395.668761 -36.426898) (xy 395.672686 -36.453572) (xy 398.228564 -36.453572) (xy 398.232635 -36.39795)
			(xy 398.244761 -36.343513) (xy 398.264684 -36.291422) (xy 398.29198 -36.242787) (xy 398.326066 -36.198644)
			(xy 398.366215 -36.159935) (xy 398.411573 -36.127484) (xy 398.461173 -36.101983) (xy 398.513957 -36.083976)
			(xy 398.5688 -36.073846) (xy 398.624534 -36.071809) (xy 398.679971 -36.077909) (xy 398.733928 -36.092015)
			(xy 398.785257 -36.113827) (xy 398.832863 -36.142881) (xy 398.875731 -36.178556) (xy 398.912948 -36.220093)
			(xy 398.943721 -36.266606) (xy 398.953257 -36.286948) (xy 405.50033 -36.286948) (xy 405.504401 -36.231326)
			(xy 405.516527 -36.176889) (xy 405.53645 -36.124798) (xy 405.563746 -36.076163) (xy 405.597832 -36.03202)
			(xy 405.637981 -35.993311) (xy 405.683339 -35.96086) (xy 405.732939 -35.935359) (xy 405.785723 -35.917352)
			(xy 405.840566 -35.907222) (xy 405.8963 -35.905185) (xy 405.951737 -35.911285) (xy 406.005694 -35.925391)
			(xy 406.057023 -35.947203) (xy 406.104629 -35.976257) (xy 406.147497 -36.011932) (xy 406.184714 -36.053469)
			(xy 406.215487 -36.099982) (xy 406.239159 -36.150479) (xy 406.255227 -36.203886) (xy 406.263347 -36.259062)
			(xy 406.263856 -36.286948) (xy 406.263347 -36.314834) (xy 406.255227 -36.37001) (xy 406.239159 -36.423417)
			(xy 406.215487 -36.473914) (xy 406.184714 -36.520427) (xy 406.147497 -36.561964) (xy 406.104629 -36.597639)
			(xy 406.057023 -36.626693) (xy 406.005694 -36.648505) (xy 405.951737 -36.662611) (xy 405.8963 -36.668711)
			(xy 405.840566 -36.666674) (xy 405.785723 -36.656544) (xy 405.732939 -36.638537) (xy 405.683339 -36.613036)
			(xy 405.637981 -36.580585) (xy 405.597832 -36.541876) (xy 405.563746 -36.497733) (xy 405.53645 -36.449098)
			(xy 405.516527 -36.397007) (xy 405.504401 -36.34257) (xy 405.50033 -36.286948) (xy 398.953257 -36.286948)
			(xy 398.967393 -36.317103) (xy 398.983461 -36.37051) (xy 398.991581 -36.425686) (xy 398.99209 -36.453572)
			(xy 398.991581 -36.481458) (xy 398.983461 -36.536634) (xy 398.967393 -36.590041) (xy 398.943721 -36.640538)
			(xy 398.912948 -36.687051) (xy 398.875731 -36.728588) (xy 398.832863 -36.764263) (xy 398.785257 -36.793317)
			(xy 398.733928 -36.815129) (xy 398.679971 -36.829235) (xy 398.624534 -36.835335) (xy 398.5688 -36.833298)
			(xy 398.513957 -36.823168) (xy 398.461173 -36.805161) (xy 398.411573 -36.77966) (xy 398.366215 -36.747209)
			(xy 398.326066 -36.7085) (xy 398.29198 -36.664357) (xy 398.264684 -36.615722) (xy 398.244761 -36.563631)
			(xy 398.232635 -36.509194) (xy 398.228564 -36.453572) (xy 395.672686 -36.453572) (xy 395.676881 -36.482074)
			(xy 395.67739 -36.50996) (xy 395.676881 -36.537846) (xy 395.668761 -36.593022) (xy 395.652693 -36.646429)
			(xy 395.629021 -36.696926) (xy 395.598248 -36.743439) (xy 395.561031 -36.784976) (xy 395.518163 -36.820651)
			(xy 395.470557 -36.849705) (xy 395.419228 -36.871517) (xy 395.365271 -36.885623) (xy 395.309834 -36.891723)
			(xy 395.2541 -36.889686) (xy 395.199257 -36.879556) (xy 395.146473 -36.861549) (xy 395.096873 -36.836048)
			(xy 395.051515 -36.803597) (xy 395.011366 -36.764888) (xy 394.97728 -36.720745) (xy 394.949984 -36.67211)
			(xy 394.930061 -36.620019) (xy 394.917935 -36.565582) (xy 394.913864 -36.50996) (xy 390.235707 -36.50996)
			(xy 390.476232 -37.090604) (xy 390.490295 -37.125599) (xy 390.513685 -37.197306) (xy 390.522968 -37.23386)
			(xy 390.52373 -37.236654) (xy 390.524492 -37.239194) (xy 390.533382 -37.260022) (xy 390.533382 -37.26053)
			(xy 390.545066 -37.28847) (xy 390.54532 -37.28847) (xy 390.5504 -37.300662) (xy 390.5504 -37.30117)
			(xy 390.569112 -37.347187) (xy 390.598383 -37.442121) (xy 390.605065 -37.47516) (xy 392.059158 -37.47516)
			(xy 392.063229 -37.419538) (xy 392.075355 -37.365101) (xy 392.095278 -37.31301) (xy 392.122574 -37.264375)
			(xy 392.15666 -37.220232) (xy 392.196809 -37.181523) (xy 392.242167 -37.149072) (xy 392.291767 -37.123571)
			(xy 392.344551 -37.105564) (xy 392.399394 -37.095434) (xy 392.455128 -37.093397) (xy 392.510565 -37.099497)
			(xy 392.564522 -37.113603) (xy 392.615851 -37.135415) (xy 392.663457 -37.164469) (xy 392.706325 -37.200144)
			(xy 392.743542 -37.241681) (xy 392.774315 -37.288194) (xy 392.797987 -37.338691) (xy 392.814055 -37.392098)
			(xy 392.822175 -37.447274) (xy 392.822684 -37.47516) (xy 392.822175 -37.503046) (xy 392.814055 -37.558222)
			(xy 392.797987 -37.611629) (xy 392.774315 -37.662126) (xy 392.774162 -37.662358) (xy 394.248384 -37.662358)
			(xy 394.252455 -37.606736) (xy 394.264581 -37.552299) (xy 394.284504 -37.500208) (xy 394.3118 -37.451573)
			(xy 394.345886 -37.40743) (xy 394.386035 -37.368721) (xy 394.431393 -37.33627) (xy 394.480993 -37.310769)
			(xy 394.533777 -37.292762) (xy 394.58862 -37.282632) (xy 394.644354 -37.280595) (xy 394.699791 -37.286695)
			(xy 394.753748 -37.300801) (xy 394.805077 -37.322613) (xy 394.852683 -37.351667) (xy 394.895551 -37.387342)
			(xy 394.932768 -37.428879) (xy 394.963541 -37.475392) (xy 394.987213 -37.525889) (xy 395.003281 -37.579296)
			(xy 395.011401 -37.634472) (xy 395.01191 -37.662358) (xy 395.011401 -37.690244) (xy 395.003281 -37.74542)
			(xy 394.994647 -37.774118) (xy 405.764744 -37.774118) (xy 405.768815 -37.718496) (xy 405.780941 -37.664059)
			(xy 405.800864 -37.611968) (xy 405.82816 -37.563333) (xy 405.862246 -37.51919) (xy 405.902395 -37.480481)
			(xy 405.947753 -37.44803) (xy 405.997353 -37.422529) (xy 406.050137 -37.404522) (xy 406.10498 -37.394392)
			(xy 406.160714 -37.392355) (xy 406.216151 -37.398455) (xy 406.270108 -37.412561) (xy 406.321437 -37.434373)
			(xy 406.369043 -37.463427) (xy 406.411911 -37.499102) (xy 406.449128 -37.540639) (xy 406.479901 -37.587152)
			(xy 406.503573 -37.637649) (xy 406.519641 -37.691056) (xy 406.527761 -37.746232) (xy 406.52827 -37.774118)
			(xy 406.527761 -37.802004) (xy 406.519641 -37.85718) (xy 406.503573 -37.910587) (xy 406.479901 -37.961084)
			(xy 406.449128 -38.007597) (xy 406.411911 -38.049134) (xy 406.369043 -38.084809) (xy 406.321437 -38.113863)
			(xy 406.270108 -38.135675) (xy 406.216151 -38.149781) (xy 406.160714 -38.155881) (xy 406.10498 -38.153844)
			(xy 406.050137 -38.143714) (xy 405.997353 -38.125707) (xy 405.947753 -38.100206) (xy 405.902395 -38.067755)
			(xy 405.862246 -38.029046) (xy 405.82816 -37.984903) (xy 405.800864 -37.936268) (xy 405.780941 -37.884177)
			(xy 405.768815 -37.82974) (xy 405.764744 -37.774118) (xy 394.994647 -37.774118) (xy 394.987213 -37.798827)
			(xy 394.963541 -37.849324) (xy 394.932768 -37.895837) (xy 394.895551 -37.937374) (xy 394.852683 -37.973049)
			(xy 394.805077 -38.002103) (xy 394.753748 -38.023915) (xy 394.699791 -38.038021) (xy 394.644354 -38.044121)
			(xy 394.58862 -38.042084) (xy 394.533777 -38.031954) (xy 394.480993 -38.013947) (xy 394.431393 -37.988446)
			(xy 394.386035 -37.955995) (xy 394.345886 -37.917286) (xy 394.3118 -37.873143) (xy 394.284504 -37.824508)
			(xy 394.264581 -37.772417) (xy 394.252455 -37.71798) (xy 394.248384 -37.662358) (xy 392.774162 -37.662358)
			(xy 392.743542 -37.708639) (xy 392.706325 -37.750176) (xy 392.663457 -37.785851) (xy 392.615851 -37.814905)
			(xy 392.564522 -37.836717) (xy 392.510565 -37.850823) (xy 392.455128 -37.856923) (xy 392.399394 -37.854886)
			(xy 392.344551 -37.844756) (xy 392.291767 -37.826749) (xy 392.242167 -37.801248) (xy 392.196809 -37.768797)
			(xy 392.15666 -37.730088) (xy 392.122574 -37.685945) (xy 392.095278 -37.63731) (xy 392.075355 -37.585219)
			(xy 392.063229 -37.530782) (xy 392.059158 -37.47516) (xy 390.605065 -37.47516) (xy 390.618075 -37.539493)
			(xy 390.627995 -37.63834) (xy 390.628632 -37.688012) (xy 390.628632 -37.704522) (xy 390.628632 -37.705538)
			(xy 390.616948 -38.411912) (xy 390.6139 -38.593268) (xy 390.612544 -38.640617) (xy 390.602525 -38.729947)
			(xy 398.00102 -38.729947) (xy 398.00102 -38.675453) (xy 398.008775 -38.621512) (xy 398.024128 -38.569225)
			(xy 398.046765 -38.519654) (xy 398.076226 -38.47381) (xy 398.111912 -38.432625) (xy 398.153096 -38.396937)
			(xy 398.198939 -38.367474) (xy 398.248508 -38.344834) (xy 398.300795 -38.329479) (xy 398.354735 -38.321721)
			(xy 398.381982 -38.321234) (xy 398.410286 -38.321722) (xy 398.466276 -38.330072) (xy 398.520416 -38.346607)
			(xy 398.571517 -38.370962) (xy 398.618457 -38.402603) (xy 398.660204 -38.440835) (xy 398.695841 -38.484818)
			(xy 398.710658 -38.50894) (xy 398.718214 -38.521004) (xy 398.738841 -38.540607) (xy 398.764082 -38.553749)
			(xy 398.791972 -38.559405) (xy 398.820338 -38.557135) (xy 398.846973 -38.547117) (xy 398.869804 -38.530129)
			(xy 398.878806 -38.5191) (xy 398.896994 -38.496225) (xy 398.939156 -38.455761) (xy 398.986992 -38.422194)
			(xy 399.039383 -38.396306) (xy 399.095108 -38.378704) (xy 399.152863 -38.369797) (xy 399.182082 -38.36924)
			(xy 399.209339 -38.369606) (xy 399.263299 -38.377362) (xy 399.315606 -38.392718) (xy 399.365194 -38.415362)
			(xy 399.411055 -38.444834) (xy 399.452255 -38.480532) (xy 399.487956 -38.52173) (xy 399.517429 -38.56759)
			(xy 399.540076 -38.617178) (xy 399.555435 -38.669484) (xy 399.563193 -38.723443) (xy 399.563193 -38.777957)
			(xy 399.555435 -38.831916) (xy 399.540076 -38.884222) (xy 399.517429 -38.93381) (xy 399.487956 -38.97967)
			(xy 399.452255 -39.020868) (xy 399.411055 -39.056566) (xy 399.365194 -39.086038) (xy 399.315606 -39.108682)
			(xy 399.263299 -39.124038) (xy 399.209339 -39.131794) (xy 399.182082 -39.132256) (xy 399.153779 -39.131722)
			(xy 399.097792 -39.123381) (xy 399.043653 -39.106855) (xy 398.992551 -39.082508) (xy 398.945611 -39.050873)
			(xy 398.903862 -39.012647) (xy 398.868223 -38.968669) (xy 398.853406 -38.94455) (xy 398.845767 -38.932544)
			(xy 398.825156 -38.912946) (xy 398.799933 -38.899804) (xy 398.772061 -38.894142) (xy 398.743709 -38.8964)
			(xy 398.717085 -38.906403) (xy 398.69426 -38.923371) (xy 398.685258 -38.93439) (xy 398.667088 -38.95728)
			(xy 398.624922 -38.997743) (xy 398.577083 -39.03131) (xy 398.524688 -39.057194) (xy 398.46896 -39.074793)
			(xy 398.411202 -39.083695) (xy 398.381982 -39.08425) (xy 398.354735 -39.083679) (xy 398.300795 -39.075921)
			(xy 398.248508 -39.060566) (xy 398.198939 -39.037926) (xy 398.153096 -39.008463) (xy 398.111912 -38.972775)
			(xy 398.076226 -38.93159) (xy 398.046765 -38.885746) (xy 398.024128 -38.836175) (xy 398.008775 -38.783888)
			(xy 398.00102 -38.729947) (xy 390.602525 -38.729947) (xy 390.601986 -38.734756) (xy 390.592818 -38.781228)
			(xy 390.54278 -39.020242) (xy 390.343585 -39.97198) (xy 400.195794 -39.97198) (xy 400.199865 -39.916358)
			(xy 400.211991 -39.861921) (xy 400.231914 -39.80983) (xy 400.25921 -39.761195) (xy 400.293296 -39.717052)
			(xy 400.333445 -39.678343) (xy 400.378803 -39.645892) (xy 400.428403 -39.620391) (xy 400.481187 -39.602384)
			(xy 400.53603 -39.592254) (xy 400.591764 -39.590217) (xy 400.647201 -39.596317) (xy 400.701158 -39.610423)
			(xy 400.752487 -39.632235) (xy 400.800093 -39.661289) (xy 400.842961 -39.696964) (xy 400.880178 -39.738501)
			(xy 400.910951 -39.785014) (xy 400.934623 -39.835511) (xy 400.950691 -39.888918) (xy 400.958811 -39.944094)
			(xy 400.95932 -39.97198) (xy 400.958811 -39.999866) (xy 400.950691 -40.055042) (xy 400.934623 -40.108449)
			(xy 400.910951 -40.158946) (xy 400.880178 -40.205459) (xy 400.842961 -40.246996) (xy 400.800093 -40.282671)
			(xy 400.752487 -40.311725) (xy 400.701158 -40.333537) (xy 400.647201 -40.347643) (xy 400.591764 -40.353743)
			(xy 400.53603 -40.351706) (xy 400.481187 -40.341576) (xy 400.428403 -40.323569) (xy 400.378803 -40.298068)
			(xy 400.333445 -40.265617) (xy 400.293296 -40.226908) (xy 400.25921 -40.182765) (xy 400.231914 -40.13413)
			(xy 400.211991 -40.082039) (xy 400.199865 -40.027602) (xy 400.195794 -39.97198) (xy 390.343585 -39.97198)
			(xy 390.167622 -40.81272) (xy 390.167368 -40.813482) (xy 390.16605 -40.823163) (xy 390.169956 -40.84229)
			(xy 390.180693 -40.858594) (xy 390.18845 -40.864536) (xy 390.265158 -40.917622) (xy 390.273601 -40.922899)
			(xy 390.293025 -40.927185) (xy 390.312624 -40.92379) (xy 390.321292 -40.918892) (xy 390.344259 -40.904929)
			(xy 390.39328 -40.882889) (xy 390.44491 -40.867949) (xy 390.498126 -40.860404) (xy 390.525 -40.859964)
			(xy 390.553739 -40.860485) (xy 390.610565 -40.869109) (xy 390.665455 -40.886161) (xy 390.717165 -40.911256)
			(xy 390.764524 -40.943826) (xy 390.785858 -40.963088) (xy 390.786112 -40.963342) (xy 390.790095 -40.966811)
			(xy 390.79919 -40.97218) (xy 390.804146 -40.97401) (xy 390.808153 -40.975297) (xy 390.816449 -40.976706)
			(xy 390.820656 -40.976804) (xy 390.889744 -40.976804) (xy 390.893952 -40.97672) (xy 390.90225 -40.975309)
			(xy 390.906254 -40.97401) (xy 390.911212 -40.972187) (xy 390.920302 -40.966808) (xy 390.924288 -40.963342)
			(xy 390.924542 -40.963088) (xy 390.94587 -40.943819) (xy 390.993233 -40.911257) (xy 391.044945 -40.886167)
			(xy 391.099835 -40.869119) (xy 391.156662 -40.860497) (xy 391.1854 -40.859964) (xy 391.212653 -40.86045)
			(xy 391.266605 -40.868207) (xy 391.318904 -40.883563) (xy 391.368484 -40.906206) (xy 391.414338 -40.935674)
			(xy 391.455531 -40.971369) (xy 391.491226 -41.012562) (xy 391.520694 -41.058416) (xy 391.543337 -41.107996)
			(xy 391.558693 -41.160295) (xy 391.56645 -41.214247) (xy 391.56645 -41.268753) (xy 391.558693 -41.322705)
			(xy 391.543337 -41.375004) (xy 391.520694 -41.424584) (xy 391.491226 -41.470438) (xy 391.455531 -41.511631)
			(xy 391.414338 -41.547326) (xy 391.368484 -41.576794) (xy 391.318904 -41.599437) (xy 391.266605 -41.614793)
			(xy 391.212653 -41.62255) (xy 391.1854 -41.62298) (xy 391.156661 -41.622459) (xy 391.099834 -41.613836)
			(xy 391.044943 -41.596785) (xy 390.993232 -41.571692) (xy 390.94587 -41.539126) (xy 390.924542 -41.519856)
			(xy 390.924288 -41.519602) (xy 390.920312 -41.516123) (xy 390.911217 -41.510748) (xy 390.906254 -41.508934)
			(xy 390.902247 -41.507649) (xy 390.893951 -41.506241) (xy 390.889744 -41.50614) (xy 390.820656 -41.50614)
			(xy 390.816448 -41.506224) (xy 390.808151 -41.507637) (xy 390.804146 -41.508934) (xy 390.799187 -41.510755)
			(xy 390.790093 -41.516129) (xy 390.786112 -41.519602) (xy 390.785858 -41.519856) (xy 390.764529 -41.539123)
			(xy 390.717165 -41.571682) (xy 390.665453 -41.596768) (xy 390.610563 -41.613814) (xy 390.553738 -41.622435)
			(xy 390.525 -41.62298) (xy 390.512262 -41.622902) (xy 390.486841 -41.621248) (xy 390.4742 -41.619678)
			(xy 390.447703 -41.615664) (xy 390.396111 -41.601171) (xy 390.347056 -41.579595) (xy 390.301506 -41.551362)
			(xy 390.260358 -41.51703) (xy 390.224423 -41.477273) (xy 390.209024 -41.45534) (xy 390.209024 -41.455086)
			(xy 390.204643 -41.449132) (xy 390.193155 -41.43984) (xy 390.186418 -41.436798) (xy 390.179421 -41.434197)
			(xy 390.164569 -41.432768) (xy 390.157208 -41.434004) (xy 390.065514 -41.451784) (xy 390.056878 -41.454324)
			(xy 390.049076 -41.457664) (xy 390.036105 -41.468596) (xy 390.027424 -41.483169) (xy 390.025382 -41.491408)
			(xy 389.74141 -42.848276) (xy 389.645678 -43.305222) (xy 392.607292 -43.305222) (xy 392.607773 -43.277852)
			(xy 392.615587 -43.223674) (xy 392.631073 -43.171171) (xy 392.653912 -43.121424) (xy 392.683633 -43.075456)
			(xy 392.701272 -43.054524) (xy 392.701526 -43.05427) (xy 392.707092 -43.04717) (xy 392.71335 -43.030263)
			(xy 392.713718 -43.02125) (xy 392.713718 -42.954194) (xy 392.71336 -42.945177) (xy 392.707113 -42.928261)
			(xy 392.701526 -42.921174) (xy 392.701272 -42.921174) (xy 392.701272 -42.92092) (xy 392.683624 -42.899995)
			(xy 392.653915 -42.85402) (xy 392.631081 -42.80427) (xy 392.615592 -42.751768) (xy 392.607765 -42.697592)
			(xy 392.607292 -42.670222) (xy 392.607831 -42.641484) (xy 392.61645 -42.584657) (xy 392.633497 -42.529767)
			(xy 392.658585 -42.478055) (xy 392.691147 -42.430691) (xy 392.710416 -42.409364) (xy 392.71702 -42.402506)
			(xy 392.724132 -42.384472) (xy 392.724132 -42.295572) (xy 392.71702 -42.277538) (xy 392.710416 -42.27068)
			(xy 392.691167 -42.249334) (xy 392.658602 -42.201975) (xy 392.63351 -42.150266) (xy 392.616459 -42.095378)
			(xy 392.607834 -42.038554) (xy 392.607832 -41.981078) (xy 392.616451 -41.924253) (xy 392.633498 -41.869364)
			(xy 392.658586 -41.817653) (xy 392.691147 -41.770291) (xy 392.710416 -41.748964) (xy 392.71702 -41.742106)
			(xy 392.724132 -41.724072) (xy 392.724132 -41.635172) (xy 392.71702 -41.617138) (xy 392.710416 -41.61028)
			(xy 392.691152 -41.588947) (xy 392.658586 -41.541586) (xy 392.633492 -41.489876) (xy 392.61644 -41.434987)
			(xy 392.607815 -41.378161) (xy 392.607292 -41.349422) (xy 392.607778 -41.322171) (xy 392.615534 -41.268223)
			(xy 392.630889 -41.215928) (xy 392.653531 -41.166351) (xy 392.682997 -41.120501) (xy 392.718688 -41.07931)
			(xy 392.759879 -41.043619) (xy 392.805729 -41.014153) (xy 392.855306 -40.991511) (xy 392.907601 -40.976156)
			(xy 392.961549 -40.9684) (xy 393.016051 -40.9684) (xy 393.039172 -40.971724) (xy 400.89404 -40.971724)
			(xy 400.898111 -40.916102) (xy 400.910237 -40.861665) (xy 400.93016 -40.809574) (xy 400.957456 -40.760939)
			(xy 400.991542 -40.716796) (xy 401.031691 -40.678087) (xy 401.077049 -40.645636) (xy 401.126649 -40.620135)
			(xy 401.179433 -40.602128) (xy 401.234276 -40.591998) (xy 401.29001 -40.589961) (xy 401.345447 -40.596061)
			(xy 401.399404 -40.610167) (xy 401.450733 -40.631979) (xy 401.498339 -40.661033) (xy 401.541207 -40.696708)
			(xy 401.578424 -40.738245) (xy 401.609197 -40.784758) (xy 401.632869 -40.835255) (xy 401.648937 -40.888662)
			(xy 401.657057 -40.943838) (xy 401.657566 -40.971724) (xy 401.657057 -40.99961) (xy 401.648937 -41.054786)
			(xy 401.632869 -41.108193) (xy 401.609197 -41.15869) (xy 401.578424 -41.205203) (xy 401.541207 -41.24674)
			(xy 401.498339 -41.282415) (xy 401.450733 -41.311469) (xy 401.399404 -41.333281) (xy 401.345447 -41.347387)
			(xy 401.29001 -41.353487) (xy 401.234276 -41.35145) (xy 401.179433 -41.34132) (xy 401.126649 -41.323313)
			(xy 401.077049 -41.297812) (xy 401.031691 -41.265361) (xy 400.991542 -41.226652) (xy 400.957456 -41.182509)
			(xy 400.93016 -41.133874) (xy 400.910237 -41.081783) (xy 400.898111 -41.027346) (xy 400.89404 -40.971724)
			(xy 393.039172 -40.971724) (xy 393.069999 -40.976156) (xy 393.122294 -40.991511) (xy 393.171871 -41.014153)
			(xy 393.217721 -41.043619) (xy 393.258912 -41.07931) (xy 393.294603 -41.120501) (xy 393.324069 -41.166351)
			(xy 393.346711 -41.215928) (xy 393.362066 -41.268223) (xy 393.369822 -41.322171) (xy 393.370308 -41.349422)
			(xy 393.369796 -41.378161) (xy 393.36117 -41.434989) (xy 393.344117 -41.48988) (xy 393.319023 -41.541591)
			(xy 393.286456 -41.588953) (xy 393.267184 -41.61028) (xy 393.26058 -41.617138) (xy 393.253468 -41.635172)
			(xy 393.253468 -41.724072) (xy 393.26058 -41.742106) (xy 393.267184 -41.748964) (xy 393.286476 -41.770272)
			(xy 393.31904 -41.817638) (xy 393.34413 -41.869353) (xy 393.361178 -41.924246) (xy 393.369798 -41.981076)
			(xy 393.369796 -42.038556) (xy 393.361171 -42.095385) (xy 393.344118 -42.150277) (xy 393.319024 -42.20199)
			(xy 393.286456 -42.249353) (xy 393.267184 -42.27068) (xy 393.26058 -42.277538) (xy 393.253468 -42.295572)
			(xy 393.253468 -42.384472) (xy 393.26058 -42.402506) (xy 393.267184 -42.409364) (xy 393.286469 -42.430679)
			(xy 393.319032 -42.478045) (xy 393.344122 -42.529759) (xy 393.361169 -42.584653) (xy 393.369789 -42.641482)
			(xy 393.370308 -42.670222) (xy 393.369853 -42.697593) (xy 393.362032 -42.751772) (xy 393.34654 -42.804275)
			(xy 393.325985 -42.849038) (xy 395.191994 -42.849038) (xy 395.196065 -42.793416) (xy 395.208191 -42.738979)
			(xy 395.228114 -42.686888) (xy 395.25541 -42.638253) (xy 395.289496 -42.59411) (xy 395.329645 -42.555401)
			(xy 395.375003 -42.52295) (xy 395.424603 -42.497449) (xy 395.477387 -42.479442) (xy 395.53223 -42.469312)
			(xy 395.587964 -42.467275) (xy 395.643401 -42.473375) (xy 395.697358 -42.487481) (xy 395.748687 -42.509293)
			(xy 395.796293 -42.538347) (xy 395.839161 -42.574022) (xy 395.876378 -42.615559) (xy 395.907151 -42.662072)
			(xy 395.930823 -42.712569) (xy 395.946891 -42.765976) (xy 395.955011 -42.821152) (xy 395.955372 -42.84091)
			(xy 401.23313 -42.84091) (xy 401.237201 -42.785288) (xy 401.249327 -42.730851) (xy 401.26925 -42.67876)
			(xy 401.296546 -42.630125) (xy 401.330632 -42.585982) (xy 401.370781 -42.547273) (xy 401.416139 -42.514822)
			(xy 401.465739 -42.489321) (xy 401.518523 -42.471314) (xy 401.573366 -42.461184) (xy 401.6291 -42.459147)
			(xy 401.684537 -42.465247) (xy 401.738494 -42.479353) (xy 401.789823 -42.501165) (xy 401.837429 -42.530219)
			(xy 401.880297 -42.565894) (xy 401.917514 -42.607431) (xy 401.948287 -42.653944) (xy 401.971959 -42.704441)
			(xy 401.988027 -42.757848) (xy 401.996147 -42.813024) (xy 401.996656 -42.84091) (xy 401.996147 -42.868796)
			(xy 401.988027 -42.923972) (xy 401.971959 -42.977379) (xy 401.948287 -43.027876) (xy 401.917514 -43.074389)
			(xy 401.880297 -43.115926) (xy 401.837429 -43.151601) (xy 401.789823 -43.180655) (xy 401.738494 -43.202467)
			(xy 401.684537 -43.216573) (xy 401.6291 -43.222673) (xy 401.573366 -43.220636) (xy 401.518523 -43.210506)
			(xy 401.465739 -43.192499) (xy 401.416139 -43.166998) (xy 401.370781 -43.134547) (xy 401.330632 -43.095838)
			(xy 401.296546 -43.051695) (xy 401.26925 -43.00306) (xy 401.249327 -42.950969) (xy 401.237201 -42.896532)
			(xy 401.23313 -42.84091) (xy 395.955372 -42.84091) (xy 395.95552 -42.849038) (xy 395.955011 -42.876924)
			(xy 395.946891 -42.9321) (xy 395.930823 -42.985507) (xy 395.907151 -43.036004) (xy 395.876378 -43.082517)
			(xy 395.839161 -43.124054) (xy 395.796293 -43.159729) (xy 395.748687 -43.188783) (xy 395.697358 -43.210595)
			(xy 395.643401 -43.224701) (xy 395.587964 -43.230801) (xy 395.53223 -43.228764) (xy 395.477387 -43.218634)
			(xy 395.424603 -43.200627) (xy 395.375003 -43.175126) (xy 395.329645 -43.142675) (xy 395.289496 -43.103966)
			(xy 395.25541 -43.059823) (xy 395.228114 -43.011188) (xy 395.208191 -42.959097) (xy 395.196065 -42.90466)
			(xy 395.191994 -42.849038) (xy 393.325985 -42.849038) (xy 393.323696 -42.854022) (xy 393.29397 -42.899988)
			(xy 393.276328 -42.92092) (xy 393.276074 -42.921174) (xy 393.270489 -42.928262) (xy 393.264242 -42.945178)
			(xy 393.263882 -42.954194) (xy 393.263882 -43.02125) (xy 393.264267 -43.030264) (xy 393.270495 -43.047181)
			(xy 393.276074 -43.05427) (xy 393.276328 -43.05427) (xy 393.276328 -43.054524) (xy 393.293949 -43.07547)
			(xy 393.323663 -43.12144) (xy 393.346502 -43.171184) (xy 393.361997 -43.223681) (xy 393.369831 -43.277854)
			(xy 393.370308 -43.305222) (xy 393.369822 -43.332473) (xy 393.362066 -43.386421) (xy 393.346711 -43.438716)
			(xy 393.324069 -43.488293) (xy 393.294603 -43.534143) (xy 393.258912 -43.575334) (xy 393.217721 -43.611025)
			(xy 393.171871 -43.640491) (xy 393.122294 -43.663133) (xy 393.069999 -43.678488) (xy 393.016051 -43.686244)
			(xy 392.961549 -43.686244) (xy 392.907601 -43.678488) (xy 392.855306 -43.663133) (xy 392.805729 -43.640491)
			(xy 392.759879 -43.611025) (xy 392.718688 -43.575334) (xy 392.682997 -43.534143) (xy 392.653531 -43.488293)
			(xy 392.630889 -43.438716) (xy 392.615534 -43.386421) (xy 392.607778 -43.332473) (xy 392.607292 -43.305222)
			(xy 389.645678 -43.305222) (xy 389.555373 -43.73626) (xy 394.513052 -43.73626) (xy 394.517123 -43.680638)
			(xy 394.529249 -43.626201) (xy 394.549172 -43.57411) (xy 394.576468 -43.525475) (xy 394.610554 -43.481332)
			(xy 394.650703 -43.442623) (xy 394.696061 -43.410172) (xy 394.745661 -43.384671) (xy 394.798445 -43.366664)
			(xy 394.853288 -43.356534) (xy 394.909022 -43.354497) (xy 394.964459 -43.360597) (xy 395.018416 -43.374703)
			(xy 395.069745 -43.396515) (xy 395.117351 -43.425569) (xy 395.160219 -43.461244) (xy 395.197436 -43.502781)
			(xy 395.228209 -43.549294) (xy 395.236435 -43.566842) (xy 397.633442 -43.566842) (xy 397.637513 -43.51122)
			(xy 397.649639 -43.456783) (xy 397.669562 -43.404692) (xy 397.696858 -43.356057) (xy 397.730944 -43.311914)
			(xy 397.771093 -43.273205) (xy 397.816451 -43.240754) (xy 397.866051 -43.215253) (xy 397.918835 -43.197246)
			(xy 397.973678 -43.187116) (xy 398.029412 -43.185079) (xy 398.084849 -43.191179) (xy 398.138806 -43.205285)
			(xy 398.190135 -43.227097) (xy 398.237741 -43.256151) (xy 398.280609 -43.291826) (xy 398.317826 -43.333363)
			(xy 398.348599 -43.379876) (xy 398.372271 -43.430373) (xy 398.388339 -43.48378) (xy 398.396459 -43.538956)
			(xy 398.396968 -43.566842) (xy 398.396459 -43.594728) (xy 398.388339 -43.649904) (xy 398.372271 -43.703311)
			(xy 398.348599 -43.753808) (xy 398.317826 -43.800321) (xy 398.280609 -43.841858) (xy 398.262522 -43.85691)
			(xy 399.019774 -43.85691) (xy 399.023845 -43.801288) (xy 399.035971 -43.746851) (xy 399.055894 -43.69476)
			(xy 399.08319 -43.646125) (xy 399.117276 -43.601982) (xy 399.157425 -43.563273) (xy 399.202783 -43.530822)
			(xy 399.252383 -43.505321) (xy 399.305167 -43.487314) (xy 399.36001 -43.477184) (xy 399.415744 -43.475147)
			(xy 399.471181 -43.481247) (xy 399.525138 -43.495353) (xy 399.576467 -43.517165) (xy 399.624073 -43.546219)
			(xy 399.666941 -43.581894) (xy 399.704158 -43.623431) (xy 399.734931 -43.669944) (xy 399.758603 -43.720441)
			(xy 399.774671 -43.773848) (xy 399.782791 -43.829024) (xy 399.7833 -43.85691) (xy 399.782791 -43.884796)
			(xy 399.774671 -43.939972) (xy 399.758603 -43.993379) (xy 399.734931 -44.043876) (xy 399.704158 -44.090389)
			(xy 399.666941 -44.131926) (xy 399.624073 -44.167601) (xy 399.576467 -44.196655) (xy 399.525138 -44.218467)
			(xy 399.471181 -44.232573) (xy 399.415744 -44.238673) (xy 399.36001 -44.236636) (xy 399.305167 -44.226506)
			(xy 399.252383 -44.208499) (xy 399.202783 -44.182998) (xy 399.157425 -44.150547) (xy 399.117276 -44.111838)
			(xy 399.08319 -44.067695) (xy 399.055894 -44.01906) (xy 399.035971 -43.966969) (xy 399.023845 -43.912532)
			(xy 399.019774 -43.85691) (xy 398.262522 -43.85691) (xy 398.237741 -43.877533) (xy 398.190135 -43.906587)
			(xy 398.138806 -43.928399) (xy 398.084849 -43.942505) (xy 398.029412 -43.948605) (xy 397.973678 -43.946568)
			(xy 397.918835 -43.936438) (xy 397.866051 -43.918431) (xy 397.816451 -43.89293) (xy 397.771093 -43.860479)
			(xy 397.730944 -43.82177) (xy 397.696858 -43.777627) (xy 397.669562 -43.728992) (xy 397.649639 -43.676901)
			(xy 397.637513 -43.622464) (xy 397.633442 -43.566842) (xy 395.236435 -43.566842) (xy 395.251881 -43.599791)
			(xy 395.267949 -43.653198) (xy 395.276069 -43.708374) (xy 395.276578 -43.73626) (xy 395.276069 -43.764146)
			(xy 395.267949 -43.819322) (xy 395.251881 -43.872729) (xy 395.228209 -43.923226) (xy 395.197436 -43.969739)
			(xy 395.160219 -44.011276) (xy 395.117351 -44.046951) (xy 395.069745 -44.076005) (xy 395.018416 -44.097817)
			(xy 394.964459 -44.111923) (xy 394.909022 -44.118023) (xy 394.853288 -44.115986) (xy 394.798445 -44.105856)
			(xy 394.745661 -44.087849) (xy 394.696061 -44.062348) (xy 394.650703 -44.029897) (xy 394.610554 -43.991188)
			(xy 394.576468 -43.947045) (xy 394.549172 -43.89841) (xy 394.529249 -43.846319) (xy 394.517123 -43.791882)
			(xy 394.513052 -43.73626) (xy 389.555373 -43.73626) (xy 389.478266 -44.104306) (xy 389.478266 -44.105322)
			(xy 389.287466 -45.114464) (xy 394.365478 -45.114464) (xy 394.369549 -45.058842) (xy 394.381675 -45.004405)
			(xy 394.401598 -44.952314) (xy 394.428894 -44.903679) (xy 394.46298 -44.859536) (xy 394.503129 -44.820827)
			(xy 394.548487 -44.788376) (xy 394.598087 -44.762875) (xy 394.650871 -44.744868) (xy 394.705714 -44.734738)
			(xy 394.761448 -44.732701) (xy 394.816885 -44.738801) (xy 394.870842 -44.752907) (xy 394.922171 -44.774719)
			(xy 394.969777 -44.803773) (xy 395.012645 -44.839448) (xy 395.042627 -44.87291) (xy 401.23313 -44.87291)
			(xy 401.237201 -44.817288) (xy 401.249327 -44.762851) (xy 401.26925 -44.71076) (xy 401.296546 -44.662125)
			(xy 401.330632 -44.617982) (xy 401.370781 -44.579273) (xy 401.416139 -44.546822) (xy 401.465739 -44.521321)
			(xy 401.518523 -44.503314) (xy 401.573366 -44.493184) (xy 401.6291 -44.491147) (xy 401.684537 -44.497247)
			(xy 401.738494 -44.511353) (xy 401.789823 -44.533165) (xy 401.837429 -44.562219) (xy 401.880297 -44.597894)
			(xy 401.917514 -44.639431) (xy 401.948287 -44.685944) (xy 401.971959 -44.736441) (xy 401.988027 -44.789848)
			(xy 401.996147 -44.845024) (xy 401.996656 -44.87291) (xy 401.996147 -44.900796) (xy 401.988027 -44.955972)
			(xy 401.971959 -45.009379) (xy 401.948287 -45.059876) (xy 401.917514 -45.106389) (xy 401.880297 -45.147926)
			(xy 401.837429 -45.183601) (xy 401.789823 -45.212655) (xy 401.738494 -45.234467) (xy 401.684537 -45.248573)
			(xy 401.6291 -45.254673) (xy 401.573366 -45.252636) (xy 401.518523 -45.242506) (xy 401.465739 -45.224499)
			(xy 401.416139 -45.198998) (xy 401.370781 -45.166547) (xy 401.330632 -45.127838) (xy 401.296546 -45.083695)
			(xy 401.26925 -45.03506) (xy 401.249327 -44.982969) (xy 401.237201 -44.928532) (xy 401.23313 -44.87291)
			(xy 395.042627 -44.87291) (xy 395.049862 -44.880985) (xy 395.080635 -44.927498) (xy 395.104307 -44.977995)
			(xy 395.120375 -45.031402) (xy 395.128495 -45.086578) (xy 395.129004 -45.114464) (xy 395.128495 -45.14235)
			(xy 395.120375 -45.197526) (xy 395.104307 -45.250933) (xy 395.080635 -45.30143) (xy 395.049862 -45.347943)
			(xy 395.04422 -45.35424) (xy 399.003772 -45.35424) (xy 399.007843 -45.298618) (xy 399.019969 -45.244181)
			(xy 399.039892 -45.19209) (xy 399.067188 -45.143455) (xy 399.101274 -45.099312) (xy 399.141423 -45.060603)
			(xy 399.186781 -45.028152) (xy 399.236381 -45.002651) (xy 399.289165 -44.984644) (xy 399.344008 -44.974514)
			(xy 399.399742 -44.972477) (xy 399.455179 -44.978577) (xy 399.509136 -44.992683) (xy 399.560465 -45.014495)
			(xy 399.608071 -45.043549) (xy 399.650939 -45.079224) (xy 399.688156 -45.120761) (xy 399.718929 -45.167274)
			(xy 399.742601 -45.217771) (xy 399.758669 -45.271178) (xy 399.766789 -45.326354) (xy 399.767298 -45.35424)
			(xy 399.766789 -45.382126) (xy 399.758669 -45.437302) (xy 399.742601 -45.490709) (xy 399.718929 -45.541206)
			(xy 399.688156 -45.587719) (xy 399.650939 -45.629256) (xy 399.608071 -45.664931) (xy 399.560465 -45.693985)
			(xy 399.509136 -45.715797) (xy 399.455179 -45.729903) (xy 399.399742 -45.736003) (xy 399.344008 -45.733966)
			(xy 399.289165 -45.723836) (xy 399.236381 -45.705829) (xy 399.186781 -45.680328) (xy 399.141423 -45.647877)
			(xy 399.101274 -45.609168) (xy 399.067188 -45.565025) (xy 399.039892 -45.51639) (xy 399.019969 -45.464299)
			(xy 399.007843 -45.409862) (xy 399.003772 -45.35424) (xy 395.04422 -45.35424) (xy 395.012645 -45.38948)
			(xy 394.969777 -45.425155) (xy 394.922171 -45.454209) (xy 394.870842 -45.476021) (xy 394.816885 -45.490127)
			(xy 394.761448 -45.496227) (xy 394.705714 -45.49419) (xy 394.650871 -45.48406) (xy 394.598087 -45.466053)
			(xy 394.548487 -45.440552) (xy 394.503129 -45.408101) (xy 394.46298 -45.369392) (xy 394.428894 -45.325249)
			(xy 394.401598 -45.276614) (xy 394.381675 -45.224523) (xy 394.369549 -45.170086) (xy 394.365478 -45.114464)
			(xy 389.287466 -45.114464) (xy 389.104494 -46.082204) (xy 392.35253 -46.082204) (xy 392.352959 -46.05495)
			(xy 392.360717 -46.000995) (xy 392.376074 -45.948695) (xy 392.398719 -45.899112) (xy 392.42819 -45.853257)
			(xy 392.463887 -45.812063) (xy 392.505084 -45.77637) (xy 392.550942 -45.746903) (xy 392.600526 -45.724262)
			(xy 392.652829 -45.708909) (xy 392.706783 -45.701157) (xy 392.734038 -45.700696) (xy 392.760942 -45.701129)
			(xy 392.814213 -45.708706) (xy 392.865892 -45.723691) (xy 392.914954 -45.745785) (xy 392.960426 -45.774552)
			(xy 393.001406 -45.809421) (xy 393.037083 -45.8497) (xy 393.0523 -45.871892) (xy 393.059412 -45.882814)
			(xy 393.082272 -45.894752) (xy 393.19454 -45.89272) (xy 393.216892 -45.879766) (xy 393.22375 -45.86859)
			(xy 393.238651 -45.844975) (xy 393.274333 -45.802023) (xy 393.315895 -45.764731) (xy 393.362449 -45.733895)
			(xy 393.413 -45.710174) (xy 393.466468 -45.694074) (xy 393.521712 -45.68594) (xy 393.549632 -45.685456)
			(xy 393.576626 -45.685899) (xy 393.630075 -45.693509) (xy 393.681919 -45.708574) (xy 393.731123 -45.730792)
			(xy 393.776706 -45.75972) (xy 393.797536 -45.776896) (xy 393.805664 -45.784008) (xy 393.826238 -45.790104)
			(xy 393.911582 -45.779182) (xy 393.922127 -45.777409) (xy 393.94041 -45.766354) (xy 393.946888 -45.757846)
			(xy 393.962255 -45.736626) (xy 393.99784 -45.698173) (xy 394.038355 -45.664953) (xy 394.083035 -45.637594)
			(xy 394.131041 -45.616608) (xy 394.181468 -45.602393) (xy 394.233366 -45.595215) (xy 394.259562 -45.594778)
			(xy 394.286816 -45.595267) (xy 394.340769 -45.603019) (xy 394.393069 -45.618371) (xy 394.442652 -45.641011)
			(xy 394.488508 -45.670477) (xy 394.529704 -45.706169) (xy 394.565401 -45.747361) (xy 394.594871 -45.793214)
			(xy 394.617516 -45.842795) (xy 394.632873 -45.895094) (xy 394.640631 -45.949046) (xy 394.640631 -46.003554)
			(xy 394.632873 -46.057506) (xy 394.617516 -46.109805) (xy 394.594871 -46.159386) (xy 394.565401 -46.205239)
			(xy 394.529704 -46.246431) (xy 394.488508 -46.282123) (xy 394.442652 -46.311589) (xy 394.393069 -46.334229)
			(xy 394.340769 -46.349581) (xy 394.286816 -46.357333) (xy 394.259562 -46.357794) (xy 394.232568 -46.357343)
			(xy 394.17912 -46.349733) (xy 394.127277 -46.33467) (xy 394.078073 -46.312454) (xy 394.032489 -46.283528)
			(xy 394.011658 -46.266354) (xy 394.00353 -46.259242) (xy 393.982956 -46.253146) (xy 393.897612 -46.264068)
			(xy 393.887071 -46.265856) (xy 393.868788 -46.276902) (xy 393.862306 -46.285404) (xy 393.844689 -46.309701)
			(xy 393.803096 -46.352963) (xy 393.779502 -46.37151) (xy 393.771628 -46.377352) (xy 393.761214 -46.394878)
			(xy 393.748006 -46.485302) (xy 393.752832 -46.504606) (xy 393.758674 -46.51248) (xy 393.758674 -46.512734)
			(xy 393.776177 -46.537478) (xy 393.80398 -46.591331) (xy 393.822916 -46.648903) (xy 393.830119 -46.693836)
			(xy 398.976342 -46.693836) (xy 398.976828 -46.666585) (xy 398.984584 -46.612637) (xy 398.999939 -46.560342)
			(xy 399.022581 -46.510765) (xy 399.052047 -46.464915) (xy 399.087738 -46.423724) (xy 399.128929 -46.388033)
			(xy 399.174779 -46.358567) (xy 399.224356 -46.335925) (xy 399.276651 -46.32057) (xy 399.330599 -46.312814)
			(xy 399.385101 -46.312814) (xy 399.439049 -46.32057) (xy 399.491344 -46.335925) (xy 399.540921 -46.358567)
			(xy 399.586771 -46.388033) (xy 399.627962 -46.423724) (xy 399.663653 -46.464915) (xy 399.693119 -46.510765)
			(xy 399.715761 -46.560342) (xy 399.731116 -46.612637) (xy 399.738872 -46.666585) (xy 399.739358 -46.693836)
			(xy 399.738891 -46.720264) (xy 399.731581 -46.772612) (xy 399.717106 -46.823447) (xy 399.695744 -46.871793)
			(xy 399.682208 -46.894496) (xy 399.681954 -46.89475) (xy 399.676617 -46.904768) (xy 399.67436 -46.927318)
			(xy 399.677636 -46.938184) (xy 399.703798 -47.01286) (xy 399.708161 -47.023386) (xy 399.724264 -47.03947)
			(xy 399.734786 -47.043848) (xy 399.73504 -47.043848) (xy 399.759547 -47.052921) (xy 399.806 -47.076863)
			(xy 399.848752 -47.106918) (xy 399.887004 -47.142525) (xy 399.920041 -47.183017) (xy 399.947245 -47.227638)
			(xy 399.968107 -47.275553) (xy 399.982237 -47.325866) (xy 399.989371 -47.377636) (xy 399.989802 -47.403766)
			(xy 399.989316 -47.431017) (xy 399.987793 -47.441612) (xy 401.261832 -47.441612) (xy 401.265903 -47.38599)
			(xy 401.278029 -47.331553) (xy 401.297952 -47.279462) (xy 401.325248 -47.230827) (xy 401.359334 -47.186684)
			(xy 401.399483 -47.147975) (xy 401.444841 -47.115524) (xy 401.494441 -47.090023) (xy 401.547225 -47.072016)
			(xy 401.602068 -47.061886) (xy 401.657802 -47.059849) (xy 401.713239 -47.065949) (xy 401.767196 -47.080055)
			(xy 401.818525 -47.101867) (xy 401.866131 -47.130921) (xy 401.908999 -47.166596) (xy 401.946216 -47.208133)
			(xy 401.976989 -47.254646) (xy 402.000661 -47.305143) (xy 402.016729 -47.35855) (xy 402.024849 -47.413726)
			(xy 402.025358 -47.441612) (xy 402.024849 -47.469498) (xy 402.016729 -47.524674) (xy 402.000661 -47.578081)
			(xy 401.976989 -47.628578) (xy 401.946216 -47.675091) (xy 401.908999 -47.716628) (xy 401.866131 -47.752303)
			(xy 401.818525 -47.781357) (xy 401.767196 -47.803169) (xy 401.713239 -47.817275) (xy 401.657802 -47.823375)
			(xy 401.602068 -47.821338) (xy 401.547225 -47.811208) (xy 401.494441 -47.793201) (xy 401.444841 -47.7677)
			(xy 401.399483 -47.735249) (xy 401.359334 -47.69654) (xy 401.325248 -47.652397) (xy 401.297952 -47.603762)
			(xy 401.278029 -47.551671) (xy 401.265903 -47.497234) (xy 401.261832 -47.441612) (xy 399.987793 -47.441612)
			(xy 399.98156 -47.484965) (xy 399.966205 -47.53726) (xy 399.943563 -47.586837) (xy 399.914097 -47.632687)
			(xy 399.878406 -47.673878) (xy 399.837215 -47.709569) (xy 399.791365 -47.739035) (xy 399.741788 -47.761677)
			(xy 399.689493 -47.777032) (xy 399.635545 -47.784788) (xy 399.581043 -47.784788) (xy 399.527095 -47.777032)
			(xy 399.4748 -47.761677) (xy 399.425223 -47.739035) (xy 399.379373 -47.709569) (xy 399.338182 -47.673878)
			(xy 399.302491 -47.632687) (xy 399.273025 -47.586837) (xy 399.250383 -47.53726) (xy 399.235028 -47.484965)
			(xy 399.227272 -47.431017) (xy 399.226786 -47.403766) (xy 399.227262 -47.377339) (xy 399.23457 -47.324991)
			(xy 399.249043 -47.274156) (xy 399.270402 -47.225809) (xy 399.283936 -47.203106) (xy 399.28419 -47.202852)
			(xy 399.289525 -47.192834) (xy 399.291782 -47.170284) (xy 399.288508 -47.159418) (xy 399.262346 -47.084742)
			(xy 399.257962 -47.074227) (xy 399.241873 -47.058138) (xy 399.231358 -47.053754) (xy 399.231104 -47.053754)
			(xy 399.206585 -47.044711) (xy 399.160134 -47.020763) (xy 399.117384 -46.990702) (xy 399.079133 -46.955091)
			(xy 399.046099 -46.914595) (xy 399.018897 -46.869971) (xy 398.998036 -46.822054) (xy 398.983907 -46.771739)
			(xy 398.976773 -46.719967) (xy 398.976342 -46.693836) (xy 393.830119 -46.693836) (xy 393.832509 -46.708745)
			(xy 393.833096 -46.739048) (xy 393.832667 -46.766301) (xy 393.824903 -46.820251) (xy 393.809542 -46.872548)
			(xy 393.786894 -46.922126) (xy 393.757422 -46.967977) (xy 393.721724 -47.009167) (xy 393.680529 -47.044858)
			(xy 393.634673 -47.074323) (xy 393.585092 -47.096963) (xy 393.532793 -47.112316) (xy 393.478841 -47.120071)
			(xy 393.451588 -47.120556) (xy 393.425554 -47.120109) (xy 393.373972 -47.113021) (xy 393.32383 -47.098991)
			(xy 393.276059 -47.07828) (xy 393.231544 -47.051272) (xy 393.21105 -47.035212) (xy 393.203285 -47.029483)
			(xy 393.184881 -47.023734) (xy 393.175236 -47.024036) (xy 393.09548 -47.030386) (xy 393.0777 -47.039022)
			(xy 393.07135 -47.046388) (xy 393.053167 -47.066032) (xy 393.01226 -47.100554) (xy 392.966931 -47.129023)
			(xy 392.91807 -47.150881) (xy 392.866635 -47.165699) (xy 392.813634 -47.173186) (xy 392.78687 -47.173642)
			(xy 392.75962 -47.17315) (xy 392.705674 -47.16539) (xy 392.653381 -47.150033) (xy 392.603806 -47.127391)
			(xy 392.557958 -47.097925) (xy 392.516769 -47.062234) (xy 392.481078 -47.021046) (xy 392.451611 -46.975197)
			(xy 392.428968 -46.925622) (xy 392.41361 -46.87333) (xy 392.40585 -46.819384) (xy 392.405362 -46.792134)
			(xy 392.405897 -46.76336) (xy 392.414547 -46.706467) (xy 392.431641 -46.651517) (xy 392.456792 -46.599757)
			(xy 392.48943 -46.55236) (xy 392.50874 -46.531022) (xy 392.516106 -46.523148) (xy 392.523218 -46.503336)
			(xy 392.515852 -46.40707) (xy 392.505946 -46.388274) (xy 392.497564 -46.38167) (xy 392.475388 -46.363434)
			(xy 392.436176 -46.321503) (xy 392.403688 -46.27417) (xy 392.378657 -46.222504) (xy 392.36165 -46.167671)
			(xy 392.353048 -46.110909) (xy 392.35253 -46.082204) (xy 389.104494 -46.082204) (xy 388.882382 -47.256954)
			(xy 388.683902 -48.30699) (xy 398.853912 -48.30699) (xy 398.857983 -48.251368) (xy 398.870109 -48.196931)
			(xy 398.890032 -48.14484) (xy 398.917328 -48.096205) (xy 398.951414 -48.052062) (xy 398.991563 -48.013353)
			(xy 399.036921 -47.980902) (xy 399.086521 -47.955401) (xy 399.139305 -47.937394) (xy 399.194148 -47.927264)
			(xy 399.249882 -47.925227) (xy 399.305319 -47.931327) (xy 399.359276 -47.945433) (xy 399.410605 -47.967245)
			(xy 399.458211 -47.996299) (xy 399.501079 -48.031974) (xy 399.538296 -48.073511) (xy 399.569069 -48.120024)
			(xy 399.592741 -48.170521) (xy 399.608809 -48.223928) (xy 399.616929 -48.279104) (xy 399.617438 -48.30699)
			(xy 399.616929 -48.334876) (xy 399.608809 -48.390052) (xy 399.592741 -48.443459) (xy 399.569069 -48.493956)
			(xy 399.538296 -48.540469) (xy 399.501079 -48.582006) (xy 399.458211 -48.617681) (xy 399.410605 -48.646735)
			(xy 399.359276 -48.668547) (xy 399.305319 -48.682653) (xy 399.249882 -48.688753) (xy 399.194148 -48.686716)
			(xy 399.139305 -48.676586) (xy 399.086521 -48.658579) (xy 399.036921 -48.633078) (xy 398.991563 -48.600627)
			(xy 398.951414 -48.561918) (xy 398.917328 -48.517775) (xy 398.890032 -48.46914) (xy 398.870109 -48.417049)
			(xy 398.857983 -48.362612) (xy 398.853912 -48.30699) (xy 388.683902 -48.30699) (xy 388.599593 -48.753014)
			(xy 395.468346 -48.753014) (xy 395.472417 -48.697392) (xy 395.484543 -48.642955) (xy 395.504466 -48.590864)
			(xy 395.531762 -48.542229) (xy 395.565848 -48.498086) (xy 395.605997 -48.459377) (xy 395.651355 -48.426926)
			(xy 395.700955 -48.401425) (xy 395.753739 -48.383418) (xy 395.808582 -48.373288) (xy 395.864316 -48.371251)
			(xy 395.919753 -48.377351) (xy 395.97371 -48.391457) (xy 396.025039 -48.413269) (xy 396.072645 -48.442323)
			(xy 396.115513 -48.477998) (xy 396.15273 -48.519535) (xy 396.183503 -48.566048) (xy 396.207175 -48.616545)
			(xy 396.223243 -48.669952) (xy 396.231363 -48.725128) (xy 396.231872 -48.753014) (xy 396.231363 -48.7809)
			(xy 396.223243 -48.836076) (xy 396.207175 -48.889483) (xy 396.205779 -48.89246) (xy 397.514062 -48.89246)
			(xy 397.518133 -48.836838) (xy 397.530259 -48.782401) (xy 397.550182 -48.73031) (xy 397.577478 -48.681675)
			(xy 397.611564 -48.637532) (xy 397.651713 -48.598823) (xy 397.697071 -48.566372) (xy 397.746671 -48.540871)
			(xy 397.799455 -48.522864) (xy 397.854298 -48.512734) (xy 397.910032 -48.510697) (xy 397.965469 -48.516797)
			(xy 398.019426 -48.530903) (xy 398.070755 -48.552715) (xy 398.118361 -48.581769) (xy 398.161229 -48.617444)
			(xy 398.198446 -48.658981) (xy 398.229219 -48.705494) (xy 398.252891 -48.755991) (xy 398.268959 -48.809398)
			(xy 398.277079 -48.864574) (xy 398.277588 -48.89246) (xy 398.277079 -48.920346) (xy 398.274641 -48.93691)
			(xy 401.23313 -48.93691) (xy 401.237201 -48.881288) (xy 401.249327 -48.826851) (xy 401.26925 -48.77476)
			(xy 401.296546 -48.726125) (xy 401.330632 -48.681982) (xy 401.370781 -48.643273) (xy 401.416139 -48.610822)
			(xy 401.465739 -48.585321) (xy 401.518523 -48.567314) (xy 401.573366 -48.557184) (xy 401.6291 -48.555147)
			(xy 401.684537 -48.561247) (xy 401.738494 -48.575353) (xy 401.789823 -48.597165) (xy 401.837429 -48.626219)
			(xy 401.880297 -48.661894) (xy 401.917514 -48.703431) (xy 401.948287 -48.749944) (xy 401.971959 -48.800441)
			(xy 401.988027 -48.853848) (xy 401.996147 -48.909024) (xy 401.996656 -48.93691) (xy 401.996147 -48.964796)
			(xy 401.988027 -49.019972) (xy 401.971959 -49.073379) (xy 401.948287 -49.123876) (xy 401.917514 -49.170389)
			(xy 401.880297 -49.211926) (xy 401.837429 -49.247601) (xy 401.789823 -49.276655) (xy 401.738494 -49.298467)
			(xy 401.684537 -49.312573) (xy 401.6291 -49.318673) (xy 401.573366 -49.316636) (xy 401.518523 -49.306506)
			(xy 401.465739 -49.288499) (xy 401.416139 -49.262998) (xy 401.370781 -49.230547) (xy 401.330632 -49.191838)
			(xy 401.296546 -49.147695) (xy 401.26925 -49.09906) (xy 401.249327 -49.046969) (xy 401.237201 -48.992532)
			(xy 401.23313 -48.93691) (xy 398.274641 -48.93691) (xy 398.268959 -48.975522) (xy 398.252891 -49.028929)
			(xy 398.229219 -49.079426) (xy 398.198446 -49.125939) (xy 398.161229 -49.167476) (xy 398.118361 -49.203151)
			(xy 398.070755 -49.232205) (xy 398.019426 -49.254017) (xy 397.965469 -49.268123) (xy 397.910032 -49.274223)
			(xy 397.854298 -49.272186) (xy 397.799455 -49.262056) (xy 397.746671 -49.244049) (xy 397.697071 -49.218548)
			(xy 397.651713 -49.186097) (xy 397.611564 -49.147388) (xy 397.577478 -49.103245) (xy 397.550182 -49.05461)
			(xy 397.530259 -49.002519) (xy 397.518133 -48.948082) (xy 397.514062 -48.89246) (xy 396.205779 -48.89246)
			(xy 396.183503 -48.93998) (xy 396.15273 -48.986493) (xy 396.115513 -49.02803) (xy 396.072645 -49.063705)
			(xy 396.025039 -49.092759) (xy 395.97371 -49.114571) (xy 395.919753 -49.128677) (xy 395.864316 -49.134777)
			(xy 395.808582 -49.13274) (xy 395.753739 -49.12261) (xy 395.700955 -49.104603) (xy 395.651355 -49.079102)
			(xy 395.605997 -49.046651) (xy 395.565848 -49.007942) (xy 395.531762 -48.963799) (xy 395.504466 -48.915164)
			(xy 395.484543 -48.863073) (xy 395.472417 -48.808636) (xy 395.468346 -48.753014) (xy 388.599593 -48.753014)
			(xy 388.523734 -49.154334) (xy 388.45744 -49.505108) (xy 388.456678 -49.513744) (xy 388.449841 -49.95291)
			(xy 401.23313 -49.95291) (xy 401.237201 -49.897288) (xy 401.249327 -49.842851) (xy 401.26925 -49.79076)
			(xy 401.296546 -49.742125) (xy 401.330632 -49.697982) (xy 401.370781 -49.659273) (xy 401.416139 -49.626822)
			(xy 401.465739 -49.601321) (xy 401.518523 -49.583314) (xy 401.573366 -49.573184) (xy 401.6291 -49.571147)
			(xy 401.684537 -49.577247) (xy 401.738494 -49.591353) (xy 401.789823 -49.613165) (xy 401.837429 -49.642219)
			(xy 401.880297 -49.677894) (xy 401.917514 -49.719431) (xy 401.948287 -49.765944) (xy 401.971959 -49.816441)
			(xy 401.988027 -49.869848) (xy 401.996147 -49.925024) (xy 401.996656 -49.95291) (xy 401.996147 -49.980796)
			(xy 401.988027 -50.035972) (xy 401.971959 -50.089379) (xy 401.948287 -50.139876) (xy 401.917514 -50.186389)
			(xy 401.880297 -50.227926) (xy 401.837429 -50.263601) (xy 401.789823 -50.292655) (xy 401.738494 -50.314467)
			(xy 401.684537 -50.328573) (xy 401.6291 -50.334673) (xy 401.573366 -50.332636) (xy 401.518523 -50.322506)
			(xy 401.465739 -50.304499) (xy 401.416139 -50.278998) (xy 401.370781 -50.246547) (xy 401.330632 -50.207838)
			(xy 401.296546 -50.163695) (xy 401.26925 -50.11506) (xy 401.249327 -50.062969) (xy 401.237201 -50.008532)
			(xy 401.23313 -49.95291) (xy 388.449841 -49.95291) (xy 388.433238 -51.019456) (xy 399.049492 -51.019456)
			(xy 399.053563 -50.963834) (xy 399.065689 -50.909397) (xy 399.085612 -50.857306) (xy 399.112908 -50.808671)
			(xy 399.146994 -50.764528) (xy 399.187143 -50.725819) (xy 399.232501 -50.693368) (xy 399.282101 -50.667867)
			(xy 399.334885 -50.64986) (xy 399.389728 -50.63973) (xy 399.445462 -50.637693) (xy 399.500899 -50.643793)
			(xy 399.554856 -50.657899) (xy 399.606185 -50.679711) (xy 399.653791 -50.708765) (xy 399.696659 -50.74444)
			(xy 399.733876 -50.785977) (xy 399.764649 -50.83249) (xy 399.788321 -50.882987) (xy 399.804389 -50.936394)
			(xy 399.812509 -50.99157) (xy 399.813018 -51.019456) (xy 399.812509 -51.047342) (xy 399.804389 -51.102518)
			(xy 399.788321 -51.155925) (xy 399.764649 -51.206422) (xy 399.739793 -51.243992) (xy 407.433018 -51.243992)
			(xy 407.433475 -51.216621) (xy 407.441294 -51.162442) (xy 407.456785 -51.109938) (xy 407.479629 -51.060192)
			(xy 407.509356 -51.014225) (xy 407.526998 -50.993294) (xy 407.527252 -50.99304) (xy 407.532834 -50.985951)
			(xy 407.539082 -50.969036) (xy 407.539444 -50.96002) (xy 407.539444 -50.892964) (xy 407.539117 -50.883944)
			(xy 407.53285 -50.867026) (xy 407.527252 -50.859944) (xy 407.526998 -50.859944) (xy 407.526998 -50.85969)
			(xy 407.50934 -50.838773) (xy 407.479631 -50.792796) (xy 407.456799 -50.743045) (xy 407.441312 -50.690541)
			(xy 407.433489 -50.636362) (xy 407.433018 -50.608992) (xy 407.433448 -50.581738) (xy 407.441207 -50.527784)
			(xy 407.456565 -50.475484) (xy 407.47921 -50.425902) (xy 407.508682 -50.380048) (xy 407.544379 -50.338855)
			(xy 407.585575 -50.303161) (xy 407.631432 -50.273694) (xy 407.681016 -50.251053) (xy 407.733318 -50.235699)
			(xy 407.787272 -50.227946) (xy 407.814526 -50.227484) (xy 407.843443 -50.228024) (xy 407.900614 -50.236744)
			(xy 407.955814 -50.253995) (xy 408.007776 -50.279383) (xy 408.055311 -50.312324) (xy 408.097326 -50.352065)
			(xy 408.115516 -50.37455) (xy 408.123117 -50.383363) (xy 408.144023 -50.393542) (xy 408.155648 -50.394108)
			(xy 408.235404 -50.394108) (xy 408.247034 -50.393554) (xy 408.267943 -50.383375) (xy 408.275536 -50.37455)
			(xy 408.293694 -50.352039) (xy 408.335722 -50.312308) (xy 408.383264 -50.279373) (xy 408.435232 -50.25399)
			(xy 408.490435 -50.236739) (xy 408.547608 -50.228016) (xy 408.576526 -50.227484) (xy 408.603778 -50.227954)
			(xy 408.657725 -50.235713) (xy 408.71002 -50.251071) (xy 408.759597 -50.273715) (xy 408.805447 -50.303183)
			(xy 408.846636 -50.338876) (xy 408.882328 -50.380068) (xy 408.911794 -50.425919) (xy 408.934435 -50.475497)
			(xy 408.94979 -50.527792) (xy 408.957548 -50.58174) (xy 408.958034 -50.608992) (xy 408.95755 -50.635305)
			(xy 408.950317 -50.687433) (xy 408.936001 -50.738075) (xy 408.914871 -50.786273) (xy 408.887329 -50.831117)
			(xy 408.853894 -50.871758) (xy 408.834844 -50.889916) (xy 408.82744 -50.897436) (xy 408.818916 -50.916717)
			(xy 408.818334 -50.927254) (xy 408.818334 -51.00193) (xy 408.818877 -51.012478) (xy 408.827401 -51.031774)
			(xy 408.834844 -51.039268) (xy 408.853934 -51.057389) (xy 408.887386 -51.098027) (xy 408.91494 -51.142875)
			(xy 408.936072 -51.191082) (xy 408.950382 -51.241735) (xy 408.957599 -51.293874) (xy 408.958034 -51.320192)
			(xy 408.957515 -51.347442) (xy 408.94976 -51.401387) (xy 408.934407 -51.45368) (xy 408.911769 -51.503255)
			(xy 408.882306 -51.549104) (xy 408.846618 -51.590294) (xy 408.805432 -51.625986) (xy 408.759585 -51.655453)
			(xy 408.710012 -51.678095) (xy 408.65772 -51.693453) (xy 408.603776 -51.701212) (xy 408.576526 -51.7017)
			(xy 408.548862 -51.701167) (xy 408.494113 -51.693172) (xy 408.441092 -51.677358) (xy 408.390908 -51.654059)
			(xy 408.344612 -51.623761) (xy 408.303174 -51.587098) (xy 408.26746 -51.54484) (xy 408.252422 -51.521614)
			(xy 408.245785 -51.511938) (xy 408.225924 -51.499495) (xy 408.214322 -51.497738) (xy 408.134312 -51.489864)
			(xy 408.122674 -51.489243) (xy 408.100837 -51.497315) (xy 408.092402 -51.505358) (xy 408.092148 -51.505612)
			(xy 408.074077 -51.524203) (xy 408.033742 -51.55678) (xy 407.989366 -51.583591) (xy 407.941766 -51.604142)
			(xy 407.89182 -51.618054) (xy 407.84045 -51.625069) (xy 407.814526 -51.6255) (xy 407.787273 -51.62502)
			(xy 407.733323 -51.617267) (xy 407.681025 -51.601914) (xy 407.631444 -51.579274) (xy 407.58559 -51.549808)
			(xy 407.544397 -51.514116) (xy 407.508703 -51.472924) (xy 407.479235 -51.427072) (xy 407.456593 -51.377492)
			(xy 407.441237 -51.325195) (xy 407.433481 -51.271245) (xy 407.433018 -51.243992) (xy 399.739793 -51.243992)
			(xy 399.733876 -51.252935) (xy 399.696659 -51.294472) (xy 399.653791 -51.330147) (xy 399.606185 -51.359201)
			(xy 399.554856 -51.381013) (xy 399.500899 -51.395119) (xy 399.445462 -51.401219) (xy 399.389728 -51.399182)
			(xy 399.334885 -51.389052) (xy 399.282101 -51.371045) (xy 399.232501 -51.345544) (xy 399.187143 -51.313093)
			(xy 399.146994 -51.274384) (xy 399.112908 -51.230241) (xy 399.085612 -51.181606) (xy 399.065689 -51.129515)
			(xy 399.053563 -51.075078) (xy 399.049492 -51.019456) (xy 388.433238 -51.019456) (xy 388.417422 -52.035456)
			(xy 401.241258 -52.035456) (xy 401.245329 -51.979834) (xy 401.257455 -51.925397) (xy 401.277378 -51.873306)
			(xy 401.304674 -51.824671) (xy 401.33876 -51.780528) (xy 401.378909 -51.741819) (xy 401.424267 -51.709368)
			(xy 401.473867 -51.683867) (xy 401.526651 -51.66586) (xy 401.581494 -51.65573) (xy 401.637228 -51.653693)
			(xy 401.692665 -51.659793) (xy 401.746622 -51.673899) (xy 401.797951 -51.695711) (xy 401.845557 -51.724765)
			(xy 401.888425 -51.76044) (xy 401.925642 -51.801977) (xy 401.956415 -51.84849) (xy 401.980087 -51.898987)
			(xy 401.996155 -51.952394) (xy 402.004275 -52.00757) (xy 402.004784 -52.035456) (xy 402.004275 -52.063342)
			(xy 401.996155 -52.118518) (xy 401.980087 -52.171925) (xy 401.956415 -52.222422) (xy 401.925642 -52.268935)
			(xy 401.888425 -52.310472) (xy 401.845557 -52.346147) (xy 401.797951 -52.375201) (xy 401.746622 -52.397013)
			(xy 401.692665 -52.411119) (xy 401.637228 -52.417219) (xy 401.581494 -52.415182) (xy 401.526651 -52.405052)
			(xy 401.473867 -52.387045) (xy 401.424267 -52.361544) (xy 401.378909 -52.329093) (xy 401.33876 -52.290384)
			(xy 401.304674 -52.246241) (xy 401.277378 -52.197606) (xy 401.257455 -52.145515) (xy 401.245329 -52.091078)
			(xy 401.241258 -52.035456) (xy 388.417422 -52.035456) (xy 388.410704 -52.467002) (xy 388.410744 -52.473128)
			(xy 388.413437 -52.485077) (xy 388.416038 -52.490624) (xy 388.421626 -52.501546) (xy 388.424928 -52.504086)
			(xy 388.446908 -52.519846) (xy 388.48673 -52.556443) (xy 388.52114 -52.598169) (xy 388.549484 -52.644232)
			(xy 388.571223 -52.693755) (xy 388.585944 -52.745797) (xy 388.593368 -52.79937) (xy 388.593838 -52.826412)
			(xy 388.593379 -52.853825) (xy 388.585736 -52.908116) (xy 388.570602 -52.960812) (xy 388.548272 -53.010885)
			(xy 388.519181 -53.057357) (xy 388.50189 -53.078634) (xy 388.501636 -53.078888) (xy 388.495794 -53.086)
			(xy 388.489698 -53.10251) (xy 388.489698 -53.117242) (xy 388.489554 -53.122681) (xy 388.487245 -53.133312)
			(xy 388.485126 -53.138324) (xy 388.478776 -53.152294) (xy 388.475107 -53.16146) (xy 388.474293 -53.181167)
			(xy 388.480947 -53.199735) (xy 388.487158 -53.207412) (xy 388.496302 -53.217826) (xy 388.512404 -53.238023)
			(xy 388.539605 -53.281934) (xy 388.560652 -53.329105) (xy 388.575164 -53.378678) (xy 388.582877 -53.429752)
			(xy 388.583678 -53.45557) (xy 388.583678 -53.461666) (xy 388.583069 -53.491575) (xy 388.573688 -53.550653)
			(xy 388.555212 -53.607547) (xy 388.528093 -53.660865) (xy 388.511034 -53.68544) (xy 388.504684 -53.694076)
			(xy 388.500874 -53.698902) (xy 388.49554 -53.707538) (xy 388.495032 -53.708554) (xy 388.492571 -53.71388)
			(xy 388.489879 -53.725296) (xy 388.489698 -53.73116) (xy 388.489698 -53.752242) (xy 388.489554 -53.757681)
			(xy 388.487245 -53.768312) (xy 388.485126 -53.773324) (xy 388.478776 -53.787294) (xy 388.475107 -53.79646)
			(xy 388.474293 -53.816167) (xy 388.480947 -53.834735) (xy 388.487158 -53.842412) (xy 388.496302 -53.852826)
			(xy 388.512404 -53.873023) (xy 388.539605 -53.916934) (xy 388.560652 -53.964105) (xy 388.575164 -54.013678)
			(xy 388.582877 -54.064752) (xy 388.583678 -54.09057) (xy 388.583678 -54.096666) (xy 388.583069 -54.126575)
			(xy 388.573688 -54.185653) (xy 388.555212 -54.242547) (xy 388.528093 -54.295865) (xy 388.511034 -54.32044)
			(xy 388.504684 -54.329076) (xy 388.500874 -54.333902) (xy 388.49554 -54.342538) (xy 388.495032 -54.343554)
			(xy 388.492571 -54.34888) (xy 388.489879 -54.360296) (xy 388.489698 -54.36616) (xy 388.489698 -54.387242)
			(xy 388.489554 -54.392681) (xy 388.487245 -54.403312) (xy 388.485126 -54.408324) (xy 388.479538 -54.4195)
			(xy 388.475612 -54.428767) (xy 388.474462 -54.448838) (xy 388.481065 -54.467827) (xy 388.487412 -54.475634)
			(xy 388.487412 -54.475888) (xy 388.505674 -54.49706) (xy 388.536497 -54.543706) (xy 388.560206 -54.594341)
			(xy 388.576295 -54.647886) (xy 388.584421 -54.703203) (xy 388.584948 -54.731158) (xy 388.584948 -54.731412)
			(xy 388.584412 -54.760444) (xy 388.579734 -54.791102) (xy 390.476486 -54.791102) (xy 390.476957 -54.763732)
			(xy 390.484774 -54.709553) (xy 390.500262 -54.65705) (xy 390.523103 -54.607303) (xy 390.552826 -54.561336)
			(xy 390.570466 -54.540404) (xy 390.57072 -54.54015) (xy 390.576294 -54.533055) (xy 390.582548 -54.516145)
			(xy 390.582912 -54.50713) (xy 390.582912 -54.440074) (xy 390.582565 -54.431056) (xy 390.57631 -54.41414)
			(xy 390.57072 -54.407054) (xy 390.570466 -54.407054) (xy 390.570466 -54.4068) (xy 390.552826 -54.385866)
			(xy 390.523098 -54.3399) (xy 390.50025 -54.290154) (xy 390.484752 -54.237652) (xy 390.476922 -54.183472)
			(xy 390.476922 -54.128731) (xy 390.484751 -54.074551) (xy 390.500249 -54.022049) (xy 390.523096 -53.972303)
			(xy 390.552824 -53.926336) (xy 390.570466 -53.905404) (xy 390.57072 -53.90515) (xy 390.576294 -53.898055)
			(xy 390.582548 -53.881145) (xy 390.582912 -53.87213) (xy 390.582912 -53.805074) (xy 390.582565 -53.796056)
			(xy 390.57631 -53.77914) (xy 390.57072 -53.772054) (xy 390.570466 -53.772054) (xy 390.570466 -53.7718)
			(xy 390.552826 -53.750866) (xy 390.523098 -53.7049) (xy 390.50025 -53.655154) (xy 390.484752 -53.602652)
			(xy 390.476922 -53.548472) (xy 390.476922 -53.493731) (xy 390.484751 -53.439551) (xy 390.500249 -53.387049)
			(xy 390.523096 -53.337303) (xy 390.552824 -53.291336) (xy 390.570466 -53.270404) (xy 390.57072 -53.27015)
			(xy 390.576294 -53.263055) (xy 390.582548 -53.246145) (xy 390.582912 -53.23713) (xy 390.582912 -53.170074)
			(xy 390.582565 -53.161056) (xy 390.57631 -53.14414) (xy 390.57072 -53.137054) (xy 390.570466 -53.137054)
			(xy 390.570466 -53.1368) (xy 390.552808 -53.115883) (xy 390.5231 -53.069906) (xy 390.500269 -53.020154)
			(xy 390.484782 -52.96765) (xy 390.476958 -52.913472) (xy 390.476486 -52.886102) (xy 390.476972 -52.858851)
			(xy 390.484728 -52.804903) (xy 390.500083 -52.752608) (xy 390.522725 -52.703031) (xy 390.552191 -52.657181)
			(xy 390.587882 -52.61599) (xy 390.629073 -52.580299) (xy 390.674923 -52.550833) (xy 390.7245 -52.528191)
			(xy 390.776795 -52.512836) (xy 390.830743 -52.50508) (xy 390.885245 -52.50508) (xy 390.939193 -52.512836)
			(xy 390.991488 -52.528191) (xy 391.030588 -52.546048) (xy 395.979696 -52.546048) (xy 395.979696 -52.491552)
			(xy 395.987451 -52.437612) (xy 396.002803 -52.385323) (xy 396.025439 -52.335752) (xy 396.054899 -52.289906)
			(xy 396.090584 -52.248719) (xy 396.131766 -52.213029) (xy 396.177608 -52.183563) (xy 396.227176 -52.16092)
			(xy 396.279463 -52.145562) (xy 396.333402 -52.1378) (xy 396.36065 -52.13731) (xy 396.388019 -52.137803)
			(xy 396.442197 -52.145614) (xy 396.4947 -52.161097) (xy 396.544448 -52.183932) (xy 396.590415 -52.213651)
			(xy 396.611348 -52.23129) (xy 396.611602 -52.231544) (xy 396.61868 -52.237143) (xy 396.635604 -52.243381)
			(xy 396.644622 -52.243736) (xy 396.711678 -52.243736) (xy 396.720693 -52.243361) (xy 396.737609 -52.237125)
			(xy 396.744698 -52.231544) (xy 396.744698 -52.23129) (xy 396.744952 -52.23129) (xy 396.765885 -52.213649)
			(xy 396.811853 -52.183925) (xy 396.861599 -52.161079) (xy 396.914101 -52.145583) (xy 396.968279 -52.137754)
			(xy 397.023021 -52.137754) (xy 397.077199 -52.145583) (xy 397.129701 -52.161079) (xy 397.179447 -52.183925)
			(xy 397.225415 -52.213649) (xy 397.246348 -52.23129) (xy 397.246602 -52.231544) (xy 397.25368 -52.237143)
			(xy 397.270604 -52.243381) (xy 397.279622 -52.243736) (xy 397.346678 -52.243736) (xy 397.355693 -52.243361)
			(xy 397.372609 -52.237125) (xy 397.379698 -52.231544) (xy 397.379698 -52.23129) (xy 397.379952 -52.23129)
			(xy 397.40089 -52.213658) (xy 397.446861 -52.183946) (xy 397.496607 -52.161109) (xy 397.549107 -52.145616)
			(xy 397.603281 -52.137785) (xy 397.63065 -52.13731) (xy 397.657906 -52.137733) (xy 397.711865 -52.145485)
			(xy 397.764172 -52.160837) (xy 397.813761 -52.183478) (xy 397.859622 -52.212946) (xy 397.900823 -52.248642)
			(xy 397.936524 -52.289838) (xy 397.965998 -52.335695) (xy 397.988645 -52.385281) (xy 398.004004 -52.437586)
			(xy 398.011763 -52.491544) (xy 398.011763 -52.546056) (xy 398.005818 -52.587398) (xy 399.055334 -52.587398)
			(xy 399.059405 -52.531776) (xy 399.071531 -52.477339) (xy 399.091454 -52.425248) (xy 399.11875 -52.376613)
			(xy 399.152836 -52.33247) (xy 399.192985 -52.293761) (xy 399.238343 -52.26131) (xy 399.287943 -52.235809)
			(xy 399.340727 -52.217802) (xy 399.39557 -52.207672) (xy 399.451304 -52.205635) (xy 399.506741 -52.211735)
			(xy 399.560698 -52.225841) (xy 399.612027 -52.247653) (xy 399.659633 -52.276707) (xy 399.702501 -52.312382)
			(xy 399.739718 -52.353919) (xy 399.770491 -52.400432) (xy 399.794163 -52.450929) (xy 399.810231 -52.504336)
			(xy 399.817827 -52.555948) (xy 406.883902 -52.555948) (xy 406.883902 -52.501452) (xy 406.891657 -52.44751)
			(xy 406.90701 -52.395221) (xy 406.929647 -52.345649) (xy 406.959109 -52.299803) (xy 406.994795 -52.258616)
			(xy 407.035979 -52.222927) (xy 407.081823 -52.193462) (xy 407.131393 -52.17082) (xy 407.183681 -52.155464)
			(xy 407.237622 -52.147704) (xy 407.26487 -52.147216) (xy 407.29224 -52.147696) (xy 407.346418 -52.15551)
			(xy 407.398922 -52.170995) (xy 407.448669 -52.193834) (xy 407.494636 -52.223556) (xy 407.515568 -52.241196)
			(xy 407.515822 -52.24145) (xy 407.522894 -52.247058) (xy 407.539822 -52.253291) (xy 407.548842 -52.253642)
			(xy 407.615898 -52.253642) (xy 407.624916 -52.253296) (xy 407.641834 -52.247042) (xy 407.648918 -52.24145)
			(xy 407.648918 -52.241196) (xy 407.649172 -52.241196) (xy 407.670103 -52.223556) (xy 407.716076 -52.193844)
			(xy 407.765824 -52.171009) (xy 407.818325 -52.155518) (xy 407.872501 -52.14769) (xy 407.89987 -52.147216)
			(xy 407.927126 -52.147629) (xy 407.981084 -52.155383) (xy 408.033388 -52.170737) (xy 408.082976 -52.19338)
			(xy 408.128835 -52.222849) (xy 408.170034 -52.258545) (xy 408.205733 -52.299741) (xy 408.235206 -52.345598)
			(xy 408.257852 -52.395183) (xy 408.273211 -52.447487) (xy 408.280969 -52.501444) (xy 408.280969 -52.555956)
			(xy 408.273211 -52.609913) (xy 408.257852 -52.662217) (xy 408.235206 -52.711802) (xy 408.205733 -52.757659)
			(xy 408.170034 -52.798855) (xy 408.128835 -52.834551) (xy 408.082976 -52.86402) (xy 408.033388 -52.886663)
			(xy 407.981084 -52.902017) (xy 407.927126 -52.909771) (xy 407.89987 -52.910232) (xy 407.872498 -52.9098)
			(xy 407.818317 -52.901977) (xy 407.765813 -52.88648) (xy 407.716067 -52.863631) (xy 407.670102 -52.833898)
			(xy 407.649172 -52.816252) (xy 407.648918 -52.815998) (xy 407.641831 -52.810413) (xy 407.624914 -52.804165)
			(xy 407.615898 -52.803806) (xy 407.548842 -52.803806) (xy 407.539827 -52.804182) (xy 407.52291 -52.810416)
			(xy 407.515822 -52.815998) (xy 407.515822 -52.816252) (xy 407.515568 -52.816252) (xy 407.494615 -52.833865)
			(xy 407.448649 -52.863583) (xy 407.398907 -52.886424) (xy 407.34641 -52.901921) (xy 407.292238 -52.909755)
			(xy 407.26487 -52.910232) (xy 407.237622 -52.909696) (xy 407.183681 -52.901936) (xy 407.131393 -52.88658)
			(xy 407.081823 -52.863938) (xy 407.035979 -52.834473) (xy 406.994795 -52.798784) (xy 406.959109 -52.757597)
			(xy 406.929647 -52.711751) (xy 406.90701 -52.662179) (xy 406.891657 -52.60989) (xy 406.883902 -52.555948)
			(xy 399.817827 -52.555948) (xy 399.818351 -52.559512) (xy 399.81886 -52.587398) (xy 399.818351 -52.615284)
			(xy 399.810231 -52.67046) (xy 399.794163 -52.723867) (xy 399.770491 -52.774364) (xy 399.739718 -52.820877)
			(xy 399.702501 -52.862414) (xy 399.659633 -52.898089) (xy 399.612027 -52.927143) (xy 399.560698 -52.948955)
			(xy 399.506741 -52.963061) (xy 399.451304 -52.969161) (xy 399.39557 -52.967124) (xy 399.340727 -52.956994)
			(xy 399.287943 -52.938987) (xy 399.238343 -52.913486) (xy 399.192985 -52.881035) (xy 399.152836 -52.842326)
			(xy 399.11875 -52.798183) (xy 399.091454 -52.749548) (xy 399.071531 -52.697457) (xy 399.059405 -52.64302)
			(xy 399.055334 -52.587398) (xy 398.005818 -52.587398) (xy 398.004004 -52.600014) (xy 397.988645 -52.652319)
			(xy 397.965998 -52.701905) (xy 397.936524 -52.747762) (xy 397.900823 -52.788958) (xy 397.859622 -52.824654)
			(xy 397.813761 -52.854122) (xy 397.764172 -52.876763) (xy 397.711865 -52.892115) (xy 397.657907 -52.899867)
			(xy 397.63065 -52.900326) (xy 397.60328 -52.899849) (xy 397.549101 -52.892036) (xy 397.496597 -52.876551)
			(xy 397.44685 -52.853711) (xy 397.400883 -52.823987) (xy 397.379952 -52.806346) (xy 397.379698 -52.806092)
			(xy 397.372617 -52.800498) (xy 397.355696 -52.794256) (xy 397.346678 -52.7939) (xy 397.279622 -52.7939)
			(xy 397.270606 -52.794267) (xy 397.253689 -52.800508) (xy 397.246602 -52.806092) (xy 397.246348 -52.806346)
			(xy 397.225415 -52.823987) (xy 397.179447 -52.853711) (xy 397.129701 -52.876557) (xy 397.077199 -52.892053)
			(xy 397.023021 -52.899882) (xy 396.968279 -52.899882) (xy 396.914101 -52.892053) (xy 396.861599 -52.876557)
			(xy 396.811853 -52.853711) (xy 396.765885 -52.823987) (xy 396.744952 -52.806346) (xy 396.744698 -52.806092)
			(xy 396.737617 -52.800498) (xy 396.720696 -52.794256) (xy 396.711678 -52.7939) (xy 396.644622 -52.7939)
			(xy 396.635606 -52.794267) (xy 396.618689 -52.800508) (xy 396.611602 -52.806092) (xy 396.611602 -52.806346)
			(xy 396.611348 -52.806346) (xy 396.590402 -52.823968) (xy 396.544434 -52.853684) (xy 396.49469 -52.876524)
			(xy 396.442192 -52.892019) (xy 396.388018 -52.899851) (xy 396.36065 -52.900326) (xy 396.333402 -52.8998)
			(xy 396.279463 -52.892038) (xy 396.227176 -52.87668) (xy 396.177608 -52.854037) (xy 396.131766 -52.824571)
			(xy 396.090584 -52.788881) (xy 396.054899 -52.747694) (xy 396.025439 -52.701848) (xy 396.002803 -52.652277)
			(xy 395.987451 -52.599988) (xy 395.979696 -52.546048) (xy 391.030588 -52.546048) (xy 391.041065 -52.550833)
			(xy 391.086915 -52.580299) (xy 391.128106 -52.61599) (xy 391.163797 -52.657181) (xy 391.193263 -52.703031)
			(xy 391.215905 -52.752608) (xy 391.23126 -52.804903) (xy 391.239016 -52.858851) (xy 391.239502 -52.886102)
			(xy 391.239037 -52.913472) (xy 391.231219 -52.967651) (xy 391.215729 -53.020154) (xy 391.192887 -53.069901)
			(xy 391.163163 -53.115868) (xy 391.145522 -53.1368) (xy 391.145268 -53.137054) (xy 391.139691 -53.144147)
			(xy 391.13344 -53.161059) (xy 391.133076 -53.170074) (xy 391.133076 -53.23713) (xy 391.133424 -53.246148)
			(xy 391.139678 -53.263064) (xy 391.145268 -53.27015) (xy 391.145522 -53.27015) (xy 391.145522 -53.270404)
			(xy 391.163163 -53.291336) (xy 391.192884 -53.337305) (xy 391.215726 -53.387052) (xy 391.23122 -53.439554)
			(xy 391.239047 -53.493731) (xy 391.239047 -53.548472) (xy 391.231219 -53.602649) (xy 391.215725 -53.655151)
			(xy 391.192882 -53.704897) (xy 391.163161 -53.750866) (xy 391.146592 -53.77053) (xy 391.510774 -53.77053)
			(xy 391.511286 -53.741612) (xy 391.520012 -53.68444) (xy 391.537269 -53.62924) (xy 391.562662 -53.577277)
			(xy 391.595608 -53.529744) (xy 391.635353 -53.487729) (xy 391.65784 -53.46954) (xy 391.666626 -53.461912)
			(xy 391.676819 -53.441027) (xy 391.677398 -53.429408) (xy 391.677398 -53.349652) (xy 391.676873 -53.338018)
			(xy 391.666674 -53.317109) (xy 391.65784 -53.30952) (xy 391.635374 -53.291308) (xy 391.595636 -53.249293)
			(xy 391.562694 -53.201763) (xy 391.537302 -53.149806) (xy 391.520043 -53.094612) (xy 391.51131 -53.037445)
			(xy 391.510774 -53.00853) (xy 391.511283 -52.981279) (xy 391.519036 -52.92733) (xy 391.534387 -52.875034)
			(xy 391.557025 -52.825456) (xy 391.586488 -52.779603) (xy 391.622177 -52.738411) (xy 391.663365 -52.702717)
			(xy 391.709213 -52.673248) (xy 391.758789 -52.650604) (xy 391.811083 -52.635246) (xy 391.865031 -52.627487)
			(xy 391.892282 -52.627022) (xy 391.918596 -52.627494) (xy 391.970724 -52.634727) (xy 392.021367 -52.649045)
			(xy 392.069567 -52.670176) (xy 392.11441 -52.697722) (xy 392.15505 -52.73116) (xy 392.173206 -52.750212)
			(xy 392.180722 -52.75762) (xy 392.200006 -52.766141) (xy 392.210544 -52.766722) (xy 392.28522 -52.766722)
			(xy 392.295765 -52.766157) (xy 392.315061 -52.757646) (xy 392.322558 -52.750212) (xy 392.340695 -52.731138)
			(xy 392.381328 -52.697682) (xy 392.426172 -52.670125) (xy 392.474377 -52.64899) (xy 392.525028 -52.634677)
			(xy 392.577165 -52.627457) (xy 392.603482 -52.627022) (xy 392.630736 -52.627472) (xy 392.684689 -52.635227)
			(xy 392.736989 -52.650583) (xy 392.786571 -52.673225) (xy 392.832425 -52.702694) (xy 392.873619 -52.738389)
			(xy 392.909313 -52.779584) (xy 392.93878 -52.82544) (xy 392.961421 -52.875023) (xy 392.976775 -52.927323)
			(xy 392.984529 -52.981276) (xy 392.98499 -53.00853) (xy 392.984506 -53.036196) (xy 392.982275 -53.051456)
			(xy 401.241258 -53.051456) (xy 401.245329 -52.995834) (xy 401.257455 -52.941397) (xy 401.277378 -52.889306)
			(xy 401.304674 -52.840671) (xy 401.33876 -52.796528) (xy 401.378909 -52.757819) (xy 401.424267 -52.725368)
			(xy 401.473867 -52.699867) (xy 401.526651 -52.68186) (xy 401.581494 -52.67173) (xy 401.637228 -52.669693)
			(xy 401.692665 -52.675793) (xy 401.746622 -52.689899) (xy 401.797951 -52.711711) (xy 401.845557 -52.740765)
			(xy 401.888425 -52.77644) (xy 401.925642 -52.817977) (xy 401.956415 -52.86449) (xy 401.980087 -52.914987)
			(xy 401.996155 -52.968394) (xy 402.004275 -53.02357) (xy 402.004784 -53.051456) (xy 402.004275 -53.079342)
			(xy 401.996155 -53.134518) (xy 401.980087 -53.187925) (xy 401.956415 -53.238422) (xy 401.925642 -53.284935)
			(xy 401.888425 -53.326472) (xy 401.845557 -53.362147) (xy 401.797951 -53.391201) (xy 401.746622 -53.413013)
			(xy 401.692665 -53.427119) (xy 401.637228 -53.433219) (xy 401.581494 -53.431182) (xy 401.526651 -53.421052)
			(xy 401.473867 -53.403045) (xy 401.424267 -53.377544) (xy 401.378909 -53.345093) (xy 401.33876 -53.306384)
			(xy 401.304674 -53.262241) (xy 401.277378 -53.213606) (xy 401.257455 -53.161515) (xy 401.245329 -53.107078)
			(xy 401.241258 -53.051456) (xy 392.982275 -53.051456) (xy 392.976502 -53.090947) (xy 392.960681 -53.143969)
			(xy 392.937373 -53.194154) (xy 392.907068 -53.240449) (xy 392.870398 -53.281886) (xy 392.828133 -53.317598)
			(xy 392.804904 -53.332634) (xy 392.795223 -53.339267) (xy 392.782779 -53.35913) (xy 392.781028 -53.370734)
			(xy 392.773154 -53.450744) (xy 392.772501 -53.462383) (xy 392.780596 -53.484222) (xy 392.788648 -53.492654)
			(xy 392.788902 -53.492908) (xy 392.80747 -53.511002) (xy 392.840049 -53.551331) (xy 392.866864 -53.595703)
			(xy 392.887419 -53.643299) (xy 392.901335 -53.693241) (xy 392.908356 -53.744608) (xy 392.90879 -53.77053)
			(xy 392.90835 -53.797783) (xy 392.900589 -53.851733) (xy 392.885229 -53.90403) (xy 392.862583 -53.953608)
			(xy 392.833112 -53.999459) (xy 392.797416 -54.04065) (xy 392.756221 -54.076341) (xy 392.710366 -54.105806)
			(xy 392.660785 -54.128446) (xy 392.608486 -54.143799) (xy 392.554535 -54.151553) (xy 392.527282 -54.152038)
			(xy 392.499911 -54.151598) (xy 392.44573 -54.143776) (xy 392.393226 -54.128282) (xy 392.343479 -54.105434)
			(xy 392.297514 -54.075703) (xy 392.276584 -54.058058) (xy 392.27633 -54.057804) (xy 392.269239 -54.052224)
			(xy 392.252326 -54.045973) (xy 392.24331 -54.045612) (xy 392.176254 -54.045612) (xy 392.167239 -54.045992)
			(xy 392.150322 -54.052224) (xy 392.143234 -54.057804) (xy 392.143234 -54.058058) (xy 392.14298 -54.058058)
			(xy 392.122023 -54.075667) (xy 392.076058 -54.105384) (xy 392.026317 -54.128227) (xy 391.973821 -54.143725)
			(xy 391.91965 -54.15156) (xy 391.892282 -54.152038) (xy 391.865032 -54.151539) (xy 391.811086 -54.143781)
			(xy 391.758793 -54.128425) (xy 391.709218 -54.105784) (xy 391.663369 -54.076319) (xy 391.62218 -54.040629)
			(xy 391.586489 -53.99944) (xy 391.557022 -53.953593) (xy 391.534379 -53.904018) (xy 391.519022 -53.851726)
			(xy 391.511262 -53.79778) (xy 391.510774 -53.77053) (xy 391.146592 -53.77053) (xy 391.145522 -53.7718)
			(xy 391.145268 -53.772054) (xy 391.139691 -53.779147) (xy 391.13344 -53.796059) (xy 391.133076 -53.805074)
			(xy 391.133076 -53.87213) (xy 391.133424 -53.881148) (xy 391.139678 -53.898064) (xy 391.145268 -53.90515)
			(xy 391.145522 -53.90515) (xy 391.145522 -53.905404) (xy 391.163163 -53.926336) (xy 391.192884 -53.972305)
			(xy 391.215726 -54.022052) (xy 391.23122 -54.074554) (xy 391.239047 -54.128731) (xy 391.239047 -54.183472)
			(xy 391.231219 -54.237649) (xy 391.215725 -54.290151) (xy 391.201933 -54.320186) (xy 393.430506 -54.320186)
			(xy 393.430962 -54.292815) (xy 393.438782 -54.238636) (xy 393.454274 -54.186133) (xy 393.477117 -54.136386)
			(xy 393.506844 -54.090419) (xy 393.524486 -54.069488) (xy 393.52474 -54.069234) (xy 393.530323 -54.062145)
			(xy 393.536571 -54.04523) (xy 393.536932 -54.036214) (xy 393.536932 -53.969158) (xy 393.53654 -53.960145)
			(xy 393.530316 -53.943228) (xy 393.52474 -53.936138) (xy 393.524486 -53.936138) (xy 393.524486 -53.935884)
			(xy 393.506871 -53.914933) (xy 393.477156 -53.868965) (xy 393.454315 -53.819222) (xy 393.438819 -53.766726)
			(xy 393.430984 -53.712554) (xy 393.430506 -53.685186) (xy 393.430992 -53.657935) (xy 393.438748 -53.603987)
			(xy 393.454103 -53.551692) (xy 393.476745 -53.502115) (xy 393.506211 -53.456265) (xy 393.541902 -53.415074)
			(xy 393.583093 -53.379383) (xy 393.628943 -53.349917) (xy 393.67852 -53.327275) (xy 393.730815 -53.31192)
			(xy 393.784763 -53.304164) (xy 393.839265 -53.304164) (xy 393.893213 -53.31192) (xy 393.945508 -53.327275)
			(xy 393.995085 -53.349917) (xy 394.040935 -53.379383) (xy 394.082126 -53.415074) (xy 394.117817 -53.456265)
			(xy 394.14371 -53.496555) (xy 406.433441 -53.496555) (xy 406.433441 -53.442045) (xy 406.441199 -53.388089)
			(xy 406.456557 -53.335787) (xy 406.479202 -53.286203) (xy 406.508674 -53.240347) (xy 406.544372 -53.199152)
			(xy 406.58557 -53.163457) (xy 406.631428 -53.133989) (xy 406.681014 -53.111347) (xy 406.733317 -53.095993)
			(xy 406.787273 -53.088239) (xy 406.814528 -53.087778) (xy 406.8419 -53.088209) (xy 406.896081 -53.096032)
			(xy 406.948585 -53.111528) (xy 406.998332 -53.134379) (xy 407.044296 -53.164112) (xy 407.065226 -53.181758)
			(xy 407.06548 -53.182012) (xy 407.072567 -53.187598) (xy 407.089484 -53.193845) (xy 407.0985 -53.194204)
			(xy 407.165556 -53.194204) (xy 407.174571 -53.193825) (xy 407.191488 -53.187593) (xy 407.198576 -53.182012)
			(xy 407.198576 -53.181758) (xy 407.19883 -53.181758) (xy 407.219772 -53.164131) (xy 407.265743 -53.134419)
			(xy 407.315488 -53.111581) (xy 407.367986 -53.096087) (xy 407.42216 -53.088254) (xy 407.449528 -53.087778)
			(xy 407.476777 -53.088294) (xy 407.53072 -53.096054) (xy 407.583009 -53.111411) (xy 407.632581 -53.134052)
			(xy 407.678426 -53.163518) (xy 407.719611 -53.199209) (xy 407.755298 -53.240396) (xy 407.784761 -53.286244)
			(xy 407.807399 -53.335817) (xy 407.822752 -53.388108) (xy 407.830508 -53.442051) (xy 407.830508 -53.496549)
			(xy 407.822752 -53.550492) (xy 407.807399 -53.602783) (xy 407.784761 -53.652356) (xy 407.755298 -53.698204)
			(xy 407.719611 -53.739391) (xy 407.678426 -53.775082) (xy 407.632581 -53.804548) (xy 407.583009 -53.827189)
			(xy 407.53072 -53.842546) (xy 407.476777 -53.850306) (xy 407.449528 -53.850794) (xy 407.422158 -53.850313)
			(xy 407.36798 -53.842499) (xy 407.315477 -53.827013) (xy 407.26573 -53.804175) (xy 407.219762 -53.774454)
			(xy 407.19883 -53.756814) (xy 407.198576 -53.75656) (xy 407.191504 -53.750952) (xy 407.174576 -53.744719)
			(xy 407.165556 -53.744368) (xy 407.0985 -53.744368) (xy 407.089484 -53.744732) (xy 407.072567 -53.750976)
			(xy 407.06548 -53.75656) (xy 407.06548 -53.756814) (xy 407.065226 -53.756814) (xy 407.044297 -53.774457)
			(xy 406.998323 -53.804167) (xy 406.948575 -53.827002) (xy 406.896073 -53.842493) (xy 406.841897 -53.85032)
			(xy 406.814528 -53.850794) (xy 406.787273 -53.850361) (xy 406.733317 -53.842607) (xy 406.681014 -53.827253)
			(xy 406.631428 -53.804611) (xy 406.58557 -53.775143) (xy 406.544372 -53.739448) (xy 406.508674 -53.698253)
			(xy 406.479202 -53.652397) (xy 406.456557 -53.602813) (xy 406.441199 -53.550511) (xy 406.433441 -53.496555)
			(xy 394.14371 -53.496555) (xy 394.147283 -53.502115) (xy 394.169925 -53.551692) (xy 394.18528 -53.603987)
			(xy 394.193036 -53.657935) (xy 394.193522 -53.685186) (xy 394.193067 -53.712557) (xy 394.185249 -53.766737)
			(xy 394.169759 -53.819241) (xy 394.146914 -53.868988) (xy 394.117186 -53.914953) (xy 394.099542 -53.935884)
			(xy 394.099288 -53.936138) (xy 394.09372 -53.943237) (xy 394.087462 -53.960144) (xy 394.087096 -53.969158)
			(xy 394.087096 -54.036214) (xy 394.087447 -54.045231) (xy 394.093699 -54.062148) (xy 394.099288 -54.069234)
			(xy 394.099542 -54.069234) (xy 394.099542 -54.069488) (xy 394.117196 -54.090408) (xy 394.146904 -54.136385)
			(xy 394.169737 -54.186135) (xy 394.185225 -54.238639) (xy 394.19305 -54.292816) (xy 394.193522 -54.320186)
			(xy 394.193036 -54.347437) (xy 394.18528 -54.401385) (xy 394.169925 -54.45368) (xy 394.147283 -54.503257)
			(xy 394.117817 -54.549107) (xy 394.082126 -54.590298) (xy 394.040935 -54.625989) (xy 393.995085 -54.655455)
			(xy 393.945508 -54.678097) (xy 393.893213 -54.693452) (xy 393.839265 -54.701208) (xy 393.784763 -54.701208)
			(xy 393.730815 -54.693452) (xy 393.67852 -54.678097) (xy 393.628943 -54.655455) (xy 393.583093 -54.625989)
			(xy 393.541902 -54.590298) (xy 393.506211 -54.549107) (xy 393.476745 -54.503257) (xy 393.454103 -54.45368)
			(xy 393.438748 -54.401385) (xy 393.430992 -54.347437) (xy 393.430506 -54.320186) (xy 391.201933 -54.320186)
			(xy 391.192882 -54.339897) (xy 391.163161 -54.385866) (xy 391.145522 -54.4068) (xy 391.145268 -54.407054)
			(xy 391.139691 -54.414147) (xy 391.13344 -54.431059) (xy 391.133076 -54.440074) (xy 391.133076 -54.50713)
			(xy 391.133424 -54.516148) (xy 391.139678 -54.533064) (xy 391.145268 -54.54015) (xy 391.145522 -54.54015)
			(xy 391.145522 -54.540404) (xy 391.16318 -54.561321) (xy 391.192888 -54.607298) (xy 391.21572 -54.65705)
			(xy 391.231207 -54.709554) (xy 391.23903 -54.763732) (xy 391.239147 -54.770528) (xy 394.371068 -54.770528)
			(xy 394.371534 -54.743158) (xy 394.379349 -54.688978) (xy 394.394837 -54.636474) (xy 394.41768 -54.586727)
			(xy 394.447406 -54.540761) (xy 394.465048 -54.51983) (xy 394.465302 -54.519576) (xy 394.470905 -54.512501)
			(xy 394.477142 -54.495575) (xy 394.477494 -54.486556) (xy 394.477494 -54.4195) (xy 394.477138 -54.410483)
			(xy 394.47089 -54.393566) (xy 394.465302 -54.38648) (xy 394.465048 -54.38648) (xy 394.465048 -54.386226)
			(xy 394.447415 -54.365289) (xy 394.417701 -54.319318) (xy 394.394863 -54.269572) (xy 394.37937 -54.217072)
			(xy 394.371542 -54.162897) (xy 394.371068 -54.135528) (xy 394.371554 -54.108277) (xy 394.37931 -54.054329)
			(xy 394.394665 -54.002034) (xy 394.417307 -53.952457) (xy 394.446773 -53.906607) (xy 394.482464 -53.865416)
			(xy 394.523655 -53.829725) (xy 394.569505 -53.800259) (xy 394.619082 -53.777617) (xy 394.671377 -53.762262)
			(xy 394.725325 -53.754506) (xy 394.779827 -53.754506) (xy 394.833775 -53.762262) (xy 394.88607 -53.777617)
			(xy 394.935647 -53.800259) (xy 394.981497 -53.829725) (xy 395.022688 -53.865416) (xy 395.058379 -53.906607)
			(xy 395.087845 -53.952457) (xy 395.09292 -53.96357) (xy 399.072098 -53.96357) (xy 399.076169 -53.907948)
			(xy 399.088295 -53.853511) (xy 399.108218 -53.80142) (xy 399.135514 -53.752785) (xy 399.1696 -53.708642)
			(xy 399.209749 -53.669933) (xy 399.255107 -53.637482) (xy 399.304707 -53.611981) (xy 399.357491 -53.593974)
			(xy 399.412334 -53.583844) (xy 399.468068 -53.581807) (xy 399.523505 -53.587907) (xy 399.577462 -53.602013)
			(xy 399.628791 -53.623825) (xy 399.676397 -53.652879) (xy 399.719265 -53.688554) (xy 399.756482 -53.730091)
			(xy 399.787255 -53.776604) (xy 399.810927 -53.827101) (xy 399.826995 -53.880508) (xy 399.835115 -53.935684)
			(xy 399.835624 -53.96357) (xy 399.835115 -53.991456) (xy 399.826995 -54.046632) (xy 399.810927 -54.100039)
			(xy 399.787255 -54.150536) (xy 399.756482 -54.197049) (xy 399.719265 -54.238586) (xy 399.676397 -54.274261)
			(xy 399.628791 -54.303315) (xy 399.577462 -54.325127) (xy 399.523505 -54.339233) (xy 399.468068 -54.345333)
			(xy 399.412334 -54.343296) (xy 399.357491 -54.333166) (xy 399.304707 -54.315159) (xy 399.255107 -54.289658)
			(xy 399.209749 -54.257207) (xy 399.1696 -54.218498) (xy 399.135514 -54.174355) (xy 399.108218 -54.12572)
			(xy 399.088295 -54.073629) (xy 399.076169 -54.019192) (xy 399.072098 -53.96357) (xy 395.09292 -53.96357)
			(xy 395.110487 -54.002034) (xy 395.125842 -54.054329) (xy 395.133598 -54.108277) (xy 395.134084 -54.135528)
			(xy 395.133638 -54.162899) (xy 395.125816 -54.217079) (xy 395.110322 -54.269583) (xy 395.087476 -54.319329)
			(xy 395.057747 -54.365295) (xy 395.040104 -54.386226) (xy 395.03985 -54.38648) (xy 395.03426 -54.393564)
			(xy 395.028016 -54.410483) (xy 395.027658 -54.4195) (xy 395.027658 -54.486556) (xy 395.028023 -54.495572)
			(xy 395.034264 -54.51249) (xy 395.03985 -54.519576) (xy 395.040104 -54.519576) (xy 395.040104 -54.51983)
			(xy 395.057724 -54.540777) (xy 395.087439 -54.586746) (xy 395.110278 -54.63649) (xy 395.125774 -54.688987)
			(xy 395.133607 -54.74316) (xy 395.134084 -54.770528) (xy 395.133598 -54.797779) (xy 395.125842 -54.851727)
			(xy 395.110487 -54.904022) (xy 395.087845 -54.953599) (xy 395.065059 -54.989055) (xy 404.201045 -54.989055)
			(xy 404.201045 -54.934545) (xy 404.208803 -54.880591) (xy 404.22416 -54.82829) (xy 404.246805 -54.778707)
			(xy 404.276276 -54.732852) (xy 404.311973 -54.691657) (xy 404.353169 -54.655963) (xy 404.399026 -54.626494)
			(xy 404.448611 -54.603853) (xy 404.500913 -54.588498) (xy 404.554867 -54.580743) (xy 404.582122 -54.580282)
			(xy 404.610214 -54.580759) (xy 404.665792 -54.58899) (xy 404.719562 -54.605284) (xy 404.770359 -54.629289)
			(xy 404.817086 -54.660487) (xy 404.85873 -54.698201) (xy 404.894392 -54.741616) (xy 404.909274 -54.765448)
			(xy 404.914608 -54.774338) (xy 404.931626 -54.78653) (xy 405.024844 -54.80685) (xy 405.045418 -54.802532)
			(xy 405.054054 -54.79669) (xy 405.078128 -54.780706) (xy 405.130056 -54.75536) (xy 405.185211 -54.73813)
			(xy 405.242332 -54.72941) (xy 405.271224 -54.728872) (xy 405.298475 -54.729355) (xy 405.352422 -54.737115)
			(xy 405.404715 -54.752472) (xy 405.454291 -54.775114) (xy 405.500141 -54.804581) (xy 405.54133 -54.840273)
			(xy 405.577021 -54.881463) (xy 405.606488 -54.927312) (xy 405.62913 -54.976888) (xy 405.644486 -55.029182)
			(xy 405.652245 -55.083129) (xy 405.652732 -55.11038) (xy 405.652271 -55.137751) (xy 405.644454 -55.191931)
			(xy 405.628965 -55.244434) (xy 405.606122 -55.294181) (xy 405.576395 -55.340147) (xy 405.558752 -55.361078)
			(xy 405.558498 -55.361332) (xy 405.552934 -55.368434) (xy 405.546674 -55.385339) (xy 405.546306 -55.394352)
			(xy 405.546306 -55.461408) (xy 405.546658 -55.470425) (xy 405.552909 -55.487342) (xy 405.558498 -55.494428)
			(xy 405.558752 -55.494428) (xy 405.558752 -55.494682) (xy 405.576374 -55.51563) (xy 405.606101 -55.561595)
			(xy 405.628949 -55.611338) (xy 405.644448 -55.663838) (xy 405.652279 -55.718015) (xy 405.652281 -55.772755)
			(xy 405.644454 -55.826932) (xy 405.62896 -55.879433) (xy 405.606116 -55.929179) (xy 405.576392 -55.975146)
			(xy 405.558752 -55.996078) (xy 405.558498 -55.996332) (xy 405.552934 -56.003434) (xy 405.546674 -56.020339)
			(xy 405.546306 -56.029352) (xy 405.546306 -56.096408) (xy 405.546658 -56.105425) (xy 405.552909 -56.122342)
			(xy 405.558498 -56.129428) (xy 405.558752 -56.129428) (xy 405.558752 -56.129682) (xy 405.576389 -56.150616)
			(xy 405.606103 -56.196588) (xy 405.62894 -56.246335) (xy 405.644431 -56.298835) (xy 405.652259 -56.353011)
			(xy 405.652732 -56.38038) (xy 405.652246 -56.407631) (xy 405.64449 -56.461579) (xy 405.629135 -56.513874)
			(xy 405.606493 -56.563451) (xy 405.577027 -56.609301) (xy 405.541336 -56.650492) (xy 405.500145 -56.686183)
			(xy 405.454295 -56.715649) (xy 405.404718 -56.738291) (xy 405.352423 -56.753646) (xy 405.298475 -56.761402)
			(xy 405.243973 -56.761402) (xy 405.190025 -56.753646) (xy 405.13773 -56.738291) (xy 405.088153 -56.715649)
			(xy 405.042303 -56.686183) (xy 405.001112 -56.650492) (xy 404.965421 -56.609301) (xy 404.935955 -56.563451)
			(xy 404.913313 -56.513874) (xy 404.897958 -56.461579) (xy 404.890202 -56.407631) (xy 404.889716 -56.38038)
			(xy 404.890166 -56.353009) (xy 404.897987 -56.298829) (xy 404.91348 -56.246326) (xy 404.936325 -56.196579)
			(xy 404.966053 -56.150613) (xy 404.983696 -56.129682) (xy 404.98395 -56.129428) (xy 404.989537 -56.122342)
			(xy 404.995782 -56.105425) (xy 404.996142 -56.096408) (xy 404.996142 -56.029352) (xy 404.995773 -56.020336)
			(xy 404.989535 -56.003418) (xy 404.98395 -55.996332) (xy 404.983696 -55.996332) (xy 404.983696 -55.996078)
			(xy 404.966037 -55.975161) (xy 404.936315 -55.929189) (xy 404.913473 -55.87944) (xy 404.89798 -55.826936)
			(xy 404.890154 -55.772756) (xy 404.890156 -55.718014) (xy 404.897986 -55.663834) (xy 404.913484 -55.611331)
			(xy 404.93633 -55.561584) (xy 404.966055 -55.515615) (xy 404.983696 -55.494682) (xy 404.98395 -55.494428)
			(xy 404.989537 -55.487342) (xy 404.995782 -55.470425) (xy 404.996142 -55.461408) (xy 404.996142 -55.394352)
			(xy 404.995773 -55.385336) (xy 404.989535 -55.368418) (xy 404.98395 -55.361332) (xy 404.983696 -55.360824)
			(xy 404.972752 -55.348089) (xy 404.952911 -55.320998) (xy 404.944072 -55.306722) (xy 404.938738 -55.297832)
			(xy 404.92172 -55.28564) (xy 404.828502 -55.26532) (xy 404.807928 -55.269638) (xy 404.799292 -55.27548)
			(xy 404.77523 -55.291483) (xy 404.723298 -55.316826) (xy 404.66814 -55.334051) (xy 404.611015 -55.342764)
			(xy 404.582122 -55.343298) (xy 404.554867 -55.342857) (xy 404.500913 -55.335102) (xy 404.448611 -55.319747)
			(xy 404.399026 -55.297106) (xy 404.353169 -55.267637) (xy 404.311973 -55.231943) (xy 404.276276 -55.190748)
			(xy 404.246805 -55.144893) (xy 404.22416 -55.09531) (xy 404.208803 -55.043009) (xy 404.201045 -54.989055)
			(xy 395.065059 -54.989055) (xy 395.058379 -54.999449) (xy 395.022688 -55.04064) (xy 394.981497 -55.076331)
			(xy 394.935647 -55.105797) (xy 394.88607 -55.128439) (xy 394.833775 -55.143794) (xy 394.779827 -55.15155)
			(xy 394.725325 -55.15155) (xy 394.671377 -55.143794) (xy 394.619082 -55.128439) (xy 394.569505 -55.105797)
			(xy 394.523655 -55.076331) (xy 394.482464 -55.04064) (xy 394.446773 -54.999449) (xy 394.417307 -54.953599)
			(xy 394.394665 -54.904022) (xy 394.37931 -54.851727) (xy 394.371554 -54.797779) (xy 394.371068 -54.770528)
			(xy 391.239147 -54.770528) (xy 391.239502 -54.791102) (xy 391.239016 -54.818353) (xy 391.23126 -54.872301)
			(xy 391.215905 -54.924596) (xy 391.193263 -54.974173) (xy 391.163797 -55.020023) (xy 391.128106 -55.061214)
			(xy 391.086915 -55.096905) (xy 391.041065 -55.126371) (xy 390.991488 -55.149013) (xy 390.939193 -55.164368)
			(xy 390.885245 -55.172124) (xy 390.830743 -55.172124) (xy 390.776795 -55.164368) (xy 390.7245 -55.149013)
			(xy 390.674923 -55.126371) (xy 390.629073 -55.096905) (xy 390.587882 -55.061214) (xy 390.552191 -55.020023)
			(xy 390.522725 -54.974173) (xy 390.500083 -54.924596) (xy 390.484728 -54.872301) (xy 390.476972 -54.818353)
			(xy 390.476486 -54.791102) (xy 388.579734 -54.791102) (xy 388.575653 -54.817845) (xy 388.558338 -54.873267)
			(xy 388.532863 -54.925445) (xy 388.49981 -54.973184) (xy 388.459935 -55.015392) (xy 388.437374 -55.033672)
			(xy 388.432294 -55.037482) (xy 388.426452 -55.044848) (xy 388.425182 -55.04688) (xy 388.424928 -55.047388)
			(xy 388.415276 -55.06593) (xy 388.415276 -55.066438) (xy 388.41299 -55.070756) (xy 388.411466 -55.077106)
			(xy 388.409942 -55.091076) (xy 388.427214 -55.59044) (xy 388.431797 -55.722266) (xy 400.134072 -55.722266)
			(xy 400.138143 -55.666644) (xy 400.150269 -55.612207) (xy 400.170192 -55.560116) (xy 400.197488 -55.511481)
			(xy 400.231574 -55.467338) (xy 400.271723 -55.428629) (xy 400.317081 -55.396178) (xy 400.366681 -55.370677)
			(xy 400.419465 -55.35267) (xy 400.474308 -55.34254) (xy 400.530042 -55.340503) (xy 400.585479 -55.346603)
			(xy 400.639436 -55.360709) (xy 400.690765 -55.382521) (xy 400.738371 -55.411575) (xy 400.749522 -55.420855)
			(xy 402.524645 -55.420855) (xy 402.524645 -55.366345) (xy 402.532403 -55.312391) (xy 402.54776 -55.26009)
			(xy 402.570405 -55.210507) (xy 402.599876 -55.164652) (xy 402.635573 -55.123457) (xy 402.676769 -55.087763)
			(xy 402.722626 -55.058294) (xy 402.772211 -55.035653) (xy 402.824513 -55.020298) (xy 402.878467 -55.012543)
			(xy 402.905722 -55.012082) (xy 402.932036 -55.012541) (xy 402.984165 -55.019778) (xy 403.034808 -55.034099)
			(xy 403.083006 -55.055233) (xy 403.12785 -55.082781) (xy 403.168489 -55.11622) (xy 403.186646 -55.135272)
			(xy 403.194152 -55.142692) (xy 403.213444 -55.151207) (xy 403.223984 -55.151782) (xy 403.29866 -55.151782)
			(xy 403.30921 -55.15125) (xy 403.328505 -55.142718) (xy 403.335998 -55.135272) (xy 403.354156 -55.116219)
			(xy 403.394786 -55.082763) (xy 403.439626 -55.055204) (xy 403.487826 -55.034065) (xy 403.538473 -55.019747)
			(xy 403.590606 -55.012521) (xy 403.616922 -55.012082) (xy 403.644171 -55.01259) (xy 403.698115 -55.020349)
			(xy 403.750406 -55.035705) (xy 403.799979 -55.058347) (xy 403.845825 -55.087813) (xy 403.887012 -55.123504)
			(xy 403.9227 -55.164692) (xy 403.952164 -55.21054) (xy 403.974802 -55.260115) (xy 403.990156 -55.312406)
			(xy 403.997912 -55.366351) (xy 403.997912 -55.420849) (xy 403.990156 -55.474794) (xy 403.974802 -55.527085)
			(xy 403.952164 -55.57666) (xy 403.9227 -55.622508) (xy 403.887012 -55.663696) (xy 403.845826 -55.699387)
			(xy 403.799979 -55.728853) (xy 403.750406 -55.751495) (xy 403.698115 -55.766851) (xy 403.644171 -55.77461)
			(xy 403.616922 -55.775098) (xy 403.590609 -55.774617) (xy 403.538481 -55.767385) (xy 403.487838 -55.753068)
			(xy 403.439639 -55.731939) (xy 403.394795 -55.704395) (xy 403.354155 -55.670959) (xy 403.335998 -55.651908)
			(xy 403.328478 -55.644505) (xy 403.309197 -55.635981) (xy 403.29866 -55.635398) (xy 403.223984 -55.635398)
			(xy 403.213432 -55.635905) (xy 403.194137 -55.644456) (xy 403.186646 -55.651908) (xy 403.168511 -55.670984)
			(xy 403.127877 -55.704439) (xy 403.083032 -55.731995) (xy 403.034827 -55.75313) (xy 402.984176 -55.767443)
			(xy 402.932039 -55.774662) (xy 402.905722 -55.775098) (xy 402.878467 -55.774657) (xy 402.824513 -55.766902)
			(xy 402.772211 -55.751547) (xy 402.722626 -55.728906) (xy 402.676769 -55.699437) (xy 402.635573 -55.663743)
			(xy 402.599876 -55.622548) (xy 402.570405 -55.576693) (xy 402.54776 -55.52711) (xy 402.532403 -55.474809)
			(xy 402.524645 -55.420855) (xy 400.749522 -55.420855) (xy 400.781239 -55.44725) (xy 400.818456 -55.488787)
			(xy 400.849229 -55.5353) (xy 400.872901 -55.585797) (xy 400.888969 -55.639204) (xy 400.897089 -55.69438)
			(xy 400.897598 -55.722266) (xy 400.897089 -55.750152) (xy 400.888969 -55.805328) (xy 400.872901 -55.858735)
			(xy 400.849229 -55.909232) (xy 400.818456 -55.955745) (xy 400.781239 -55.997282) (xy 400.738371 -56.032957)
			(xy 400.690765 -56.062011) (xy 400.639436 -56.083823) (xy 400.585479 -56.097929) (xy 400.530042 -56.104029)
			(xy 400.474308 -56.101992) (xy 400.419465 -56.091862) (xy 400.366681 -56.073855) (xy 400.317081 -56.048354)
			(xy 400.271723 -56.015903) (xy 400.231574 -55.977194) (xy 400.197488 -55.933051) (xy 400.170192 -55.884416)
			(xy 400.150269 -55.832325) (xy 400.138143 -55.777888) (xy 400.134072 -55.722266) (xy 388.431797 -55.722266)
			(xy 388.43585 -55.838852) (xy 388.441692 -56.007254) (xy 388.4422 -56.019192) (xy 388.442708 -56.035448)
			(xy 388.455408 -56.397652) (xy 388.458202 -56.474106) (xy 388.458202 -56.474614) (xy 388.460488 -56.528716)
			(xy 388.460996 -56.532526) (xy 388.46252 -56.53786) (xy 388.467854 -56.550306) (xy 388.470648 -56.555132)
			(xy 388.47522 -56.559958) (xy 388.476236 -56.560974) (xy 388.496082 -56.58225) (xy 388.529745 -56.629703)
			(xy 388.555813 -56.681716) (xy 388.573681 -56.737085) (xy 388.582935 -56.794525) (xy 388.583678 -56.82361)
			(xy 388.583678 -56.827928) (xy 388.583172 -56.85393) (xy 388.575974 -56.905436) (xy 388.561838 -56.955485)
			(xy 388.54112 -57.002934) (xy 395.863572 -57.002934) (xy 395.864098 -56.974844) (xy 395.872321 -56.919268)
			(xy 395.888607 -56.8655) (xy 395.912604 -56.814703) (xy 395.943794 -56.767976) (xy 395.981501 -56.72633)
			(xy 396.02491 -56.690666) (xy 396.048738 -56.675782) (xy 396.057628 -56.670448) (xy 396.06982 -56.65343)
			(xy 396.09014 -56.560212) (xy 396.085822 -56.539638) (xy 396.07998 -56.531002) (xy 396.063976 -56.506941)
			(xy 396.038635 -56.455008) (xy 396.021411 -56.399849) (xy 396.012696 -56.342725) (xy 396.012162 -56.313832)
			(xy 396.012685 -56.286581) (xy 396.020437 -56.232634) (xy 396.035787 -56.180339) (xy 396.058424 -56.130761)
			(xy 396.087886 -56.084909) (xy 396.123573 -56.043717) (xy 396.16476 -56.008023) (xy 396.210607 -55.978554)
			(xy 396.260181 -55.955909) (xy 396.312473 -55.94055) (xy 396.366419 -55.932789) (xy 396.39367 -55.932324)
			(xy 396.42104 -55.932802) (xy 396.475219 -55.940616) (xy 396.527722 -55.956102) (xy 396.577469 -55.978941)
			(xy 396.623436 -56.008664) (xy 396.644368 -56.026304) (xy 396.644622 -56.026558) (xy 396.651693 -56.032167)
			(xy 396.668622 -56.038399) (xy 396.677642 -56.03875) (xy 396.744698 -56.03875) (xy 396.753716 -56.038403)
			(xy 396.770633 -56.032149) (xy 396.777718 -56.026558) (xy 396.777718 -56.026304) (xy 396.777972 -56.026304)
			(xy 396.798905 -56.008663) (xy 396.844873 -55.978939) (xy 396.894619 -55.956093) (xy 396.947121 -55.940597)
			(xy 397.001299 -55.932768) (xy 397.056041 -55.932768) (xy 397.110219 -55.940597) (xy 397.162721 -55.956093)
			(xy 397.212467 -55.978939) (xy 397.258435 -56.008663) (xy 397.279368 -56.026304) (xy 397.279622 -56.026558)
			(xy 397.286693 -56.032167) (xy 397.303622 -56.038399) (xy 397.312642 -56.03875) (xy 397.379698 -56.03875)
			(xy 397.388716 -56.038403) (xy 397.405633 -56.032149) (xy 397.412718 -56.026558) (xy 397.412718 -56.026304)
			(xy 397.412972 -56.026304) (xy 397.433904 -56.008665) (xy 397.479877 -55.978953) (xy 397.529624 -55.956117)
			(xy 397.582125 -55.940626) (xy 397.636301 -55.932798) (xy 397.66367 -55.932324) (xy 397.690927 -55.932721)
			(xy 397.744885 -55.940475) (xy 397.797191 -55.95583) (xy 397.846779 -55.978472) (xy 397.89264 -56.007942)
			(xy 397.93384 -56.043639) (xy 397.96954 -56.084836) (xy 397.999013 -56.130694) (xy 398.02166 -56.180281)
			(xy 398.037019 -56.232585) (xy 398.044777 -56.286543) (xy 398.044777 -56.297068) (xy 398.386552 -56.297068)
			(xy 398.390623 -56.241446) (xy 398.402749 -56.187009) (xy 398.422672 -56.134918) (xy 398.449968 -56.086283)
			(xy 398.484054 -56.04214) (xy 398.524203 -56.003431) (xy 398.569561 -55.97098) (xy 398.619161 -55.945479)
			(xy 398.671945 -55.927472) (xy 398.726788 -55.917342) (xy 398.782522 -55.915305) (xy 398.837959 -55.921405)
			(xy 398.891916 -55.935511) (xy 398.943245 -55.957323) (xy 398.990851 -55.986377) (xy 399.033719 -56.022052)
			(xy 399.070936 -56.063589) (xy 399.101709 -56.110102) (xy 399.125381 -56.160599) (xy 399.141449 -56.214006)
			(xy 399.149569 -56.269182) (xy 399.150078 -56.297068) (xy 399.149569 -56.324954) (xy 399.141449 -56.38013)
			(xy 399.125381 -56.433537) (xy 399.101709 -56.484034) (xy 399.070936 -56.530547) (xy 399.033719 -56.572084)
			(xy 398.990851 -56.607759) (xy 398.943245 -56.636813) (xy 398.891916 -56.658625) (xy 398.837959 -56.672731)
			(xy 398.782522 -56.678831) (xy 398.726788 -56.676794) (xy 398.671945 -56.666664) (xy 398.619161 -56.648657)
			(xy 398.569561 -56.623156) (xy 398.524203 -56.590705) (xy 398.484054 -56.551996) (xy 398.449968 -56.507853)
			(xy 398.422672 -56.459218) (xy 398.402749 -56.407127) (xy 398.390623 -56.35269) (xy 398.386552 -56.297068)
			(xy 398.044777 -56.297068) (xy 398.044777 -56.341057) (xy 398.037019 -56.395015) (xy 398.02166 -56.447319)
			(xy 397.999013 -56.496906) (xy 397.96954 -56.542764) (xy 397.93384 -56.583961) (xy 397.89264 -56.619658)
			(xy 397.846779 -56.649128) (xy 397.797191 -56.67177) (xy 397.744885 -56.687125) (xy 397.690927 -56.694879)
			(xy 397.66367 -56.69534) (xy 397.636298 -56.694906) (xy 397.582117 -56.687083) (xy 397.529613 -56.671587)
			(xy 397.479867 -56.648738) (xy 397.433902 -56.619005) (xy 397.412972 -56.60136) (xy 397.412718 -56.601106)
			(xy 397.40563 -56.595521) (xy 397.388714 -56.589273) (xy 397.379698 -56.588914) (xy 397.312642 -56.588914)
			(xy 397.303627 -56.589288) (xy 397.28671 -56.595524) (xy 397.279622 -56.601106) (xy 397.279622 -56.60136)
			(xy 397.279368 -56.60136) (xy 397.258435 -56.619001) (xy 397.212467 -56.648725) (xy 397.162721 -56.671571)
			(xy 397.110219 -56.687067) (xy 397.056041 -56.694896) (xy 397.001299 -56.694896) (xy 396.947121 -56.687067)
			(xy 396.894619 -56.671571) (xy 396.844873 -56.648725) (xy 396.798905 -56.619001) (xy 396.777972 -56.60136)
			(xy 396.777718 -56.601106) (xy 396.77063 -56.595521) (xy 396.753714 -56.589273) (xy 396.744698 -56.588914)
			(xy 396.677642 -56.588914) (xy 396.668627 -56.589288) (xy 396.65171 -56.595524) (xy 396.644622 -56.601106)
			(xy 396.644114 -56.60136) (xy 396.631383 -56.612308) (xy 396.604289 -56.632147) (xy 396.590012 -56.640984)
			(xy 396.581122 -56.646318) (xy 396.56893 -56.663336) (xy 396.54861 -56.756554) (xy 396.552928 -56.777128)
			(xy 396.55877 -56.785764) (xy 396.574753 -56.809838) (xy 396.600101 -56.861766) (xy 396.617331 -56.916921)
			(xy 396.626051 -56.974042) (xy 396.626588 -57.002934) (xy 396.626102 -57.030185) (xy 396.618346 -57.084133)
			(xy 396.602991 -57.136428) (xy 396.580349 -57.186005) (xy 396.550883 -57.231855) (xy 396.515192 -57.273046)
			(xy 396.474001 -57.308737) (xy 396.428151 -57.338203) (xy 396.378574 -57.360845) (xy 396.326279 -57.3762)
			(xy 396.272331 -57.383956) (xy 396.217829 -57.383956) (xy 396.163881 -57.3762) (xy 396.111586 -57.360845)
			(xy 396.062009 -57.338203) (xy 396.016159 -57.308737) (xy 395.974968 -57.273046) (xy 395.939277 -57.231855)
			(xy 395.909811 -57.186005) (xy 395.887169 -57.136428) (xy 395.871814 -57.084133) (xy 395.864058 -57.030185)
			(xy 395.863572 -57.002934) (xy 388.54112 -57.002934) (xy 388.541027 -57.003147) (xy 388.513928 -57.047535)
			(xy 388.497826 -57.067958) (xy 388.492492 -57.074562) (xy 388.480046 -57.107582) (xy 388.480554 -57.117996)
			(xy 388.483094 -57.184544) (xy 388.483348 -57.192164) (xy 388.48919 -57.20969) (xy 388.495286 -57.217056)
			(xy 388.49554 -57.21731) (xy 388.499096 -57.221628) (xy 388.59079 -57.332372) (xy 388.596715 -57.340181)
			(xy 388.602683 -57.358833) (xy 388.601201 -57.378361) (xy 388.592487 -57.395899) (xy 388.585456 -57.40273)
			(xy 388.58063 -57.407556) (xy 388.581646 -57.421526) (xy 388.581646 -57.42305) (xy 388.583678 -57.46115)
			(xy 388.583678 -57.470548) (xy 388.583068 -57.48528) (xy 404.90597 -57.48528) (xy 404.910041 -57.429658)
			(xy 404.922167 -57.375221) (xy 404.94209 -57.32313) (xy 404.969386 -57.274495) (xy 405.003472 -57.230352)
			(xy 405.043621 -57.191643) (xy 405.088979 -57.159192) (xy 405.138579 -57.133691) (xy 405.191363 -57.115684)
			(xy 405.246206 -57.105554) (xy 405.30194 -57.103517) (xy 405.357377 -57.109617) (xy 405.411334 -57.123723)
			(xy 405.462663 -57.145535) (xy 405.510269 -57.174589) (xy 405.553137 -57.210264) (xy 405.590354 -57.251801)
			(xy 405.621127 -57.298314) (xy 405.644799 -57.348811) (xy 405.660867 -57.402218) (xy 405.668987 -57.457394)
			(xy 405.669496 -57.48528) (xy 405.668987 -57.513166) (xy 405.660867 -57.568342) (xy 405.644799 -57.621749)
			(xy 405.621127 -57.672246) (xy 405.590354 -57.718759) (xy 405.553137 -57.760296) (xy 405.510269 -57.795971)
			(xy 405.462663 -57.825025) (xy 405.411334 -57.846837) (xy 405.357377 -57.860943) (xy 405.30194 -57.867043)
			(xy 405.246206 -57.865006) (xy 405.191363 -57.854876) (xy 405.138579 -57.836869) (xy 405.088979 -57.811368)
			(xy 405.043621 -57.778917) (xy 405.003472 -57.740208) (xy 404.969386 -57.696065) (xy 404.94209 -57.64743)
			(xy 404.922167 -57.595339) (xy 404.910041 -57.540902) (xy 404.90597 -57.48528) (xy 388.583068 -57.48528)
			(xy 388.582522 -57.498471) (xy 388.573052 -57.553547) (xy 388.555655 -57.606655) (xy 388.530702 -57.656659)
			(xy 388.515098 -57.679844) (xy 388.513574 -57.681876) (xy 388.511034 -57.686194) (xy 388.506208 -57.692798)
			(xy 388.503668 -57.701434) (xy 388.501128 -57.709816) (xy 388.502398 -57.742582) (xy 388.502398 -57.74309)
			(xy 388.505192 -57.820814) (xy 388.505954 -57.842658) (xy 388.506208 -57.850024) (xy 388.515606 -57.87898)
			(xy 388.519924 -57.885076) (xy 388.521956 -57.888124) (xy 388.522464 -57.888886) (xy 388.524242 -57.891426)
			(xy 388.526528 -57.894982) (xy 388.539873 -57.91739) (xy 388.561029 -57.965061) (xy 388.575503 -58.015166)
			(xy 388.583025 -58.066775) (xy 388.583678 -58.092848) (xy 388.583678 -58.096658) (xy 388.583271 -58.121562)
			(xy 388.576787 -58.170946) (xy 388.563935 -58.219067) (xy 388.544934 -58.265109) (xy 388.532878 -58.286904)
			(xy 388.529576 -58.292492) (xy 388.522464 -58.317892) (xy 388.522718 -58.32602) (xy 388.52602 -58.420508)
			(xy 388.529576 -58.52287) (xy 388.531862 -58.535824) (xy 388.533386 -58.541158) (xy 388.535926 -58.546238)
			(xy 388.536434 -58.547) (xy 388.536688 -58.547508) (xy 388.537196 -58.54827) (xy 388.551346 -58.575563)
			(xy 388.571714 -58.633566) (xy 388.579911 -58.679334) (xy 396.295372 -58.679334) (xy 396.295804 -58.653019)
			(xy 396.303048 -58.600889) (xy 396.317374 -58.550246) (xy 396.338513 -58.502048) (xy 396.366065 -58.457205)
			(xy 396.399508 -58.416566) (xy 396.418562 -58.39841) (xy 396.425955 -58.390881) (xy 396.434486 -58.371607)
			(xy 396.435072 -58.361072) (xy 396.435072 -58.286396) (xy 396.434567 -58.275843) (xy 396.426016 -58.256548)
			(xy 396.418562 -58.249058) (xy 396.399486 -58.230923) (xy 396.366032 -58.190288) (xy 396.338477 -58.145443)
			(xy 396.317342 -58.097239) (xy 396.303029 -58.046588) (xy 396.295808 -57.994451) (xy 396.295372 -57.968134)
			(xy 396.295858 -57.940883) (xy 396.303614 -57.886935) (xy 396.318969 -57.83464) (xy 396.341611 -57.785063)
			(xy 396.371077 -57.739213) (xy 396.406768 -57.698022) (xy 396.447959 -57.662331) (xy 396.493809 -57.632865)
			(xy 396.543386 -57.610223) (xy 396.595681 -57.594868) (xy 396.649629 -57.587112) (xy 396.704131 -57.587112)
			(xy 396.758079 -57.594868) (xy 396.810374 -57.610223) (xy 396.859951 -57.632865) (xy 396.905801 -57.662331)
			(xy 396.946992 -57.698022) (xy 396.982683 -57.739213) (xy 397.012149 -57.785063) (xy 397.034791 -57.83464)
			(xy 397.050146 -57.886935) (xy 397.057902 -57.940883) (xy 397.058388 -57.968134) (xy 397.057947 -57.994449)
			(xy 397.050707 -58.046579) (xy 397.043439 -58.072274) (xy 400.293584 -58.072274) (xy 400.297655 -58.016652)
			(xy 400.309781 -57.962215) (xy 400.329704 -57.910124) (xy 400.357 -57.861489) (xy 400.391086 -57.817346)
			(xy 400.431235 -57.778637) (xy 400.476593 -57.746186) (xy 400.526193 -57.720685) (xy 400.578977 -57.702678)
			(xy 400.63382 -57.692548) (xy 400.689554 -57.690511) (xy 400.744991 -57.696611) (xy 400.798948 -57.710717)
			(xy 400.850277 -57.732529) (xy 400.897883 -57.761583) (xy 400.940751 -57.797258) (xy 400.977968 -57.838795)
			(xy 401.008741 -57.885308) (xy 401.032413 -57.935805) (xy 401.048481 -57.989212) (xy 401.056601 -58.044388)
			(xy 401.05711 -58.072274) (xy 401.05704 -58.076084) (xy 405.658064 -58.076084) (xy 405.662135 -58.020462)
			(xy 405.674261 -57.966025) (xy 405.694184 -57.913934) (xy 405.72148 -57.865299) (xy 405.755566 -57.821156)
			(xy 405.795715 -57.782447) (xy 405.841073 -57.749996) (xy 405.890673 -57.724495) (xy 405.943457 -57.706488)
			(xy 405.9983 -57.696358) (xy 406.054034 -57.694321) (xy 406.109471 -57.700421) (xy 406.163428 -57.714527)
			(xy 406.214757 -57.736339) (xy 406.262363 -57.765393) (xy 406.305231 -57.801068) (xy 406.342448 -57.842605)
			(xy 406.358784 -57.867296) (xy 407.943048 -57.867296) (xy 407.947119 -57.811674) (xy 407.959245 -57.757237)
			(xy 407.979168 -57.705146) (xy 408.006464 -57.656511) (xy 408.04055 -57.612368) (xy 408.080699 -57.573659)
			(xy 408.126057 -57.541208) (xy 408.175657 -57.515707) (xy 408.228441 -57.4977) (xy 408.283284 -57.48757)
			(xy 408.339018 -57.485533) (xy 408.394455 -57.491633) (xy 408.448412 -57.505739) (xy 408.499741 -57.527551)
			(xy 408.547347 -57.556605) (xy 408.590215 -57.59228) (xy 408.627432 -57.633817) (xy 408.658205 -57.68033)
			(xy 408.681877 -57.730827) (xy 408.697945 -57.784234) (xy 408.706065 -57.83941) (xy 408.706574 -57.867296)
			(xy 408.706065 -57.895182) (xy 408.697945 -57.950358) (xy 408.681877 -58.003765) (xy 408.658205 -58.054262)
			(xy 408.627432 -58.100775) (xy 408.590215 -58.142312) (xy 408.547347 -58.177987) (xy 408.499741 -58.207041)
			(xy 408.448412 -58.228853) (xy 408.394455 -58.242959) (xy 408.339018 -58.249059) (xy 408.283284 -58.247022)
			(xy 408.228441 -58.236892) (xy 408.175657 -58.218885) (xy 408.126057 -58.193384) (xy 408.080699 -58.160933)
			(xy 408.04055 -58.122224) (xy 408.006464 -58.078081) (xy 407.979168 -58.029446) (xy 407.959245 -57.977355)
			(xy 407.947119 -57.922918) (xy 407.943048 -57.867296) (xy 406.358784 -57.867296) (xy 406.373221 -57.889118)
			(xy 406.396893 -57.939615) (xy 406.412961 -57.993022) (xy 406.421081 -58.048198) (xy 406.42159 -58.076084)
			(xy 406.421081 -58.10397) (xy 406.412961 -58.159146) (xy 406.396893 -58.212553) (xy 406.373221 -58.26305)
			(xy 406.342448 -58.309563) (xy 406.305231 -58.3511) (xy 406.262363 -58.386775) (xy 406.214757 -58.415829)
			(xy 406.163428 -58.437641) (xy 406.109471 -58.451747) (xy 406.054034 -58.457847) (xy 405.9983 -58.45581)
			(xy 405.943457 -58.44568) (xy 405.890673 -58.427673) (xy 405.841073 -58.402172) (xy 405.795715 -58.369721)
			(xy 405.755566 -58.331012) (xy 405.72148 -58.286869) (xy 405.694184 -58.238234) (xy 405.674261 -58.186143)
			(xy 405.662135 -58.131706) (xy 405.658064 -58.076084) (xy 401.05704 -58.076084) (xy 401.056601 -58.10016)
			(xy 401.048481 -58.155336) (xy 401.032413 -58.208743) (xy 401.008741 -58.25924) (xy 400.977968 -58.305753)
			(xy 400.940751 -58.34729) (xy 400.897883 -58.382965) (xy 400.850277 -58.412019) (xy 400.798948 -58.433831)
			(xy 400.744991 -58.447937) (xy 400.689554 -58.454037) (xy 400.63382 -58.452) (xy 400.578977 -58.44187)
			(xy 400.526193 -58.423863) (xy 400.476593 -58.398362) (xy 400.431235 -58.365911) (xy 400.391086 -58.327202)
			(xy 400.357 -58.283059) (xy 400.329704 -58.234424) (xy 400.309781 -58.182333) (xy 400.297655 -58.127896)
			(xy 400.293584 -58.072274) (xy 397.043439 -58.072274) (xy 397.036383 -58.097222) (xy 397.015246 -58.145421)
			(xy 396.987695 -58.190264) (xy 396.954252 -58.230902) (xy 396.935198 -58.249058) (xy 396.927813 -58.256593)
			(xy 396.919279 -58.275863) (xy 396.918688 -58.286396) (xy 396.918688 -58.361072) (xy 396.919222 -58.371621)
			(xy 396.927754 -58.390916) (xy 396.935198 -58.39841) (xy 396.954251 -58.416568) (xy 396.987708 -58.457197)
			(xy 397.015268 -58.502037) (xy 397.036407 -58.550237) (xy 397.039513 -58.561224) (xy 406.862278 -58.561224)
			(xy 406.866349 -58.505602) (xy 406.878475 -58.451165) (xy 406.898398 -58.399074) (xy 406.925694 -58.350439)
			(xy 406.95978 -58.306296) (xy 406.999929 -58.267587) (xy 407.045287 -58.235136) (xy 407.094887 -58.209635)
			(xy 407.147671 -58.191628) (xy 407.202514 -58.181498) (xy 407.258248 -58.179461) (xy 407.313685 -58.185561)
			(xy 407.367642 -58.199667) (xy 407.418971 -58.221479) (xy 407.466577 -58.250533) (xy 407.509445 -58.286208)
			(xy 407.546662 -58.327745) (xy 407.577435 -58.374258) (xy 407.601107 -58.424755) (xy 407.617175 -58.478162)
			(xy 407.625295 -58.533338) (xy 407.625804 -58.561224) (xy 407.625295 -58.58911) (xy 407.617175 -58.644286)
			(xy 407.601107 -58.697693) (xy 407.577435 -58.74819) (xy 407.546662 -58.794703) (xy 407.509445 -58.83624)
			(xy 407.466577 -58.871915) (xy 407.418971 -58.900969) (xy 407.367642 -58.922781) (xy 407.313685 -58.936887)
			(xy 407.258248 -58.942987) (xy 407.202514 -58.94095) (xy 407.147671 -58.93082) (xy 407.094887 -58.912813)
			(xy 407.045287 -58.887312) (xy 406.999929 -58.854861) (xy 406.95978 -58.816152) (xy 406.925694 -58.772009)
			(xy 406.898398 -58.723374) (xy 406.878475 -58.671283) (xy 406.866349 -58.616846) (xy 406.862278 -58.561224)
			(xy 397.039513 -58.561224) (xy 397.050724 -58.600884) (xy 397.057949 -58.653018) (xy 397.058388 -58.679334)
			(xy 397.057902 -58.706585) (xy 397.050146 -58.760533) (xy 397.034791 -58.812828) (xy 397.012149 -58.862405)
			(xy 396.982683 -58.908255) (xy 396.946992 -58.949446) (xy 396.905801 -58.985137) (xy 396.859951 -59.014603)
			(xy 396.810374 -59.037245) (xy 396.758079 -59.0526) (xy 396.704131 -59.060356) (xy 396.649629 -59.060356)
			(xy 396.595681 -59.0526) (xy 396.543386 -59.037245) (xy 396.493809 -59.014603) (xy 396.447959 -58.985137)
			(xy 396.406768 -58.949446) (xy 396.371077 -58.908255) (xy 396.341611 -58.862405) (xy 396.318969 -58.812828)
			(xy 396.303614 -58.760533) (xy 396.295858 -58.706585) (xy 396.295372 -58.679334) (xy 388.579911 -58.679334)
			(xy 388.582551 -58.694077) (xy 388.583678 -58.7248) (xy 388.583678 -58.732674) (xy 388.583156 -58.759709)
			(xy 388.57541 -58.813223) (xy 388.56017 -58.865102) (xy 388.549388 -58.8899) (xy 388.549134 -58.890408)
			(xy 388.547864 -58.893202) (xy 388.546086 -58.89879) (xy 388.543038 -58.90768) (xy 388.552341 -59.174634)
			(xy 405.393142 -59.174634) (xy 405.397213 -59.119012) (xy 405.409339 -59.064575) (xy 405.429262 -59.012484)
			(xy 405.456558 -58.963849) (xy 405.490644 -58.919706) (xy 405.530793 -58.880997) (xy 405.576151 -58.848546)
			(xy 405.625751 -58.823045) (xy 405.678535 -58.805038) (xy 405.733378 -58.794908) (xy 405.789112 -58.792871)
			(xy 405.844549 -58.798971) (xy 405.898506 -58.813077) (xy 405.949835 -58.834889) (xy 405.997441 -58.863943)
			(xy 406.040309 -58.899618) (xy 406.077526 -58.941155) (xy 406.108299 -58.987668) (xy 406.131971 -59.038165)
			(xy 406.148039 -59.091572) (xy 406.156159 -59.146748) (xy 406.156668 -59.174634) (xy 406.156159 -59.20252)
			(xy 406.148039 -59.257696) (xy 406.131971 -59.311103) (xy 406.108299 -59.3616) (xy 406.077526 -59.408113)
			(xy 406.040309 -59.44965) (xy 405.997441 -59.485325) (xy 405.949835 -59.514379) (xy 405.898506 -59.536191)
			(xy 405.844549 -59.550297) (xy 405.789112 -59.556397) (xy 405.733378 -59.55436) (xy 405.678535 -59.54423)
			(xy 405.625751 -59.526223) (xy 405.576151 -59.500722) (xy 405.530793 -59.468271) (xy 405.490644 -59.429562)
			(xy 405.456558 -59.385419) (xy 405.429262 -59.336784) (xy 405.409339 -59.284693) (xy 405.397213 -59.230256)
			(xy 405.393142 -59.174634) (xy 388.552341 -59.174634) (xy 388.568946 -59.651138) (xy 388.581809 -60.019254)
			(xy 396.435761 -60.019254) (xy 396.435761 -59.964746) (xy 396.443519 -59.910793) (xy 396.458877 -59.858493)
			(xy 396.481521 -59.808912) (xy 396.510992 -59.763058) (xy 396.546689 -59.721865) (xy 396.587885 -59.686172)
			(xy 396.633742 -59.656705) (xy 396.683325 -59.634065) (xy 396.735626 -59.618712) (xy 396.78958 -59.610959)
			(xy 396.816834 -59.610498) (xy 396.844205 -59.610945) (xy 396.898385 -59.618767) (xy 396.950888 -59.634261)
			(xy 397.000635 -59.657107) (xy 397.046601 -59.686835) (xy 397.067532 -59.704478) (xy 397.067786 -59.704732)
			(xy 397.07487 -59.710322) (xy 397.091789 -59.716566) (xy 397.100806 -59.716924) (xy 397.167862 -59.716924)
			(xy 397.176876 -59.716544) (xy 397.193793 -59.710312) (xy 397.200882 -59.704732) (xy 397.200882 -59.704478)
			(xy 397.201136 -59.704478) (xy 397.222069 -59.686837) (xy 397.268037 -59.657113) (xy 397.317783 -59.634267)
			(xy 397.370285 -59.618771) (xy 397.424463 -59.610942) (xy 397.479205 -59.610942) (xy 397.533383 -59.618771)
			(xy 397.585885 -59.634267) (xy 397.635631 -59.657113) (xy 397.681599 -59.686837) (xy 397.702532 -59.704478)
			(xy 397.702786 -59.704732) (xy 397.70987 -59.710322) (xy 397.726789 -59.716566) (xy 397.735806 -59.716924)
			(xy 397.802862 -59.716924) (xy 397.811876 -59.716544) (xy 397.828793 -59.710312) (xy 397.835882 -59.704732)
			(xy 397.835882 -59.704478) (xy 397.836136 -59.704478) (xy 397.857079 -59.686852) (xy 397.903049 -59.657139)
			(xy 397.952794 -59.634301) (xy 398.005292 -59.618807) (xy 398.059466 -59.610974) (xy 398.086834 -59.610498)
			(xy 398.114084 -59.610974) (xy 398.168029 -59.618735) (xy 398.22032 -59.634093) (xy 398.269894 -59.656736)
			(xy 398.315741 -59.686204) (xy 398.356928 -59.721896) (xy 398.392616 -59.763086) (xy 398.42208 -59.808936)
			(xy 398.444719 -59.858511) (xy 398.460073 -59.910804) (xy 398.467828 -59.96475) (xy 398.467828 -60.01925)
			(xy 398.460073 -60.073196) (xy 398.444719 -60.125489) (xy 398.42208 -60.175064) (xy 398.392616 -60.220914)
			(xy 398.356928 -60.262104) (xy 398.315741 -60.297796) (xy 398.269894 -60.327264) (xy 398.22032 -60.349907)
			(xy 398.168029 -60.365265) (xy 398.114084 -60.373026) (xy 398.086834 -60.373514) (xy 398.059465 -60.373025)
			(xy 398.005287 -60.365212) (xy 397.952784 -60.349728) (xy 397.903037 -60.326892) (xy 397.857069 -60.297173)
			(xy 397.836136 -60.279534) (xy 397.835882 -60.27928) (xy 397.828806 -60.273678) (xy 397.811881 -60.267441)
			(xy 397.802862 -60.267088) (xy 397.735806 -60.267088) (xy 397.72679 -60.267451) (xy 397.709873 -60.273695)
			(xy 397.702786 -60.27928) (xy 397.702532 -60.279534) (xy 397.681599 -60.297175) (xy 397.635631 -60.326899)
			(xy 397.585885 -60.349745) (xy 397.533383 -60.365241) (xy 397.479205 -60.37307) (xy 397.424463 -60.37307)
			(xy 397.370285 -60.365241) (xy 397.317783 -60.349745) (xy 397.268037 -60.326899) (xy 397.222069 -60.297175)
			(xy 397.201136 -60.279534) (xy 397.200882 -60.27928) (xy 397.193806 -60.273678) (xy 397.176881 -60.267441)
			(xy 397.167862 -60.267088) (xy 397.100806 -60.267088) (xy 397.09179 -60.267451) (xy 397.074873 -60.273695)
			(xy 397.067786 -60.27928) (xy 397.067786 -60.279534) (xy 397.067532 -60.279534) (xy 397.046603 -60.297177)
			(xy 397.000629 -60.326887) (xy 396.95088 -60.349722) (xy 396.898379 -60.365212) (xy 396.844203 -60.37304)
			(xy 396.816834 -60.373514) (xy 396.78958 -60.373041) (xy 396.735626 -60.365288) (xy 396.683325 -60.349935)
			(xy 396.633742 -60.327295) (xy 396.587885 -60.297828) (xy 396.546689 -60.262135) (xy 396.510992 -60.220942)
			(xy 396.481521 -60.175088) (xy 396.458877 -60.125507) (xy 396.443519 -60.073207) (xy 396.435761 -60.019254)
			(xy 388.581809 -60.019254) (xy 388.603268 -60.633356) (xy 408.096972 -60.633356) (xy 408.101043 -60.577734)
			(xy 408.113169 -60.523297) (xy 408.133092 -60.471206) (xy 408.160388 -60.422571) (xy 408.194474 -60.378428)
			(xy 408.234623 -60.339719) (xy 408.279981 -60.307268) (xy 408.329581 -60.281767) (xy 408.382365 -60.26376)
			(xy 408.437208 -60.25363) (xy 408.492942 -60.251593) (xy 408.548379 -60.257693) (xy 408.602336 -60.271799)
			(xy 408.653665 -60.293611) (xy 408.701271 -60.322665) (xy 408.744139 -60.35834) (xy 408.781356 -60.399877)
			(xy 408.812129 -60.44639) (xy 408.835801 -60.496887) (xy 408.851869 -60.550294) (xy 408.859989 -60.60547)
			(xy 408.860498 -60.633356) (xy 408.859989 -60.661242) (xy 408.851869 -60.716418) (xy 408.835801 -60.769825)
			(xy 408.812129 -60.820322) (xy 408.781356 -60.866835) (xy 408.744139 -60.908372) (xy 408.701271 -60.944047)
			(xy 408.653665 -60.973101) (xy 408.602336 -60.994913) (xy 408.548379 -61.009019) (xy 408.492942 -61.015119)
			(xy 408.437208 -61.013082) (xy 408.382365 -61.002952) (xy 408.329581 -60.984945) (xy 408.279981 -60.959444)
			(xy 408.234623 -60.926993) (xy 408.194474 -60.888284) (xy 408.160388 -60.844141) (xy 408.133092 -60.795506)
			(xy 408.113169 -60.743415) (xy 408.101043 -60.688978) (xy 408.096972 -60.633356) (xy 388.603268 -60.633356)
			(xy 388.633126 -61.487812) (xy 406.604468 -61.487812) (xy 406.608539 -61.43219) (xy 406.620665 -61.377753)
			(xy 406.640588 -61.325662) (xy 406.667884 -61.277027) (xy 406.70197 -61.232884) (xy 406.742119 -61.194175)
			(xy 406.787477 -61.161724) (xy 406.837077 -61.136223) (xy 406.889861 -61.118216) (xy 406.944704 -61.108086)
			(xy 407.000438 -61.106049) (xy 407.055875 -61.112149) (xy 407.109832 -61.126255) (xy 407.161161 -61.148067)
			(xy 407.208767 -61.177121) (xy 407.251635 -61.212796) (xy 407.288852 -61.254333) (xy 407.319625 -61.300846)
			(xy 407.343297 -61.351343) (xy 407.359365 -61.40475) (xy 407.367485 -61.459926) (xy 407.367994 -61.487812)
			(xy 407.367485 -61.515698) (xy 407.359365 -61.570874) (xy 407.343297 -61.624281) (xy 407.319625 -61.674778)
			(xy 407.288852 -61.721291) (xy 407.251635 -61.762828) (xy 407.208767 -61.798503) (xy 407.161161 -61.827557)
			(xy 407.109832 -61.849369) (xy 407.055875 -61.863475) (xy 407.000438 -61.869575) (xy 406.944704 -61.867538)
			(xy 406.889861 -61.857408) (xy 406.837077 -61.839401) (xy 406.787477 -61.8139) (xy 406.742119 -61.781449)
			(xy 406.70197 -61.74274) (xy 406.667884 -61.698597) (xy 406.640588 -61.649962) (xy 406.620665 -61.597871)
			(xy 406.608539 -61.543434) (xy 406.604468 -61.487812) (xy 388.633126 -61.487812) (xy 388.634732 -61.533786)
			(xy 388.655227 -62.121034) (xy 404.542242 -62.121034) (xy 404.546313 -62.065412) (xy 404.558439 -62.010975)
			(xy 404.578362 -61.958884) (xy 404.605658 -61.910249) (xy 404.639744 -61.866106) (xy 404.679893 -61.827397)
			(xy 404.725251 -61.794946) (xy 404.774851 -61.769445) (xy 404.827635 -61.751438) (xy 404.882478 -61.741308)
			(xy 404.938212 -61.739271) (xy 404.993649 -61.745371) (xy 405.047606 -61.759477) (xy 405.098935 -61.781289)
			(xy 405.146541 -61.810343) (xy 405.189409 -61.846018) (xy 405.226626 -61.887555) (xy 405.257399 -61.934068)
			(xy 405.281071 -61.984565) (xy 405.297139 -62.037972) (xy 405.305259 -62.093148) (xy 405.305768 -62.121034)
			(xy 405.305259 -62.14892) (xy 405.297139 -62.204096) (xy 405.281071 -62.257503) (xy 405.257399 -62.308)
			(xy 405.226626 -62.354513) (xy 405.189409 -62.39605) (xy 405.146541 -62.431725) (xy 405.098935 -62.460779)
			(xy 405.047606 -62.482591) (xy 404.993649 -62.496697) (xy 404.938212 -62.502797) (xy 404.882478 -62.50076)
			(xy 404.827635 -62.49063) (xy 404.774851 -62.472623) (xy 404.725251 -62.447122) (xy 404.679893 -62.414671)
			(xy 404.639744 -62.375962) (xy 404.605658 -62.331819) (xy 404.578362 -62.283184) (xy 404.558439 -62.231093)
			(xy 404.546313 -62.176656) (xy 404.542242 -62.121034) (xy 388.655227 -62.121034) (xy 388.693357 -63.213554)
			(xy 396.420765 -63.213554) (xy 396.420765 -63.159046) (xy 396.428523 -63.105092) (xy 396.443882 -63.052792)
			(xy 396.466527 -63.00321) (xy 396.495999 -62.957355) (xy 396.531697 -62.916163) (xy 396.572894 -62.88047)
			(xy 396.618752 -62.851004) (xy 396.668337 -62.828365) (xy 396.720639 -62.813013) (xy 396.774594 -62.805262)
			(xy 396.801848 -62.804802) (xy 396.829217 -62.805298) (xy 396.883395 -62.813109) (xy 396.935898 -62.828591)
			(xy 396.985645 -62.851426) (xy 397.031613 -62.881144) (xy 397.052546 -62.898782) (xy 397.0528 -62.899036)
			(xy 397.059879 -62.904633) (xy 397.076802 -62.910872) (xy 397.08582 -62.911228) (xy 397.152876 -62.911228)
			(xy 397.161891 -62.910853) (xy 397.178808 -62.904617) (xy 397.185896 -62.899036) (xy 397.185896 -62.898782)
			(xy 397.18615 -62.898782) (xy 397.207083 -62.881141) (xy 397.253051 -62.851417) (xy 397.302797 -62.828571)
			(xy 397.355299 -62.813075) (xy 397.409477 -62.805246) (xy 397.464219 -62.805246) (xy 397.518397 -62.813075)
			(xy 397.570899 -62.828571) (xy 397.620645 -62.851417) (xy 397.666613 -62.881141) (xy 397.687546 -62.898782)
			(xy 397.6878 -62.899036) (xy 397.694879 -62.904633) (xy 397.711802 -62.910872) (xy 397.72082 -62.911228)
			(xy 397.787876 -62.911228) (xy 397.796891 -62.910853) (xy 397.813808 -62.904617) (xy 397.820896 -62.899036)
			(xy 397.820896 -62.898782) (xy 397.82115 -62.898782) (xy 397.842088 -62.88115) (xy 397.888059 -62.851438)
			(xy 397.937805 -62.828601) (xy 397.990305 -62.813108) (xy 398.044479 -62.805277) (xy 398.071848 -62.804802)
			(xy 398.099098 -62.805271) (xy 398.153042 -62.813033) (xy 398.205332 -62.828393) (xy 398.254905 -62.851038)
			(xy 398.30075 -62.880506) (xy 398.341936 -62.916198) (xy 398.377623 -62.957388) (xy 398.407086 -63.003238)
			(xy 398.429724 -63.052813) (xy 398.439536 -63.086234) (xy 401.687536 -63.086234) (xy 401.691607 -63.030612)
			(xy 401.703733 -62.976175) (xy 401.723656 -62.924084) (xy 401.750952 -62.875449) (xy 401.785038 -62.831306)
			(xy 401.825187 -62.792597) (xy 401.870545 -62.760146) (xy 401.920145 -62.734645) (xy 401.972929 -62.716638)
			(xy 402.027772 -62.706508) (xy 402.083506 -62.704471) (xy 402.138943 -62.710571) (xy 402.1929 -62.724677)
			(xy 402.244229 -62.746489) (xy 402.291835 -62.775543) (xy 402.334703 -62.811218) (xy 402.37192 -62.852755)
			(xy 402.402693 -62.899268) (xy 402.426365 -62.949765) (xy 402.442433 -63.003172) (xy 402.450553 -63.058348)
			(xy 402.451062 -63.086234) (xy 402.450553 -63.11412) (xy 402.442433 -63.169296) (xy 402.426365 -63.222703)
			(xy 402.402693 -63.2732) (xy 402.40254 -63.273432) (xy 403.876762 -63.273432) (xy 403.880833 -63.21781)
			(xy 403.892959 -63.163373) (xy 403.912882 -63.111282) (xy 403.940178 -63.062647) (xy 403.974264 -63.018504)
			(xy 404.014413 -62.979795) (xy 404.059771 -62.947344) (xy 404.109371 -62.921843) (xy 404.162155 -62.903836)
			(xy 404.216998 -62.893706) (xy 404.272732 -62.891669) (xy 404.328169 -62.897769) (xy 404.382126 -62.911875)
			(xy 404.433455 -62.933687) (xy 404.481061 -62.962741) (xy 404.523929 -62.998416) (xy 404.561146 -63.039953)
			(xy 404.591919 -63.086466) (xy 404.615591 -63.136963) (xy 404.631659 -63.19037) (xy 404.639779 -63.245546)
			(xy 404.640288 -63.273432) (xy 404.639779 -63.301318) (xy 404.631659 -63.356494) (xy 404.615591 -63.409901)
			(xy 404.591919 -63.460398) (xy 404.561146 -63.506911) (xy 404.523929 -63.548448) (xy 404.481061 -63.584123)
			(xy 404.433455 -63.613177) (xy 404.382126 -63.634989) (xy 404.328169 -63.649095) (xy 404.272732 -63.655195)
			(xy 404.216998 -63.653158) (xy 404.162155 -63.643028) (xy 404.109371 -63.625021) (xy 404.059771 -63.59952)
			(xy 404.014413 -63.567069) (xy 403.974264 -63.52836) (xy 403.940178 -63.484217) (xy 403.912882 -63.435582)
			(xy 403.892959 -63.383491) (xy 403.880833 -63.329054) (xy 403.876762 -63.273432) (xy 402.40254 -63.273432)
			(xy 402.37192 -63.319713) (xy 402.334703 -63.36125) (xy 402.291835 -63.396925) (xy 402.244229 -63.425979)
			(xy 402.1929 -63.447791) (xy 402.138943 -63.461897) (xy 402.083506 -63.467997) (xy 402.027772 -63.46596)
			(xy 401.972929 -63.45583) (xy 401.920145 -63.437823) (xy 401.870545 -63.412322) (xy 401.825187 -63.379871)
			(xy 401.785038 -63.341162) (xy 401.750952 -63.297019) (xy 401.723656 -63.248384) (xy 401.703733 -63.196293)
			(xy 401.691607 -63.141856) (xy 401.687536 -63.086234) (xy 398.439536 -63.086234) (xy 398.445077 -63.105105)
			(xy 398.452832 -63.15905) (xy 398.452832 -63.21355) (xy 398.445077 -63.267495) (xy 398.429724 -63.319787)
			(xy 398.407086 -63.369362) (xy 398.377623 -63.415212) (xy 398.341936 -63.456402) (xy 398.30075 -63.492094)
			(xy 398.254905 -63.521562) (xy 398.205332 -63.544207) (xy 398.153042 -63.559567) (xy 398.099098 -63.567329)
			(xy 398.071848 -63.567818) (xy 398.044478 -63.567344) (xy 397.990298 -63.559531) (xy 397.937795 -63.544045)
			(xy 397.888047 -63.521204) (xy 397.842081 -63.49148) (xy 397.82115 -63.473838) (xy 397.820896 -63.473584)
			(xy 397.813816 -63.467988) (xy 397.796894 -63.461747) (xy 397.787876 -63.461392) (xy 397.72082 -63.461392)
			(xy 397.711804 -63.46176) (xy 397.694887 -63.468) (xy 397.6878 -63.473584) (xy 397.687546 -63.473838)
			(xy 397.666613 -63.491479) (xy 397.620645 -63.521203) (xy 397.570899 -63.544049) (xy 397.518397 -63.559545)
			(xy 397.464219 -63.567374) (xy 397.409477 -63.567374) (xy 397.355299 -63.559545) (xy 397.302797 -63.544049)
			(xy 397.253051 -63.521203) (xy 397.207083 -63.491479) (xy 397.18615 -63.473838) (xy 397.185896 -63.473584)
			(xy 397.178816 -63.467988) (xy 397.161894 -63.461747) (xy 397.152876 -63.461392) (xy 397.08582 -63.461392)
			(xy 397.076804 -63.46176) (xy 397.059887 -63.468) (xy 397.0528 -63.473584) (xy 397.0528 -63.473838)
			(xy 397.052546 -63.473838) (xy 397.031613 -63.491475) (xy 396.98564 -63.521186) (xy 396.935892 -63.544022)
			(xy 396.883392 -63.559514) (xy 396.829217 -63.567343) (xy 396.801848 -63.567818) (xy 396.774594 -63.567338)
			(xy 396.720639 -63.559587) (xy 396.668337 -63.544235) (xy 396.618752 -63.521596) (xy 396.572894 -63.49213)
			(xy 396.531697 -63.456437) (xy 396.495999 -63.415245) (xy 396.466527 -63.36939) (xy 396.443882 -63.319808)
			(xy 396.428523 -63.267508) (xy 396.420765 -63.213554) (xy 388.693357 -63.213554) (xy 388.707122 -63.60795)
			(xy 388.718044 -63.920624) (xy 388.718044 -63.921132) (xy 388.73369 -64.312292) (xy 407.20594 -64.312292)
			(xy 407.210011 -64.25667) (xy 407.222137 -64.202233) (xy 407.24206 -64.150142) (xy 407.269356 -64.101507)
			(xy 407.303442 -64.057364) (xy 407.343591 -64.018655) (xy 407.388949 -63.986204) (xy 407.438549 -63.960703)
			(xy 407.491333 -63.942696) (xy 407.546176 -63.932566) (xy 407.60191 -63.930529) (xy 407.657347 -63.936629)
			(xy 407.711304 -63.950735) (xy 407.762633 -63.972547) (xy 407.810239 -64.001601) (xy 407.853107 -64.037276)
			(xy 407.890324 -64.078813) (xy 407.921097 -64.125326) (xy 407.944769 -64.175823) (xy 407.960837 -64.22923)
			(xy 407.968957 -64.284406) (xy 407.969466 -64.312292) (xy 407.968957 -64.340178) (xy 407.960837 -64.395354)
			(xy 407.944769 -64.448761) (xy 407.921097 -64.499258) (xy 407.890324 -64.545771) (xy 407.853107 -64.587308)
			(xy 407.810239 -64.622983) (xy 407.762633 -64.652037) (xy 407.711304 -64.673849) (xy 407.657347 -64.687955)
			(xy 407.60191 -64.694055) (xy 407.546176 -64.692018) (xy 407.491333 -64.681888) (xy 407.438549 -64.663881)
			(xy 407.388949 -64.63838) (xy 407.343591 -64.605929) (xy 407.303442 -64.56722) (xy 407.269356 -64.523077)
			(xy 407.24206 -64.474442) (xy 407.222137 -64.422351) (xy 407.210011 -64.367914) (xy 407.20594 -64.312292)
			(xy 388.73369 -64.312292) (xy 388.764018 -65.070482) (xy 388.764018 -65.071498) (xy 388.766357 -65.100962)
			(xy 394.432534 -65.100962) (xy 394.436605 -65.04534) (xy 394.448731 -64.990903) (xy 394.468654 -64.938812)
			(xy 394.49595 -64.890177) (xy 394.530036 -64.846034) (xy 394.570185 -64.807325) (xy 394.615543 -64.774874)
			(xy 394.665143 -64.749373) (xy 394.717927 -64.731366) (xy 394.77277 -64.721236) (xy 394.828504 -64.719199)
			(xy 394.883941 -64.725299) (xy 394.937898 -64.739405) (xy 394.989227 -64.761217) (xy 395.036833 -64.790271)
			(xy 395.079701 -64.825946) (xy 395.116918 -64.867483) (xy 395.147691 -64.913996) (xy 395.171363 -64.964493)
			(xy 395.187431 -65.0179) (xy 395.195551 -65.073076) (xy 395.19606 -65.100962) (xy 395.195551 -65.128848)
			(xy 395.187431 -65.184024) (xy 395.171363 -65.237431) (xy 395.147691 -65.287928) (xy 395.116918 -65.334441)
			(xy 395.079701 -65.375978) (xy 395.036833 -65.411653) (xy 394.989227 -65.440707) (xy 394.937898 -65.462519)
			(xy 394.883941 -65.476625) (xy 394.828504 -65.482725) (xy 394.77277 -65.480688) (xy 394.717927 -65.470558)
			(xy 394.665143 -65.452551) (xy 394.615543 -65.42705) (xy 394.570185 -65.394599) (xy 394.530036 -65.35589)
			(xy 394.49595 -65.311747) (xy 394.468654 -65.263112) (xy 394.448731 -65.211021) (xy 394.436605 -65.156584)
			(xy 394.432534 -65.100962) (xy 388.766357 -65.100962) (xy 388.773416 -65.189862) (xy 388.781036 -65.283334)
			(xy 388.784846 -65.32753) (xy 388.786443 -65.337615) (xy 388.796402 -65.355422) (xy 388.80415 -65.362074)
			(xy 388.815834 -65.369694) (xy 388.8359 -65.382648) (xy 388.84098 -65.38595) (xy 388.841488 -65.386204)
			(xy 388.85114 -65.392554) (xy 388.860538 -65.397126) (xy 388.865451 -65.398738) (xy 388.875692 -65.400144)
			(xy 388.880858 -65.39992) (xy 388.881874 -65.39992) (xy 388.886192 -65.399666) (xy 388.896352 -65.397634)
			(xy 388.899908 -65.396364) (xy 388.931009 -65.38593) (xy 388.995634 -65.374685) (xy 389.028432 -65.374012)
			(xy 389.03148 -65.374012) (xy 389.058601 -65.374687) (xy 389.112247 -65.382763) (xy 389.164208 -65.398358)
			(xy 389.213435 -65.421156) (xy 389.258936 -65.450699) (xy 389.299794 -65.486389) (xy 389.335183 -65.527507)
			(xy 389.36439 -65.573224) (xy 389.386827 -65.622617) (xy 389.40204 -65.674691) (xy 389.409722 -65.728395)
			(xy 389.410194 -65.75552) (xy 389.409706 -65.78277) (xy 389.401947 -65.836715) (xy 389.38659 -65.889006)
			(xy 389.363948 -65.93858) (xy 389.334481 -65.984427) (xy 389.298789 -66.025613) (xy 389.257599 -66.061301)
			(xy 389.21175 -66.090764) (xy 389.162174 -66.113402) (xy 389.109881 -66.128755) (xy 389.055936 -66.136509)
			(xy 389.028686 -66.137028) (xy 389.010083 -66.136767) (xy 388.97306 -66.133079) (xy 388.954772 -66.129662)
			(xy 388.954264 -66.129662) (xy 388.942692 -66.128079) (xy 388.920204 -66.134302) (xy 388.911084 -66.1416)
			(xy 388.881112 -66.168524) (xy 388.87273 -66.176144) (xy 388.864478 -66.184415) (xy 388.855895 -66.206119)
			(xy 388.85622 -66.2178) (xy 388.878572 -66.497708) (xy 388.88162 -66.536062) (xy 388.891272 -66.656204)
			(xy 388.892814 -66.665133) (xy 388.901272 -66.681144) (xy 388.907782 -66.687446) (xy 388.915402 -66.693796)
			(xy 388.929118 -66.704464) (xy 388.944612 -66.716402) (xy 388.949247 -66.719409) (xy 388.959503 -66.723507)
			(xy 388.964932 -66.72453) (xy 388.982204 -66.72453) (xy 388.986268 -66.723768) (xy 389.001467 -66.721475)
			(xy 389.032112 -66.719055) (xy 389.047482 -66.718942) (xy 389.047736 -66.718942) (xy 389.073563 -66.719362)
			(xy 389.124747 -66.726304) (xy 389.174532 -66.74007) (xy 389.222012 -66.760409) (xy 389.266324 -66.786952)
			(xy 389.28675 -66.802762) (xy 389.287004 -66.803016) (xy 389.293862 -66.80835) (xy 389.301736 -66.811144)
			(xy 389.305915 -66.812554) (xy 389.314599 -66.814089) (xy 389.319008 -66.814192) (xy 389.338566 -66.814192)
			(xy 389.344005 -66.814338) (xy 389.354634 -66.816652) (xy 389.359648 -66.818764) (xy 389.373618 -66.825114)
			(xy 389.382786 -66.828799) (xy 389.402509 -66.829639) (xy 389.4211 -66.823) (xy 389.428736 -66.816732)
			(xy 389.43915 -66.807588) (xy 389.459768 -66.79116) (xy 389.504665 -66.763527) (xy 389.552932 -66.742325)
			(xy 389.603654 -66.727955) (xy 389.655869 -66.720689) (xy 389.682228 -66.720212) (xy 389.682736 -66.720212)
			(xy 389.709984 -66.720701) (xy 389.763925 -66.728461) (xy 389.816213 -66.743818) (xy 389.865783 -66.76646)
			(xy 389.911626 -66.795926) (xy 389.95281 -66.831616) (xy 389.988496 -66.872803) (xy 390.017957 -66.918649)
			(xy 390.040594 -66.968221) (xy 390.055947 -67.02051) (xy 390.063702 -67.074452) (xy 390.063702 -67.128948)
			(xy 390.055947 -67.18289) (xy 390.040594 -67.235179) (xy 390.017957 -67.284751) (xy 389.988496 -67.330597)
			(xy 389.95281 -67.371784) (xy 389.911626 -67.407474) (xy 389.865783 -67.43694) (xy 389.816213 -67.459582)
			(xy 389.763925 -67.474939) (xy 389.709984 -67.482699) (xy 389.682736 -67.483228) (xy 389.65719 -67.482815)
			(xy 389.606555 -67.475991) (xy 389.557284 -67.462475) (xy 389.510255 -67.442506) (xy 389.46631 -67.416443)
			(xy 389.446008 -67.400932) (xy 389.441182 -67.397122) (xy 389.435594 -67.394582) (xy 389.43026 -67.391788)
			(xy 389.419084 -67.389248) (xy 389.391906 -67.389248) (xy 389.386466 -67.389108) (xy 389.375832 -67.386806)
			(xy 389.370824 -67.384676) (xy 389.359902 -67.379088) (xy 389.356568 -67.377509) (xy 389.349554 -67.375222)
			(xy 389.345932 -67.374516) (xy 389.332216 -67.374008) (xy 389.322564 -67.375278) (xy 389.309356 -67.381628)
			(xy 389.30326 -67.386708) (xy 389.282094 -67.405033) (xy 389.235411 -67.435939) (xy 389.184725 -67.459716)
			(xy 389.131117 -67.475857) (xy 389.075729 -67.484016) (xy 389.047736 -67.484498) (xy 389.045704 -67.484498)
			(xy 389.032242 -67.484498) (xy 389.026073 -67.488054) (xy 393.079222 -67.488054) (xy 393.083293 -67.432432)
			(xy 393.095419 -67.377995) (xy 393.115342 -67.325904) (xy 393.142638 -67.277269) (xy 393.176724 -67.233126)
			(xy 393.216873 -67.194417) (xy 393.262231 -67.161966) (xy 393.311831 -67.136465) (xy 393.364615 -67.118458)
			(xy 393.419458 -67.108328) (xy 393.475192 -67.106291) (xy 393.530629 -67.112391) (xy 393.584586 -67.126497)
			(xy 393.635915 -67.148309) (xy 393.683521 -67.177363) (xy 393.726389 -67.213038) (xy 393.763606 -67.254575)
			(xy 393.794379 -67.301088) (xy 393.818051 -67.351585) (xy 393.834119 -67.404992) (xy 393.842239 -67.460168)
			(xy 393.842748 -67.488054) (xy 393.842239 -67.51594) (xy 393.839054 -67.537584) (xy 394.37132 -67.537584)
			(xy 394.375391 -67.481962) (xy 394.387517 -67.427525) (xy 394.40744 -67.375434) (xy 394.434736 -67.326799)
			(xy 394.468822 -67.282656) (xy 394.508971 -67.243947) (xy 394.554329 -67.211496) (xy 394.603929 -67.185995)
			(xy 394.656713 -67.167988) (xy 394.711556 -67.157858) (xy 394.76729 -67.155821) (xy 394.822727 -67.161921)
			(xy 394.876684 -67.176027) (xy 394.928013 -67.197839) (xy 394.975619 -67.226893) (xy 395.018487 -67.262568)
			(xy 395.055704 -67.304105) (xy 395.086477 -67.350618) (xy 395.110149 -67.401115) (xy 395.126217 -67.454522)
			(xy 395.134337 -67.509698) (xy 395.134846 -67.537584) (xy 395.134337 -67.56547) (xy 395.130292 -67.592956)
			(xy 395.645384 -67.592956) (xy 395.649455 -67.537334) (xy 395.661581 -67.482897) (xy 395.681504 -67.430806)
			(xy 395.7088 -67.382171) (xy 395.742886 -67.338028) (xy 395.783035 -67.299319) (xy 395.828393 -67.266868)
			(xy 395.877993 -67.241367) (xy 395.930777 -67.22336) (xy 395.98562 -67.21323) (xy 396.041354 -67.211193)
			(xy 396.096791 -67.217293) (xy 396.150748 -67.231399) (xy 396.202077 -67.253211) (xy 396.249683 -67.282265)
			(xy 396.292551 -67.31794) (xy 396.329768 -67.359477) (xy 396.360541 -67.40599) (xy 396.384213 -67.456487)
			(xy 396.400281 -67.509894) (xy 396.408398 -67.565051) (xy 398.746693 -67.565051) (xy 398.746693 -67.510549)
			(xy 398.75445 -67.456601) (xy 398.769806 -67.404306) (xy 398.792448 -67.354729) (xy 398.821916 -67.308879)
			(xy 398.857609 -67.26769) (xy 398.8988 -67.232) (xy 398.944652 -67.202536) (xy 398.994231 -67.179897)
			(xy 399.046526 -67.164545) (xy 399.100475 -67.156791) (xy 399.127726 -67.15633) (xy 399.155097 -67.156774)
			(xy 399.209277 -67.164596) (xy 399.261781 -67.18009) (xy 399.311528 -67.202937) (xy 399.357493 -67.232666)
			(xy 399.378424 -67.25031) (xy 399.378678 -67.250564) (xy 399.385761 -67.256155) (xy 399.402681 -67.262397)
			(xy 399.411698 -67.262756) (xy 399.478754 -67.262756) (xy 399.48777 -67.262387) (xy 399.504687 -67.256149)
			(xy 399.511774 -67.250564) (xy 399.511774 -67.25031) (xy 399.512028 -67.25031) (xy 399.532978 -67.232693)
			(xy 399.578945 -67.202977) (xy 399.628689 -67.180137) (xy 399.681185 -67.164641) (xy 399.735358 -67.156807)
			(xy 399.762726 -67.15633) (xy 399.789979 -67.156742) (xy 399.843929 -67.164502) (xy 399.896226 -67.179861)
			(xy 399.945805 -67.202506) (xy 399.991656 -67.231976) (xy 400.032848 -67.267671) (xy 400.06854 -67.308864)
			(xy 400.098007 -67.354718) (xy 400.120648 -67.404299) (xy 400.136004 -67.456596) (xy 400.14376 -67.510547)
			(xy 400.14376 -67.565053) (xy 400.136004 -67.619004) (xy 400.120648 -67.671301) (xy 400.098007 -67.720882)
			(xy 400.06854 -67.766736) (xy 400.032848 -67.807929) (xy 399.991656 -67.843624) (xy 399.945805 -67.873094)
			(xy 399.896226 -67.895739) (xy 399.843929 -67.911098) (xy 399.789979 -67.918858) (xy 399.762726 -67.919346)
			(xy 399.735356 -67.918878) (xy 399.681176 -67.911063) (xy 399.628673 -67.895575) (xy 399.578926 -67.872733)
			(xy 399.532959 -67.843008) (xy 399.512028 -67.825366) (xy 399.511774 -67.825112) (xy 399.504669 -67.819552)
			(xy 399.487767 -67.813289) (xy 399.478754 -67.81292) (xy 399.411698 -67.81292) (xy 399.40268 -67.813272)
			(xy 399.385763 -67.819522) (xy 399.378678 -67.825112) (xy 399.378678 -67.825366) (xy 399.378424 -67.825366)
			(xy 399.357489 -67.843002) (xy 399.311518 -67.872715) (xy 399.261771 -67.895553) (xy 399.209271 -67.911044)
			(xy 399.155095 -67.918872) (xy 399.127726 -67.919346) (xy 399.100475 -67.918809) (xy 399.046526 -67.911055)
			(xy 398.994231 -67.895703) (xy 398.944652 -67.873064) (xy 398.8988 -67.8436) (xy 398.857609 -67.80791)
			(xy 398.821916 -67.766721) (xy 398.792448 -67.720871) (xy 398.769806 -67.671294) (xy 398.75445 -67.618999)
			(xy 398.746693 -67.565051) (xy 396.408398 -67.565051) (xy 396.408401 -67.56507) (xy 396.40891 -67.592956)
			(xy 396.408401 -67.620842) (xy 396.400281 -67.676018) (xy 396.384213 -67.729425) (xy 396.360541 -67.779922)
			(xy 396.329768 -67.826435) (xy 396.292551 -67.867972) (xy 396.249683 -67.903647) (xy 396.202077 -67.932701)
			(xy 396.150748 -67.954513) (xy 396.096791 -67.968619) (xy 396.041354 -67.974719) (xy 395.98562 -67.972682)
			(xy 395.930777 -67.962552) (xy 395.877993 -67.944545) (xy 395.828393 -67.919044) (xy 395.783035 -67.886593)
			(xy 395.742886 -67.847884) (xy 395.7088 -67.803741) (xy 395.681504 -67.755106) (xy 395.661581 -67.703015)
			(xy 395.649455 -67.648578) (xy 395.645384 -67.592956) (xy 395.130292 -67.592956) (xy 395.126217 -67.620646)
			(xy 395.110149 -67.674053) (xy 395.086477 -67.72455) (xy 395.055704 -67.771063) (xy 395.018487 -67.8126)
			(xy 394.975619 -67.848275) (xy 394.928013 -67.877329) (xy 394.876684 -67.899141) (xy 394.822727 -67.913247)
			(xy 394.76729 -67.919347) (xy 394.711556 -67.91731) (xy 394.656713 -67.90718) (xy 394.603929 -67.889173)
			(xy 394.554329 -67.863672) (xy 394.508971 -67.831221) (xy 394.468822 -67.792512) (xy 394.434736 -67.748369)
			(xy 394.40744 -67.699734) (xy 394.387517 -67.647643) (xy 394.375391 -67.593206) (xy 394.37132 -67.537584)
			(xy 393.839054 -67.537584) (xy 393.834119 -67.571116) (xy 393.818051 -67.624523) (xy 393.794379 -67.67502)
			(xy 393.763606 -67.721533) (xy 393.726389 -67.76307) (xy 393.683521 -67.798745) (xy 393.635915 -67.827799)
			(xy 393.584586 -67.849611) (xy 393.530629 -67.863717) (xy 393.475192 -67.869817) (xy 393.419458 -67.86778)
			(xy 393.364615 -67.85765) (xy 393.311831 -67.839643) (xy 393.262231 -67.814142) (xy 393.216873 -67.781691)
			(xy 393.176724 -67.742982) (xy 393.142638 -67.698839) (xy 393.115342 -67.650204) (xy 393.095419 -67.598113)
			(xy 393.083293 -67.543676) (xy 393.079222 -67.488054) (xy 389.026073 -67.488054) (xy 389.010652 -67.496944)
			(xy 389.000238 -67.505072) (xy 388.990332 -67.515486) (xy 388.989824 -67.515994) (xy 388.971536 -67.535552)
			(xy 388.970266 -67.536822) (xy 388.966964 -67.546728) (xy 388.965438 -67.551657) (xy 388.964164 -67.561895)
			(xy 388.964424 -67.567048) (xy 389.046257 -68.586604) (xy 390.925304 -68.586604) (xy 390.925771 -68.559234)
			(xy 390.933589 -68.505055) (xy 390.949077 -68.452552) (xy 390.971919 -68.402805) (xy 391.001643 -68.356838)
			(xy 391.019284 -68.335906) (xy 391.019538 -68.335652) (xy 391.025113 -68.328558) (xy 391.031366 -68.311647)
			(xy 391.03173 -68.302632) (xy 391.03173 -68.235576) (xy 391.031378 -68.226559) (xy 391.025126 -68.209642)
			(xy 391.019538 -68.202556) (xy 391.019284 -68.202556) (xy 391.019284 -68.202302) (xy 391.00163 -68.181382)
			(xy 390.971921 -68.135406) (xy 390.949088 -68.085655) (xy 390.9336 -68.033152) (xy 390.925776 -67.978974)
			(xy 390.925304 -67.951604) (xy 390.925759 -67.924351) (xy 390.933516 -67.870399) (xy 390.948872 -67.8181)
			(xy 390.971515 -67.768519) (xy 391.000984 -67.722666) (xy 391.036678 -67.681472) (xy 391.077872 -67.645779)
			(xy 391.123726 -67.616311) (xy 391.173308 -67.593669) (xy 391.225607 -67.578314) (xy 391.279559 -67.570559)
			(xy 391.306812 -67.570096) (xy 391.333126 -67.570557) (xy 391.385255 -67.577793) (xy 391.435898 -67.592114)
			(xy 391.484097 -67.613247) (xy 391.52894 -67.640795) (xy 391.569579 -67.674234) (xy 391.587736 -67.693286)
			(xy 391.595244 -67.700703) (xy 391.614534 -67.709219) (xy 391.625074 -67.709796) (xy 391.69975 -67.709796)
			(xy 391.710298 -67.709255) (xy 391.729594 -67.700728) (xy 391.737088 -67.693286) (xy 391.755254 -67.674241)
			(xy 391.795882 -67.640783) (xy 391.84072 -67.613223) (xy 391.888919 -67.592083) (xy 391.939564 -67.577763)
			(xy 391.991696 -67.570536) (xy 392.018012 -67.570096) (xy 392.045382 -67.570556) (xy 392.099562 -67.578375)
			(xy 392.152065 -67.593866) (xy 392.201812 -67.616709) (xy 392.247778 -67.646434) (xy 392.26871 -67.664076)
			(xy 392.268964 -67.66433) (xy 392.276054 -67.669911) (xy 392.292968 -67.67616) (xy 392.301984 -67.676522)
			(xy 392.36904 -67.676522) (xy 392.378058 -67.676179) (xy 392.394975 -67.669921) (xy 392.40206 -67.66433)
			(xy 392.40206 -67.664076) (xy 392.402314 -67.664076) (xy 392.423265 -67.64646) (xy 392.469233 -67.616746)
			(xy 392.518976 -67.593906) (xy 392.571472 -67.578409) (xy 392.625644 -67.570574) (xy 392.653012 -67.570096)
			(xy 392.680264 -67.570567) (xy 392.734212 -67.578325) (xy 392.786507 -67.593682) (xy 392.836085 -67.616325)
			(xy 392.881936 -67.645792) (xy 392.923126 -67.681486) (xy 392.958817 -67.722677) (xy 392.988283 -67.768529)
			(xy 393.010924 -67.818108) (xy 393.026279 -67.870403) (xy 393.034035 -67.924352) (xy 393.03452 -67.951604)
			(xy 393.034076 -67.978975) (xy 393.026256 -68.033156) (xy 393.010763 -68.08566) (xy 392.987915 -68.135407)
			(xy 392.958185 -68.181372) (xy 392.94054 -68.202302) (xy 392.940286 -68.202556) (xy 392.93471 -68.20965)
			(xy 392.928457 -68.226561) (xy 392.928094 -68.235576) (xy 392.928094 -68.302632) (xy 392.928437 -68.31165)
			(xy 392.934695 -68.328567) (xy 392.940286 -68.335652) (xy 392.94054 -68.335652) (xy 392.94054 -68.335906)
			(xy 392.958202 -68.35682) (xy 392.987909 -68.402798) (xy 393.01074 -68.45255) (xy 393.026226 -68.505055)
			(xy 393.034049 -68.559234) (xy 393.03452 -68.586604) (xy 393.034026 -68.613855) (xy 393.026269 -68.667802)
			(xy 393.010914 -68.720095) (xy 392.994275 -68.75653) (xy 396.470378 -68.75653) (xy 396.470843 -68.729159)
			(xy 396.478658 -68.67498) (xy 396.494146 -68.622476) (xy 396.516989 -68.572729) (xy 396.546715 -68.526763)
			(xy 396.564358 -68.505832) (xy 396.564612 -68.505578) (xy 396.570215 -68.498503) (xy 396.576452 -68.481577)
			(xy 396.576804 -68.472558) (xy 396.576804 -68.405502) (xy 396.576445 -68.396485) (xy 396.570199 -68.379568)
			(xy 396.564612 -68.372482) (xy 396.564358 -68.372482) (xy 396.564358 -68.372228) (xy 396.546712 -68.351302)
			(xy 396.517002 -68.305327) (xy 396.494168 -68.255578) (xy 396.478679 -68.203076) (xy 396.470851 -68.148899)
			(xy 396.470378 -68.12153) (xy 396.470883 -68.094279) (xy 396.478636 -68.04033) (xy 396.493987 -67.988034)
			(xy 396.516625 -67.938455) (xy 396.546089 -67.892602) (xy 396.581778 -67.851409) (xy 396.622967 -67.815715)
			(xy 396.668816 -67.786246) (xy 396.718392 -67.763603) (xy 396.770687 -67.748245) (xy 396.824635 -67.740486)
			(xy 396.851886 -67.740022) (xy 396.879256 -67.740491) (xy 396.933435 -67.748307) (xy 396.985939 -67.763795)
			(xy 397.035686 -67.786637) (xy 397.081652 -67.816361) (xy 397.102584 -67.834002) (xy 397.102838 -67.834256)
			(xy 397.109933 -67.839829) (xy 397.126844 -67.846083) (xy 397.135858 -67.846448) (xy 397.202914 -67.846448)
			(xy 397.211933 -67.846109) (xy 397.22885 -67.83985) (xy 397.235934 -67.834256) (xy 397.235934 -67.834002)
			(xy 397.236188 -67.834002) (xy 397.257114 -67.816355) (xy 397.303088 -67.786645) (xy 397.352837 -67.76381)
			(xy 397.40534 -67.748321) (xy 397.459516 -67.740495) (xy 397.486886 -67.740022) (xy 397.5132 -67.740492)
			(xy 397.565329 -67.747725) (xy 397.615972 -67.762043) (xy 397.664171 -67.783175) (xy 397.709014 -67.810721)
			(xy 397.749654 -67.84416) (xy 397.76781 -67.863212) (xy 397.775324 -67.870622) (xy 397.79461 -67.879141)
			(xy 397.805148 -67.879722) (xy 397.879824 -67.879722) (xy 397.89037 -67.879159) (xy 397.909665 -67.870647)
			(xy 397.917162 -67.863212) (xy 397.935297 -67.844136) (xy 397.975931 -67.81068) (xy 398.020775 -67.783123)
			(xy 398.06898 -67.761988) (xy 398.119631 -67.747676) (xy 398.171769 -67.740457) (xy 398.198086 -67.740022)
			(xy 398.22534 -67.740468) (xy 398.279293 -67.748224) (xy 398.331593 -67.76358) (xy 398.381175 -67.786223)
			(xy 398.42703 -67.815692) (xy 398.468223 -67.851388) (xy 398.503917 -67.892583) (xy 398.533385 -67.938439)
			(xy 398.556026 -67.988022) (xy 398.571379 -68.040323) (xy 398.579133 -68.094276) (xy 398.579594 -68.12153)
			(xy 398.579147 -68.148901) (xy 398.571325 -68.203081) (xy 398.555831 -68.255584) (xy 398.532985 -68.305331)
			(xy 398.503257 -68.351297) (xy 398.485614 -68.372228) (xy 398.48536 -68.372482) (xy 398.47977 -68.379566)
			(xy 398.473526 -68.396485) (xy 398.473168 -68.405502) (xy 398.473168 -68.472558) (xy 398.473552 -68.481572)
			(xy 398.479782 -68.498489) (xy 398.48536 -68.505578) (xy 398.485614 -68.505578) (xy 398.485614 -68.505832)
			(xy 398.503237 -68.526777) (xy 398.532951 -68.572747) (xy 398.555789 -68.622491) (xy 398.571284 -68.674988)
			(xy 398.579117 -68.729162) (xy 398.579594 -68.75653) (xy 398.57915 -68.783783) (xy 398.571389 -68.837733)
			(xy 398.556029 -68.890029) (xy 398.533384 -68.939607) (xy 398.503913 -68.985458) (xy 398.468217 -69.026648)
			(xy 398.427023 -69.062339) (xy 398.381169 -69.091805) (xy 398.331588 -69.114445) (xy 398.27929 -69.129798)
			(xy 398.225339 -69.137553) (xy 398.198086 -69.138038) (xy 398.171771 -69.1376) (xy 398.11964 -69.130362)
			(xy 398.068996 -69.116038) (xy 398.020797 -69.0949) (xy 397.975954 -69.067348) (xy 397.935317 -69.033903)
			(xy 397.917162 -69.014848) (xy 397.90965 -69.007435) (xy 397.890363 -68.998916) (xy 397.879824 -68.998338)
			(xy 397.805148 -68.998338) (xy 397.794598 -68.998868) (xy 397.775302 -69.007402) (xy 397.76781 -69.014848)
			(xy 397.749652 -69.033901) (xy 397.709022 -69.067356) (xy 397.664182 -69.094915) (xy 397.615982 -69.116053)
			(xy 397.565335 -69.130371) (xy 397.513202 -69.137598) (xy 397.486886 -69.138038) (xy 397.459515 -69.137595)
			(xy 397.405334 -69.129774) (xy 397.35283 -69.11428) (xy 397.303084 -69.091433) (xy 397.257118 -69.061702)
			(xy 397.236188 -69.044058) (xy 397.235934 -69.043804) (xy 397.228842 -69.038226) (xy 397.211929 -69.031974)
			(xy 397.202914 -69.031612) (xy 397.135858 -69.031612) (xy 397.126844 -69.031994) (xy 397.109926 -69.038224)
			(xy 397.102838 -69.043804) (xy 397.102838 -69.044058) (xy 397.102584 -69.044058) (xy 397.081626 -69.061665)
			(xy 397.035661 -69.091383) (xy 396.98592 -69.114226) (xy 396.933425 -69.129724) (xy 396.879253 -69.13756)
			(xy 396.851886 -69.138038) (xy 396.824636 -69.137535) (xy 396.77069 -69.129778) (xy 396.718398 -69.114422)
			(xy 396.668822 -69.091782) (xy 396.622973 -69.062317) (xy 396.581784 -69.026627) (xy 396.546093 -68.985439)
			(xy 396.516626 -68.939592) (xy 396.493983 -68.890017) (xy 396.478626 -68.837725) (xy 396.470866 -68.78378)
			(xy 396.470378 -68.75653) (xy 392.994275 -68.75653) (xy 392.988273 -68.769672) (xy 392.958808 -68.815522)
			(xy 392.923117 -68.856712) (xy 392.881928 -68.892403) (xy 392.836079 -68.92187) (xy 392.786503 -68.944511)
			(xy 392.734209 -68.959868) (xy 392.680263 -68.967625) (xy 392.653012 -68.968112) (xy 392.625642 -68.967636)
			(xy 392.571464 -68.95982) (xy 392.518961 -68.944333) (xy 392.469214 -68.921494) (xy 392.423246 -68.891772)
			(xy 392.402314 -68.874132) (xy 392.40206 -68.873878) (xy 392.394962 -68.868308) (xy 392.378054 -68.862052)
			(xy 392.36904 -68.861686) (xy 392.301984 -68.861686) (xy 392.292967 -68.862039) (xy 392.27605 -68.86829)
			(xy 392.268964 -68.873878) (xy 392.268964 -68.874132) (xy 392.26871 -68.874132) (xy 392.247789 -68.891785)
			(xy 392.201813 -68.921494) (xy 392.152062 -68.944326) (xy 392.099559 -68.959814) (xy 392.045382 -68.967639)
			(xy 392.018012 -68.968112) (xy 391.991698 -68.967633) (xy 391.939571 -68.9604) (xy 391.888928 -68.946083)
			(xy 391.840729 -68.924952) (xy 391.795886 -68.897409) (xy 391.755245 -68.863972) (xy 391.737088 -68.844922)
			(xy 391.72957 -68.837516) (xy 391.710287 -68.828993) (xy 391.69975 -68.828412) (xy 391.625074 -68.828412)
			(xy 391.614527 -68.828964) (xy 391.595231 -68.837483) (xy 391.587736 -68.844922) (xy 391.569609 -68.864006)
			(xy 391.528973 -68.89746) (xy 391.484126 -68.925014) (xy 391.43592 -68.946148) (xy 391.385268 -68.960459)
			(xy 391.33313 -68.967677) (xy 391.306812 -68.968112) (xy 391.27956 -68.967634) (xy 391.225609 -68.959878)
			(xy 391.173312 -68.944524) (xy 391.123732 -68.921883) (xy 391.077879 -68.892417) (xy 391.036687 -68.856725)
			(xy 391.000993 -68.815533) (xy 390.971525 -68.769682) (xy 390.948882 -68.720103) (xy 390.933525 -68.667806)
			(xy 390.925768 -68.613856) (xy 390.925304 -68.586604) (xy 389.046257 -68.586604) (xy 389.284579 -71.555864)
			(xy 393.494512 -71.555864) (xy 393.498583 -71.500242) (xy 393.510709 -71.445805) (xy 393.530632 -71.393714)
			(xy 393.557928 -71.345079) (xy 393.592014 -71.300936) (xy 393.632163 -71.262227) (xy 393.677521 -71.229776)
			(xy 393.727121 -71.204275) (xy 393.779905 -71.186268) (xy 393.834748 -71.176138) (xy 393.890482 -71.174101)
			(xy 393.945919 -71.180201) (xy 393.999876 -71.194307) (xy 394.051205 -71.216119) (xy 394.098811 -71.245173)
			(xy 394.141679 -71.280848) (xy 394.178896 -71.322385) (xy 394.209669 -71.368898) (xy 394.233341 -71.419395)
			(xy 394.249409 -71.472802) (xy 394.257529 -71.527978) (xy 394.258038 -71.555864) (xy 394.257529 -71.58375)
			(xy 394.25169 -71.623428) (xy 395.003526 -71.623428) (xy 395.007597 -71.567806) (xy 395.019723 -71.513369)
			(xy 395.039646 -71.461278) (xy 395.066942 -71.412643) (xy 395.101028 -71.3685) (xy 395.141177 -71.329791)
			(xy 395.186535 -71.29734) (xy 395.236135 -71.271839) (xy 395.288919 -71.253832) (xy 395.343762 -71.243702)
			(xy 395.399496 -71.241665) (xy 395.454933 -71.247765) (xy 395.50889 -71.261871) (xy 395.560219 -71.283683)
			(xy 395.607825 -71.312737) (xy 395.650693 -71.348412) (xy 395.68791 -71.389949) (xy 395.718683 -71.436462)
			(xy 395.742355 -71.486959) (xy 395.758423 -71.540366) (xy 395.766543 -71.595542) (xy 395.767052 -71.623428)
			(xy 395.766543 -71.651314) (xy 395.758423 -71.70649) (xy 395.742355 -71.759897) (xy 395.718683 -71.810394)
			(xy 395.68791 -71.856907) (xy 395.650693 -71.898444) (xy 395.607825 -71.934119) (xy 395.560219 -71.963173)
			(xy 395.50889 -71.984985) (xy 395.454933 -71.999091) (xy 395.399496 -72.005191) (xy 395.343762 -72.003154)
			(xy 395.288919 -71.993024) (xy 395.236135 -71.975017) (xy 395.186535 -71.949516) (xy 395.141177 -71.917065)
			(xy 395.101028 -71.878356) (xy 395.066942 -71.834213) (xy 395.039646 -71.785578) (xy 395.019723 -71.733487)
			(xy 395.007597 -71.67905) (xy 395.003526 -71.623428) (xy 394.25169 -71.623428) (xy 394.249409 -71.638926)
			(xy 394.233341 -71.692333) (xy 394.209669 -71.74283) (xy 394.178896 -71.789343) (xy 394.141679 -71.83088)
			(xy 394.098811 -71.866555) (xy 394.051205 -71.895609) (xy 393.999876 -71.917421) (xy 393.945919 -71.931527)
			(xy 393.890482 -71.937627) (xy 393.834748 -71.93559) (xy 393.779905 -71.92546) (xy 393.727121 -71.907453)
			(xy 393.677521 -71.881952) (xy 393.632163 -71.849501) (xy 393.592014 -71.810792) (xy 393.557928 -71.766649)
			(xy 393.530632 -71.718014) (xy 393.510709 -71.665923) (xy 393.498583 -71.611486) (xy 393.494512 -71.555864)
			(xy 389.284579 -71.555864) (xy 389.400396 -72.998838) (xy 405.177496 -72.998838) (xy 405.181567 -72.943216)
			(xy 405.193693 -72.888779) (xy 405.213616 -72.836688) (xy 405.240912 -72.788053) (xy 405.274998 -72.74391)
			(xy 405.315147 -72.705201) (xy 405.360505 -72.67275) (xy 405.410105 -72.647249) (xy 405.462889 -72.629242)
			(xy 405.517732 -72.619112) (xy 405.573466 -72.617075) (xy 405.628903 -72.623175) (xy 405.68286 -72.637281)
			(xy 405.734189 -72.659093) (xy 405.781795 -72.688147) (xy 405.824663 -72.723822) (xy 405.86188 -72.765359)
			(xy 405.892653 -72.811872) (xy 405.916325 -72.862369) (xy 405.932393 -72.915776) (xy 405.940513 -72.970952)
			(xy 405.941022 -72.998838) (xy 405.940513 -73.026724) (xy 405.932393 -73.0819) (xy 405.916325 -73.135307)
			(xy 405.892653 -73.185804) (xy 405.86188 -73.232317) (xy 405.824663 -73.273854) (xy 405.781795 -73.309529)
			(xy 405.734189 -73.338583) (xy 405.68286 -73.360395) (xy 405.628903 -73.374501) (xy 405.573466 -73.380601)
			(xy 405.517732 -73.378564) (xy 405.462889 -73.368434) (xy 405.410105 -73.350427) (xy 405.360505 -73.324926)
			(xy 405.315147 -73.292475) (xy 405.274998 -73.253766) (xy 405.240912 -73.209623) (xy 405.213616 -73.160988)
			(xy 405.193693 -73.108897) (xy 405.181567 -73.05446) (xy 405.177496 -72.998838) (xy 389.400396 -72.998838)
			(xy 389.524348 -74.543158) (xy 405.05202 -74.543158) (xy 405.056091 -74.487536) (xy 405.068217 -74.433099)
			(xy 405.08814 -74.381008) (xy 405.115436 -74.332373) (xy 405.149522 -74.28823) (xy 405.189671 -74.249521)
			(xy 405.235029 -74.21707) (xy 405.284629 -74.191569) (xy 405.337413 -74.173562) (xy 405.392256 -74.163432)
			(xy 405.44799 -74.161395) (xy 405.503427 -74.167495) (xy 405.557384 -74.181601) (xy 405.608713 -74.203413)
			(xy 405.656319 -74.232467) (xy 405.699187 -74.268142) (xy 405.736404 -74.309679) (xy 405.767177 -74.356192)
			(xy 405.790849 -74.406689) (xy 405.806917 -74.460096) (xy 405.815037 -74.515272) (xy 405.815546 -74.543158)
			(xy 405.815037 -74.571044) (xy 405.806917 -74.62622) (xy 405.790849 -74.679627) (xy 405.767177 -74.730124)
			(xy 405.736404 -74.776637) (xy 405.699187 -74.818174) (xy 405.656319 -74.853849) (xy 405.608713 -74.882903)
			(xy 405.557384 -74.904715) (xy 405.503427 -74.918821) (xy 405.44799 -74.924921) (xy 405.392256 -74.922884)
			(xy 405.337413 -74.912754) (xy 405.284629 -74.894747) (xy 405.235029 -74.869246) (xy 405.189671 -74.836795)
			(xy 405.149522 -74.798086) (xy 405.115436 -74.753943) (xy 405.08814 -74.705308) (xy 405.068217 -74.653217)
			(xy 405.056091 -74.59878) (xy 405.05202 -74.543158) (xy 389.524348 -74.543158) (xy 389.762446 -77.509624)
			(xy 391.980926 -77.509624) (xy 391.984997 -77.454002) (xy 391.997123 -77.399565) (xy 392.017046 -77.347474)
			(xy 392.044342 -77.298839) (xy 392.078428 -77.254696) (xy 392.118577 -77.215987) (xy 392.163935 -77.183536)
			(xy 392.213535 -77.158035) (xy 392.266319 -77.140028) (xy 392.321162 -77.129898) (xy 392.376896 -77.127861)
			(xy 392.432333 -77.133961) (xy 392.48629 -77.148067) (xy 392.537619 -77.169879) (xy 392.585225 -77.198933)
			(xy 392.628093 -77.234608) (xy 392.66531 -77.276145) (xy 392.696083 -77.322658) (xy 392.719755 -77.373155)
			(xy 392.735823 -77.426562) (xy 392.743943 -77.481738) (xy 392.744452 -77.509624) (xy 392.744443 -77.510132)
			(xy 393.554456 -77.510132) (xy 393.558527 -77.45451) (xy 393.570653 -77.400073) (xy 393.590576 -77.347982)
			(xy 393.617872 -77.299347) (xy 393.651958 -77.255204) (xy 393.692107 -77.216495) (xy 393.737465 -77.184044)
			(xy 393.787065 -77.158543) (xy 393.839849 -77.140536) (xy 393.894692 -77.130406) (xy 393.950426 -77.128369)
			(xy 394.005863 -77.134469) (xy 394.05982 -77.148575) (xy 394.111149 -77.170387) (xy 394.158755 -77.199441)
			(xy 394.201623 -77.235116) (xy 394.23884 -77.276653) (xy 394.269613 -77.323166) (xy 394.293285 -77.373663)
			(xy 394.309353 -77.42707) (xy 394.317473 -77.482246) (xy 394.317982 -77.510132) (xy 394.317473 -77.538018)
			(xy 394.309353 -77.593194) (xy 394.293285 -77.646601) (xy 394.269613 -77.697098) (xy 394.23884 -77.743611)
			(xy 394.201623 -77.785148) (xy 394.158755 -77.820823) (xy 394.111149 -77.849877) (xy 394.05982 -77.871689)
			(xy 394.005863 -77.885795) (xy 393.950426 -77.891895) (xy 393.894692 -77.889858) (xy 393.839849 -77.879728)
			(xy 393.787065 -77.861721) (xy 393.737465 -77.83622) (xy 393.692107 -77.803769) (xy 393.651958 -77.76506)
			(xy 393.617872 -77.720917) (xy 393.590576 -77.672282) (xy 393.570653 -77.620191) (xy 393.558527 -77.565754)
			(xy 393.554456 -77.510132) (xy 392.744443 -77.510132) (xy 392.743943 -77.53751) (xy 392.735823 -77.592686)
			(xy 392.719755 -77.646093) (xy 392.696083 -77.69659) (xy 392.66531 -77.743103) (xy 392.628093 -77.78464)
			(xy 392.585225 -77.820315) (xy 392.537619 -77.849369) (xy 392.48629 -77.871181) (xy 392.432333 -77.885287)
			(xy 392.376896 -77.891387) (xy 392.321162 -77.88935) (xy 392.266319 -77.87922) (xy 392.213535 -77.861213)
			(xy 392.163935 -77.835712) (xy 392.118577 -77.803261) (xy 392.078428 -77.764552) (xy 392.044342 -77.720409)
			(xy 392.017046 -77.671774) (xy 391.997123 -77.619683) (xy 391.984997 -77.565246) (xy 391.980926 -77.509624)
			(xy 389.762446 -77.509624) (xy 389.77951 -77.722222) (xy 389.990923 -80.356202) (xy 392.196064 -80.356202)
			(xy 392.200135 -80.30058) (xy 392.212261 -80.246143) (xy 392.232184 -80.194052) (xy 392.25948 -80.145417)
			(xy 392.293566 -80.101274) (xy 392.333715 -80.062565) (xy 392.379073 -80.030114) (xy 392.428673 -80.004613)
			(xy 392.481457 -79.986606) (xy 392.5363 -79.976476) (xy 392.592034 -79.974439) (xy 392.647471 -79.980539)
			(xy 392.701428 -79.994645) (xy 392.752757 -80.016457) (xy 392.800363 -80.045511) (xy 392.843231 -80.081186)
			(xy 392.880448 -80.122723) (xy 392.911221 -80.169236) (xy 392.934893 -80.219733) (xy 392.950961 -80.27314)
			(xy 392.959081 -80.328316) (xy 392.95959 -80.356202) (xy 394.436344 -80.356202) (xy 394.440415 -80.30058)
			(xy 394.452541 -80.246143) (xy 394.472464 -80.194052) (xy 394.49976 -80.145417) (xy 394.533846 -80.101274)
			(xy 394.573995 -80.062565) (xy 394.619353 -80.030114) (xy 394.668953 -80.004613) (xy 394.721737 -79.986606)
			(xy 394.77658 -79.976476) (xy 394.832314 -79.974439) (xy 394.887751 -79.980539) (xy 394.941708 -79.994645)
			(xy 394.993037 -80.016457) (xy 395.040643 -80.045511) (xy 395.083511 -80.081186) (xy 395.120728 -80.122723)
			(xy 395.151501 -80.169236) (xy 395.175173 -80.219733) (xy 395.191241 -80.27314) (xy 395.199361 -80.328316)
			(xy 395.19987 -80.356202) (xy 396.84274 -80.356202) (xy 396.846811 -80.30058) (xy 396.858937 -80.246143)
			(xy 396.87886 -80.194052) (xy 396.906156 -80.145417) (xy 396.940242 -80.101274) (xy 396.980391 -80.062565)
			(xy 397.025749 -80.030114) (xy 397.075349 -80.004613) (xy 397.128133 -79.986606) (xy 397.182976 -79.976476)
			(xy 397.23871 -79.974439) (xy 397.294147 -79.980539) (xy 397.348104 -79.994645) (xy 397.399433 -80.016457)
			(xy 397.447039 -80.045511) (xy 397.489907 -80.081186) (xy 397.527124 -80.122723) (xy 397.557897 -80.169236)
			(xy 397.581569 -80.219733) (xy 397.597637 -80.27314) (xy 397.605757 -80.328316) (xy 397.606266 -80.356202)
			(xy 397.605757 -80.384088) (xy 397.597637 -80.439264) (xy 397.581569 -80.492671) (xy 397.557897 -80.543168)
			(xy 397.527124 -80.589681) (xy 397.489907 -80.631218) (xy 397.447039 -80.666893) (xy 397.399433 -80.695947)
			(xy 397.348104 -80.717759) (xy 397.294147 -80.731865) (xy 397.23871 -80.737965) (xy 397.182976 -80.735928)
			(xy 397.128133 -80.725798) (xy 397.075349 -80.707791) (xy 397.025749 -80.68229) (xy 396.980391 -80.649839)
			(xy 396.940242 -80.61113) (xy 396.906156 -80.566987) (xy 396.87886 -80.518352) (xy 396.858937 -80.466261)
			(xy 396.846811 -80.411824) (xy 396.84274 -80.356202) (xy 395.19987 -80.356202) (xy 395.199361 -80.384088)
			(xy 395.191241 -80.439264) (xy 395.175173 -80.492671) (xy 395.151501 -80.543168) (xy 395.120728 -80.589681)
			(xy 395.083511 -80.631218) (xy 395.040643 -80.666893) (xy 394.993037 -80.695947) (xy 394.941708 -80.717759)
			(xy 394.887751 -80.731865) (xy 394.832314 -80.737965) (xy 394.77658 -80.735928) (xy 394.721737 -80.725798)
			(xy 394.668953 -80.707791) (xy 394.619353 -80.68229) (xy 394.573995 -80.649839) (xy 394.533846 -80.61113)
			(xy 394.49976 -80.566987) (xy 394.472464 -80.518352) (xy 394.452541 -80.466261) (xy 394.440415 -80.411824)
			(xy 394.436344 -80.356202) (xy 392.95959 -80.356202) (xy 392.959081 -80.384088) (xy 392.950961 -80.439264)
			(xy 392.934893 -80.492671) (xy 392.911221 -80.543168) (xy 392.880448 -80.589681) (xy 392.843231 -80.631218)
			(xy 392.800363 -80.666893) (xy 392.752757 -80.695947) (xy 392.701428 -80.717759) (xy 392.647471 -80.731865)
			(xy 392.592034 -80.737965) (xy 392.5363 -80.735928) (xy 392.481457 -80.725798) (xy 392.428673 -80.707791)
			(xy 392.379073 -80.68229) (xy 392.333715 -80.649839) (xy 392.293566 -80.61113) (xy 392.25948 -80.566987)
			(xy 392.232184 -80.518352) (xy 392.212261 -80.466261) (xy 392.200135 -80.411824) (xy 392.196064 -80.356202)
			(xy 389.990923 -80.356202) (xy 390.082665 -81.499202) (xy 390.559542 -81.499202) (xy 390.563613 -81.44358)
			(xy 390.575739 -81.389143) (xy 390.595662 -81.337052) (xy 390.622958 -81.288417) (xy 390.657044 -81.244274)
			(xy 390.697193 -81.205565) (xy 390.742551 -81.173114) (xy 390.792151 -81.147613) (xy 390.844935 -81.129606)
			(xy 390.899778 -81.119476) (xy 390.955512 -81.117439) (xy 391.010949 -81.123539) (xy 391.064906 -81.137645)
			(xy 391.116235 -81.159457) (xy 391.163841 -81.188511) (xy 391.206709 -81.224186) (xy 391.243926 -81.265723)
			(xy 391.274699 -81.312236) (xy 391.298371 -81.362733) (xy 391.314439 -81.41614) (xy 391.322559 -81.471316)
			(xy 391.323068 -81.499202) (xy 391.322559 -81.527088) (xy 391.314439 -81.582264) (xy 391.298371 -81.635671)
			(xy 391.274699 -81.686168) (xy 391.243926 -81.732681) (xy 391.206709 -81.774218) (xy 391.163841 -81.809893)
			(xy 391.116235 -81.838947) (xy 391.064906 -81.860759) (xy 391.010949 -81.874865) (xy 390.955512 -81.880965)
			(xy 390.899778 -81.878928) (xy 390.844935 -81.868798) (xy 390.792151 -81.850791) (xy 390.742551 -81.82529)
			(xy 390.697193 -81.792839) (xy 390.657044 -81.75413) (xy 390.622958 -81.709987) (xy 390.595662 -81.661352)
			(xy 390.575739 -81.609261) (xy 390.563613 -81.554824) (xy 390.559542 -81.499202) (xy 390.082665 -81.499202)
			(xy 390.174407 -82.642202) (xy 392.209526 -82.642202) (xy 392.213597 -82.58658) (xy 392.225723 -82.532143)
			(xy 392.245646 -82.480052) (xy 392.272942 -82.431417) (xy 392.307028 -82.387274) (xy 392.347177 -82.348565)
			(xy 392.392535 -82.316114) (xy 392.442135 -82.290613) (xy 392.494919 -82.272606) (xy 392.549762 -82.262476)
			(xy 392.605496 -82.260439) (xy 392.660933 -82.266539) (xy 392.71489 -82.280645) (xy 392.766219 -82.302457)
			(xy 392.813825 -82.331511) (xy 392.856693 -82.367186) (xy 392.89391 -82.408723) (xy 392.924683 -82.455236)
			(xy 392.948355 -82.505733) (xy 392.964423 -82.55914) (xy 392.972543 -82.614316) (xy 392.973052 -82.642202)
			(xy 396.84274 -82.642202) (xy 396.846811 -82.58658) (xy 396.858937 -82.532143) (xy 396.87886 -82.480052)
			(xy 396.906156 -82.431417) (xy 396.940242 -82.387274) (xy 396.980391 -82.348565) (xy 397.025749 -82.316114)
			(xy 397.075349 -82.290613) (xy 397.128133 -82.272606) (xy 397.182976 -82.262476) (xy 397.23871 -82.260439)
			(xy 397.294147 -82.266539) (xy 397.348104 -82.280645) (xy 397.399433 -82.302457) (xy 397.447039 -82.331511)
			(xy 397.489907 -82.367186) (xy 397.527124 -82.408723) (xy 397.557897 -82.455236) (xy 397.581569 -82.505733)
			(xy 397.597637 -82.55914) (xy 397.605757 -82.614316) (xy 397.606266 -82.642202) (xy 397.605757 -82.670088)
			(xy 397.597637 -82.725264) (xy 397.581569 -82.778671) (xy 397.557897 -82.829168) (xy 397.527124 -82.875681)
			(xy 397.489907 -82.917218) (xy 397.447039 -82.952893) (xy 397.399433 -82.981947) (xy 397.348104 -83.003759)
			(xy 397.294147 -83.017865) (xy 397.23871 -83.023965) (xy 397.182976 -83.021928) (xy 397.128133 -83.011798)
			(xy 397.075349 -82.993791) (xy 397.025749 -82.96829) (xy 396.980391 -82.935839) (xy 396.940242 -82.89713)
			(xy 396.906156 -82.852987) (xy 396.87886 -82.804352) (xy 396.858937 -82.752261) (xy 396.846811 -82.697824)
			(xy 396.84274 -82.642202) (xy 392.973052 -82.642202) (xy 392.972543 -82.670088) (xy 392.964423 -82.725264)
			(xy 392.948355 -82.778671) (xy 392.924683 -82.829168) (xy 392.89391 -82.875681) (xy 392.856693 -82.917218)
			(xy 392.813825 -82.952893) (xy 392.766219 -82.981947) (xy 392.71489 -83.003759) (xy 392.660933 -83.017865)
			(xy 392.605496 -83.023965) (xy 392.549762 -83.021928) (xy 392.494919 -83.011798) (xy 392.442135 -82.993791)
			(xy 392.392535 -82.96829) (xy 392.347177 -82.935839) (xy 392.307028 -82.89713) (xy 392.272942 -82.852987)
			(xy 392.245646 -82.804352) (xy 392.225723 -82.752261) (xy 392.213597 -82.697824) (xy 392.209526 -82.642202)
			(xy 390.174407 -82.642202) (xy 390.214651 -83.143598) (xy 394.215618 -83.143598) (xy 394.219689 -83.087976)
			(xy 394.231815 -83.033539) (xy 394.251738 -82.981448) (xy 394.279034 -82.932813) (xy 394.31312 -82.88867)
			(xy 394.353269 -82.849961) (xy 394.398627 -82.81751) (xy 394.448227 -82.792009) (xy 394.501011 -82.774002)
			(xy 394.555854 -82.763872) (xy 394.611588 -82.761835) (xy 394.667025 -82.767935) (xy 394.720982 -82.782041)
			(xy 394.772311 -82.803853) (xy 394.819917 -82.832907) (xy 394.862785 -82.868582) (xy 394.900002 -82.910119)
			(xy 394.930775 -82.956632) (xy 394.954447 -83.007129) (xy 394.970515 -83.060536) (xy 394.978635 -83.115712)
			(xy 394.979144 -83.143598) (xy 394.978635 -83.171484) (xy 394.970515 -83.22666) (xy 394.954447 -83.280067)
			(xy 394.930775 -83.330564) (xy 394.900002 -83.377077) (xy 394.862785 -83.418614) (xy 394.819917 -83.454289)
			(xy 394.772311 -83.483343) (xy 394.720982 -83.505155) (xy 394.667025 -83.519261) (xy 394.611588 -83.525361)
			(xy 394.555854 -83.523324) (xy 394.501011 -83.513194) (xy 394.448227 -83.495187) (xy 394.398627 -83.469686)
			(xy 394.353269 -83.437235) (xy 394.31312 -83.398526) (xy 394.279034 -83.354383) (xy 394.251738 -83.305748)
			(xy 394.231815 -83.253657) (xy 394.219689 -83.19922) (xy 394.215618 -83.143598) (xy 390.214651 -83.143598)
			(xy 390.266149 -83.785202) (xy 391.48842 -83.785202) (xy 391.492491 -83.72958) (xy 391.504617 -83.675143)
			(xy 391.52454 -83.623052) (xy 391.551836 -83.574417) (xy 391.585922 -83.530274) (xy 391.626071 -83.491565)
			(xy 391.671429 -83.459114) (xy 391.721029 -83.433613) (xy 391.773813 -83.415606) (xy 391.828656 -83.405476)
			(xy 391.88439 -83.403439) (xy 391.939827 -83.409539) (xy 391.993784 -83.423645) (xy 392.045113 -83.445457)
			(xy 392.092719 -83.474511) (xy 392.135587 -83.510186) (xy 392.172804 -83.551723) (xy 392.203577 -83.598236)
			(xy 392.227249 -83.648733) (xy 392.243317 -83.70214) (xy 392.251437 -83.757316) (xy 392.251946 -83.785202)
			(xy 396.84274 -83.785202) (xy 396.846811 -83.72958) (xy 396.858937 -83.675143) (xy 396.87886 -83.623052)
			(xy 396.906156 -83.574417) (xy 396.940242 -83.530274) (xy 396.980391 -83.491565) (xy 397.025749 -83.459114)
			(xy 397.075349 -83.433613) (xy 397.128133 -83.415606) (xy 397.182976 -83.405476) (xy 397.23871 -83.403439)
			(xy 397.294147 -83.409539) (xy 397.348104 -83.423645) (xy 397.399433 -83.445457) (xy 397.447039 -83.474511)
			(xy 397.489907 -83.510186) (xy 397.527124 -83.551723) (xy 397.557897 -83.598236) (xy 397.581569 -83.648733)
			(xy 397.597637 -83.70214) (xy 397.605757 -83.757316) (xy 397.606266 -83.785202) (xy 397.605757 -83.813088)
			(xy 397.597637 -83.868264) (xy 397.581569 -83.921671) (xy 397.557897 -83.972168) (xy 397.527124 -84.018681)
			(xy 397.489907 -84.060218) (xy 397.447039 -84.095893) (xy 397.399433 -84.124947) (xy 397.348104 -84.146759)
			(xy 397.294147 -84.160865) (xy 397.23871 -84.166965) (xy 397.182976 -84.164928) (xy 397.128133 -84.154798)
			(xy 397.075349 -84.136791) (xy 397.025749 -84.11129) (xy 396.980391 -84.078839) (xy 396.940242 -84.04013)
			(xy 396.906156 -83.995987) (xy 396.87886 -83.947352) (xy 396.858937 -83.895261) (xy 396.846811 -83.840824)
			(xy 396.84274 -83.785202) (xy 392.251946 -83.785202) (xy 392.251437 -83.813088) (xy 392.243317 -83.868264)
			(xy 392.227249 -83.921671) (xy 392.203577 -83.972168) (xy 392.172804 -84.018681) (xy 392.135587 -84.060218)
			(xy 392.092719 -84.095893) (xy 392.045113 -84.124947) (xy 391.993784 -84.146759) (xy 391.939827 -84.160865)
			(xy 391.88439 -84.166965) (xy 391.828656 -84.164928) (xy 391.773813 -84.154798) (xy 391.721029 -84.136791)
			(xy 391.671429 -84.11129) (xy 391.626071 -84.078839) (xy 391.585922 -84.04013) (xy 391.551836 -83.995987)
			(xy 391.52454 -83.947352) (xy 391.504617 -83.895261) (xy 391.492491 -83.840824) (xy 391.48842 -83.785202)
			(xy 390.266149 -83.785202) (xy 390.305598 -84.276692) (xy 394.311122 -84.276692) (xy 394.315193 -84.22107)
			(xy 394.327319 -84.166633) (xy 394.347242 -84.114542) (xy 394.374538 -84.065907) (xy 394.408624 -84.021764)
			(xy 394.448773 -83.983055) (xy 394.494131 -83.950604) (xy 394.543731 -83.925103) (xy 394.596515 -83.907096)
			(xy 394.651358 -83.896966) (xy 394.707092 -83.894929) (xy 394.762529 -83.901029) (xy 394.816486 -83.915135)
			(xy 394.867815 -83.936947) (xy 394.915421 -83.966001) (xy 394.958289 -84.001676) (xy 394.995506 -84.043213)
			(xy 395.026279 -84.089726) (xy 395.049951 -84.140223) (xy 395.066019 -84.19363) (xy 395.074139 -84.248806)
			(xy 395.074648 -84.276692) (xy 395.074139 -84.304578) (xy 395.066019 -84.359754) (xy 395.049951 -84.413161)
			(xy 395.026279 -84.463658) (xy 394.995506 -84.510171) (xy 394.958289 -84.551708) (xy 394.915421 -84.587383)
			(xy 394.867815 -84.616437) (xy 394.816486 -84.638249) (xy 394.762529 -84.652355) (xy 394.707092 -84.658455)
			(xy 394.651358 -84.656418) (xy 394.596515 -84.646288) (xy 394.543731 -84.628281) (xy 394.494131 -84.60278)
			(xy 394.448773 -84.570329) (xy 394.408624 -84.53162) (xy 394.374538 -84.487477) (xy 394.347242 -84.438842)
			(xy 394.327319 -84.386751) (xy 394.315193 -84.332314) (xy 394.311122 -84.276692) (xy 390.305598 -84.276692)
			(xy 390.357891 -84.928202) (xy 392.262866 -84.928202) (xy 392.266937 -84.87258) (xy 392.279063 -84.818143)
			(xy 392.298986 -84.766052) (xy 392.326282 -84.717417) (xy 392.360368 -84.673274) (xy 392.400517 -84.634565)
			(xy 392.445875 -84.602114) (xy 392.495475 -84.576613) (xy 392.548259 -84.558606) (xy 392.603102 -84.548476)
			(xy 392.658836 -84.546439) (xy 392.714273 -84.552539) (xy 392.76823 -84.566645) (xy 392.819559 -84.588457)
			(xy 392.867165 -84.617511) (xy 392.910033 -84.653186) (xy 392.94725 -84.694723) (xy 392.978023 -84.741236)
			(xy 393.001695 -84.791733) (xy 393.017763 -84.84514) (xy 393.025883 -84.900316) (xy 393.026392 -84.928202)
			(xy 396.84274 -84.928202) (xy 396.846811 -84.87258) (xy 396.858937 -84.818143) (xy 396.87886 -84.766052)
			(xy 396.906156 -84.717417) (xy 396.940242 -84.673274) (xy 396.980391 -84.634565) (xy 397.025749 -84.602114)
			(xy 397.075349 -84.576613) (xy 397.128133 -84.558606) (xy 397.182976 -84.548476) (xy 397.23871 -84.546439)
			(xy 397.294147 -84.552539) (xy 397.348104 -84.566645) (xy 397.399433 -84.588457) (xy 397.447039 -84.617511)
			(xy 397.489907 -84.653186) (xy 397.527124 -84.694723) (xy 397.544804 -84.721446) (xy 399.610832 -84.721446)
			(xy 399.614903 -84.665824) (xy 399.627029 -84.611387) (xy 399.646952 -84.559296) (xy 399.674248 -84.510661)
			(xy 399.708334 -84.466518) (xy 399.748483 -84.427809) (xy 399.793841 -84.395358) (xy 399.843441 -84.369857)
			(xy 399.896225 -84.35185) (xy 399.951068 -84.34172) (xy 400.006802 -84.339683) (xy 400.062239 -84.345783)
			(xy 400.116196 -84.359889) (xy 400.167525 -84.381701) (xy 400.215131 -84.410755) (xy 400.257999 -84.44643)
			(xy 400.295216 -84.487967) (xy 400.325989 -84.53448) (xy 400.349661 -84.584977) (xy 400.365729 -84.638384)
			(xy 400.373849 -84.69356) (xy 400.374358 -84.721446) (xy 400.373849 -84.749332) (xy 400.365729 -84.804508)
			(xy 400.349661 -84.857915) (xy 400.325989 -84.908412) (xy 400.295216 -84.954925) (xy 400.257999 -84.996462)
			(xy 400.215131 -85.032137) (xy 400.167525 -85.061191) (xy 400.116196 -85.083003) (xy 400.062239 -85.097109)
			(xy 400.006802 -85.103209) (xy 399.951068 -85.101172) (xy 399.896225 -85.091042) (xy 399.843441 -85.073035)
			(xy 399.793841 -85.047534) (xy 399.748483 -85.015083) (xy 399.708334 -84.976374) (xy 399.674248 -84.932231)
			(xy 399.646952 -84.883596) (xy 399.627029 -84.831505) (xy 399.614903 -84.777068) (xy 399.610832 -84.721446)
			(xy 397.544804 -84.721446) (xy 397.557897 -84.741236) (xy 397.581569 -84.791733) (xy 397.597637 -84.84514)
			(xy 397.605757 -84.900316) (xy 397.606266 -84.928202) (xy 397.605757 -84.956088) (xy 397.597637 -85.011264)
			(xy 397.581569 -85.064671) (xy 397.557897 -85.115168) (xy 397.527124 -85.161681) (xy 397.489907 -85.203218)
			(xy 397.447039 -85.238893) (xy 397.399433 -85.267947) (xy 397.348104 -85.289759) (xy 397.294147 -85.303865)
			(xy 397.23871 -85.309965) (xy 397.182976 -85.307928) (xy 397.128133 -85.297798) (xy 397.075349 -85.279791)
			(xy 397.025749 -85.25429) (xy 396.980391 -85.221839) (xy 396.940242 -85.18313) (xy 396.906156 -85.138987)
			(xy 396.87886 -85.090352) (xy 396.858937 -85.038261) (xy 396.846811 -84.983824) (xy 396.84274 -84.928202)
			(xy 393.026392 -84.928202) (xy 393.025883 -84.956088) (xy 393.017763 -85.011264) (xy 393.001695 -85.064671)
			(xy 392.978023 -85.115168) (xy 392.94725 -85.161681) (xy 392.910033 -85.203218) (xy 392.867165 -85.238893)
			(xy 392.819559 -85.267947) (xy 392.76823 -85.289759) (xy 392.714273 -85.303865) (xy 392.658836 -85.309965)
			(xy 392.603102 -85.307928) (xy 392.548259 -85.297798) (xy 392.495475 -85.279791) (xy 392.445875 -85.25429)
			(xy 392.400517 -85.221839) (xy 392.360368 -85.18313) (xy 392.326282 -85.138987) (xy 392.298986 -85.090352)
			(xy 392.279063 -85.038261) (xy 392.266937 -84.983824) (xy 392.262866 -84.928202) (xy 390.357891 -84.928202)
			(xy 390.403517 -85.496654) (xy 394.23162 -85.496654) (xy 394.235691 -85.441032) (xy 394.247817 -85.386595)
			(xy 394.26774 -85.334504) (xy 394.295036 -85.285869) (xy 394.329122 -85.241726) (xy 394.369271 -85.203017)
			(xy 394.414629 -85.170566) (xy 394.464229 -85.145065) (xy 394.517013 -85.127058) (xy 394.571856 -85.116928)
			(xy 394.62759 -85.114891) (xy 394.683027 -85.120991) (xy 394.736984 -85.135097) (xy 394.788313 -85.156909)
			(xy 394.835919 -85.185963) (xy 394.878787 -85.221638) (xy 394.916004 -85.263175) (xy 394.946777 -85.309688)
			(xy 394.970449 -85.360185) (xy 394.986517 -85.413592) (xy 394.994637 -85.468768) (xy 394.995146 -85.496654)
			(xy 394.994637 -85.52454) (xy 394.986517 -85.579716) (xy 394.970449 -85.633123) (xy 394.946777 -85.68362)
			(xy 394.916004 -85.730133) (xy 394.878787 -85.77167) (xy 394.835919 -85.807345) (xy 394.788313 -85.836399)
			(xy 394.736984 -85.858211) (xy 394.683027 -85.872317) (xy 394.62759 -85.878417) (xy 394.571856 -85.87638)
			(xy 394.517013 -85.86625) (xy 394.464229 -85.848243) (xy 394.414629 -85.822742) (xy 394.369271 -85.790291)
			(xy 394.329122 -85.751582) (xy 394.295036 -85.707439) (xy 394.26774 -85.658804) (xy 394.247817 -85.606713)
			(xy 394.235691 -85.552276) (xy 394.23162 -85.496654) (xy 390.403517 -85.496654) (xy 390.428226 -85.804502)
			(xy 390.429824 -85.813714) (xy 390.438684 -85.830159) (xy 390.45286 -85.842324) (xy 390.4615 -85.845904)
			(xy 390.485376 -85.85327) (xy 390.485884 -85.85327) (xy 390.498076 -85.856826) (xy 390.51103 -85.858604)
			(xy 390.526016 -85.858604) (xy 390.537192 -85.857334) (xy 390.548114 -85.853524) (xy 390.552686 -85.851238)
			(xy 390.561576 -85.843872) (xy 390.56564 -85.838792) (xy 390.571228 -85.83168) (xy 390.589458 -85.809907)
			(xy 390.631266 -85.771479) (xy 390.678309 -85.739675) (xy 390.729549 -85.715198) (xy 390.78385 -85.698588)
			(xy 390.840015 -85.690214) (xy 390.868408 -85.689694) (xy 390.868662 -85.689694) (xy 390.895916 -85.690155)
			(xy 390.949871 -85.697907) (xy 391.002173 -85.71326) (xy 391.051758 -85.7359) (xy 391.097616 -85.765367)
			(xy 391.138813 -85.80106) (xy 391.17451 -85.842254) (xy 391.203982 -85.888109) (xy 391.223336 -85.930486)
			(xy 400.536662 -85.930486) (xy 400.540733 -85.874864) (xy 400.552859 -85.820427) (xy 400.572782 -85.768336)
			(xy 400.600078 -85.719701) (xy 400.634164 -85.675558) (xy 400.674313 -85.636849) (xy 400.719671 -85.604398)
			(xy 400.769271 -85.578897) (xy 400.822055 -85.56089) (xy 400.876898 -85.55076) (xy 400.932632 -85.548723)
			(xy 400.988069 -85.554823) (xy 401.042026 -85.568929) (xy 401.093355 -85.590741) (xy 401.140961 -85.619795)
			(xy 401.183829 -85.65547) (xy 401.214494 -85.689694) (xy 404.765508 -85.689694) (xy 404.769579 -85.634072)
			(xy 404.781705 -85.579635) (xy 404.801628 -85.527544) (xy 404.828924 -85.478909) (xy 404.86301 -85.434766)
			(xy 404.903159 -85.396057) (xy 404.948517 -85.363606) (xy 404.998117 -85.338105) (xy 405.050901 -85.320098)
			(xy 405.105744 -85.309968) (xy 405.161478 -85.307931) (xy 405.216915 -85.314031) (xy 405.270872 -85.328137)
			(xy 405.322201 -85.349949) (xy 405.369807 -85.379003) (xy 405.412675 -85.414678) (xy 405.449892 -85.456215)
			(xy 405.480665 -85.502728) (xy 405.504337 -85.553225) (xy 405.520405 -85.606632) (xy 405.528525 -85.661808)
			(xy 405.529034 -85.689694) (xy 405.528525 -85.71758) (xy 405.520405 -85.772756) (xy 405.504337 -85.826163)
			(xy 405.480665 -85.87666) (xy 405.449892 -85.923173) (xy 405.412675 -85.96471) (xy 405.369807 -86.000385)
			(xy 405.322201 -86.029439) (xy 405.270872 -86.051251) (xy 405.216915 -86.065357) (xy 405.161478 -86.071457)
			(xy 405.105744 -86.06942) (xy 405.050901 -86.05929) (xy 404.998117 -86.041283) (xy 404.948517 -86.015782)
			(xy 404.903159 -85.983331) (xy 404.86301 -85.944622) (xy 404.828924 -85.900479) (xy 404.801628 -85.851844)
			(xy 404.781705 -85.799753) (xy 404.769579 -85.745316) (xy 404.765508 -85.689694) (xy 401.214494 -85.689694)
			(xy 401.221046 -85.697007) (xy 401.251819 -85.74352) (xy 401.275491 -85.794017) (xy 401.291559 -85.847424)
			(xy 401.299679 -85.9026) (xy 401.300188 -85.930486) (xy 401.299679 -85.958372) (xy 401.291559 -86.013548)
			(xy 401.275491 -86.066955) (xy 401.251819 -86.117452) (xy 401.221046 -86.163965) (xy 401.183829 -86.205502)
			(xy 401.140961 -86.241177) (xy 401.093355 -86.270231) (xy 401.042026 -86.292043) (xy 400.988069 -86.306149)
			(xy 400.932632 -86.312249) (xy 400.876898 -86.310212) (xy 400.822055 -86.300082) (xy 400.769271 -86.282075)
			(xy 400.719671 -86.256574) (xy 400.674313 -86.224123) (xy 400.634164 -86.185414) (xy 400.600078 -86.141271)
			(xy 400.572782 -86.092636) (xy 400.552859 -86.040545) (xy 400.540733 -85.986108) (xy 400.536662 -85.930486)
			(xy 391.223336 -85.930486) (xy 391.226627 -85.937691) (xy 391.241985 -85.989992) (xy 391.249743 -86.043946)
			(xy 391.249743 -86.098454) (xy 391.241985 -86.152408) (xy 391.226627 -86.204709) (xy 391.203982 -86.254291)
			(xy 391.17451 -86.300146) (xy 391.138813 -86.34134) (xy 391.097616 -86.377033) (xy 391.051758 -86.4065)
			(xy 391.002173 -86.42914) (xy 390.949871 -86.444493) (xy 390.895916 -86.452245) (xy 390.868662 -86.45271)
			(xy 390.868408 -86.45271) (xy 390.840004 -86.452171) (xy 390.783828 -86.443708) (xy 390.729532 -86.426997)
			(xy 390.678319 -86.40241) (xy 390.631325 -86.370491) (xy 390.61009 -86.351618) (xy 390.609836 -86.351364)
			(xy 390.604502 -86.346538) (xy 390.599676 -86.341712) (xy 390.585706 -86.334346) (xy 390.577832 -86.333076)
			(xy 390.570137 -86.332031) (xy 390.554752 -86.3341) (xy 390.547606 -86.33714) (xy 390.521698 -86.349332)
			(xy 390.52119 -86.34984) (xy 390.504172 -86.35746) (xy 390.499346 -86.360254) (xy 390.49198 -86.365572)
			(xy 390.481243 -86.380212) (xy 390.476207 -86.397655) (xy 390.476486 -86.406736) (xy 390.509157 -86.813898)
			(xy 400.57908 -86.813898) (xy 400.583151 -86.758276) (xy 400.595277 -86.703839) (xy 400.6152 -86.651748)
			(xy 400.642496 -86.603113) (xy 400.676582 -86.55897) (xy 400.716731 -86.520261) (xy 400.762089 -86.48781)
			(xy 400.811689 -86.462309) (xy 400.864473 -86.444302) (xy 400.919316 -86.434172) (xy 400.97505 -86.432135)
			(xy 401.030487 -86.438235) (xy 401.084444 -86.452341) (xy 401.135773 -86.474153) (xy 401.183379 -86.503207)
			(xy 401.226247 -86.538882) (xy 401.263464 -86.580419) (xy 401.294237 -86.626932) (xy 401.317909 -86.677429)
			(xy 401.333977 -86.730836) (xy 401.342097 -86.786012) (xy 401.342606 -86.813898) (xy 401.342097 -86.841784)
			(xy 401.333977 -86.89696) (xy 401.317909 -86.950367) (xy 401.294237 -87.000864) (xy 401.270725 -87.036402)
			(xy 404.775668 -87.036402) (xy 404.779739 -86.98078) (xy 404.791865 -86.926343) (xy 404.811788 -86.874252)
			(xy 404.839084 -86.825617) (xy 404.87317 -86.781474) (xy 404.913319 -86.742765) (xy 404.958677 -86.710314)
			(xy 405.008277 -86.684813) (xy 405.061061 -86.666806) (xy 405.115904 -86.656676) (xy 405.171638 -86.654639)
			(xy 405.227075 -86.660739) (xy 405.281032 -86.674845) (xy 405.332361 -86.696657) (xy 405.379967 -86.725711)
			(xy 405.422835 -86.761386) (xy 405.460052 -86.802923) (xy 405.490825 -86.849436) (xy 405.514497 -86.899933)
			(xy 405.530565 -86.95334) (xy 405.538685 -87.008516) (xy 405.539194 -87.036402) (xy 405.538685 -87.064288)
			(xy 405.530565 -87.119464) (xy 405.514497 -87.172871) (xy 405.490825 -87.223368) (xy 405.460052 -87.269881)
			(xy 405.422835 -87.311418) (xy 405.379967 -87.347093) (xy 405.332361 -87.376147) (xy 405.281032 -87.397959)
			(xy 405.227075 -87.412065) (xy 405.171638 -87.418165) (xy 405.115904 -87.416128) (xy 405.061061 -87.405998)
			(xy 405.008277 -87.387991) (xy 404.958677 -87.36249) (xy 404.913319 -87.330039) (xy 404.87317 -87.29133)
			(xy 404.839084 -87.247187) (xy 404.811788 -87.198552) (xy 404.791865 -87.146461) (xy 404.779739 -87.092024)
			(xy 404.775668 -87.036402) (xy 401.270725 -87.036402) (xy 401.263464 -87.047377) (xy 401.226247 -87.088914)
			(xy 401.183379 -87.124589) (xy 401.135773 -87.153643) (xy 401.084444 -87.175455) (xy 401.030487 -87.189561)
			(xy 400.97505 -87.195661) (xy 400.919316 -87.193624) (xy 400.864473 -87.183494) (xy 400.811689 -87.165487)
			(xy 400.762089 -87.139986) (xy 400.716731 -87.107535) (xy 400.676582 -87.068826) (xy 400.642496 -87.024683)
			(xy 400.6152 -86.976048) (xy 400.595277 -86.923957) (xy 400.583151 -86.86952) (xy 400.57908 -86.813898)
			(xy 390.509157 -86.813898) (xy 390.541277 -87.214202) (xy 392.035536 -87.214202) (xy 392.039607 -87.15858)
			(xy 392.051733 -87.104143) (xy 392.071656 -87.052052) (xy 392.098952 -87.003417) (xy 392.133038 -86.959274)
			(xy 392.173187 -86.920565) (xy 392.218545 -86.888114) (xy 392.268145 -86.862613) (xy 392.320929 -86.844606)
			(xy 392.375772 -86.834476) (xy 392.431506 -86.832439) (xy 392.486943 -86.838539) (xy 392.5409 -86.852645)
			(xy 392.592229 -86.874457) (xy 392.639835 -86.903511) (xy 392.682703 -86.939186) (xy 392.71992 -86.980723)
			(xy 392.750693 -87.027236) (xy 392.774365 -87.077733) (xy 392.790433 -87.13114) (xy 392.798553 -87.186316)
			(xy 392.799062 -87.214202) (xy 396.84274 -87.214202) (xy 396.846811 -87.15858) (xy 396.858937 -87.104143)
			(xy 396.87886 -87.052052) (xy 396.906156 -87.003417) (xy 396.940242 -86.959274) (xy 396.980391 -86.920565)
			(xy 397.025749 -86.888114) (xy 397.075349 -86.862613) (xy 397.128133 -86.844606) (xy 397.182976 -86.834476)
			(xy 397.23871 -86.832439) (xy 397.294147 -86.838539) (xy 397.348104 -86.852645) (xy 397.399433 -86.874457)
			(xy 397.447039 -86.903511) (xy 397.489907 -86.939186) (xy 397.527124 -86.980723) (xy 397.557897 -87.027236)
			(xy 397.581569 -87.077733) (xy 397.597637 -87.13114) (xy 397.605757 -87.186316) (xy 397.606266 -87.214202)
			(xy 397.605757 -87.242088) (xy 397.597637 -87.297264) (xy 397.581569 -87.350671) (xy 397.557897 -87.401168)
			(xy 397.534488 -87.436551) (xy 398.811752 -87.436551) (xy 398.811752 -87.382049) (xy 398.819507 -87.328102)
			(xy 398.834861 -87.275808) (xy 398.8575 -87.226231) (xy 398.886964 -87.180379) (xy 398.922652 -87.139188)
			(xy 398.963839 -87.103494) (xy 399.009687 -87.074024) (xy 399.059261 -87.051379) (xy 399.111553 -87.036018)
			(xy 399.165499 -87.028255) (xy 399.19275 -87.027766) (xy 399.219314 -87.028244) (xy 399.271928 -87.035605)
			(xy 399.323014 -87.050191) (xy 399.371583 -87.07172) (xy 399.416698 -87.099777) (xy 399.457486 -87.133819)
			(xy 399.493159 -87.173188) (xy 399.508472 -87.194898) (xy 399.516806 -87.206378) (xy 399.53855 -87.224582)
			(xy 399.564463 -87.2361) (xy 399.592546 -87.24004) (xy 399.620629 -87.2361) (xy 399.646542 -87.224582)
			(xy 399.668286 -87.206378) (xy 399.67662 -87.194898) (xy 399.69188 -87.173054) (xy 399.727531 -87.133451)
			(xy 399.768349 -87.099197) (xy 399.813537 -87.070959) (xy 399.862216 -87.049286) (xy 399.913439 -87.034601)
			(xy 399.966207 -87.02719) (xy 399.99285 -87.02675) (xy 400.020102 -87.027294) (xy 400.074053 -87.035044)
			(xy 400.126351 -87.050394) (xy 400.175932 -87.073031) (xy 400.221786 -87.102495) (xy 400.26298 -87.138184)
			(xy 400.298675 -87.179374) (xy 400.328145 -87.225224) (xy 400.350788 -87.274802) (xy 400.366145 -87.327098)
			(xy 400.373903 -87.381048) (xy 400.373903 -87.435552) (xy 400.366145 -87.489502) (xy 400.350788 -87.541798)
			(xy 400.328145 -87.591376) (xy 400.298675 -87.637226) (xy 400.26298 -87.678416) (xy 400.221786 -87.714105)
			(xy 400.175932 -87.743569) (xy 400.126351 -87.766206) (xy 400.074053 -87.781556) (xy 400.020102 -87.789306)
			(xy 399.99285 -87.789766) (xy 399.966287 -87.789274) (xy 399.913673 -87.781914) (xy 399.862589 -87.767329)
			(xy 399.81402 -87.745802) (xy 399.768905 -87.717748) (xy 399.728117 -87.683709) (xy 399.692442 -87.644343)
			(xy 399.677128 -87.622634) (xy 399.668794 -87.611154) (xy 399.64705 -87.59295) (xy 399.621137 -87.581432)
			(xy 399.593054 -87.577492) (xy 399.564971 -87.581432) (xy 399.539058 -87.59295) (xy 399.517314 -87.611154)
			(xy 399.50898 -87.622634) (xy 399.49373 -87.644485) (xy 399.458076 -87.684086) (xy 399.417256 -87.718339)
			(xy 399.372066 -87.746576) (xy 399.323386 -87.768247) (xy 399.272162 -87.782931) (xy 399.219393 -87.790342)
			(xy 399.19275 -87.790782) (xy 399.165499 -87.790345) (xy 399.111553 -87.782582) (xy 399.059261 -87.767221)
			(xy 399.009687 -87.744576) (xy 398.963839 -87.715106) (xy 398.922652 -87.679412) (xy 398.886964 -87.638221)
			(xy 398.8575 -87.592369) (xy 398.834861 -87.542792) (xy 398.819507 -87.490498) (xy 398.811752 -87.436551)
			(xy 397.534488 -87.436551) (xy 397.527124 -87.447681) (xy 397.489907 -87.489218) (xy 397.447039 -87.524893)
			(xy 397.399433 -87.553947) (xy 397.348104 -87.575759) (xy 397.294147 -87.589865) (xy 397.23871 -87.595965)
			(xy 397.182976 -87.593928) (xy 397.128133 -87.583798) (xy 397.075349 -87.565791) (xy 397.025749 -87.54029)
			(xy 396.980391 -87.507839) (xy 396.940242 -87.46913) (xy 396.906156 -87.424987) (xy 396.87886 -87.376352)
			(xy 396.858937 -87.324261) (xy 396.846811 -87.269824) (xy 396.84274 -87.214202) (xy 392.799062 -87.214202)
			(xy 392.798553 -87.242088) (xy 392.790433 -87.297264) (xy 392.774365 -87.350671) (xy 392.750693 -87.401168)
			(xy 392.71992 -87.447681) (xy 392.682703 -87.489218) (xy 392.639835 -87.524893) (xy 392.592229 -87.553947)
			(xy 392.5409 -87.575759) (xy 392.486943 -87.589865) (xy 392.431506 -87.595965) (xy 392.375772 -87.593928)
			(xy 392.320929 -87.583798) (xy 392.268145 -87.565791) (xy 392.218545 -87.54029) (xy 392.173187 -87.507839)
			(xy 392.133038 -87.46913) (xy 392.098952 -87.424987) (xy 392.071656 -87.376352) (xy 392.051733 -87.324261)
			(xy 392.039607 -87.269824) (xy 392.035536 -87.214202) (xy 390.541277 -87.214202) (xy 390.57193 -87.596218)
			(xy 394.29893 -87.596218) (xy 394.303001 -87.540596) (xy 394.315127 -87.486159) (xy 394.33505 -87.434068)
			(xy 394.362346 -87.385433) (xy 394.396432 -87.34129) (xy 394.436581 -87.302581) (xy 394.481939 -87.27013)
			(xy 394.531539 -87.244629) (xy 394.584323 -87.226622) (xy 394.639166 -87.216492) (xy 394.6949 -87.214455)
			(xy 394.750337 -87.220555) (xy 394.804294 -87.234661) (xy 394.855623 -87.256473) (xy 394.903229 -87.285527)
			(xy 394.946097 -87.321202) (xy 394.983314 -87.362739) (xy 395.014087 -87.409252) (xy 395.037759 -87.459749)
			(xy 395.053827 -87.513156) (xy 395.061947 -87.568332) (xy 395.062456 -87.596218) (xy 395.061947 -87.624104)
			(xy 395.053827 -87.67928) (xy 395.037759 -87.732687) (xy 395.014087 -87.783184) (xy 394.983314 -87.829697)
			(xy 394.946097 -87.871234) (xy 394.903229 -87.906909) (xy 394.855623 -87.935963) (xy 394.804294 -87.957775)
			(xy 394.750337 -87.971881) (xy 394.6949 -87.977981) (xy 394.639166 -87.975944) (xy 394.584323 -87.965814)
			(xy 394.531539 -87.947807) (xy 394.481939 -87.922306) (xy 394.436581 -87.889855) (xy 394.396432 -87.851146)
			(xy 394.362346 -87.807003) (xy 394.33505 -87.758368) (xy 394.315127 -87.706277) (xy 394.303001 -87.65184)
			(xy 394.29893 -87.596218) (xy 390.57193 -87.596218) (xy 390.605518 -88.01481) (xy 390.606984 -88.023552)
			(xy 390.61503 -88.039332) (xy 390.627983 -88.051412) (xy 390.635998 -88.055196) (xy 390.639046 -88.056466)
			(xy 390.6393 -88.056466) (xy 390.651238 -88.061546) (xy 390.655302 -88.063578) (xy 390.66597 -88.067896)
			(xy 390.672586 -88.070407) (xy 390.686633 -88.072075) (xy 390.693656 -88.071198) (xy 390.699244 -88.070182)
			(xy 390.709912 -88.066372) (xy 390.71677 -88.063324) (xy 390.725914 -88.058498) (xy 390.728708 -88.05672)
			(xy 390.730994 -88.054942) (xy 390.75107 -88.039982) (xy 390.794392 -88.014882) (xy 390.817354 -88.004904)
			(xy 390.840663 -87.995642) (xy 390.889103 -87.982625) (xy 390.938833 -87.976081) (xy 390.963912 -87.975694)
			(xy 390.964166 -87.975694) (xy 390.99142 -87.976155) (xy 391.045375 -87.983908) (xy 391.097676 -87.999261)
			(xy 391.14726 -88.021901) (xy 391.193118 -88.051368) (xy 391.234314 -88.087062) (xy 391.270011 -88.128255)
			(xy 391.299482 -88.17411) (xy 391.31582 -88.209882) (xy 393.616432 -88.209882) (xy 393.620503 -88.15426)
			(xy 393.632629 -88.099823) (xy 393.652552 -88.047732) (xy 393.679848 -87.999097) (xy 393.713934 -87.954954)
			(xy 393.754083 -87.916245) (xy 393.799441 -87.883794) (xy 393.849041 -87.858293) (xy 393.901825 -87.840286)
			(xy 393.956668 -87.830156) (xy 394.012402 -87.828119) (xy 394.067839 -87.834219) (xy 394.121796 -87.848325)
			(xy 394.173125 -87.870137) (xy 394.220731 -87.899191) (xy 394.263599 -87.934866) (xy 394.300816 -87.976403)
			(xy 394.331589 -88.022916) (xy 394.355261 -88.073413) (xy 394.371329 -88.12682) (xy 394.379449 -88.181996)
			(xy 394.379958 -88.209882) (xy 394.379449 -88.237768) (xy 394.371329 -88.292944) (xy 394.355261 -88.346351)
			(xy 394.331589 -88.396848) (xy 394.300816 -88.443361) (xy 394.263599 -88.484898) (xy 394.220731 -88.520573)
			(xy 394.173125 -88.549627) (xy 394.121796 -88.571439) (xy 394.067839 -88.585545) (xy 394.012402 -88.591645)
			(xy 393.956668 -88.589608) (xy 393.901825 -88.579478) (xy 393.849041 -88.561471) (xy 393.799441 -88.53597)
			(xy 393.754083 -88.503519) (xy 393.713934 -88.46481) (xy 393.679848 -88.420667) (xy 393.652552 -88.372032)
			(xy 393.632629 -88.319941) (xy 393.620503 -88.265504) (xy 393.616432 -88.209882) (xy 391.31582 -88.209882)
			(xy 391.322127 -88.223692) (xy 391.337485 -88.275992) (xy 391.345243 -88.329946) (xy 391.345243 -88.384454)
			(xy 391.337485 -88.438408) (xy 391.322127 -88.490708) (xy 391.299482 -88.54029) (xy 391.270011 -88.586145)
			(xy 391.234314 -88.627338) (xy 391.193118 -88.663032) (xy 391.14726 -88.692499) (xy 391.097676 -88.715139)
			(xy 391.045375 -88.730492) (xy 390.99142 -88.738245) (xy 390.964166 -88.73871) (xy 390.963658 -88.73871)
			(xy 390.932814 -88.738115) (xy 390.871928 -88.728191) (xy 390.81343 -88.708607) (xy 390.785858 -88.694768)
			(xy 390.780524 -88.691974) (xy 390.76249 -88.687402) (xy 390.75741 -88.68664) (xy 390.74344 -88.687148)
			(xy 390.712706 -88.693498) (xy 390.709912 -88.69426) (xy 390.706074 -88.695384) (xy 390.698798 -88.698702)
			(xy 390.695434 -88.700864) (xy 390.690608 -88.70442) (xy 390.6901 -88.704928) (xy 390.689338 -88.705436)
			(xy 390.68883 -88.705944) (xy 390.688322 -88.706198) (xy 390.684766 -88.709246) (xy 390.681718 -88.711532)
			(xy 390.673961 -88.719017) (xy 390.665023 -88.738613) (xy 390.664446 -88.749378) (xy 390.724631 -89.500202)
			(xy 392.158218 -89.500202) (xy 392.162289 -89.44458) (xy 392.174415 -89.390143) (xy 392.194338 -89.338052)
			(xy 392.221634 -89.289417) (xy 392.25572 -89.245274) (xy 392.295869 -89.206565) (xy 392.341227 -89.174114)
			(xy 392.390827 -89.148613) (xy 392.443611 -89.130606) (xy 392.498454 -89.120476) (xy 392.554188 -89.118439)
			(xy 392.609625 -89.124539) (xy 392.663582 -89.138645) (xy 392.714911 -89.160457) (xy 392.762517 -89.189511)
			(xy 392.805385 -89.225186) (xy 392.842602 -89.266723) (xy 392.873375 -89.313236) (xy 392.897047 -89.363733)
			(xy 392.913115 -89.41714) (xy 392.921235 -89.472316) (xy 392.921744 -89.500202) (xy 396.84274 -89.500202)
			(xy 396.846811 -89.44458) (xy 396.858937 -89.390143) (xy 396.87886 -89.338052) (xy 396.906156 -89.289417)
			(xy 396.940242 -89.245274) (xy 396.980391 -89.206565) (xy 397.025749 -89.174114) (xy 397.075349 -89.148613)
			(xy 397.128133 -89.130606) (xy 397.182976 -89.120476) (xy 397.23871 -89.118439) (xy 397.294147 -89.124539)
			(xy 397.348104 -89.138645) (xy 397.374674 -89.149936) (xy 404.612346 -89.149936) (xy 404.616417 -89.094314)
			(xy 404.628543 -89.039877) (xy 404.648466 -88.987786) (xy 404.675762 -88.939151) (xy 404.709848 -88.895008)
			(xy 404.749997 -88.856299) (xy 404.795355 -88.823848) (xy 404.844955 -88.798347) (xy 404.897739 -88.78034)
			(xy 404.952582 -88.77021) (xy 405.008316 -88.768173) (xy 405.063753 -88.774273) (xy 405.11771 -88.788379)
			(xy 405.169039 -88.810191) (xy 405.216645 -88.839245) (xy 405.259513 -88.87492) (xy 405.29673 -88.916457)
			(xy 405.327503 -88.96297) (xy 405.351175 -89.013467) (xy 405.367243 -89.066874) (xy 405.375363 -89.12205)
			(xy 405.375872 -89.149936) (xy 405.37558 -89.165938) (xy 406.561034 -89.165938) (xy 406.565105 -89.110316)
			(xy 406.577231 -89.055879) (xy 406.597154 -89.003788) (xy 406.62445 -88.955153) (xy 406.658536 -88.91101)
			(xy 406.698685 -88.872301) (xy 406.744043 -88.83985) (xy 406.793643 -88.814349) (xy 406.846427 -88.796342)
			(xy 406.90127 -88.786212) (xy 406.957004 -88.784175) (xy 407.012441 -88.790275) (xy 407.066398 -88.804381)
			(xy 407.117727 -88.826193) (xy 407.165333 -88.855247) (xy 407.208201 -88.890922) (xy 407.245418 -88.932459)
			(xy 407.276191 -88.978972) (xy 407.299863 -89.029469) (xy 407.315931 -89.082876) (xy 407.324051 -89.138052)
			(xy 407.32456 -89.165938) (xy 407.324051 -89.193824) (xy 407.315931 -89.249) (xy 407.299863 -89.302407)
			(xy 407.276191 -89.352904) (xy 407.245418 -89.399417) (xy 407.208201 -89.440954) (xy 407.165333 -89.476629)
			(xy 407.117727 -89.505683) (xy 407.066398 -89.527495) (xy 407.012441 -89.541601) (xy 406.957004 -89.547701)
			(xy 406.90127 -89.545664) (xy 406.846427 -89.535534) (xy 406.793643 -89.517527) (xy 406.744043 -89.492026)
			(xy 406.698685 -89.459575) (xy 406.658536 -89.420866) (xy 406.62445 -89.376723) (xy 406.597154 -89.328088)
			(xy 406.577231 -89.275997) (xy 406.565105 -89.22156) (xy 406.561034 -89.165938) (xy 405.37558 -89.165938)
			(xy 405.375363 -89.177822) (xy 405.367243 -89.232998) (xy 405.351175 -89.286405) (xy 405.327503 -89.336902)
			(xy 405.29673 -89.383415) (xy 405.259513 -89.424952) (xy 405.216645 -89.460627) (xy 405.169039 -89.489681)
			(xy 405.11771 -89.511493) (xy 405.063753 -89.525599) (xy 405.008316 -89.531699) (xy 404.952582 -89.529662)
			(xy 404.897739 -89.519532) (xy 404.844955 -89.501525) (xy 404.795355 -89.476024) (xy 404.749997 -89.443573)
			(xy 404.709848 -89.404864) (xy 404.675762 -89.360721) (xy 404.648466 -89.312086) (xy 404.628543 -89.259995)
			(xy 404.616417 -89.205558) (xy 404.612346 -89.149936) (xy 397.374674 -89.149936) (xy 397.399433 -89.160457)
			(xy 397.447039 -89.189511) (xy 397.489907 -89.225186) (xy 397.527124 -89.266723) (xy 397.557897 -89.313236)
			(xy 397.581569 -89.363733) (xy 397.597637 -89.41714) (xy 397.605757 -89.472316) (xy 397.606266 -89.500202)
			(xy 397.605757 -89.528088) (xy 397.597637 -89.583264) (xy 397.581569 -89.636671) (xy 397.557897 -89.687168)
			(xy 397.527124 -89.733681) (xy 397.489907 -89.775218) (xy 397.447039 -89.810893) (xy 397.399433 -89.839947)
			(xy 397.348104 -89.861759) (xy 397.294147 -89.875865) (xy 397.23871 -89.881965) (xy 397.182976 -89.879928)
			(xy 397.128133 -89.869798) (xy 397.075349 -89.851791) (xy 397.025749 -89.82629) (xy 396.980391 -89.793839)
			(xy 396.940242 -89.75513) (xy 396.906156 -89.710987) (xy 396.87886 -89.662352) (xy 396.858937 -89.610261)
			(xy 396.846811 -89.555824) (xy 396.84274 -89.500202) (xy 392.921744 -89.500202) (xy 392.921235 -89.528088)
			(xy 392.913115 -89.583264) (xy 392.897047 -89.636671) (xy 392.873375 -89.687168) (xy 392.842602 -89.733681)
			(xy 392.805385 -89.775218) (xy 392.762517 -89.810893) (xy 392.714911 -89.839947) (xy 392.663582 -89.861759)
			(xy 392.609625 -89.875865) (xy 392.554188 -89.881965) (xy 392.498454 -89.879928) (xy 392.443611 -89.869798)
			(xy 392.390827 -89.851791) (xy 392.341227 -89.82629) (xy 392.295869 -89.793839) (xy 392.25572 -89.75513)
			(xy 392.221634 -89.710987) (xy 392.194338 -89.662352) (xy 392.174415 -89.610261) (xy 392.162289 -89.555824)
			(xy 392.158218 -89.500202) (xy 390.724631 -89.500202) (xy 390.736074 -89.64295) (xy 390.738021 -89.652854)
			(xy 390.748476 -89.670103) (xy 390.764737 -89.682036) (xy 390.774428 -89.68486) (xy 390.774682 -89.68486)
			(xy 390.808075 -89.693674) (xy 390.87121 -89.721652) (xy 390.900158 -89.740486) (xy 390.92157 -89.755596)
			(xy 390.960445 -89.790738) (xy 390.99416 -89.830857) (xy 391.022086 -89.875201) (xy 391.043698 -89.922942)
			(xy 391.058593 -89.973185) (xy 391.066493 -90.024991) (xy 391.067248 -90.077391) (xy 391.064496 -90.103452)
			(xy 391.060759 -90.129763) (xy 391.046951 -90.18108) (xy 391.02617 -90.22999) (xy 390.998814 -90.27555)
			(xy 390.982454 -90.296492) (xy 390.9626 -90.320138) (xy 390.916582 -90.361298) (xy 390.86453 -90.394499)
			(xy 390.836404 -90.407236) (xy 390.832594 -90.409014) (xy 390.801606 -90.45575) (xy 390.801606 -90.45702)
			(xy 391.18348 -95.214948) (xy 395.574279 -95.214948) (xy 395.578234 -95.123111) (xy 395.590069 -95.031954)
			(xy 395.609696 -94.942151) (xy 395.63697 -94.854369) (xy 395.67169 -94.769255) (xy 395.713598 -94.687442)
			(xy 395.762384 -94.609534) (xy 395.817687 -94.536109) (xy 395.879097 -94.467709) (xy 395.946159 -94.404842)
			(xy 396.018378 -94.347972) (xy 396.095218 -94.297521) (xy 396.176111 -94.253862) (xy 396.260457 -94.217319)
			(xy 396.347633 -94.188162) (xy 396.436992 -94.166608) (xy 396.527873 -94.152814) (xy 396.619604 -94.146884)
			(xy 396.711505 -94.148862) (xy 396.802896 -94.158733) (xy 396.8931 -94.176423) (xy 396.981449 -94.201803)
			(xy 397.067289 -94.234683) (xy 397.149985 -94.274821) (xy 397.228925 -94.32192) (xy 397.303523 -94.37563)
			(xy 397.373229 -94.435554) (xy 397.437524 -94.501248) (xy 397.495935 -94.572226) (xy 397.548027 -94.647963)
			(xy 397.593416 -94.727898) (xy 397.631766 -94.811438) (xy 397.662791 -94.897966) (xy 397.686264 -94.986841)
			(xy 397.70201 -95.077405) (xy 397.709912 -95.168987) (xy 397.710406 -95.214948) (xy 397.709912 -95.260909)
			(xy 397.70201 -95.352491) (xy 397.691875 -95.410782) (xy 405.066244 -95.410782) (xy 405.070315 -95.35516)
			(xy 405.082441 -95.300723) (xy 405.102364 -95.248632) (xy 405.12966 -95.199997) (xy 405.163746 -95.155854)
			(xy 405.203895 -95.117145) (xy 405.249253 -95.084694) (xy 405.298853 -95.059193) (xy 405.351637 -95.041186)
			(xy 405.40648 -95.031056) (xy 405.462214 -95.029019) (xy 405.517651 -95.035119) (xy 405.571608 -95.049225)
			(xy 405.622937 -95.071037) (xy 405.670543 -95.100091) (xy 405.713411 -95.135766) (xy 405.750628 -95.177303)
			(xy 405.781401 -95.223816) (xy 405.805073 -95.274313) (xy 405.821141 -95.32772) (xy 405.829261 -95.382896)
			(xy 405.82977 -95.410782) (xy 405.829261 -95.438668) (xy 405.821141 -95.493844) (xy 405.805073 -95.547251)
			(xy 405.781401 -95.597748) (xy 405.750628 -95.644261) (xy 405.713411 -95.685798) (xy 405.670543 -95.721473)
			(xy 405.622937 -95.750527) (xy 405.571608 -95.772339) (xy 405.517651 -95.786445) (xy 405.462214 -95.792545)
			(xy 405.40648 -95.790508) (xy 405.351637 -95.780378) (xy 405.298853 -95.762371) (xy 405.249253 -95.73687)
			(xy 405.203895 -95.704419) (xy 405.163746 -95.66571) (xy 405.12966 -95.621567) (xy 405.102364 -95.572932)
			(xy 405.082441 -95.520841) (xy 405.070315 -95.466404) (xy 405.066244 -95.410782) (xy 397.691875 -95.410782)
			(xy 397.686264 -95.443055) (xy 397.662791 -95.53193) (xy 397.631766 -95.618458) (xy 397.593416 -95.701998)
			(xy 397.548027 -95.781933) (xy 397.495935 -95.85767) (xy 397.437524 -95.928648) (xy 397.373229 -95.994342)
			(xy 397.303523 -96.054266) (xy 397.228925 -96.107976) (xy 397.149985 -96.155075) (xy 397.067289 -96.195213)
			(xy 396.981449 -96.228093) (xy 396.8931 -96.253473) (xy 396.802896 -96.271163) (xy 396.711505 -96.281034)
			(xy 396.619604 -96.283012) (xy 396.527873 -96.277082) (xy 396.436992 -96.263288) (xy 396.347633 -96.241734)
			(xy 396.260457 -96.212577) (xy 396.176111 -96.176034) (xy 396.095218 -96.132375) (xy 396.018378 -96.081924)
			(xy 395.946159 -96.025054) (xy 395.879097 -95.962187) (xy 395.817687 -95.893787) (xy 395.762384 -95.820362)
			(xy 395.713598 -95.742454) (xy 395.67169 -95.660641) (xy 395.63697 -95.575527) (xy 395.609696 -95.487745)
			(xy 395.590069 -95.397942) (xy 395.578234 -95.306785) (xy 395.574279 -95.214948) (xy 391.18348 -95.214948)
			(xy 391.283332 -96.45904) (xy 405.137618 -96.45904) (xy 405.141689 -96.403418) (xy 405.153815 -96.348981)
			(xy 405.173738 -96.29689) (xy 405.201034 -96.248255) (xy 405.23512 -96.204112) (xy 405.275269 -96.165403)
			(xy 405.320627 -96.132952) (xy 405.370227 -96.107451) (xy 405.423011 -96.089444) (xy 405.477854 -96.079314)
			(xy 405.533588 -96.077277) (xy 405.589025 -96.083377) (xy 405.642982 -96.097483) (xy 405.694311 -96.119295)
			(xy 405.741917 -96.148349) (xy 405.784785 -96.184024) (xy 405.822002 -96.225561) (xy 405.852775 -96.272074)
			(xy 405.876447 -96.322571) (xy 405.892515 -96.375978) (xy 405.900635 -96.431154) (xy 405.901144 -96.45904)
			(xy 405.900635 -96.486926) (xy 405.892515 -96.542102) (xy 405.876447 -96.595509) (xy 405.852775 -96.646006)
			(xy 405.822002 -96.692519) (xy 405.784785 -96.734056) (xy 405.741917 -96.769731) (xy 405.694311 -96.798785)
			(xy 405.642982 -96.820597) (xy 405.589025 -96.834703) (xy 405.533588 -96.840803) (xy 405.477854 -96.838766)
			(xy 405.423011 -96.828636) (xy 405.370227 -96.810629) (xy 405.320627 -96.785128) (xy 405.275269 -96.752677)
			(xy 405.23512 -96.713968) (xy 405.201034 -96.669825) (xy 405.173738 -96.62119) (xy 405.153815 -96.569099)
			(xy 405.141689 -96.514662) (xy 405.137618 -96.45904) (xy 391.283332 -96.45904) (xy 391.331219 -97.055686)
			(xy 399.905472 -97.055686) (xy 399.909543 -97.000064) (xy 399.921669 -96.945627) (xy 399.941592 -96.893536)
			(xy 399.968888 -96.844901) (xy 400.002974 -96.800758) (xy 400.043123 -96.762049) (xy 400.088481 -96.729598)
			(xy 400.138081 -96.704097) (xy 400.190865 -96.68609) (xy 400.245708 -96.67596) (xy 400.301442 -96.673923)
			(xy 400.356879 -96.680023) (xy 400.410836 -96.694129) (xy 400.462165 -96.715941) (xy 400.509771 -96.744995)
			(xy 400.552639 -96.78067) (xy 400.589856 -96.822207) (xy 400.620629 -96.86872) (xy 400.644301 -96.919217)
			(xy 400.660369 -96.972624) (xy 400.668489 -97.0278) (xy 400.668998 -97.055686) (xy 400.668489 -97.083572)
			(xy 400.660369 -97.138748) (xy 400.644301 -97.192155) (xy 400.620629 -97.242652) (xy 400.589856 -97.289165)
			(xy 400.552639 -97.330702) (xy 400.509771 -97.366377) (xy 400.462165 -97.395431) (xy 400.410836 -97.417243)
			(xy 400.356879 -97.431349) (xy 400.301442 -97.437449) (xy 400.245708 -97.435412) (xy 400.190865 -97.425282)
			(xy 400.138081 -97.407275) (xy 400.088481 -97.381774) (xy 400.043123 -97.349323) (xy 400.002974 -97.310614)
			(xy 399.968888 -97.266471) (xy 399.941592 -97.217836) (xy 399.921669 -97.165745) (xy 399.909543 -97.111308)
			(xy 399.905472 -97.055686) (xy 391.331219 -97.055686) (xy 391.581683 -100.17633) (xy 401.939252 -100.17633)
			(xy 401.939252 -99.31273) (xy 401.939742 -99.282762) (xy 401.947565 -99.22334) (xy 401.963078 -99.165447)
			(xy 401.986014 -99.110074) (xy 402.015981 -99.058168) (xy 402.052468 -99.010618) (xy 402.094848 -98.968238)
			(xy 402.142398 -98.931751) (xy 402.194304 -98.901784) (xy 402.249677 -98.878848) (xy 402.30757 -98.863335)
			(xy 402.366992 -98.855512) (xy 402.426928 -98.855512) (xy 402.48635 -98.863335) (xy 402.544243 -98.878848)
			(xy 402.599616 -98.901784) (xy 402.651522 -98.931751) (xy 402.699072 -98.968238) (xy 402.741452 -99.010618)
			(xy 402.777939 -99.058168) (xy 402.807906 -99.110074) (xy 402.830842 -99.165447) (xy 402.846355 -99.22334)
			(xy 402.854178 -99.282762) (xy 402.854668 -99.31273) (xy 402.854668 -100.17633) (xy 402.854178 -100.206298)
			(xy 402.846355 -100.26572) (xy 402.830842 -100.323613) (xy 402.807906 -100.378986) (xy 402.777939 -100.430892)
			(xy 402.741452 -100.478442) (xy 402.699072 -100.520822) (xy 402.651522 -100.557309) (xy 402.599616 -100.587276)
			(xy 402.544243 -100.610212) (xy 402.48635 -100.625725) (xy 402.426928 -100.633548) (xy 402.366992 -100.633548)
			(xy 402.30757 -100.625725) (xy 402.249677 -100.610212) (xy 402.194304 -100.587276) (xy 402.142398 -100.557309)
			(xy 402.094848 -100.520822) (xy 402.052468 -100.478442) (xy 402.015981 -100.430892) (xy 401.986014 -100.378986)
			(xy 401.963078 -100.323613) (xy 401.947565 -100.26572) (xy 401.939742 -100.206298) (xy 401.939252 -100.17633)
			(xy 391.581683 -100.17633) (xy 391.72616 -101.976428) (xy 400.085052 -101.976428) (xy 400.085052 -101.112828)
			(xy 400.085542 -101.08286) (xy 400.093365 -101.023438) (xy 400.108878 -100.965545) (xy 400.131814 -100.910172)
			(xy 400.161781 -100.858266) (xy 400.198268 -100.810716) (xy 400.240648 -100.768336) (xy 400.288198 -100.731849)
			(xy 400.340104 -100.701882) (xy 400.395477 -100.678946) (xy 400.45337 -100.663433) (xy 400.512792 -100.65561)
			(xy 400.572728 -100.65561) (xy 400.63215 -100.663433) (xy 400.690043 -100.678946) (xy 400.745416 -100.701882)
			(xy 400.797322 -100.731849) (xy 400.842313 -100.766372) (xy 405.89784 -100.766372) (xy 405.901911 -100.71075)
			(xy 405.914037 -100.656313) (xy 405.93396 -100.604222) (xy 405.961256 -100.555587) (xy 405.995342 -100.511444)
			(xy 406.035491 -100.472735) (xy 406.080849 -100.440284) (xy 406.130449 -100.414783) (xy 406.183233 -100.396776)
			(xy 406.238076 -100.386646) (xy 406.29381 -100.384609) (xy 406.349247 -100.390709) (xy 406.403204 -100.404815)
			(xy 406.454533 -100.426627) (xy 406.502139 -100.455681) (xy 406.545007 -100.491356) (xy 406.582224 -100.532893)
			(xy 406.612997 -100.579406) (xy 406.636669 -100.629903) (xy 406.652737 -100.68331) (xy 406.660857 -100.738486)
			(xy 406.661366 -100.766372) (xy 406.660857 -100.794258) (xy 406.652737 -100.849434) (xy 406.636669 -100.902841)
			(xy 406.612997 -100.953338) (xy 406.582224 -100.999851) (xy 406.545007 -101.041388) (xy 406.502139 -101.077063)
			(xy 406.454533 -101.106117) (xy 406.403204 -101.127929) (xy 406.349247 -101.142035) (xy 406.29381 -101.148135)
			(xy 406.238076 -101.146098) (xy 406.183233 -101.135968) (xy 406.130449 -101.117961) (xy 406.080849 -101.09246)
			(xy 406.035491 -101.060009) (xy 405.995342 -101.0213) (xy 405.961256 -100.977157) (xy 405.93396 -100.928522)
			(xy 405.914037 -100.876431) (xy 405.901911 -100.821994) (xy 405.89784 -100.766372) (xy 400.842313 -100.766372)
			(xy 400.844872 -100.768336) (xy 400.887252 -100.810716) (xy 400.923739 -100.858266) (xy 400.953706 -100.910172)
			(xy 400.976642 -100.965545) (xy 400.992155 -101.023438) (xy 400.999978 -101.08286) (xy 401.000468 -101.112828)
			(xy 401.000468 -101.976428) (xy 400.999978 -102.006396) (xy 400.992155 -102.065818) (xy 400.976642 -102.123711)
			(xy 400.953706 -102.179084) (xy 400.923739 -102.23099) (xy 400.887252 -102.27854) (xy 400.844872 -102.32092)
			(xy 400.797322 -102.357407) (xy 400.745416 -102.387374) (xy 400.690043 -102.41031) (xy 400.63215 -102.425823)
			(xy 400.572728 -102.433646) (xy 400.512792 -102.433646) (xy 400.45337 -102.425823) (xy 400.395477 -102.41031)
			(xy 400.340104 -102.387374) (xy 400.288198 -102.357407) (xy 400.240648 -102.32092) (xy 400.198268 -102.27854)
			(xy 400.161781 -102.23099) (xy 400.131814 -102.179084) (xy 400.108878 -102.123711) (xy 400.093365 -102.065818)
			(xy 400.085542 -102.006396) (xy 400.085052 -101.976428) (xy 391.72616 -101.976428) (xy 391.870617 -103.776272)
			(xy 401.939252 -103.776272) (xy 401.939252 -102.912672) (xy 401.939742 -102.882704) (xy 401.947565 -102.823282)
			(xy 401.963078 -102.765389) (xy 401.986014 -102.710016) (xy 402.015981 -102.65811) (xy 402.052468 -102.61056)
			(xy 402.094848 -102.56818) (xy 402.142398 -102.531693) (xy 402.194304 -102.501726) (xy 402.249677 -102.47879)
			(xy 402.30757 -102.463277) (xy 402.366992 -102.455454) (xy 402.426928 -102.455454) (xy 402.48635 -102.463277)
			(xy 402.544243 -102.47879) (xy 402.599616 -102.501726) (xy 402.651522 -102.531693) (xy 402.699072 -102.56818)
			(xy 402.741452 -102.61056) (xy 402.777939 -102.65811) (xy 402.807906 -102.710016) (xy 402.830842 -102.765389)
			(xy 402.846355 -102.823282) (xy 402.854178 -102.882704) (xy 402.854668 -102.912672) (xy 402.854668 -103.776272)
			(xy 402.854178 -103.80624) (xy 402.846355 -103.865662) (xy 402.830842 -103.923555) (xy 402.807906 -103.978928)
			(xy 402.777939 -104.030834) (xy 402.741452 -104.078384) (xy 402.699072 -104.120764) (xy 402.651522 -104.157251)
			(xy 402.599616 -104.187218) (xy 402.544243 -104.210154) (xy 402.48635 -104.225667) (xy 402.426928 -104.23349)
			(xy 402.366992 -104.23349) (xy 402.30757 -104.225667) (xy 402.249677 -104.210154) (xy 402.194304 -104.187218)
			(xy 402.142398 -104.157251) (xy 402.094848 -104.120764) (xy 402.052468 -104.078384) (xy 402.015981 -104.030834)
			(xy 401.986014 -103.978928) (xy 401.963078 -103.923555) (xy 401.947565 -103.865662) (xy 401.939742 -103.80624)
			(xy 401.939252 -103.776272) (xy 391.870617 -103.776272) (xy 391.906252 -104.220264) (xy 391.909046 -104.269794)
			(xy 391.948659 -105.57637) (xy 400.085052 -105.57637) (xy 400.085052 -104.71277) (xy 400.085542 -104.682802)
			(xy 400.093365 -104.62338) (xy 400.108878 -104.565487) (xy 400.131814 -104.510114) (xy 400.161781 -104.458208)
			(xy 400.198268 -104.410658) (xy 400.240648 -104.368278) (xy 400.288198 -104.331791) (xy 400.340104 -104.301824)
			(xy 400.395477 -104.278888) (xy 400.45337 -104.263375) (xy 400.512792 -104.255552) (xy 400.572728 -104.255552)
			(xy 400.63215 -104.263375) (xy 400.690043 -104.278888) (xy 400.745416 -104.301824) (xy 400.797322 -104.331791)
			(xy 400.844872 -104.368278) (xy 400.887252 -104.410658) (xy 400.923739 -104.458208) (xy 400.953706 -104.510114)
			(xy 400.976642 -104.565487) (xy 400.992155 -104.62338) (xy 400.999978 -104.682802) (xy 401.000468 -104.71277)
			(xy 401.000468 -105.57637) (xy 400.999978 -105.606338) (xy 400.992155 -105.66576) (xy 400.976642 -105.723653)
			(xy 400.953706 -105.779026) (xy 400.923739 -105.830932) (xy 400.887252 -105.878482) (xy 400.844872 -105.920862)
			(xy 400.797322 -105.957349) (xy 400.745416 -105.987316) (xy 400.690043 -106.010252) (xy 400.63215 -106.025765)
			(xy 400.572728 -106.033588) (xy 400.512792 -106.033588) (xy 400.45337 -106.025765) (xy 400.395477 -106.010252)
			(xy 400.340104 -105.987316) (xy 400.288198 -105.957349) (xy 400.240648 -105.920862) (xy 400.198268 -105.878482)
			(xy 400.161781 -105.830932) (xy 400.131814 -105.779026) (xy 400.108878 -105.723653) (xy 400.093365 -105.66576)
			(xy 400.085542 -105.606338) (xy 400.085052 -105.57637) (xy 391.948659 -105.57637) (xy 392.003227 -107.376214)
			(xy 401.939252 -107.376214) (xy 401.939252 -106.512614) (xy 401.939742 -106.482646) (xy 401.947565 -106.423224)
			(xy 401.963078 -106.365331) (xy 401.986014 -106.309958) (xy 402.015981 -106.258052) (xy 402.052468 -106.210502)
			(xy 402.094848 -106.168122) (xy 402.142398 -106.131635) (xy 402.194304 -106.101668) (xy 402.249677 -106.078732)
			(xy 402.30757 -106.063219) (xy 402.366992 -106.055396) (xy 402.426928 -106.055396) (xy 402.48635 -106.063219)
			(xy 402.544243 -106.078732) (xy 402.599616 -106.101668) (xy 402.651522 -106.131635) (xy 402.699072 -106.168122)
			(xy 402.741452 -106.210502) (xy 402.777939 -106.258052) (xy 402.807906 -106.309958) (xy 402.830842 -106.365331)
			(xy 402.846355 -106.423224) (xy 402.854178 -106.482646) (xy 402.854668 -106.512614) (xy 402.854668 -107.376214)
			(xy 402.854178 -107.406182) (xy 402.846355 -107.465604) (xy 402.830842 -107.523497) (xy 402.807906 -107.57887)
			(xy 402.777939 -107.630776) (xy 402.741452 -107.678326) (xy 402.699072 -107.720706) (xy 402.651522 -107.757193)
			(xy 402.599616 -107.78716) (xy 402.544243 -107.810096) (xy 402.48635 -107.825609) (xy 402.426928 -107.833432)
			(xy 402.366992 -107.833432) (xy 402.30757 -107.825609) (xy 402.249677 -107.810096) (xy 402.194304 -107.78716)
			(xy 402.142398 -107.757193) (xy 402.094848 -107.720706) (xy 402.052468 -107.678326) (xy 402.015981 -107.630776)
			(xy 401.986014 -107.57887) (xy 401.963078 -107.523497) (xy 401.947565 -107.465604) (xy 401.939742 -107.406182)
			(xy 401.939252 -107.376214) (xy 392.003227 -107.376214) (xy 392.057803 -109.176312) (xy 400.085052 -109.176312)
			(xy 400.085052 -108.312712) (xy 400.085542 -108.282744) (xy 400.093365 -108.223322) (xy 400.108878 -108.165429)
			(xy 400.131814 -108.110056) (xy 400.161781 -108.05815) (xy 400.198268 -108.0106) (xy 400.240648 -107.96822)
			(xy 400.288198 -107.931733) (xy 400.340104 -107.901766) (xy 400.395477 -107.87883) (xy 400.45337 -107.863317)
			(xy 400.512792 -107.855494) (xy 400.572728 -107.855494) (xy 400.63215 -107.863317) (xy 400.690043 -107.87883)
			(xy 400.745416 -107.901766) (xy 400.797322 -107.931733) (xy 400.844872 -107.96822) (xy 400.887252 -108.0106)
			(xy 400.923739 -108.05815) (xy 400.953706 -108.110056) (xy 400.976642 -108.165429) (xy 400.992155 -108.223322)
			(xy 400.999978 -108.282744) (xy 401.000468 -108.312712) (xy 401.000468 -109.176312) (xy 400.999978 -109.20628)
			(xy 400.992155 -109.265702) (xy 400.976642 -109.323595) (xy 400.953706 -109.378968) (xy 400.923739 -109.430874)
			(xy 400.887252 -109.478424) (xy 400.844872 -109.520804) (xy 400.797322 -109.557291) (xy 400.745416 -109.587258)
			(xy 400.690043 -109.610194) (xy 400.63215 -109.625707) (xy 400.572728 -109.63353) (xy 400.512792 -109.63353)
			(xy 400.45337 -109.625707) (xy 400.395477 -109.610194) (xy 400.340104 -109.587258) (xy 400.288198 -109.557291)
			(xy 400.240648 -109.520804) (xy 400.198268 -109.478424) (xy 400.161781 -109.430874) (xy 400.131814 -109.378968)
			(xy 400.108878 -109.323595) (xy 400.093365 -109.265702) (xy 400.085542 -109.20628) (xy 400.085052 -109.176312)
			(xy 392.057803 -109.176312) (xy 392.112379 -110.97641) (xy 401.939252 -110.97641) (xy 401.939252 -110.11281)
			(xy 401.939742 -110.082842) (xy 401.947565 -110.02342) (xy 401.963078 -109.965527) (xy 401.986014 -109.910154)
			(xy 402.015981 -109.858248) (xy 402.052468 -109.810698) (xy 402.094848 -109.768318) (xy 402.142398 -109.731831)
			(xy 402.194304 -109.701864) (xy 402.249677 -109.678928) (xy 402.30757 -109.663415) (xy 402.366992 -109.655592)
			(xy 402.426928 -109.655592) (xy 402.48635 -109.663415) (xy 402.544243 -109.678928) (xy 402.599616 -109.701864)
			(xy 402.651522 -109.731831) (xy 402.699072 -109.768318) (xy 402.741452 -109.810698) (xy 402.777939 -109.858248)
			(xy 402.807906 -109.910154) (xy 402.830842 -109.965527) (xy 402.846355 -110.02342) (xy 402.854178 -110.082842)
			(xy 402.854668 -110.11281) (xy 402.854668 -110.97641) (xy 402.854178 -111.006378) (xy 402.846355 -111.0658)
			(xy 402.830842 -111.123693) (xy 402.807906 -111.179066) (xy 402.777939 -111.230972) (xy 402.741452 -111.278522)
			(xy 402.699072 -111.320902) (xy 402.651522 -111.357389) (xy 402.599616 -111.387356) (xy 402.544243 -111.410292)
			(xy 402.48635 -111.425805) (xy 402.426928 -111.433628) (xy 402.366992 -111.433628) (xy 402.30757 -111.425805)
			(xy 402.249677 -111.410292) (xy 402.194304 -111.387356) (xy 402.142398 -111.357389) (xy 402.094848 -111.320902)
			(xy 402.052468 -111.278522) (xy 402.015981 -111.230972) (xy 401.986014 -111.179066) (xy 401.963078 -111.123693)
			(xy 401.947565 -111.0658) (xy 401.939742 -111.006378) (xy 401.939252 -110.97641) (xy 392.112379 -110.97641)
			(xy 392.166954 -112.776508) (xy 400.085052 -112.776508) (xy 400.085052 -111.912908) (xy 400.085542 -111.88294)
			(xy 400.093365 -111.823518) (xy 400.108878 -111.765625) (xy 400.131814 -111.710252) (xy 400.161781 -111.658346)
			(xy 400.198268 -111.610796) (xy 400.240648 -111.568416) (xy 400.288198 -111.531929) (xy 400.340104 -111.501962)
			(xy 400.395477 -111.479026) (xy 400.45337 -111.463513) (xy 400.512792 -111.45569) (xy 400.572728 -111.45569)
			(xy 400.63215 -111.463513) (xy 400.690043 -111.479026) (xy 400.745416 -111.501962) (xy 400.797322 -111.531929)
			(xy 400.844872 -111.568416) (xy 400.887252 -111.610796) (xy 400.923739 -111.658346) (xy 400.953706 -111.710252)
			(xy 400.976642 -111.765625) (xy 400.992155 -111.823518) (xy 400.999978 -111.88294) (xy 401.000468 -111.912908)
			(xy 401.000468 -112.776508) (xy 400.999978 -112.806476) (xy 400.992155 -112.865898) (xy 400.976642 -112.923791)
			(xy 400.953706 -112.979164) (xy 400.923739 -113.03107) (xy 400.887252 -113.07862) (xy 400.844872 -113.121)
			(xy 400.797322 -113.157487) (xy 400.745416 -113.187454) (xy 400.690043 -113.21039) (xy 400.63215 -113.225903)
			(xy 400.572728 -113.233726) (xy 400.512792 -113.233726) (xy 400.45337 -113.225903) (xy 400.395477 -113.21039)
			(xy 400.340104 -113.187454) (xy 400.288198 -113.157487) (xy 400.240648 -113.121) (xy 400.198268 -113.07862)
			(xy 400.161781 -113.03107) (xy 400.131814 -112.979164) (xy 400.108878 -112.923791) (xy 400.093365 -112.865898)
			(xy 400.085542 -112.806476) (xy 400.085052 -112.776508) (xy 392.166954 -112.776508) (xy 392.258663 -115.801394)
			(xy 404.147272 -115.801394) (xy 404.151343 -115.745772) (xy 404.163469 -115.691335) (xy 404.183392 -115.639244)
			(xy 404.210688 -115.590609) (xy 404.244774 -115.546466) (xy 404.284923 -115.507757) (xy 404.330281 -115.475306)
			(xy 404.379881 -115.449805) (xy 404.432665 -115.431798) (xy 404.487508 -115.421668) (xy 404.543242 -115.419631)
			(xy 404.598679 -115.425731) (xy 404.652636 -115.439837) (xy 404.703965 -115.461649) (xy 404.751571 -115.490703)
			(xy 404.794439 -115.526378) (xy 404.831656 -115.567915) (xy 404.862429 -115.614428) (xy 404.886101 -115.664925)
			(xy 404.902169 -115.718332) (xy 404.910289 -115.773508) (xy 404.910798 -115.801394) (xy 404.910289 -115.82928)
			(xy 404.902169 -115.884456) (xy 404.886101 -115.937863) (xy 404.862429 -115.98836) (xy 404.831656 -116.034873)
			(xy 404.794439 -116.07641) (xy 404.751571 -116.112085) (xy 404.703965 -116.141139) (xy 404.652636 -116.162951)
			(xy 404.598679 -116.177057) (xy 404.543242 -116.183157) (xy 404.487508 -116.18112) (xy 404.432665 -116.17099)
			(xy 404.379881 -116.152983) (xy 404.330281 -116.127482) (xy 404.284923 -116.095031) (xy 404.244774 -116.056322)
			(xy 404.210688 -116.012179) (xy 404.183392 -115.963544) (xy 404.163469 -115.911453) (xy 404.151343 -115.857016)
			(xy 404.147272 -115.801394) (xy 392.258663 -115.801394) (xy 392.331212 -118.194328) (xy 403.844504 -118.194328)
			(xy 403.848575 -118.138706) (xy 403.860701 -118.084269) (xy 403.880624 -118.032178) (xy 403.90792 -117.983543)
			(xy 403.942006 -117.9394) (xy 403.982155 -117.900691) (xy 404.027513 -117.86824) (xy 404.077113 -117.842739)
			(xy 404.129897 -117.824732) (xy 404.18474 -117.814602) (xy 404.240474 -117.812565) (xy 404.295911 -117.818665)
			(xy 404.349868 -117.832771) (xy 404.401197 -117.854583) (xy 404.448803 -117.883637) (xy 404.491671 -117.919312)
			(xy 404.528888 -117.960849) (xy 404.559661 -118.007362) (xy 404.583333 -118.057859) (xy 404.599401 -118.111266)
			(xy 404.607521 -118.166442) (xy 404.60803 -118.194328) (xy 404.607521 -118.222214) (xy 404.599401 -118.27739)
			(xy 404.583333 -118.330797) (xy 404.559661 -118.381294) (xy 404.528888 -118.427807) (xy 404.491671 -118.469344)
			(xy 404.448803 -118.505019) (xy 404.401197 -118.534073) (xy 404.349868 -118.555885) (xy 404.295911 -118.569991)
			(xy 404.240474 -118.576091) (xy 404.18474 -118.574054) (xy 404.129897 -118.563924) (xy 404.077113 -118.545917)
			(xy 404.027513 -118.520416) (xy 403.982155 -118.487965) (xy 403.942006 -118.449256) (xy 403.90792 -118.405113)
			(xy 403.880624 -118.356478) (xy 403.860701 -118.304387) (xy 403.848575 -118.24995) (xy 403.844504 -118.194328)
			(xy 392.331212 -118.194328) (xy 392.371834 -119.534178) (xy 392.372088 -119.545608) (xy 392.372088 -119.551196)
			(xy 392.372088 -119.56415) (xy 392.372088 -119.575072) (xy 392.366597 -120.086374) (xy 401.939252 -120.086374)
			(xy 401.939252 -119.222774) (xy 401.939742 -119.192806) (xy 401.947565 -119.133384) (xy 401.963078 -119.075491)
			(xy 401.986014 -119.020118) (xy 402.015981 -118.968212) (xy 402.052468 -118.920662) (xy 402.094848 -118.878282)
			(xy 402.142398 -118.841795) (xy 402.194304 -118.811828) (xy 402.249677 -118.788892) (xy 402.30757 -118.773379)
			(xy 402.366992 -118.765556) (xy 402.426928 -118.765556) (xy 402.48635 -118.773379) (xy 402.544243 -118.788892)
			(xy 402.599616 -118.811828) (xy 402.651522 -118.841795) (xy 402.699072 -118.878282) (xy 402.741452 -118.920662)
			(xy 402.777939 -118.968212) (xy 402.807906 -119.020118) (xy 402.830842 -119.075491) (xy 402.846355 -119.133384)
			(xy 402.854178 -119.192806) (xy 402.854668 -119.222774) (xy 402.854668 -120.086374) (xy 402.854178 -120.116342)
			(xy 402.846355 -120.175764) (xy 402.830842 -120.233657) (xy 402.807906 -120.28903) (xy 402.777939 -120.340936)
			(xy 402.741452 -120.388486) (xy 402.699072 -120.430866) (xy 402.651522 -120.467353) (xy 402.599616 -120.49732)
			(xy 402.544243 -120.520256) (xy 402.48635 -120.535769) (xy 402.426928 -120.543592) (xy 402.366992 -120.543592)
			(xy 402.30757 -120.535769) (xy 402.249677 -120.520256) (xy 402.194304 -120.49732) (xy 402.142398 -120.467353)
			(xy 402.094848 -120.430866) (xy 402.052468 -120.388486) (xy 402.015981 -120.340936) (xy 401.986014 -120.28903)
			(xy 401.963078 -120.233657) (xy 401.947565 -120.175764) (xy 401.939742 -120.116342) (xy 401.939252 -120.086374)
			(xy 392.366597 -120.086374) (xy 392.347264 -121.886472) (xy 400.085052 -121.886472) (xy 400.085052 -121.022872)
			(xy 400.085542 -120.992904) (xy 400.093365 -120.933482) (xy 400.108878 -120.875589) (xy 400.131814 -120.820216)
			(xy 400.161781 -120.76831) (xy 400.198268 -120.72076) (xy 400.240648 -120.67838) (xy 400.288198 -120.641893)
			(xy 400.340104 -120.611926) (xy 400.395477 -120.58899) (xy 400.45337 -120.573477) (xy 400.512792 -120.565654)
			(xy 400.572728 -120.565654) (xy 400.63215 -120.573477) (xy 400.690043 -120.58899) (xy 400.745416 -120.611926)
			(xy 400.797322 -120.641893) (xy 400.844872 -120.67838) (xy 400.887252 -120.72076) (xy 400.923739 -120.76831)
			(xy 400.953706 -120.820216) (xy 400.976642 -120.875589) (xy 400.992155 -120.933482) (xy 400.999978 -120.992904)
			(xy 401.000468 -121.022872) (xy 401.000468 -121.886472) (xy 400.999978 -121.91644) (xy 400.992155 -121.975862)
			(xy 400.976642 -122.033755) (xy 400.953706 -122.089128) (xy 400.923739 -122.141034) (xy 400.887252 -122.188584)
			(xy 400.844872 -122.230964) (xy 400.797322 -122.267451) (xy 400.745416 -122.297418) (xy 400.690043 -122.320354)
			(xy 400.63215 -122.335867) (xy 400.572728 -122.34369) (xy 400.512792 -122.34369) (xy 400.45337 -122.335867)
			(xy 400.395477 -122.320354) (xy 400.340104 -122.297418) (xy 400.288198 -122.267451) (xy 400.240648 -122.230964)
			(xy 400.198268 -122.188584) (xy 400.161781 -122.141034) (xy 400.131814 -122.089128) (xy 400.108878 -122.033755)
			(xy 400.093365 -121.975862) (xy 400.085542 -121.91644) (xy 400.085052 -121.886472) (xy 392.347264 -121.886472)
			(xy 392.327934 -123.686316) (xy 401.939252 -123.686316) (xy 401.939252 -122.822716) (xy 401.939742 -122.792748)
			(xy 401.947565 -122.733326) (xy 401.963078 -122.675433) (xy 401.986014 -122.62006) (xy 402.015981 -122.568154)
			(xy 402.052468 -122.520604) (xy 402.094848 -122.478224) (xy 402.142398 -122.441737) (xy 402.194304 -122.41177)
			(xy 402.249677 -122.388834) (xy 402.30757 -122.373321) (xy 402.366992 -122.365498) (xy 402.426928 -122.365498)
			(xy 402.48635 -122.373321) (xy 402.544243 -122.388834) (xy 402.599616 -122.41177) (xy 402.651522 -122.441737)
			(xy 402.699072 -122.478224) (xy 402.741452 -122.520604) (xy 402.777939 -122.568154) (xy 402.807906 -122.62006)
			(xy 402.830842 -122.675433) (xy 402.846355 -122.733326) (xy 402.854178 -122.792748) (xy 402.854668 -122.822716)
			(xy 402.854668 -123.686316) (xy 402.854178 -123.716284) (xy 402.846355 -123.775706) (xy 402.830842 -123.833599)
			(xy 402.807906 -123.888972) (xy 402.777939 -123.940878) (xy 402.741452 -123.988428) (xy 402.699072 -124.030808)
			(xy 402.651522 -124.067295) (xy 402.599616 -124.097262) (xy 402.544243 -124.120198) (xy 402.48635 -124.135711)
			(xy 402.426928 -124.143534) (xy 402.366992 -124.143534) (xy 402.30757 -124.135711) (xy 402.249677 -124.120198)
			(xy 402.194304 -124.097262) (xy 402.142398 -124.067295) (xy 402.094848 -124.030808) (xy 402.052468 -123.988428)
			(xy 402.015981 -123.940878) (xy 401.986014 -123.888972) (xy 401.963078 -123.833599) (xy 401.947565 -123.775706)
			(xy 401.939742 -123.716284) (xy 401.939252 -123.686316) (xy 392.327934 -123.686316) (xy 392.319256 -124.49429)
			(xy 392.308553 -125.486414) (xy 400.085052 -125.486414) (xy 400.085052 -124.622814) (xy 400.085542 -124.592846)
			(xy 400.093365 -124.533424) (xy 400.108878 -124.475531) (xy 400.131814 -124.420158) (xy 400.161781 -124.368252)
			(xy 400.198268 -124.320702) (xy 400.240648 -124.278322) (xy 400.288198 -124.241835) (xy 400.340104 -124.211868)
			(xy 400.395477 -124.188932) (xy 400.45337 -124.173419) (xy 400.512792 -124.165596) (xy 400.572728 -124.165596)
			(xy 400.63215 -124.173419) (xy 400.690043 -124.188932) (xy 400.745416 -124.211868) (xy 400.797322 -124.241835)
			(xy 400.844872 -124.278322) (xy 400.887252 -124.320702) (xy 400.923739 -124.368252) (xy 400.953706 -124.420158)
			(xy 400.976642 -124.475531) (xy 400.992155 -124.533424) (xy 400.999978 -124.592846) (xy 401.000468 -124.622814)
			(xy 401.000468 -125.486414) (xy 400.999978 -125.516382) (xy 400.992155 -125.575804) (xy 400.976642 -125.633697)
			(xy 400.953706 -125.68907) (xy 400.923739 -125.740976) (xy 400.887252 -125.788526) (xy 400.844872 -125.830906)
			(xy 400.797322 -125.867393) (xy 400.745416 -125.89736) (xy 400.690043 -125.920296) (xy 400.63215 -125.935809)
			(xy 400.572728 -125.943632) (xy 400.512792 -125.943632) (xy 400.45337 -125.935809) (xy 400.395477 -125.920296)
			(xy 400.340104 -125.89736) (xy 400.288198 -125.867393) (xy 400.240648 -125.830906) (xy 400.198268 -125.788526)
			(xy 400.161781 -125.740976) (xy 400.131814 -125.68907) (xy 400.108878 -125.633697) (xy 400.093365 -125.575804)
			(xy 400.085542 -125.516382) (xy 400.085052 -125.486414) (xy 392.308553 -125.486414) (xy 392.247374 -131.157218)
			(xy 392.245877 -131.29641) (xy 401.939252 -131.29641) (xy 401.939252 -130.43281) (xy 401.939742 -130.402842)
			(xy 401.947565 -130.34342) (xy 401.963078 -130.285527) (xy 401.986014 -130.230154) (xy 402.015981 -130.178248)
			(xy 402.052468 -130.130698) (xy 402.094848 -130.088318) (xy 402.142398 -130.051831) (xy 402.194304 -130.021864)
			(xy 402.249677 -129.998928) (xy 402.30757 -129.983415) (xy 402.366992 -129.975592) (xy 402.426928 -129.975592)
			(xy 402.48635 -129.983415) (xy 402.544243 -129.998928) (xy 402.599616 -130.021864) (xy 402.651522 -130.051831)
			(xy 402.699072 -130.088318) (xy 402.741452 -130.130698) (xy 402.777939 -130.178248) (xy 402.807906 -130.230154)
			(xy 402.830842 -130.285527) (xy 402.846355 -130.34342) (xy 402.854178 -130.402842) (xy 402.854668 -130.43281)
			(xy 402.854668 -131.29641) (xy 402.854178 -131.326378) (xy 402.846355 -131.3858) (xy 402.830842 -131.443693)
			(xy 402.807906 -131.499066) (xy 402.777939 -131.550972) (xy 402.741452 -131.598522) (xy 402.699072 -131.640902)
			(xy 402.651522 -131.677389) (xy 402.599616 -131.707356) (xy 402.544243 -131.730292) (xy 402.48635 -131.745805)
			(xy 402.426928 -131.753628) (xy 402.366992 -131.753628) (xy 402.30757 -131.745805) (xy 402.249677 -131.730292)
			(xy 402.194304 -131.707356) (xy 402.142398 -131.677389) (xy 402.094848 -131.640902) (xy 402.052468 -131.598522)
			(xy 402.015981 -131.550972) (xy 401.986014 -131.499066) (xy 401.963078 -131.443693) (xy 401.947565 -131.3858)
			(xy 401.939742 -131.326378) (xy 401.939252 -131.29641) (xy 392.245877 -131.29641) (xy 392.226515 -133.096508)
			(xy 400.085052 -133.096508) (xy 400.085052 -132.232908) (xy 400.085542 -132.20294) (xy 400.093365 -132.143518)
			(xy 400.108878 -132.085625) (xy 400.131814 -132.030252) (xy 400.161781 -131.978346) (xy 400.198268 -131.930796)
			(xy 400.240648 -131.888416) (xy 400.288198 -131.851929) (xy 400.340104 -131.821962) (xy 400.395477 -131.799026)
			(xy 400.45337 -131.783513) (xy 400.512792 -131.77569) (xy 400.572728 -131.77569) (xy 400.63215 -131.783513)
			(xy 400.690043 -131.799026) (xy 400.745416 -131.821962) (xy 400.797322 -131.851929) (xy 400.844872 -131.888416)
			(xy 400.887252 -131.930796) (xy 400.923739 -131.978346) (xy 400.953706 -132.030252) (xy 400.976642 -132.085625)
			(xy 400.992155 -132.143518) (xy 400.999978 -132.20294) (xy 401.000468 -132.232908) (xy 401.000468 -133.096508)
			(xy 400.999978 -133.126476) (xy 400.992155 -133.185898) (xy 400.976642 -133.243791) (xy 400.953706 -133.299164)
			(xy 400.923739 -133.35107) (xy 400.887252 -133.39862) (xy 400.844872 -133.441) (xy 400.797322 -133.477487)
			(xy 400.745416 -133.507454) (xy 400.690043 -133.53039) (xy 400.63215 -133.545903) (xy 400.572728 -133.553726)
			(xy 400.512792 -133.553726) (xy 400.45337 -133.545903) (xy 400.395477 -133.53039) (xy 400.340104 -133.507454)
			(xy 400.288198 -133.477487) (xy 400.240648 -133.441) (xy 400.198268 -133.39862) (xy 400.161781 -133.35107)
			(xy 400.131814 -133.299164) (xy 400.108878 -133.243791) (xy 400.093365 -133.185898) (xy 400.085542 -133.126476)
			(xy 400.085052 -133.096508) (xy 392.226515 -133.096508) (xy 392.207155 -134.896352) (xy 401.939252 -134.896352)
			(xy 401.939252 -134.032752) (xy 401.939742 -134.002784) (xy 401.947565 -133.943362) (xy 401.963078 -133.885469)
			(xy 401.986014 -133.830096) (xy 402.015981 -133.77819) (xy 402.052468 -133.73064) (xy 402.094848 -133.68826)
			(xy 402.142398 -133.651773) (xy 402.194304 -133.621806) (xy 402.249677 -133.59887) (xy 402.30757 -133.583357)
			(xy 402.366992 -133.575534) (xy 402.426928 -133.575534) (xy 402.48635 -133.583357) (xy 402.544243 -133.59887)
			(xy 402.599616 -133.621806) (xy 402.651522 -133.651773) (xy 402.699072 -133.68826) (xy 402.741452 -133.73064)
			(xy 402.777939 -133.77819) (xy 402.807906 -133.830096) (xy 402.830842 -133.885469) (xy 402.846355 -133.943362)
			(xy 402.854178 -134.002784) (xy 402.854668 -134.032752) (xy 402.854668 -134.896352) (xy 402.854178 -134.92632)
			(xy 402.846355 -134.985742) (xy 402.830842 -135.043635) (xy 402.807906 -135.099008) (xy 402.777939 -135.150914)
			(xy 402.741452 -135.198464) (xy 402.699072 -135.240844) (xy 402.651522 -135.277331) (xy 402.599616 -135.307298)
			(xy 402.544243 -135.330234) (xy 402.48635 -135.345747) (xy 402.426928 -135.35357) (xy 402.366992 -135.35357)
			(xy 402.30757 -135.345747) (xy 402.249677 -135.330234) (xy 402.194304 -135.307298) (xy 402.142398 -135.277331)
			(xy 402.094848 -135.240844) (xy 402.052468 -135.198464) (xy 402.015981 -135.150914) (xy 401.986014 -135.099008)
			(xy 401.963078 -135.043635) (xy 401.947565 -134.985742) (xy 401.939742 -134.92632) (xy 401.939252 -134.896352)
			(xy 392.207155 -134.896352) (xy 392.187793 -136.69645) (xy 400.085052 -136.69645) (xy 400.085052 -135.83285)
			(xy 400.085542 -135.802882) (xy 400.093365 -135.74346) (xy 400.108878 -135.685567) (xy 400.131814 -135.630194)
			(xy 400.161781 -135.578288) (xy 400.198268 -135.530738) (xy 400.240648 -135.488358) (xy 400.288198 -135.451871)
			(xy 400.340104 -135.421904) (xy 400.395477 -135.398968) (xy 400.45337 -135.383455) (xy 400.512792 -135.375632)
			(xy 400.572728 -135.375632) (xy 400.63215 -135.383455) (xy 400.690043 -135.398968) (xy 400.745416 -135.421904)
			(xy 400.797322 -135.451871) (xy 400.844872 -135.488358) (xy 400.887252 -135.530738) (xy 400.923739 -135.578288)
			(xy 400.953706 -135.630194) (xy 400.976642 -135.685567) (xy 400.992155 -135.74346) (xy 400.999978 -135.802882)
			(xy 401.000468 -135.83285) (xy 401.000468 -136.69645) (xy 400.999978 -136.726418) (xy 400.992155 -136.78584)
			(xy 400.976642 -136.843733) (xy 400.953706 -136.899106) (xy 400.923739 -136.951012) (xy 400.887252 -136.998562)
			(xy 400.844872 -137.040942) (xy 400.797322 -137.077429) (xy 400.745416 -137.107396) (xy 400.690043 -137.130332)
			(xy 400.63215 -137.145845) (xy 400.572728 -137.153668) (xy 400.512792 -137.153668) (xy 400.45337 -137.145845)
			(xy 400.395477 -137.130332) (xy 400.340104 -137.107396) (xy 400.288198 -137.077429) (xy 400.240648 -137.040942)
			(xy 400.198268 -136.998562) (xy 400.161781 -136.951012) (xy 400.131814 -136.899106) (xy 400.108878 -136.843733)
			(xy 400.093365 -136.78584) (xy 400.085542 -136.726418) (xy 400.085052 -136.69645) (xy 392.187793 -136.69645)
			(xy 392.181334 -137.296906) (xy 392.181841 -137.308232) (xy 392.191337 -137.328789) (xy 392.199622 -137.33653)
			(xy 392.203291 -137.339458) (xy 392.21147 -137.34406) (xy 392.215878 -137.345674) (xy 392.261344 -137.361168)
			(xy 392.30935 -137.377424) (xy 392.319354 -137.379801) (xy 392.339734 -137.377236) (xy 392.357455 -137.366846)
			(xy 392.36396 -137.358882) (xy 392.380438 -137.337522) (xy 392.417621 -137.298433) (xy 392.438128 -137.280904)
			(xy 392.460568 -137.262903) (xy 392.509119 -137.232043) (xy 392.561151 -137.207503) (xy 392.615846 -137.18967)
			(xy 392.672343 -137.178824) (xy 392.701018 -137.17651) (xy 392.71194 -137.175748) (xy 392.730228 -137.175494)
			(xy 392.730736 -137.175494) (xy 392.760701 -137.175998) (xy 392.820115 -137.183845) (xy 392.877997 -137.199375)
			(xy 392.93336 -137.222322) (xy 392.985257 -137.252293) (xy 393.032802 -137.288777) (xy 393.075182 -137.331151)
			(xy 393.111672 -137.378691) (xy 393.141651 -137.430584) (xy 393.164605 -137.485944) (xy 393.180142 -137.543824)
			(xy 393.187998 -137.603237) (xy 393.188444 -137.633202) (xy 393.188444 -138.497056) (xy 393.187954 -138.52704)
			(xy 393.183073 -138.564112) (xy 394.991334 -138.564112) (xy 394.995405 -138.50849) (xy 395.007531 -138.454053)
			(xy 395.027454 -138.401962) (xy 395.05475 -138.353327) (xy 395.088836 -138.309184) (xy 395.128985 -138.270475)
			(xy 395.174343 -138.238024) (xy 395.223943 -138.212523) (xy 395.276727 -138.194516) (xy 395.33157 -138.184386)
			(xy 395.387304 -138.182349) (xy 395.442741 -138.188449) (xy 395.496698 -138.202555) (xy 395.548027 -138.224367)
			(xy 395.595633 -138.253421) (xy 395.638501 -138.289096) (xy 395.675718 -138.330633) (xy 395.706491 -138.377146)
			(xy 395.730163 -138.427643) (xy 395.746231 -138.48105) (xy 395.754351 -138.536226) (xy 395.75486 -138.564112)
			(xy 395.754351 -138.591998) (xy 395.746231 -138.647174) (xy 395.730163 -138.700581) (xy 395.706491 -138.751078)
			(xy 395.675718 -138.797591) (xy 395.638501 -138.839128) (xy 395.595633 -138.874803) (xy 395.548027 -138.903857)
			(xy 395.496698 -138.925669) (xy 395.442741 -138.939775) (xy 395.387304 -138.945875) (xy 395.33157 -138.943838)
			(xy 395.276727 -138.933708) (xy 395.223943 -138.915701) (xy 395.174343 -138.8902) (xy 395.128985 -138.857749)
			(xy 395.088836 -138.81904) (xy 395.05475 -138.774897) (xy 395.027454 -138.726262) (xy 395.007531 -138.674171)
			(xy 394.995405 -138.619734) (xy 394.991334 -138.564112) (xy 393.183073 -138.564112) (xy 393.180126 -138.586496)
			(xy 393.164605 -138.644421) (xy 393.141656 -138.699825) (xy 393.111672 -138.751759) (xy 393.075166 -138.799335)
			(xy 393.032761 -138.84174) (xy 392.985185 -138.878246) (xy 392.933251 -138.90823) (xy 392.877847 -138.931179)
			(xy 392.819922 -138.9467) (xy 392.760466 -138.954528) (xy 392.700498 -138.954528) (xy 392.641042 -138.9467)
			(xy 392.583117 -138.931179) (xy 392.527713 -138.90823) (xy 392.475779 -138.878246) (xy 392.428203 -138.84174)
			(xy 392.385798 -138.799335) (xy 392.349292 -138.751759) (xy 392.319308 -138.699825) (xy 392.296359 -138.644421)
			(xy 392.280838 -138.586496) (xy 392.27301 -138.52704) (xy 392.27252 -138.497056) (xy 392.27252 -138.284458)
			(xy 392.27252 -138.284204) (xy 392.271988 -138.274266) (xy 392.264324 -138.25592) (xy 392.250262 -138.241864)
			(xy 392.231912 -138.234208) (xy 392.221974 -138.233658) (xy 392.221212 -138.233658) (xy 392.211302 -138.234182)
			(xy 392.192999 -138.241797) (xy 392.178944 -138.255779) (xy 392.171235 -138.274043) (xy 392.170666 -138.28395)
			(xy 392.16838 -138.498326) (xy 392.162284 -139.05611) (xy 392.157204 -139.510516) (xy 392.159236 -139.512294)
			(xy 392.188192 -139.538202) (xy 392.195419 -139.544164) (xy 392.212871 -139.550938) (xy 392.222228 -139.55141)
			(xy 392.227308 -139.55141) (xy 392.229848 -139.551156) (xy 392.240166 -139.550093) (xy 392.260878 -139.548947)
			(xy 392.27125 -139.54887) (xy 392.296796 -139.549282) (xy 392.347432 -139.556104) (xy 392.396705 -139.569619)
			(xy 392.443734 -139.589586) (xy 392.48768 -139.615648) (xy 392.507978 -139.631166) (xy 392.512804 -139.634976)
			(xy 392.5189 -139.638024) (xy 392.530584 -139.641834) (xy 392.54049 -139.64285) (xy 392.56208 -139.64285)
			(xy 392.567521 -139.642988) (xy 392.578156 -139.645288) (xy 392.583162 -139.647422) (xy 392.597132 -139.653772)
			(xy 392.606299 -139.657456) (xy 392.626019 -139.658292) (xy 392.644605 -139.651646) (xy 392.65225 -139.64539)
			(xy 392.662664 -139.636246) (xy 392.683199 -139.619874) (xy 392.727907 -139.592317) (xy 392.775964 -139.571137)
			(xy 392.826468 -139.556732) (xy 392.878468 -139.549372) (xy 392.904726 -139.54887) (xy 392.90625 -139.54887)
			(xy 392.933327 -139.549347) (xy 392.986935 -139.557011) (xy 393.03892 -139.572178) (xy 393.088239 -139.594544)
			(xy 393.1339 -139.623659) (xy 393.174985 -139.658937) (xy 393.210669 -139.699671) (xy 393.240235 -139.745041)
			(xy 393.263088 -139.794136) (xy 393.27877 -139.845968) (xy 393.286966 -139.899498) (xy 393.287758 -139.926568)
			(xy 393.287758 -139.930886) (xy 393.287155 -139.960797) (xy 393.277787 -140.019882) (xy 393.259324 -140.076785)
			(xy 393.232218 -140.130115) (xy 393.215114 -140.15466) (xy 393.208764 -140.163042) (xy 393.204954 -140.167868)
			(xy 393.19962 -140.176504) (xy 393.199112 -140.17752) (xy 393.196648 -140.182845) (xy 393.19395 -140.194261)
			(xy 393.193778 -140.200126) (xy 393.193778 -140.221208) (xy 393.193637 -140.226648) (xy 393.191334 -140.237281)
			(xy 393.189206 -140.24229) (xy 393.182856 -140.25626) (xy 393.179181 -140.265427) (xy 393.178356 -140.285142)
			(xy 393.185001 -140.303721) (xy 393.191238 -140.311378) (xy 393.200382 -140.321792) (xy 393.216815 -140.342409)
			(xy 393.244456 -140.387303) (xy 393.265667 -140.43557) (xy 393.280046 -140.486292) (xy 393.287321 -140.53851)
			(xy 393.287758 -140.56487) (xy 393.287758 -140.565378) (xy 393.287296 -140.592631) (xy 393.279541 -140.646581)
			(xy 393.264187 -140.698879) (xy 393.241545 -140.748459) (xy 393.212077 -140.794311) (xy 393.176382 -140.835502)
			(xy 393.135188 -140.871193) (xy 393.089334 -140.900658) (xy 393.039753 -140.923297) (xy 392.987454 -140.938647)
			(xy 392.933503 -140.946398) (xy 392.90625 -140.946886) (xy 392.880703 -140.946474) (xy 392.830067 -140.939653)
			(xy 392.780793 -140.926139) (xy 392.733762 -140.906175) (xy 392.689814 -140.880116) (xy 392.669522 -140.86459)
			(xy 392.664696 -140.86078) (xy 392.659108 -140.85824) (xy 392.653774 -140.855446) (xy 392.642598 -140.852906)
			(xy 392.61542 -140.852906) (xy 392.609979 -140.852768) (xy 392.599343 -140.850471) (xy 392.594338 -140.848334)
			(xy 392.583162 -140.842746) (xy 392.573897 -140.838828) (xy 392.553833 -140.837691) (xy 392.534856 -140.844302)
			(xy 392.527028 -140.85062) (xy 392.526774 -140.85062) (xy 392.505603 -140.868885) (xy 392.458958 -140.899716)
			(xy 392.408324 -140.923432) (xy 392.354778 -140.939529) (xy 392.29946 -140.947664) (xy 392.271504 -140.948156)
			(xy 392.270996 -140.948156) (xy 392.257102 -140.948024) (xy 392.229388 -140.945992) (xy 392.215624 -140.944092)
			(xy 392.202416 -140.942314) (xy 392.177778 -140.951712) (xy 392.167364 -140.957808) (xy 392.164824 -140.95984)
			(xy 392.163046 -140.961364) (xy 392.152886 -140.97) (xy 392.1506 -140.972032) (xy 392.146282 -140.981176)
			(xy 392.144078 -140.986235) (xy 392.141653 -140.996997) (xy 392.141456 -141.002512) (xy 392.124115 -142.60068)
			(xy 399.905728 -142.60068) (xy 399.906192 -142.573275) (xy 399.914043 -142.519031) (xy 399.92958 -142.466469)
			(xy 399.952483 -142.416674) (xy 399.982281 -142.370671) (xy 399.999962 -142.349728) (xy 400.000216 -142.349474)
			(xy 400.00578 -142.342372) (xy 400.01204 -142.325467) (xy 400.012408 -142.316454) (xy 400.012408 -142.249144)
			(xy 400.012028 -142.240129) (xy 400.005796 -142.223212) (xy 400.000216 -142.216124) (xy 399.999708 -142.215616)
			(xy 399.982064 -142.194688) (xy 399.952353 -142.148714) (xy 399.929518 -142.098966) (xy 399.914028 -142.046464)
			(xy 399.906201 -141.992287) (xy 399.905728 -141.964918) (xy 399.906214 -141.937667) (xy 399.91397 -141.883719)
			(xy 399.929325 -141.831424) (xy 399.951967 -141.781847) (xy 399.981433 -141.735997) (xy 400.017124 -141.694806)
			(xy 400.058315 -141.659115) (xy 400.104165 -141.629649) (xy 400.153742 -141.607007) (xy 400.206037 -141.591652)
			(xy 400.259985 -141.583896) (xy 400.314487 -141.583896) (xy 400.368435 -141.591652) (xy 400.42073 -141.607007)
			(xy 400.470307 -141.629649) (xy 400.516157 -141.659115) (xy 400.557348 -141.694806) (xy 400.593039 -141.735997)
			(xy 400.622505 -141.781847) (xy 400.645147 -141.831424) (xy 400.660502 -141.883719) (xy 400.668258 -141.937667)
			(xy 400.668744 -141.964918) (xy 400.668286 -141.992323) (xy 400.660434 -142.046568) (xy 400.644896 -142.09913)
			(xy 400.621992 -142.148925) (xy 400.592192 -142.194927) (xy 400.57451 -142.21587) (xy 400.574256 -142.216124)
			(xy 400.568648 -142.223196) (xy 400.562415 -142.240124) (xy 400.562064 -142.249144) (xy 400.562064 -142.316454)
			(xy 400.562451 -142.325468) (xy 400.568679 -142.342384) (xy 400.574256 -142.349474) (xy 400.574764 -142.349982)
			(xy 400.592403 -142.370915) (xy 400.622116 -142.416887) (xy 400.644952 -142.466634) (xy 400.660443 -142.519135)
			(xy 400.668271 -142.573311) (xy 400.668744 -142.60068) (xy 400.668258 -142.627931) (xy 400.660502 -142.681879)
			(xy 400.645147 -142.734174) (xy 400.622505 -142.783751) (xy 400.593039 -142.829601) (xy 400.557348 -142.870792)
			(xy 400.516157 -142.906483) (xy 400.470307 -142.935949) (xy 400.42073 -142.958591) (xy 400.368435 -142.973946)
			(xy 400.314487 -142.981702) (xy 400.259985 -142.981702) (xy 400.206037 -142.973946) (xy 400.153742 -142.958591)
			(xy 400.104165 -142.935949) (xy 400.058315 -142.906483) (xy 400.017124 -142.870792) (xy 399.981433 -142.829601)
			(xy 399.951967 -142.783751) (xy 399.929325 -142.734174) (xy 399.91397 -142.681879) (xy 399.906214 -142.627931)
			(xy 399.905728 -142.60068) (xy 392.124115 -142.60068) (xy 392.106912 -144.186148) (xy 392.106658 -144.21231)
			(xy 392.105896 -144.27962) (xy 392.106091 -144.288514) (xy 392.111943 -144.305304) (xy 392.117326 -144.312386)
			(xy 392.167364 -144.367758) (xy 392.17364 -144.373458) (xy 392.188952 -144.380717) (xy 392.197336 -144.381982)
			(xy 392.198098 -144.381982) (xy 392.210036 -144.383252) (xy 392.21029 -144.383252) (xy 392.218997 -144.383897)
			(xy 392.236004 -144.38) (xy 392.243564 -144.375632) (xy 392.302746 -144.33423) (xy 392.309023 -144.329295)
			(xy 392.318359 -144.316352) (xy 392.321034 -144.30883) (xy 392.321796 -144.305274) (xy 392.328813 -144.277743)
			(xy 392.349888 -144.224982) (xy 392.378552 -144.175929) (xy 392.414173 -144.13167) (xy 392.455964 -144.093181)
			(xy 392.502999 -144.061314) (xy 392.55424 -144.036775) (xy 392.608553 -144.020104) (xy 392.664737 -144.011672)
			(xy 392.693144 -144.011142) (xy 392.693398 -144.011142) (xy 392.72511 -144.011798) (xy 392.787656 -144.022327)
			(xy 392.847608 -144.043029) (xy 392.87577 -144.057624) (xy 392.876278 -144.057878) (xy 392.882138 -144.060813)
			(xy 392.89487 -144.063907) (xy 392.901424 -144.063974) (xy 392.91387 -144.06372) (xy 392.954764 -144.03959)
			(xy 392.961285 -144.034838) (xy 392.971252 -144.02216) (xy 392.974322 -144.014698) (xy 392.974322 -143.999204)
			(xy 392.974863 -143.971991) (xy 392.982711 -143.918131) (xy 392.998135 -143.865933) (xy 393.020822 -143.816458)
			(xy 393.05031 -143.77071) (xy 393.086002 -143.729617) (xy 393.127172 -143.694015) (xy 393.172984 -143.664625)
			(xy 393.222508 -143.642046) (xy 393.274739 -143.626735) (xy 393.328616 -143.619003) (xy 393.35583 -143.618458)
			(xy 393.358878 -143.618458) (xy 393.38612 -143.618941) (xy 393.440049 -143.626689) (xy 393.492328 -143.642029)
			(xy 393.541894 -143.66465) (xy 393.587737 -143.694091) (xy 393.628926 -143.729755) (xy 393.664623 -143.770915)
			(xy 393.694102 -143.816734) (xy 393.716763 -143.866281) (xy 393.732145 -143.918547) (xy 393.739936 -143.972471)
			(xy 393.740386 -143.999712) (xy 393.740386 -144.00022) (xy 393.738862 -144.032732) (xy 393.738608 -144.036288)
			(xy 393.738608 -144.03832) (xy 393.738862 -144.041876) (xy 393.740386 -144.075658) (xy 393.740386 -144.076166)
			(xy 393.739935 -144.102887) (xy 393.732479 -144.155806) (xy 393.717721 -144.20717) (xy 393.69595 -144.255976)
			(xy 393.66759 -144.301272) (xy 393.633195 -144.342175) (xy 393.61364 -144.360392) (xy 393.605512 -144.367758)
			(xy 393.601194 -144.37741) (xy 393.597892 -144.384522) (xy 393.59459 -144.411192) (xy 393.594336 -144.412716)
			(xy 393.604242 -144.42821) (xy 393.61854 -144.451372) (xy 393.64114 -144.500888) (xy 393.656472 -144.553114)
			(xy 393.664223 -144.606989) (xy 393.664694 -144.634204) (xy 393.664186 -144.656048) (xy 393.66444 -144.66316)
			(xy 393.665755 -144.674735) (xy 393.667155 -144.697992) (xy 393.667234 -144.709642) (xy 393.667234 -144.710404)
			(xy 393.666745 -144.737825) (xy 393.658943 -144.792108) (xy 393.643498 -144.844729) (xy 393.620724 -144.894618)
			(xy 393.591085 -144.94076) (xy 393.555183 -144.982216) (xy 393.513749 -145.018144) (xy 393.467626 -145.047811)
			(xy 393.417751 -145.070616) (xy 393.365139 -145.086093) (xy 393.31086 -145.093928) (xy 393.28344 -145.094452)
			(xy 393.283186 -145.094452) (xy 393.272684 -145.094318) (xy 393.251717 -145.093048) (xy 393.241276 -145.091912)
			(xy 393.23137 -145.090896) (xy 393.22248 -145.093182) (xy 393.218294 -145.094349) (xy 393.210374 -145.097924)
			(xy 393.206732 -145.100294) (xy 393.160758 -145.134584) (xy 393.152884 -145.140426) (xy 393.138406 -145.163032)
			(xy 393.136882 -145.167096) (xy 393.131802 -145.17878) (xy 393.130786 -145.183606) (xy 393.124048 -145.211467)
			(xy 393.103349 -145.264918) (xy 393.074886 -145.314672) (xy 393.039301 -145.359607) (xy 392.997394 -145.398714)
			(xy 392.950108 -145.431112) (xy 392.898509 -145.456071) (xy 392.843756 -145.473031) (xy 392.787082 -145.481608)
			(xy 392.758422 -145.482056) (xy 392.731415 -145.481582) (xy 392.677943 -145.473956) (xy 392.62608 -145.458867)
			(xy 392.576863 -145.436616) (xy 392.531274 -145.407649) (xy 392.490225 -145.372543) (xy 392.454535 -145.332001)
			(xy 392.424918 -145.286831) (xy 392.412982 -145.2626) (xy 392.409172 -145.254472) (xy 392.390376 -145.235676)
			(xy 392.386898 -145.232386) (xy 392.378976 -145.227011) (xy 392.374628 -145.225008) (xy 392.333226 -145.206974)
			(xy 392.329207 -145.205345) (xy 392.32078 -145.203306) (xy 392.316462 -145.20291) (xy 392.305286 -145.202402)
			(xy 392.299698 -145.204434) (xy 392.29538 -145.205958) (xy 392.278362 -145.2118) (xy 392.269726 -145.214594)
			(xy 392.263122 -145.21942) (xy 392.259751 -145.222076) (xy 392.253882 -145.228337) (xy 392.251438 -145.231866)
			(xy 392.234674 -145.257266) (xy 392.232277 -145.261099) (xy 392.228701 -145.269401) (xy 392.227562 -145.273776)
			(xy 392.22553 -145.281904) (xy 392.226546 -145.29054) (xy 392.228324 -145.329148) (xy 392.2268 -145.362422)
			(xy 392.226546 -145.364962) (xy 392.226546 -145.366994) (xy 392.2268 -145.371058) (xy 392.228324 -145.405348)
			(xy 392.228324 -145.405602) (xy 392.227895 -145.431736) (xy 392.22076 -145.483514) (xy 392.206623 -145.533833)
			(xy 392.18575 -145.581752) (xy 392.15853 -145.626373) (xy 392.125475 -145.66686) (xy 392.106658 -145.685002)
			(xy 392.106404 -145.685256) (xy 392.099489 -145.692379) (xy 392.091245 -145.710417) (xy 392.090402 -145.720308)
			(xy 392.08583 -146.151346) (xy 392.07948 -146.72564) (xy 392.07948 -146.729196) (xy 392.080139 -146.739864)
			(xy 397.006064 -146.739864) (xy 397.006556 -146.704455) (xy 397.015098 -146.634155) (xy 397.032054 -146.565397)
			(xy 397.057176 -146.499185) (xy 397.090097 -146.436484) (xy 397.130337 -146.37821) (xy 397.17731 -146.325213)
			(xy 397.23033 -146.278266) (xy 397.288623 -146.238053) (xy 397.351338 -146.205161) (xy 397.417562 -146.180071)
			(xy 397.486328 -146.163148) (xy 397.556633 -146.154639) (xy 397.592042 -146.15414) (xy 397.624914 -146.154595)
			(xy 397.690245 -146.161938) (xy 397.754345 -146.176548) (xy 397.816405 -146.198243) (xy 397.875647 -146.226749)
			(xy 397.931324 -146.261708) (xy 397.982738 -146.30268) (xy 398.006316 -146.32559) (xy 398.476724 -146.795998)
			(xy 398.843752 -146.795998) (xy 398.847823 -146.740376) (xy 398.859949 -146.685939) (xy 398.879872 -146.633848)
			(xy 398.907168 -146.585213) (xy 398.941254 -146.54107) (xy 398.981403 -146.502361) (xy 399.026761 -146.46991)
			(xy 399.076361 -146.444409) (xy 399.129145 -146.426402) (xy 399.183988 -146.416272) (xy 399.239722 -146.414235)
			(xy 399.295159 -146.420335) (xy 399.349116 -146.434441) (xy 399.400445 -146.456253) (xy 399.448051 -146.485307)
			(xy 399.490919 -146.520982) (xy 399.528136 -146.562519) (xy 399.558909 -146.609032) (xy 399.582581 -146.659529)
			(xy 399.598649 -146.712936) (xy 399.606769 -146.768112) (xy 399.607278 -146.795998) (xy 399.606769 -146.823884)
			(xy 399.598649 -146.87906) (xy 399.582581 -146.932467) (xy 399.558909 -146.982964) (xy 399.528136 -147.029477)
			(xy 399.490919 -147.071014) (xy 399.448051 -147.106689) (xy 399.400445 -147.135743) (xy 399.349116 -147.157555)
			(xy 399.295159 -147.171661) (xy 399.239722 -147.177761) (xy 399.183988 -147.175724) (xy 399.129145 -147.165594)
			(xy 399.076361 -147.147587) (xy 399.026761 -147.122086) (xy 398.981403 -147.089635) (xy 398.941254 -147.050926)
			(xy 398.907168 -147.006783) (xy 398.879872 -146.958148) (xy 398.859949 -146.906057) (xy 398.847823 -146.85162)
			(xy 398.843752 -146.795998) (xy 398.476724 -146.795998) (xy 399.174716 -147.49399) (xy 399.197634 -147.517567)
			(xy 399.23863 -147.568977) (xy 399.273618 -147.624651) (xy 399.302158 -147.683889) (xy 399.323893 -147.745948)
			(xy 399.338548 -147.810049) (xy 399.345942 -147.875387) (xy 399.34642 -147.908264) (xy 399.34642 -149.581362)
			(xy 399.363438 -149.606762) (xy 399.377662 -149.612604) (xy 399.387094 -149.616046) (xy 399.407159 -149.615995)
			(xy 399.42567 -149.608254) (xy 399.433034 -149.601428) (xy 400.972782 -148.06168) (xy 400.979621 -148.054279)
			(xy 400.987342 -148.035681) (xy 400.987768 -148.025612) (xy 400.987768 -141.807184) (xy 400.987359 -141.797113)
			(xy 400.979628 -141.778515) (xy 400.972782 -141.771116) (xy 400.362674 -141.161008) (xy 400.339792 -141.137428)
			(xy 400.298825 -141.086055) (xy 400.263868 -141.030418) (xy 400.23536 -140.971217) (xy 400.213659 -140.909197)
			(xy 400.199039 -140.845136) (xy 400.191684 -140.779842) (xy 400.191224 -140.746988) (xy 400.191224 -140.746734)
			(xy 400.191788 -140.711332) (xy 400.200316 -140.641042) (xy 400.217253 -140.572293) (xy 400.242351 -140.506086)
			(xy 400.275245 -140.443386) (xy 400.315455 -140.385106) (xy 400.362395 -140.332098) (xy 400.415381 -140.285132)
			(xy 400.473641 -140.244893) (xy 400.536325 -140.211969) (xy 400.60252 -140.186838) (xy 400.671261 -140.169868)
			(xy 400.741546 -140.161305) (xy 400.776948 -140.160756) (xy 400.809829 -140.161214) (xy 400.875177 -140.168576)
			(xy 400.939288 -140.183214) (xy 401.001356 -140.204943) (xy 401.060598 -140.233489) (xy 401.116269 -140.268493)
			(xy 401.167668 -140.309514) (xy 401.191222 -140.33246) (xy 401.98802 -141.129258) (xy 402.010924 -141.152849)
			(xy 402.051921 -141.204257) (xy 402.08691 -141.259928) (xy 402.115452 -141.319164) (xy 402.137189 -141.381221)
			(xy 402.151847 -141.445319) (xy 402.159244 -141.510656) (xy 402.159724 -141.543532) (xy 402.159724 -148.289264)
			(xy 402.159282 -148.322145) (xy 402.151918 -148.387494) (xy 402.137278 -148.451606) (xy 402.115547 -148.513674)
			(xy 402.086998 -148.572916) (xy 402.051991 -148.628587) (xy 402.010968 -148.679984) (xy 401.98802 -148.703538)
			(xy 399.826734 -150.864824) (xy 399.819896 -150.872226) (xy 399.812174 -150.890824) (xy 399.811748 -150.900892)
			(xy 399.811748 -151.257) (xy 400.877022 -151.257) (xy 400.881093 -151.201378) (xy 400.893219 -151.146941)
			(xy 400.913142 -151.09485) (xy 400.940438 -151.046215) (xy 400.974524 -151.002072) (xy 401.014673 -150.963363)
			(xy 401.060031 -150.930912) (xy 401.109631 -150.905411) (xy 401.162415 -150.887404) (xy 401.217258 -150.877274)
			(xy 401.272992 -150.875237) (xy 401.328429 -150.881337) (xy 401.382386 -150.895443) (xy 401.433715 -150.917255)
			(xy 401.481321 -150.946309) (xy 401.524189 -150.981984) (xy 401.561406 -151.023521) (xy 401.592179 -151.070034)
			(xy 401.615851 -151.120531) (xy 401.631919 -151.173938) (xy 401.640039 -151.229114) (xy 401.640548 -151.257)
			(xy 401.640039 -151.284886) (xy 401.631919 -151.340062) (xy 401.615851 -151.393469) (xy 401.592179 -151.443966)
			(xy 401.561406 -151.490479) (xy 401.524189 -151.532016) (xy 401.481321 -151.567691) (xy 401.433715 -151.596745)
			(xy 401.382386 -151.618557) (xy 401.328429 -151.632663) (xy 401.272992 -151.638763) (xy 401.217258 -151.636726)
			(xy 401.162415 -151.626596) (xy 401.109631 -151.608589) (xy 401.060031 -151.583088) (xy 401.014673 -151.550637)
			(xy 400.974524 -151.511928) (xy 400.940438 -151.467785) (xy 400.913142 -151.41915) (xy 400.893219 -151.367059)
			(xy 400.881093 -151.312622) (xy 400.877022 -151.257) (xy 399.811748 -151.257) (xy 399.811748 -153.560018)
			(xy 400.750022 -153.560018) (xy 400.754093 -153.504396) (xy 400.766219 -153.449959) (xy 400.786142 -153.397868)
			(xy 400.813438 -153.349233) (xy 400.847524 -153.30509) (xy 400.887673 -153.266381) (xy 400.933031 -153.23393)
			(xy 400.982631 -153.208429) (xy 401.035415 -153.190422) (xy 401.090258 -153.180292) (xy 401.145992 -153.178255)
			(xy 401.201429 -153.184355) (xy 401.255386 -153.198461) (xy 401.306715 -153.220273) (xy 401.354321 -153.249327)
			(xy 401.397189 -153.285002) (xy 401.434406 -153.326539) (xy 401.465179 -153.373052) (xy 401.488851 -153.423549)
			(xy 401.504919 -153.476956) (xy 401.513039 -153.532132) (xy 401.513548 -153.560018) (xy 401.513039 -153.587904)
			(xy 401.504919 -153.64308) (xy 401.488851 -153.696487) (xy 401.465179 -153.746984) (xy 401.434406 -153.793497)
			(xy 401.397189 -153.835034) (xy 401.354321 -153.870709) (xy 401.306715 -153.899763) (xy 401.255386 -153.921575)
			(xy 401.201429 -153.935681) (xy 401.145992 -153.941781) (xy 401.090258 -153.939744) (xy 401.035415 -153.929614)
			(xy 400.982631 -153.911607) (xy 400.933031 -153.886106) (xy 400.887673 -153.853655) (xy 400.847524 -153.814946)
			(xy 400.813438 -153.770803) (xy 400.786142 -153.722168) (xy 400.766219 -153.670077) (xy 400.754093 -153.61564)
			(xy 400.750022 -153.560018) (xy 399.811748 -153.560018) (xy 399.811748 -153.682954) (xy 399.812296 -153.693972)
			(xy 399.821507 -153.71399) (xy 399.829528 -153.721562) (xy 399.896838 -153.778966) (xy 399.91792 -153.785062)
			(xy 399.928842 -153.783284) (xy 399.92935 -153.783284) (xy 399.944172 -153.781051) (xy 399.974052 -153.778633)
			(xy 399.98904 -153.778458) (xy 400.016287 -153.779015) (xy 400.070225 -153.786775) (xy 400.122511 -153.802133)
			(xy 400.172078 -153.824774) (xy 400.21792 -153.854239) (xy 400.259101 -153.889927) (xy 400.294785 -153.931112)
			(xy 400.324245 -153.976957) (xy 400.346881 -154.026527) (xy 400.362233 -154.078814) (xy 400.369988 -154.132753)
			(xy 400.369988 -154.187247) (xy 400.362233 -154.241186) (xy 400.346881 -154.293473) (xy 400.324245 -154.343043)
			(xy 400.294785 -154.388888) (xy 400.259101 -154.430073) (xy 400.21792 -154.465761) (xy 400.172078 -154.495226)
			(xy 400.122511 -154.517867) (xy 400.070225 -154.533225) (xy 400.016287 -154.540985) (xy 399.98904 -154.541474)
			(xy 399.973988 -154.541309) (xy 399.943981 -154.53889) (xy 399.929096 -154.536648) (xy 399.918121 -154.535517)
			(xy 399.896928 -154.54158) (xy 399.888202 -154.548332) (xy 399.829528 -154.59837) (xy 399.821509 -154.605945)
			(xy 399.812291 -154.62596) (xy 399.811748 -154.636978) (xy 399.811748 -154.958288) (xy 401.044154 -154.958288)
			(xy 401.048225 -154.902666) (xy 401.060351 -154.848229) (xy 401.080274 -154.796138) (xy 401.10757 -154.747503)
			(xy 401.141656 -154.70336) (xy 401.181805 -154.664651) (xy 401.227163 -154.6322) (xy 401.276763 -154.606699)
			(xy 401.329547 -154.588692) (xy 401.38439 -154.578562) (xy 401.440124 -154.576525) (xy 401.495561 -154.582625)
			(xy 401.549518 -154.596731) (xy 401.600847 -154.618543) (xy 401.648453 -154.647597) (xy 401.691321 -154.683272)
			(xy 401.728538 -154.724809) (xy 401.759311 -154.771322) (xy 401.782983 -154.821819) (xy 401.799051 -154.875226)
			(xy 401.807171 -154.930402) (xy 401.80768 -154.958288) (xy 401.807171 -154.986174) (xy 401.799051 -155.04135)
			(xy 401.782983 -155.094757) (xy 401.759311 -155.145254) (xy 401.728538 -155.191767) (xy 401.691321 -155.233304)
			(xy 401.648453 -155.268979) (xy 401.600847 -155.298033) (xy 401.549518 -155.319845) (xy 401.495561 -155.333951)
			(xy 401.440124 -155.340051) (xy 401.38439 -155.338014) (xy 401.329547 -155.327884) (xy 401.276763 -155.309877)
			(xy 401.227163 -155.284376) (xy 401.181805 -155.251925) (xy 401.141656 -155.213216) (xy 401.10757 -155.169073)
			(xy 401.080274 -155.120438) (xy 401.060351 -155.068347) (xy 401.048225 -155.01391) (xy 401.044154 -154.958288)
			(xy 399.811748 -154.958288) (xy 399.811748 -155.135072) (xy 399.812366 -155.146919) (xy 399.82296 -155.168111)
			(xy 399.832068 -155.175712) (xy 399.906998 -155.231846) (xy 399.930366 -155.23591) (xy 399.94205 -155.232608)
			(xy 399.968497 -155.225264) (xy 400.022811 -155.217356) (xy 400.050254 -155.21686) (xy 400.077507 -155.217384)
			(xy 400.131458 -155.225135) (xy 400.183757 -155.240486) (xy 400.233339 -155.263124) (xy 400.279194 -155.292588)
			(xy 400.320389 -155.328279) (xy 400.356084 -155.369469) (xy 400.385554 -155.415321) (xy 400.408198 -155.4649)
			(xy 400.423555 -155.517197) (xy 400.431313 -155.571147) (xy 400.431313 -155.625653) (xy 400.423555 -155.679603)
			(xy 400.408198 -155.7319) (xy 400.385554 -155.781479) (xy 400.356084 -155.827331) (xy 400.320389 -155.868521)
			(xy 400.279194 -155.904212) (xy 400.233339 -155.933676) (xy 400.183757 -155.956314) (xy 400.131458 -155.971665)
			(xy 400.077507 -155.979416) (xy 400.050254 -155.979876) (xy 400.022811 -155.97938) (xy 399.968497 -155.971473)
			(xy 399.94205 -155.964128) (xy 399.930502 -155.961423) (xy 399.907195 -155.96565) (xy 399.897346 -155.972256)
			(xy 399.832068 -156.021024) (xy 399.822987 -156.028652) (xy 399.812376 -156.049824) (xy 399.811748 -156.061664)
			(xy 399.811748 -156.544518) (xy 401.027898 -156.544518) (xy 401.031969 -156.488896) (xy 401.044095 -156.434459)
			(xy 401.064018 -156.382368) (xy 401.091314 -156.333733) (xy 401.1254 -156.28959) (xy 401.165549 -156.250881)
			(xy 401.210907 -156.21843) (xy 401.260507 -156.192929) (xy 401.313291 -156.174922) (xy 401.368134 -156.164792)
			(xy 401.423868 -156.162755) (xy 401.479305 -156.168855) (xy 401.533262 -156.182961) (xy 401.584591 -156.204773)
			(xy 401.632197 -156.233827) (xy 401.675065 -156.269502) (xy 401.712282 -156.311039) (xy 401.743055 -156.357552)
			(xy 401.766727 -156.408049) (xy 401.782795 -156.461456) (xy 401.790915 -156.516632) (xy 401.791424 -156.544518)
			(xy 401.790915 -156.572404) (xy 401.782795 -156.62758) (xy 401.766727 -156.680987) (xy 401.743055 -156.731484)
			(xy 401.712282 -156.777997) (xy 401.675065 -156.819534) (xy 401.632197 -156.855209) (xy 401.584591 -156.884263)
			(xy 401.533262 -156.906075) (xy 401.479305 -156.920181) (xy 401.423868 -156.926281) (xy 401.368134 -156.924244)
			(xy 401.313291 -156.914114) (xy 401.260507 -156.896107) (xy 401.210907 -156.870606) (xy 401.165549 -156.838155)
			(xy 401.1254 -156.799446) (xy 401.091314 -156.755303) (xy 401.064018 -156.706668) (xy 401.044095 -156.654577)
			(xy 401.031969 -156.60014) (xy 401.027898 -156.544518) (xy 399.811748 -156.544518) (xy 399.811748 -156.595064)
			(xy 399.812305 -156.605986) (xy 399.821372 -156.62586) (xy 399.829274 -156.633418) (xy 399.895314 -156.690822)
			(xy 399.916142 -156.697172) (xy 399.927064 -156.695648) (xy 399.939954 -156.693987) (xy 399.965884 -156.69221)
			(xy 399.97888 -156.692092) (xy 400.006134 -156.692554) (xy 400.060087 -156.700309) (xy 400.112387 -156.715663)
			(xy 400.16197 -156.738304) (xy 400.207825 -156.767772) (xy 400.24902 -156.803465) (xy 400.284716 -156.844659)
			(xy 400.314186 -156.890513) (xy 400.33683 -156.940094) (xy 400.352187 -156.992394) (xy 400.359945 -157.046346)
			(xy 400.359945 -157.100854) (xy 400.352187 -157.154806) (xy 400.33683 -157.207106) (xy 400.314186 -157.256687)
			(xy 400.284716 -157.302541) (xy 400.24902 -157.343735) (xy 400.207825 -157.379428) (xy 400.16197 -157.408896)
			(xy 400.112387 -157.431537) (xy 400.060087 -157.446891) (xy 400.006134 -157.454646) (xy 399.97888 -157.455108)
			(xy 399.965884 -157.454998) (xy 399.939953 -157.45322) (xy 399.927064 -157.451552) (xy 399.91625 -157.450561)
			(xy 399.895455 -157.456758) (xy 399.886932 -157.46349) (xy 399.829274 -157.513782) (xy 399.82135 -157.521327)
			(xy 399.812266 -157.541207) (xy 399.811748 -157.552136) (xy 399.811748 -159.4104) (xy 399.99742 -159.4104)
			(xy 400.001491 -159.354778) (xy 400.013617 -159.300341) (xy 400.03354 -159.24825) (xy 400.060836 -159.199615)
			(xy 400.094922 -159.155472) (xy 400.135071 -159.116763) (xy 400.180429 -159.084312) (xy 400.230029 -159.058811)
			(xy 400.282813 -159.040804) (xy 400.337656 -159.030674) (xy 400.39339 -159.028637) (xy 400.448827 -159.034737)
			(xy 400.502784 -159.048843) (xy 400.554113 -159.070655) (xy 400.601719 -159.099709) (xy 400.644587 -159.135384)
			(xy 400.681804 -159.176921) (xy 400.712577 -159.223434) (xy 400.736249 -159.273931) (xy 400.752317 -159.327338)
			(xy 400.760437 -159.382514) (xy 400.760946 -159.4104) (xy 400.760437 -159.438286) (xy 400.752317 -159.493462)
			(xy 400.736249 -159.546869) (xy 400.712577 -159.597366) (xy 400.681804 -159.643879) (xy 400.644587 -159.685416)
			(xy 400.601719 -159.721091) (xy 400.554113 -159.750145) (xy 400.502784 -159.771957) (xy 400.448827 -159.786063)
			(xy 400.39339 -159.792163) (xy 400.337656 -159.790126) (xy 400.282813 -159.779996) (xy 400.230029 -159.761989)
			(xy 400.180429 -159.736488) (xy 400.135071 -159.704037) (xy 400.094922 -159.665328) (xy 400.060836 -159.621185)
			(xy 400.03354 -159.57255) (xy 400.013617 -159.520459) (xy 400.001491 -159.466022) (xy 399.99742 -159.4104)
			(xy 399.811748 -159.4104) (xy 399.811748 -160.29432) (xy 399.81215 -160.304392) (xy 399.819886 -160.32299)
			(xy 399.826734 -160.330388) (xy 400.022568 -160.526222) (xy 400.029982 -160.533063) (xy 400.048571 -160.540852)
			(xy 400.068725 -160.540873) (xy 400.078194 -160.537398) (xy 400.179032 -160.495488) (xy 400.19605 -160.470088)
			(xy 400.19605 -160.454594) (xy 400.19664 -160.427358) (xy 400.204418 -160.373443) (xy 400.219787 -160.321183)
			(xy 400.242434 -160.271641) (xy 400.271898 -160.225824) (xy 400.307581 -160.184665) (xy 400.348755 -160.149)
			(xy 400.394585 -160.119555) (xy 400.444137 -160.09693) (xy 400.496403 -160.081583) (xy 400.550322 -160.073828)
			(xy 400.577558 -160.07334) (xy 400.604816 -160.073704) (xy 400.658779 -160.081457) (xy 400.711088 -160.096812)
			(xy 400.76068 -160.119455) (xy 400.806544 -160.148925) (xy 400.847747 -160.184623) (xy 400.88345 -160.225822)
			(xy 400.912925 -160.271683) (xy 400.935574 -160.321272) (xy 400.950934 -160.37358) (xy 400.958693 -160.427542)
			(xy 400.958693 -160.482058) (xy 400.950934 -160.53602) (xy 400.935574 -160.588328) (xy 400.912925 -160.637917)
			(xy 400.88345 -160.683778) (xy 400.847747 -160.724977) (xy 400.806544 -160.760675) (xy 400.76068 -160.790145)
			(xy 400.711088 -160.812788) (xy 400.658779 -160.828143) (xy 400.604816 -160.835896) (xy 400.577558 -160.836356)
			(xy 400.544078 -160.835644) (xy 400.478159 -160.823884) (xy 400.446494 -160.812988) (xy 400.44624 -160.812988)
			(xy 400.437083 -160.810081) (xy 400.417891 -160.81062) (xy 400.400249 -160.818193) (xy 400.393154 -160.824672)
			(xy 400.393154 -160.824926) (xy 400.386474 -160.832388) (xy 400.378837 -160.850875) (xy 400.378828 -160.870878)
			(xy 400.386448 -160.889373) (xy 400.393154 -160.896808) (xy 400.433794 -160.937448) (xy 400.456716 -160.96099)
			(xy 400.497677 -161.012372) (xy 400.532629 -161.068016) (xy 400.561131 -161.127223) (xy 400.582825 -161.189249)
			(xy 400.597438 -161.253314) (xy 400.604788 -161.318613) (xy 400.605244 -161.351468) (xy 400.605244 -164.056314)
			(xy 400.604757 -164.091719) (xy 400.596223 -164.162012) (xy 400.579279 -164.230764) (xy 400.554175 -164.296974)
			(xy 400.521274 -164.359675) (xy 400.481057 -164.417956) (xy 400.43411 -164.470965) (xy 400.381118 -164.51793)
			(xy 400.322852 -164.558167) (xy 400.260162 -164.59109) (xy 400.193961 -164.616218) (xy 400.125215 -164.633185)
			(xy 400.054924 -164.641745) (xy 400.01952 -164.642292) (xy 400.004059 -164.642184) (xy 399.973182 -164.640533)
			(xy 399.957798 -164.63899) (xy 399.946876 -164.63772) (xy 399.926556 -164.644324) (xy 399.86204 -164.701982)
			(xy 399.854516 -164.709596) (xy 399.845848 -164.72914) (xy 399.845276 -164.739828) (xy 399.845276 -164.94252)
			(xy 399.844781 -164.976606) (xy 399.836866 -165.044316) (xy 399.821145 -165.11065) (xy 399.797829 -165.17471)
			(xy 399.767234 -165.23563) (xy 399.729773 -165.292587) (xy 399.685953 -165.344809) (xy 399.636367 -165.391591)
			(xy 399.581685 -165.4323) (xy 399.522647 -165.466386) (xy 399.460051 -165.493387) (xy 399.394744 -165.512939)
			(xy 399.327608 -165.524777) (xy 399.259552 -165.528741) (xy 399.191496 -165.524777) (xy 399.12436 -165.512939)
			(xy 399.059053 -165.493387) (xy 398.996457 -165.466386) (xy 398.937419 -165.4323) (xy 398.882737 -165.391591)
			(xy 398.833151 -165.344809) (xy 398.789331 -165.292587) (xy 398.75187 -165.23563) (xy 398.721275 -165.17471)
			(xy 398.697959 -165.11065) (xy 398.682238 -165.044316) (xy 398.674323 -164.976606) (xy 398.673828 -164.94252)
			(xy 398.673828 -161.582608) (xy 398.673417 -161.572537) (xy 398.665688 -161.553938) (xy 398.658842 -161.54654)
			(xy 398.346168 -161.23412) (xy 398.323251 -161.210541) (xy 398.282256 -161.159131) (xy 398.247268 -161.103457)
			(xy 398.218728 -161.04422) (xy 398.196993 -160.982161) (xy 398.182337 -160.918061) (xy 398.174943 -160.852723)
			(xy 398.174464 -160.819846) (xy 398.174464 -148.171916) (xy 398.17404 -148.161846) (xy 398.166319 -148.143248)
			(xy 398.159478 -148.135848) (xy 397.177768 -147.154138) (xy 397.15486 -147.130551) (xy 397.113864 -147.079142)
			(xy 397.078875 -147.02347) (xy 397.050334 -146.964234) (xy 397.028598 -146.902176) (xy 397.01394 -146.838077)
			(xy 397.006544 -146.772741) (xy 397.006064 -146.739864) (xy 392.080139 -146.739864) (xy 392.119104 -147.3708)
			(xy 392.468862 -153.05786) (xy 392.468862 -153.058876) (xy 392.62352 -155.0416) (xy 396.463772 -155.0416)
			(xy 396.467843 -154.985978) (xy 396.479969 -154.931541) (xy 396.499892 -154.87945) (xy 396.527188 -154.830815)
			(xy 396.561274 -154.786672) (xy 396.601423 -154.747963) (xy 396.646781 -154.715512) (xy 396.696381 -154.690011)
			(xy 396.749165 -154.672004) (xy 396.804008 -154.661874) (xy 396.859742 -154.659837) (xy 396.915179 -154.665937)
			(xy 396.969136 -154.680043) (xy 397.020465 -154.701855) (xy 397.068071 -154.730909) (xy 397.110939 -154.766584)
			(xy 397.148156 -154.808121) (xy 397.178929 -154.854634) (xy 397.202601 -154.905131) (xy 397.218669 -154.958538)
			(xy 397.226789 -155.013714) (xy 397.227298 -155.0416) (xy 397.226789 -155.069486) (xy 397.218669 -155.124662)
			(xy 397.202601 -155.178069) (xy 397.178929 -155.228566) (xy 397.148156 -155.275079) (xy 397.110939 -155.316616)
			(xy 397.068071 -155.352291) (xy 397.020465 -155.381345) (xy 396.969136 -155.403157) (xy 396.915179 -155.417263)
			(xy 396.859742 -155.423363) (xy 396.804008 -155.421326) (xy 396.749165 -155.411196) (xy 396.696381 -155.393189)
			(xy 396.646781 -155.367688) (xy 396.601423 -155.335237) (xy 396.561274 -155.296528) (xy 396.527188 -155.252385)
			(xy 396.499892 -155.20375) (xy 396.479969 -155.151659) (xy 396.467843 -155.097222) (xy 396.463772 -155.0416)
			(xy 392.62352 -155.0416) (xy 393.024729 -160.1851) (xy 393.824219 -160.1851) (xy 393.828174 -160.093263)
			(xy 393.840009 -160.002106) (xy 393.859636 -159.912303) (xy 393.88691 -159.824521) (xy 393.92163 -159.739407)
			(xy 393.963538 -159.657594) (xy 394.012324 -159.579686) (xy 394.067627 -159.506261) (xy 394.129037 -159.437861)
			(xy 394.196099 -159.374994) (xy 394.268318 -159.318124) (xy 394.345158 -159.267673) (xy 394.426051 -159.224014)
			(xy 394.510397 -159.187471) (xy 394.597573 -159.158314) (xy 394.686932 -159.13676) (xy 394.777813 -159.122966)
			(xy 394.869544 -159.117036) (xy 394.961445 -159.119014) (xy 395.052836 -159.128885) (xy 395.14304 -159.146575)
			(xy 395.231389 -159.171955) (xy 395.317229 -159.204835) (xy 395.399925 -159.244973) (xy 395.478865 -159.292072)
			(xy 395.553463 -159.345782) (xy 395.623169 -159.405706) (xy 395.687464 -159.4714) (xy 395.745875 -159.542378)
			(xy 395.797967 -159.618115) (xy 395.843356 -159.69805) (xy 395.881706 -159.78159) (xy 395.912731 -159.868118)
			(xy 395.936204 -159.956993) (xy 395.95195 -160.047557) (xy 395.959852 -160.139139) (xy 395.960346 -160.1851)
			(xy 395.959852 -160.231061) (xy 395.95195 -160.322643) (xy 395.936204 -160.413207) (xy 395.912731 -160.502082)
			(xy 395.881706 -160.58861) (xy 395.843356 -160.67215) (xy 395.797967 -160.752085) (xy 395.745875 -160.827822)
			(xy 395.687464 -160.8988) (xy 395.623169 -160.964494) (xy 395.553463 -161.024418) (xy 395.478865 -161.078128)
			(xy 395.399925 -161.125227) (xy 395.317229 -161.165365) (xy 395.231389 -161.198245) (xy 395.14304 -161.223625)
			(xy 395.052836 -161.241315) (xy 394.961445 -161.251186) (xy 394.869544 -161.253164) (xy 394.777813 -161.247234)
			(xy 394.686932 -161.23344) (xy 394.597573 -161.211886) (xy 394.510397 -161.182729) (xy 394.426051 -161.146186)
			(xy 394.345158 -161.102527) (xy 394.268318 -161.052076) (xy 394.196099 -160.995206) (xy 394.129037 -160.932339)
			(xy 394.067627 -160.863939) (xy 394.012324 -160.790514) (xy 393.963538 -160.712606) (xy 393.92163 -160.630793)
			(xy 393.88691 -160.545679) (xy 393.859636 -160.457897) (xy 393.840009 -160.368094) (xy 393.828174 -160.276937)
			(xy 393.824219 -160.1851) (xy 393.024729 -160.1851) (xy 393.410523 -165.130988) (xy 397.044162 -165.130988)
			(xy 397.048233 -165.075366) (xy 397.060359 -165.020929) (xy 397.080282 -164.968838) (xy 397.107578 -164.920203)
			(xy 397.141664 -164.87606) (xy 397.181813 -164.837351) (xy 397.227171 -164.8049) (xy 397.276771 -164.779399)
			(xy 397.329555 -164.761392) (xy 397.384398 -164.751262) (xy 397.440132 -164.749225) (xy 397.495569 -164.755325)
			(xy 397.549526 -164.769431) (xy 397.600855 -164.791243) (xy 397.648461 -164.820297) (xy 397.691329 -164.855972)
			(xy 397.728546 -164.897509) (xy 397.759319 -164.944022) (xy 397.782991 -164.994519) (xy 397.799059 -165.047926)
			(xy 397.807179 -165.103102) (xy 397.807688 -165.130988) (xy 397.807179 -165.158874) (xy 397.799059 -165.21405)
			(xy 397.782991 -165.267457) (xy 397.759319 -165.317954) (xy 397.728546 -165.364467) (xy 397.691329 -165.406004)
			(xy 397.648461 -165.441679) (xy 397.600855 -165.470733) (xy 397.549526 -165.492545) (xy 397.495569 -165.506651)
			(xy 397.440132 -165.512751) (xy 397.384398 -165.510714) (xy 397.329555 -165.500584) (xy 397.276771 -165.482577)
			(xy 397.227171 -165.457076) (xy 397.181813 -165.424625) (xy 397.141664 -165.385916) (xy 397.107578 -165.341773)
			(xy 397.080282 -165.293138) (xy 397.060359 -165.241047) (xy 397.048233 -165.18661) (xy 397.044162 -165.130988)
			(xy 393.410523 -165.130988) (xy 393.665295 -168.397174) (xy 398.941796 -168.397174) (xy 398.945867 -168.341552)
			(xy 398.957993 -168.287115) (xy 398.977916 -168.235024) (xy 399.005212 -168.186389) (xy 399.039298 -168.142246)
			(xy 399.079447 -168.103537) (xy 399.124805 -168.071086) (xy 399.174405 -168.045585) (xy 399.227189 -168.027578)
			(xy 399.282032 -168.017448) (xy 399.337766 -168.015411) (xy 399.393203 -168.021511) (xy 399.44716 -168.035617)
			(xy 399.498489 -168.057429) (xy 399.546095 -168.086483) (xy 399.588963 -168.122158) (xy 399.62618 -168.163695)
			(xy 399.656953 -168.210208) (xy 399.680625 -168.260705) (xy 399.696693 -168.314112) (xy 399.704813 -168.369288)
			(xy 399.705322 -168.397174) (xy 399.704813 -168.42506) (xy 399.696693 -168.480236) (xy 399.680625 -168.533643)
			(xy 399.656953 -168.58414) (xy 399.62618 -168.630653) (xy 399.588963 -168.67219) (xy 399.546095 -168.707865)
			(xy 399.498489 -168.736919) (xy 399.44716 -168.758731) (xy 399.393203 -168.772837) (xy 399.337766 -168.778937)
			(xy 399.282032 -168.7769) (xy 399.227189 -168.76677) (xy 399.174405 -168.748763) (xy 399.124805 -168.723262)
			(xy 399.079447 -168.690811) (xy 399.039298 -168.652102) (xy 399.005212 -168.607959) (xy 398.977916 -168.559324)
			(xy 398.957993 -168.507233) (xy 398.945867 -168.452796) (xy 398.941796 -168.397174) (xy 393.665295 -168.397174)
			(xy 393.714312 -169.02557) (xy 396.25219 -169.02557) (xy 396.256261 -168.969948) (xy 396.268387 -168.915511)
			(xy 396.28831 -168.86342) (xy 396.315606 -168.814785) (xy 396.349692 -168.770642) (xy 396.389841 -168.731933)
			(xy 396.435199 -168.699482) (xy 396.484799 -168.673981) (xy 396.537583 -168.655974) (xy 396.592426 -168.645844)
			(xy 396.64816 -168.643807) (xy 396.703597 -168.649907) (xy 396.757554 -168.664013) (xy 396.808883 -168.685825)
			(xy 396.856489 -168.714879) (xy 396.899357 -168.750554) (xy 396.936574 -168.792091) (xy 396.967347 -168.838604)
			(xy 396.991019 -168.889101) (xy 397.007087 -168.942508) (xy 397.015207 -168.997684) (xy 397.015716 -169.02557)
			(xy 397.015207 -169.053456) (xy 397.007087 -169.108632) (xy 396.991019 -169.162039) (xy 396.967347 -169.212536)
			(xy 396.936574 -169.259049) (xy 396.899357 -169.300586) (xy 396.856489 -169.336261) (xy 396.808883 -169.365315)
			(xy 396.757554 -169.387127) (xy 396.703597 -169.401233) (xy 396.64816 -169.407333) (xy 396.592426 -169.405296)
			(xy 396.537583 -169.395166) (xy 396.484799 -169.377159) (xy 396.435199 -169.351658) (xy 396.389841 -169.319207)
			(xy 396.349692 -169.280498) (xy 396.315606 -169.236355) (xy 396.28831 -169.18772) (xy 396.268387 -169.135629)
			(xy 396.256261 -169.081192) (xy 396.25219 -169.02557) (xy 393.714312 -169.02557) (xy 393.767767 -169.710862)
			(xy 397.16151 -169.710862) (xy 397.165581 -169.65524) (xy 397.177707 -169.600803) (xy 397.19763 -169.548712)
			(xy 397.224926 -169.500077) (xy 397.259012 -169.455934) (xy 397.299161 -169.417225) (xy 397.344519 -169.384774)
			(xy 397.394119 -169.359273) (xy 397.446903 -169.341266) (xy 397.501746 -169.331136) (xy 397.55748 -169.329099)
			(xy 397.612917 -169.335199) (xy 397.666874 -169.349305) (xy 397.718203 -169.371117) (xy 397.765809 -169.400171)
			(xy 397.808677 -169.435846) (xy 397.845894 -169.477383) (xy 397.876667 -169.523896) (xy 397.900339 -169.574393)
			(xy 397.916407 -169.6278) (xy 397.924527 -169.682976) (xy 397.925036 -169.710862) (xy 397.924527 -169.738748)
			(xy 397.916407 -169.793924) (xy 397.900339 -169.847331) (xy 397.876667 -169.897828) (xy 397.845894 -169.944341)
			(xy 397.808677 -169.985878) (xy 397.765809 -170.021553) (xy 397.718203 -170.050607) (xy 397.666874 -170.072419)
			(xy 397.612917 -170.086525) (xy 397.55748 -170.092625) (xy 397.501746 -170.090588) (xy 397.446903 -170.080458)
			(xy 397.394119 -170.062451) (xy 397.344519 -170.03695) (xy 397.299161 -170.004499) (xy 397.259012 -169.96579)
			(xy 397.224926 -169.921647) (xy 397.19763 -169.873012) (xy 397.177707 -169.820921) (xy 397.165581 -169.766484)
			(xy 397.16151 -169.710862) (xy 393.767767 -169.710862) (xy 393.945249 -171.986194) (xy 398.254218 -171.986194)
			(xy 398.258289 -171.930572) (xy 398.270415 -171.876135) (xy 398.290338 -171.824044) (xy 398.317634 -171.775409)
			(xy 398.35172 -171.731266) (xy 398.391869 -171.692557) (xy 398.437227 -171.660106) (xy 398.486827 -171.634605)
			(xy 398.539611 -171.616598) (xy 398.594454 -171.606468) (xy 398.650188 -171.604431) (xy 398.705625 -171.610531)
			(xy 398.759582 -171.624637) (xy 398.810911 -171.646449) (xy 398.858517 -171.675503) (xy 398.901385 -171.711178)
			(xy 398.938602 -171.752715) (xy 398.969375 -171.799228) (xy 398.993047 -171.849725) (xy 399.009115 -171.903132)
			(xy 399.017235 -171.958308) (xy 399.017744 -171.986194) (xy 399.017235 -172.01408) (xy 399.009115 -172.069256)
			(xy 398.993047 -172.122663) (xy 398.969375 -172.17316) (xy 398.938602 -172.219673) (xy 398.901385 -172.26121)
			(xy 398.858517 -172.296885) (xy 398.810911 -172.325939) (xy 398.759582 -172.347751) (xy 398.705625 -172.361857)
			(xy 398.650188 -172.367957) (xy 398.594454 -172.36592) (xy 398.539611 -172.35579) (xy 398.486827 -172.337783)
			(xy 398.437227 -172.312282) (xy 398.391869 -172.279831) (xy 398.35172 -172.241122) (xy 398.317634 -172.196979)
			(xy 398.290338 -172.148344) (xy 398.270415 -172.096253) (xy 398.258289 -172.041816) (xy 398.254218 -171.986194)
			(xy 393.945249 -171.986194) (xy 393.978237 -172.409104) (xy 400.429982 -172.409104) (xy 400.434053 -172.353482)
			(xy 400.446179 -172.299045) (xy 400.466102 -172.246954) (xy 400.493398 -172.198319) (xy 400.527484 -172.154176)
			(xy 400.567633 -172.115467) (xy 400.612991 -172.083016) (xy 400.662591 -172.057515) (xy 400.715375 -172.039508)
			(xy 400.770218 -172.029378) (xy 400.825952 -172.027341) (xy 400.881389 -172.033441) (xy 400.935346 -172.047547)
			(xy 400.986675 -172.069359) (xy 401.034281 -172.098413) (xy 401.077149 -172.134088) (xy 401.114366 -172.175625)
			(xy 401.145139 -172.222138) (xy 401.168811 -172.272635) (xy 401.184879 -172.326042) (xy 401.192999 -172.381218)
			(xy 401.193508 -172.409104) (xy 401.192999 -172.43699) (xy 401.184879 -172.492166) (xy 401.168811 -172.545573)
			(xy 401.145139 -172.59607) (xy 401.114366 -172.642583) (xy 401.077149 -172.68412) (xy 401.034281 -172.719795)
			(xy 400.986675 -172.748849) (xy 400.935346 -172.770661) (xy 400.881389 -172.784767) (xy 400.825952 -172.790867)
			(xy 400.770218 -172.78883) (xy 400.715375 -172.7787) (xy 400.662591 -172.760693) (xy 400.612991 -172.735192)
			(xy 400.567633 -172.702741) (xy 400.527484 -172.664032) (xy 400.493398 -172.619889) (xy 400.466102 -172.571254)
			(xy 400.446179 -172.519163) (xy 400.434053 -172.464726) (xy 400.429982 -172.409104) (xy 393.978237 -172.409104)
			(xy 394.140603 -174.490634) (xy 398.11147 -174.490634) (xy 398.115541 -174.435012) (xy 398.127667 -174.380575)
			(xy 398.14759 -174.328484) (xy 398.174886 -174.279849) (xy 398.208972 -174.235706) (xy 398.249121 -174.196997)
			(xy 398.294479 -174.164546) (xy 398.344079 -174.139045) (xy 398.396863 -174.121038) (xy 398.451706 -174.110908)
			(xy 398.50744 -174.108871) (xy 398.562877 -174.114971) (xy 398.616834 -174.129077) (xy 398.668163 -174.150889)
			(xy 398.715769 -174.179943) (xy 398.758637 -174.215618) (xy 398.795854 -174.257155) (xy 398.826627 -174.303668)
			(xy 398.850299 -174.354165) (xy 398.866367 -174.407572) (xy 398.874487 -174.462748) (xy 398.874996 -174.490634)
			(xy 398.874487 -174.51852) (xy 398.866367 -174.573696) (xy 398.850299 -174.627103) (xy 398.826627 -174.6776)
			(xy 398.795854 -174.724113) (xy 398.758637 -174.76565) (xy 398.715769 -174.801325) (xy 398.668163 -174.830379)
			(xy 398.616834 -174.852191) (xy 398.562877 -174.866297) (xy 398.50744 -174.872397) (xy 398.451706 -174.87036)
			(xy 398.396863 -174.86023) (xy 398.344079 -174.842223) (xy 398.294479 -174.816722) (xy 398.249121 -174.784271)
			(xy 398.208972 -174.745562) (xy 398.174886 -174.701419) (xy 398.14759 -174.652784) (xy 398.127667 -174.600693)
			(xy 398.115541 -174.546256) (xy 398.11147 -174.490634) (xy 394.140603 -174.490634) (xy 394.549162 -179.728368)
			(xy 399.71675 -179.728368) (xy 399.720821 -179.672746) (xy 399.732947 -179.618309) (xy 399.75287 -179.566218)
			(xy 399.780166 -179.517583) (xy 399.814252 -179.47344) (xy 399.854401 -179.434731) (xy 399.899759 -179.40228)
			(xy 399.949359 -179.376779) (xy 400.002143 -179.358772) (xy 400.056986 -179.348642) (xy 400.11272 -179.346605)
			(xy 400.168157 -179.352705) (xy 400.222114 -179.366811) (xy 400.273443 -179.388623) (xy 400.321049 -179.417677)
			(xy 400.363917 -179.453352) (xy 400.401134 -179.494889) (xy 400.431907 -179.541402) (xy 400.455579 -179.591899)
			(xy 400.471647 -179.645306) (xy 400.479767 -179.700482) (xy 400.480276 -179.728368) (xy 400.479767 -179.756254)
			(xy 400.471647 -179.81143) (xy 400.455579 -179.864837) (xy 400.431907 -179.915334) (xy 400.401134 -179.961847)
			(xy 400.363917 -180.003384) (xy 400.321049 -180.039059) (xy 400.273443 -180.068113) (xy 400.222114 -180.089925)
			(xy 400.168157 -180.104031) (xy 400.11272 -180.110131) (xy 400.056986 -180.108094) (xy 400.002143 -180.097964)
			(xy 399.949359 -180.079957) (xy 399.899759 -180.054456) (xy 399.854401 -180.022005) (xy 399.814252 -179.983296)
			(xy 399.780166 -179.939153) (xy 399.75287 -179.890518) (xy 399.732947 -179.838427) (xy 399.720821 -179.78399)
			(xy 399.71675 -179.728368) (xy 394.549162 -179.728368) (xy 396.695676 -207.246728) (xy 397.816324 -221.614238)
			(xy 397.818356 -221.61881) (xy 397.822921 -221.626989) (xy 397.83676 -221.639586) (xy 397.854211 -221.646346)
			(xy 397.863568 -221.64675) (xy 400.96313 -221.64675) (xy 400.971266 -221.64596) (xy 400.986426 -221.63987)
			(xy 400.992848 -221.634812) (xy 400.998393 -221.629802) (xy 401.006533 -221.617279) (xy 401.00885 -221.610174)
			(xy 401.010628 -221.603824) (xy 402.82495 -186.746642) (xy 403.620478 -171.462446) (xy 403.716744 -169.61231)
			(xy 403.809454 -167.829992) (xy 403.930104 -165.512242) (xy 404.001732 -164.137848) (xy 404.038308 -163.43503)
			(xy 404.433786 -155.836366) (xy 404.566628 -153.283666) (xy 405.013668 -144.69618) (xy 405.013668 -144.691608)
			(xy 405.01328 -144.683253) (xy 405.007828 -144.667451) (xy 405.003 -144.66062) (xy 404.997666 -144.654016)
			(xy 404.984204 -144.645126) (xy 404.975314 -144.642586) (xy 404.948186 -144.635207) (xy 404.896293 -144.613581)
			(xy 404.848128 -144.584588) (xy 404.804728 -144.548853) (xy 404.76703 -144.507147) (xy 404.735848 -144.460369)
			(xy 404.711852 -144.409528) (xy 404.695562 -144.355722) (xy 404.687328 -144.300109) (xy 404.68677 -144.272)
			(xy 404.687235 -144.245311) (xy 404.694662 -144.192452) (xy 404.709372 -144.141141) (xy 404.731077 -144.092376)
			(xy 404.759357 -144.047105) (xy 404.793661 -144.006209) (xy 404.833321 -143.970484) (xy 404.877566 -143.940625)
			(xy 404.925536 -143.917212) (xy 404.976296 -143.900702) (xy 405.002492 -143.895572) (xy 405.00681 -143.89481)
			(xy 405.01443 -143.89227) (xy 405.02332 -143.888968) (xy 405.026876 -143.88719) (xy 405.03348 -143.883634)
			(xy 405.037802 -143.880893) (xy 405.045343 -143.873974) (xy 405.048466 -143.869918) (xy 405.050498 -143.86687)
			(xy 405.057102 -143.856202) (xy 405.057864 -143.84274) (xy 405.061674 -143.772128) (xy 405.063706 -143.733774)
			(xy 405.06396 -143.730726) (xy 405.06396 -143.730472) (xy 405.065738 -143.695166) (xy 405.076152 -143.494506)
			(xy 405.083772 -143.34617) (xy 405.083764 -143.33554) (xy 405.076148 -143.315721) (xy 405.06904 -143.307816)
			(xy 405.056086 -143.294862) (xy 405.04872 -143.291052) (xy 405.024185 -143.277924) (xy 404.97886 -143.245643)
			(xy 404.9387 -143.207126) (xy 404.904555 -143.163189) (xy 404.877147 -143.114763) (xy 404.857056 -143.062871)
			(xy 404.844707 -143.008614) (xy 404.840364 -142.953139) (xy 404.844116 -142.897621) (xy 404.855885 -142.843235)
			(xy 404.875421 -142.791132) (xy 404.888446 -142.766542) (xy 404.888954 -142.76578) (xy 404.890224 -142.76324)
			(xy 404.904355 -142.739318) (xy 404.938475 -142.69547) (xy 404.978605 -142.657046) (xy 405.000968 -142.640558)
			(xy 405.013892 -142.631524) (xy 405.040977 -142.615373) (xy 405.05507 -142.6083) (xy 405.087582 -142.594076)
			(xy 405.08936 -142.593568) (xy 405.090884 -142.592806) (xy 405.10079 -142.58798) (xy 405.110932 -142.580946)
			(xy 405.12366 -142.559845) (xy 405.125174 -142.547594) (xy 405.126952 -142.5194) (xy 405.126952 -142.518892)
			(xy 405.13508 -142.352776) (xy 405.13508 -142.349982) (xy 405.134545 -142.339619) (xy 405.126267 -142.320613)
			(xy 405.111147 -142.30643) (xy 405.101552 -142.302484) (xy 405.099266 -142.301722) (xy 405.097488 -142.301214)
			(xy 405.071534 -142.293016) (xy 405.022077 -142.270291) (xy 404.97635 -142.240772) (xy 404.935278 -142.205058)
			(xy 404.899695 -142.163872) (xy 404.870323 -142.118051) (xy 404.847756 -142.068522) (xy 404.832452 -142.01629)
			(xy 404.824722 -141.962414) (xy 404.824184 -141.9352) (xy 404.82464 -141.908632) (xy 404.831994 -141.856008)
			(xy 404.846561 -141.804908) (xy 404.868061 -141.756317) (xy 404.896079 -141.711168) (xy 404.930076 -141.670332)
			(xy 404.969398 -141.634595) (xy 405.013288 -141.604643) (xy 405.0609 -141.581055) (xy 405.11132 -141.564284)
			(xy 405.137366 -141.559026) (xy 405.13762 -141.559026) (xy 405.14143 -141.558264) (xy 405.148624 -141.556099)
			(xy 405.161406 -141.548221) (xy 405.166576 -141.54277) (xy 405.172418 -141.536166) (xy 405.175466 -141.529054)
			(xy 405.176913 -141.525517) (xy 405.178821 -141.518117) (xy 405.179276 -141.514322) (xy 405.179276 -141.51229)
			(xy 405.182578 -141.45006) (xy 405.182832 -141.445996) (xy 405.18715 -141.36243) (xy 405.187269 -141.354971)
			(xy 405.183654 -141.340506) (xy 405.180038 -141.333982) (xy 405.176482 -141.327886) (xy 405.165306 -141.317726)
			(xy 405.158448 -141.314424) (xy 405.135218 -141.302828) (xy 405.091852 -141.274281) (xy 405.052757 -141.240117)
			(xy 405.018655 -141.200968) (xy 404.990176 -141.157557) (xy 404.967847 -141.110685) (xy 404.959566 -141.086078)
			(xy 404.955018 -141.071422) (xy 404.948024 -141.04154) (xy 404.945596 -141.026388) (xy 404.944072 -141.015466)
			(xy 404.944072 -141.014704) (xy 404.943818 -141.012418) (xy 404.941786 -140.993876) (xy 404.941532 -140.988288)
			(xy 404.941532 -140.969746) (xy 404.941944 -140.944158) (xy 404.948792 -140.893442) (xy 404.962372 -140.844101)
			(xy 404.972012 -140.820394) (xy 404.984341 -140.792886) (xy 405.016367 -140.741819) (xy 405.056009 -140.69641)
			(xy 405.102285 -140.657784) (xy 405.154049 -140.626897) (xy 405.181816 -140.615162) (xy 405.18842 -140.612368)
			(xy 405.189182 -140.612114) (xy 405.193246 -140.609066) (xy 405.201882 -140.600684) (xy 405.213566 -140.58519)
			(xy 405.214582 -140.58392) (xy 405.2189 -140.578078) (xy 405.219662 -140.577062) (xy 405.223777 -140.570996)
			(xy 405.228667 -140.557186) (xy 405.229314 -140.549884) (xy 405.234902 -140.445744) (xy 405.237442 -140.396722)
			(xy 405.24049 -140.336778) (xy 405.24303 -140.287248) (xy 405.251158 -140.132562) (xy 405.25192 -140.11656)
			(xy 405.252682 -140.104114) (xy 405.252682 -140.100304) (xy 405.252494 -140.094009) (xy 405.24941 -140.081803)
			(xy 405.246586 -140.076174) (xy 405.242014 -140.067538) (xy 405.225758 -140.049504) (xy 405.219916 -140.0429)
			(xy 405.197818 -140.030962) (xy 405.1935 -140.029438) (xy 405.181562 -140.02512) (xy 405.177498 -140.024358)
			(xy 405.149068 -140.01855) (xy 405.094267 -139.999481) (xy 405.042983 -139.972337) (xy 404.9964 -139.937742)
			(xy 404.955591 -139.896493) (xy 404.921497 -139.849542) (xy 404.894904 -139.797971) (xy 404.876424 -139.742968)
			(xy 404.87092 -139.714478) (xy 404.866905 -139.688939) (xy 404.86499 -139.637277) (xy 404.870073 -139.58583)
			(xy 404.882062 -139.535542) (xy 404.890986 -139.511278) (xy 404.903684 -139.480331) (xy 404.938312 -139.423106)
			(xy 404.95982 -139.397486) (xy 404.960074 -139.397232) (xy 404.96741 -139.38909) (xy 404.975035 -139.368565)
			(xy 404.974806 -139.357608) (xy 404.97379 -139.345416) (xy 404.97379 -139.344908) (xy 404.968964 -139.281408)
			(xy 404.968202 -139.277598) (xy 404.96617 -139.271502) (xy 404.958804 -139.256008) (xy 404.950676 -139.24915)
			(xy 404.929762 -139.230924) (xy 404.89291 -139.189462) (xy 404.862449 -139.143101) (xy 404.839021 -139.092818)
			(xy 404.82312 -139.039673) (xy 404.815081 -138.984786) (xy 404.814532 -138.95705) (xy 404.814992 -138.929796)
			(xy 404.822743 -138.875842) (xy 404.838095 -138.82354) (xy 404.860736 -138.773956) (xy 404.890203 -138.7281)
			(xy 404.925897 -138.686904) (xy 404.967092 -138.651209) (xy 405.012947 -138.62174) (xy 405.062531 -138.599099)
			(xy 405.114832 -138.583745) (xy 405.168786 -138.575993) (xy 405.19604 -138.575542) (xy 405.200612 -138.575542)
			(xy 405.222202 -138.57605) (xy 405.233124 -138.576558) (xy 405.257 -138.567414) (xy 405.261075 -138.565715)
			(xy 405.268614 -138.56112) (xy 405.271986 -138.55827) (xy 405.292306 -138.540744) (xy 405.292814 -138.540236)
			(xy 405.319738 -138.516614) (xy 405.323548 -138.513135) (xy 405.329819 -138.504944) (xy 405.332184 -138.500358)
			(xy 405.336502 -138.491214) (xy 405.33701 -138.4808) (xy 405.355806 -138.122406) (xy 405.369014 -137.867898)
			(xy 405.377396 -137.703814) (xy 405.377535 -137.69687) (xy 405.374444 -137.683336) (xy 405.3713 -137.677144)
			(xy 405.366865 -137.669671) (xy 405.354017 -137.657984) (xy 405.346154 -137.654284) (xy 405.341074 -137.65276)
			(xy 405.328022 -137.648733) (xy 405.302472 -137.63907) (xy 405.29002 -137.633456) (xy 405.265581 -137.62162)
			(xy 405.220028 -137.592063) (xy 405.179122 -137.556351) (xy 405.143688 -137.515204) (xy 405.114439 -137.469453)
			(xy 405.091967 -137.42002) (xy 405.076724 -137.367902) (xy 405.069017 -137.314151) (xy 405.068532 -137.287)
			(xy 405.069042 -137.258852) (xy 405.077326 -137.20317) (xy 405.0937 -137.149308) (xy 405.117807 -137.098436)
			(xy 405.149126 -137.051657) (xy 405.186976 -137.009985) (xy 405.230538 -136.974326) (xy 405.278864 -136.945452)
			(xy 405.330908 -136.92399) (xy 405.358092 -136.916668) (xy 405.364188 -136.915144) (xy 405.385016 -136.903968)
			(xy 405.390858 -136.899142) (xy 405.39543 -136.89457) (xy 405.409908 -136.877806) (xy 405.411178 -136.876282)
			(xy 405.411432 -136.876028) (xy 405.411432 -136.875774) (xy 405.418798 -136.863582) (xy 405.4221 -136.851644)
			(xy 405.42591 -136.774428) (xy 405.436324 -136.574022) (xy 405.443182 -136.442958) (xy 405.44623 -136.3853)
			(xy 405.472392 -135.881364) (xy 405.51608 -135.035544) (xy 405.515528 -135.028105) (xy 405.510623 -135.014026)
			(xy 405.506428 -135.007858) (xy 405.501628 -135.001688) (xy 405.489089 -134.992367) (xy 405.48179 -134.98957)
			(xy 405.478488 -134.988554) (xy 405.451791 -134.9809) (xy 405.400784 -134.95893) (xy 405.353501 -134.929797)
			(xy 405.310943 -134.894116) (xy 405.274008 -134.852641) (xy 405.243477 -134.806249) (xy 405.219996 -134.75592)
			(xy 405.204061 -134.702719) (xy 405.196008 -134.647768) (xy 405.195532 -134.62) (xy 405.19561 -134.607262)
			(xy 405.197264 -134.581841) (xy 405.198834 -134.5692) (xy 405.202837 -134.542786) (xy 405.217269 -134.491347)
			(xy 405.238729 -134.442422) (xy 405.266799 -134.396965) (xy 405.300931 -134.355865) (xy 405.340458 -134.319924)
			(xy 405.384609 -134.289842) (xy 405.432522 -134.266208) (xy 405.483261 -134.249483) (xy 405.509476 -134.244334)
			(xy 405.518112 -134.24281) (xy 405.537416 -134.232142) (xy 405.546793 -134.22535) (xy 405.558689 -134.205512)
			(xy 405.560276 -134.194042) (xy 405.56053 -134.189724) (xy 405.56053 -134.189216) (xy 406.958038 -107.340146)
			(xy 407.92273 -88.805004) (xy 407.973784 -87.82431) (xy 407.973784 -87.823802) (xy 407.974292 -87.814658)
			(xy 407.974546 -87.808308) (xy 407.974195 -87.799886) (xy 407.968751 -87.783944) (xy 407.963878 -87.777066)
			(xy 407.914602 -87.719662) (xy 407.905204 -87.71509) (xy 407.882598 -87.703914) (xy 407.873708 -87.702898)
			(xy 407.84604 -87.699369) (xy 407.792076 -87.685265) (xy 407.740741 -87.663453) (xy 407.693129 -87.634398)
			(xy 407.650256 -87.598721) (xy 407.613035 -87.55718) (xy 407.582259 -87.510662) (xy 407.558585 -87.460159)
			(xy 407.542518 -87.406747) (xy 407.534399 -87.351564) (xy 407.533856 -87.323676) (xy 407.534343 -87.296425)
			(xy 407.542102 -87.242478) (xy 407.557459 -87.190184) (xy 407.580101 -87.140607) (xy 407.609568 -87.094757)
			(xy 407.645259 -87.053567) (xy 407.686448 -87.017875) (xy 407.732297 -86.988407) (xy 407.781873 -86.965764)
			(xy 407.834166 -86.950405) (xy 407.888113 -86.942644) (xy 407.915364 -86.942168) (xy 407.922984 -86.942168)
			(xy 407.931609 -86.941784) (xy 407.947839 -86.935935) (xy 407.954734 -86.930738) (xy 407.96972 -86.916768)
			(xy 408.008074 -86.881208) (xy 408.009852 -86.87943) (xy 408.016128 -86.872515) (xy 408.023677 -86.855451)
			(xy 408.024584 -86.846156) (xy 408.046174 -86.43239) (xy 408.073352 -85.912452) (xy 408.097228 -85.45322)
			(xy 408.136344 -84.700364) (xy 408.136598 -84.697316) (xy 408.136598 -84.685632) (xy 408.13355 -84.67725)
			(xy 408.12593 -84.655914) (xy 408.120596 -84.64931) (xy 408.104783 -84.628862) (xy 408.078234 -84.584508)
			(xy 408.057926 -84.536972) (xy 408.044229 -84.487128) (xy 408.037397 -84.435889) (xy 408.03703 -84.410042)
			(xy 408.03703 -84.402676) (xy 408.038159 -84.373954) (xy 408.047989 -84.317322) (xy 408.066215 -84.26281)
			(xy 408.092424 -84.211654) (xy 408.126021 -84.165017) (xy 408.145742 -84.144104) (xy 408.152346 -84.137246)
			(xy 408.164284 -84.110068) (xy 408.167078 -84.10067) (xy 408.167332 -84.098638) (xy 408.16784 -84.092288)
			(xy 408.176222 -83.934808) (xy 408.176476 -83.928966) (xy 408.182318 -83.81873) (xy 408.182318 -83.818222)
			(xy 408.183334 -83.799426) (xy 408.180032 -83.790028) (xy 408.177746 -83.782916) (xy 408.174698 -83.776566)
			(xy 408.16911 -83.76793) (xy 408.167332 -83.764882) (xy 408.166824 -83.76412) (xy 408.15383 -83.741874)
			(xy 408.133281 -83.69463) (xy 408.119266 -83.645053) (xy 408.112039 -83.594043) (xy 408.111452 -83.568286)
			(xy 408.111452 -83.56473) (xy 408.111933 -83.53938) (xy 408.118785 -83.489142) (xy 408.132239 -83.440257)
			(xy 408.152057 -83.393589) (xy 408.177889 -83.34996) (xy 408.19324 -83.32978) (xy 408.198066 -83.323684)
			(xy 408.206448 -83.30184) (xy 408.209496 -83.293966) (xy 409.188158 -64.492886) (xy 409.188158 -64.489838)
			(xy 409.180792 -62.453774) (xy 409.180462 -62.444881) (xy 409.174382 -62.428166) (xy 409.162936 -62.414553)
			(xy 409.155392 -62.409832) (xy 409.1178 -62.388242) (xy 409.092654 -62.38748) (xy 409.088844 -62.389258)
			(xy 409.088336 -62.389512) (xy 409.075382 -62.395862) (xy 409.06827 -62.399164) (xy 409.05557 -62.404752)
			(xy 409.055316 -62.404752) (xy 409.052776 -62.405768) (xy 409.048458 -62.407546) (xy 409.048204 -62.407546)
			(xy 409.039822 -62.410594) (xy 409.036266 -62.411864) (xy 409.006548 -62.421008) (xy 409.002484 -62.422024)
			(xy 408.980599 -62.427044) (xy 408.936033 -62.432518) (xy 408.913584 -62.432946) (xy 408.909774 -62.432946)
			(xy 408.88779 -62.432625) (xy 408.844118 -62.427537) (xy 408.822652 -62.422786) (xy 408.816048 -62.421262)
			(xy 408.806142 -62.420246) (xy 408.798197 -62.420318) (xy 408.782939 -62.42472) (xy 408.77617 -62.428882)
			(xy 408.769566 -62.434216) (xy 408.708352 -62.505336) (xy 408.700885 -62.515027) (xy 408.695176 -62.538778)
			(xy 408.69743 -62.550802) (xy 408.699462 -62.558168) (xy 408.700224 -62.559692) (xy 408.700732 -62.561216)
			(xy 408.709663 -62.584163) (xy 408.722215 -62.631778) (xy 408.728535 -62.680613) (xy 408.728926 -62.705234)
			(xy 408.728926 -62.705996) (xy 408.727656 -62.736222) (xy 408.727148 -62.740286) (xy 408.727148 -62.741302)
			(xy 408.724036 -62.769351) (xy 408.710604 -62.824161) (xy 408.689242 -62.876394) (xy 408.660415 -62.924908)
			(xy 408.624755 -62.968645) (xy 408.583038 -63.00665) (xy 408.536177 -63.038093) (xy 408.485194 -63.062286)
			(xy 408.431202 -63.078703) (xy 408.375381 -63.086984) (xy 408.347164 -63.087504) (xy 408.319915 -63.087016)
			(xy 408.265971 -63.079255) (xy 408.213682 -63.063897) (xy 408.164109 -63.041254) (xy 408.118264 -63.011787)
			(xy 408.077078 -62.976096) (xy 408.041391 -62.934907) (xy 408.011929 -62.889059) (xy 407.98929 -62.839485)
			(xy 407.973937 -62.787193) (xy 407.966182 -62.733249) (xy 407.966182 -62.678751) (xy 407.973937 -62.624807)
			(xy 407.98929 -62.572515) (xy 408.011929 -62.522941) (xy 408.041391 -62.477093) (xy 408.077078 -62.435904)
			(xy 408.118264 -62.400213) (xy 408.164109 -62.370746) (xy 408.213682 -62.348103) (xy 408.265971 -62.332745)
			(xy 408.319915 -62.324984) (xy 408.347164 -62.324488) (xy 408.34818 -62.324488) (xy 408.370227 -62.324798)
			(xy 408.414027 -62.329887) (xy 408.435556 -62.334648) (xy 408.44216 -62.336172) (xy 408.452066 -62.337188)
			(xy 408.46001 -62.337114) (xy 408.475264 -62.332705) (xy 408.482038 -62.328552) (xy 408.488642 -62.323218)
			(xy 408.529536 -62.27572) (xy 408.549856 -62.252098) (xy 408.557144 -62.242764) (xy 408.562965 -62.219841)
			(xy 408.561032 -62.208156) (xy 408.558746 -62.199774) (xy 408.557476 -62.196218) (xy 408.548543 -62.173271)
			(xy 408.535986 -62.125656) (xy 408.529661 -62.076821) (xy 408.529282 -62.0522) (xy 408.529282 -62.051438)
			(xy 408.530552 -62.021212) (xy 408.531314 -62.013338) (xy 408.534585 -61.985701) (xy 408.548111 -61.931718)
			(xy 408.569336 -61.880273) (xy 408.597812 -61.832458) (xy 408.632932 -61.789289) (xy 408.673953 -61.75168)
			(xy 408.720003 -61.720431) (xy 408.770104 -61.696205) (xy 408.823194 -61.679515) (xy 408.878146 -61.670717)
			(xy 408.905964 -61.66993) (xy 408.91206 -61.66993) (xy 408.936698 -61.670692) (xy 408.937206 -61.670692)
			(xy 408.963824 -61.67299) (xy 409.016087 -61.684084) (xy 409.041346 -61.69279) (xy 409.051674 -61.696053)
			(xy 409.073255 -61.694467) (xy 409.083002 -61.689742) (xy 409.088336 -61.686694) (xy 409.12796 -61.6585)
			(xy 409.157678 -61.637418) (xy 409.164282 -61.631576) (xy 409.16733 -61.62802) (xy 409.171876 -61.621632)
			(xy 409.177174 -61.606884) (xy 409.177744 -61.599064) (xy 409.17749 -61.548518) (xy 409.175712 -60.998608)
			(xy 409.175712 -60.979304) (xy 409.175712 -60.978796) (xy 409.17749 -60.867798) (xy 409.177482 -60.864)
			(xy 409.176463 -60.856474) (xy 409.175458 -60.852812) (xy 409.16987 -60.833762) (xy 409.166568 -60.828174)
			(xy 409.152225 -60.802872) (xy 409.130538 -60.748909) (xy 409.117297 -60.692278) (xy 409.114498 -60.663328)
			(xy 409.112806 -60.635245) (xy 409.116709 -60.579122) (xy 409.128818 -60.524181) (xy 409.138374 -60.49772)
			(xy 409.146006 -60.478455) (xy 409.164847 -60.441546) (xy 409.175966 -60.42406) (xy 409.175966 -60.423806)
			(xy 409.176474 -60.423298) (xy 409.176474 -60.423044) (xy 409.18008 -60.417154) (xy 409.184336 -60.404022)
			(xy 409.184856 -60.397136) (xy 409.185618 -60.343542) (xy 409.21051 -58.728356) (xy 409.210524 -58.723966)
			(xy 409.209256 -58.715281) (xy 409.20797 -58.711084) (xy 409.204922 -58.702448) (xy 409.198826 -58.695336)
			(xy 409.182013 -58.674633) (xy 409.153726 -58.629419) (xy 409.132008 -58.580709) (xy 409.117281 -58.529449)
			(xy 409.109834 -58.476638) (xy 409.109418 -58.449972) (xy 409.109418 -58.449718) (xy 409.110942 -58.413904)
			(xy 409.111958 -58.40476) (xy 409.11362 -58.391475) (xy 409.118577 -58.365161) (xy 409.121864 -58.352182)
			(xy 409.131008 -58.317638) (xy 409.132786 -58.31205) (xy 409.133294 -58.31078) (xy 409.13431 -58.309256)
			(xy 409.135072 -58.307478) (xy 409.15209 -58.274204) (xy 409.153614 -58.27141) (xy 409.154122 -58.270394)
			(xy 409.158186 -58.263028) (xy 409.158186 -58.262774) (xy 409.166606 -58.248081) (xy 409.185687 -58.220102)
			(xy 409.196286 -58.206894) (xy 409.196794 -58.206386) (xy 409.198318 -58.204354) (xy 409.198826 -58.203592)
			(xy 409.201366 -58.201052) (xy 409.201874 -58.200544) (xy 409.203652 -58.198512) (xy 409.205176 -58.196988)
			(xy 409.205684 -58.19648) (xy 409.206192 -58.195718) (xy 409.209494 -58.192162) (xy 409.21305 -58.188098)
			(xy 409.219654 -58.171334) (xy 409.220416 -58.114184) (xy 409.26131 -55.495444) (xy 409.26131 -55.492904)
			(xy 409.171902 -53.213) (xy 409.045664 -49.986692) (xy 409.045195 -49.980115) (xy 409.041344 -49.967508)
			(xy 409.038044 -49.9618) (xy 409.034742 -49.956466) (xy 409.02636 -49.948592) (xy 409.019248 -49.944274)
			(xy 408.95905 -49.911254) (xy 408.957272 -49.910238) (xy 408.943048 -49.903126) (xy 408.934511 -49.899237)
			(xy 408.915855 -49.897411) (xy 408.906726 -49.89957) (xy 408.89809 -49.90211) (xy 408.896058 -49.903126)
			(xy 408.892502 -49.905412) (xy 408.870436 -49.917783) (xy 408.823747 -49.937261) (xy 408.774905 -49.950439)
			(xy 408.724756 -49.95709) (xy 408.699462 -49.957482) (xy 408.698954 -49.957482) (xy 408.673105 -49.957056)
			(xy 408.621878 -49.950104) (xy 408.572048 -49.936333) (xy 408.52452 -49.915993) (xy 408.480156 -49.889452)
			(xy 408.459686 -49.873662) (xy 408.459432 -49.873408) (xy 408.452574 -49.868074) (xy 408.4447 -49.86528)
			(xy 408.440521 -49.863874) (xy 408.431836 -49.86235) (xy 408.427428 -49.862232) (xy 408.408124 -49.862232)
			(xy 408.402683 -49.862094) (xy 408.392048 -49.859794) (xy 408.387042 -49.85766) (xy 408.376882 -49.852834)
			(xy 408.370854 -49.850337) (xy 408.357996 -49.848144) (xy 408.351482 -49.848516) (xy 408.347828 -49.848952)
			(xy 408.34069 -49.850744) (xy 408.337258 -49.852072) (xy 408.330908 -49.854612) (xy 408.3092 -49.874565)
			(xy 408.260862 -49.908323) (xy 408.207957 -49.934347) (xy 408.151712 -49.952031) (xy 408.093434 -49.960966)
			(xy 408.063954 -49.961546) (xy 408.0637 -49.961546) (xy 408.036476 -49.961062) (xy 407.98257 -49.953394)
			(xy 407.930269 -49.938249) (xy 407.880606 -49.915928) (xy 407.834559 -49.886869) (xy 407.81351 -49.869598)
			(xy 407.80589 -49.863502) (xy 407.800302 -49.862232) (xy 407.773124 -49.862232) (xy 407.767683 -49.862094)
			(xy 407.757048 -49.859794) (xy 407.752042 -49.85766) (xy 407.741882 -49.852834) (xy 407.735854 -49.850337)
			(xy 407.722996 -49.848144) (xy 407.716482 -49.848516) (xy 407.712828 -49.848952) (xy 407.70569 -49.850744)
			(xy 407.702258 -49.852072) (xy 407.695908 -49.854612) (xy 407.6742 -49.874565) (xy 407.625862 -49.908323)
			(xy 407.572957 -49.934347) (xy 407.516712 -49.952031) (xy 407.458434 -49.960966) (xy 407.428954 -49.961546)
			(xy 407.4287 -49.961546) (xy 407.401476 -49.961062) (xy 407.34757 -49.953394) (xy 407.295269 -49.938249)
			(xy 407.245606 -49.915928) (xy 407.199559 -49.886869) (xy 407.17851 -49.869598) (xy 407.17089 -49.863502)
			(xy 407.165302 -49.862232) (xy 407.138124 -49.862232) (xy 407.132683 -49.862094) (xy 407.122048 -49.859794)
			(xy 407.117042 -49.85766) (xy 407.103072 -49.85131) (xy 407.093904 -49.847626) (xy 407.074183 -49.846789)
			(xy 407.055596 -49.853433) (xy 407.047954 -49.859692) (xy 407.03754 -49.868836) (xy 407.016921 -49.885263)
			(xy 406.972024 -49.912892) (xy 406.923757 -49.934092) (xy 406.873035 -49.94846) (xy 406.820821 -49.955724)
			(xy 406.794462 -49.956212) (xy 406.793954 -49.956212) (xy 406.766705 -49.955723) (xy 406.712761 -49.947961)
			(xy 406.660472 -49.932602) (xy 406.6109 -49.909958) (xy 406.565054 -49.88049) (xy 406.523869 -49.844798)
			(xy 406.488182 -49.803609) (xy 406.45872 -49.75776) (xy 406.436082 -49.708185) (xy 406.420729 -49.655894)
			(xy 406.412974 -49.601949) (xy 406.412974 -49.547451) (xy 406.420729 -49.493506) (xy 406.436082 -49.441215)
			(xy 406.45872 -49.39164) (xy 406.488182 -49.345791) (xy 406.523869 -49.304602) (xy 406.565054 -49.26891)
			(xy 406.6109 -49.239442) (xy 406.660472 -49.216798) (xy 406.712761 -49.201439) (xy 406.766705 -49.193677)
			(xy 406.793954 -49.193196) (xy 406.794208 -49.193196) (xy 406.81972 -49.193616) (xy 406.870291 -49.200403)
			(xy 406.919505 -49.213869) (xy 406.966487 -49.233773) (xy 407.010397 -49.259761) (xy 407.030682 -49.275238)
			(xy 407.036016 -49.279556) (xy 407.044398 -49.283112) (xy 407.046938 -49.284128) (xy 407.051057 -49.285517)
			(xy 407.059611 -49.28705) (xy 407.063956 -49.287176) (xy 407.084784 -49.287176) (xy 407.090225 -49.287314)
			(xy 407.100861 -49.289611) (xy 407.105866 -49.291748) (xy 407.119836 -49.298098) (xy 407.125926 -49.30061)
			(xy 407.138913 -49.302799) (xy 407.14549 -49.302416) (xy 407.155142 -49.300638) (xy 407.16454 -49.292256)
			(xy 407.165302 -49.291748) (xy 407.165556 -49.291494) (xy 407.166826 -49.290224) (xy 407.188377 -49.27109)
			(xy 407.236084 -49.238761) (xy 407.288058 -49.213865) (xy 407.343149 -49.196953) (xy 407.40014 -49.188399)
			(xy 407.428954 -49.187862) (xy 407.456123 -49.188323) (xy 407.509924 -49.195942) (xy 407.562123 -49.211037)
			(xy 407.611687 -49.233307) (xy 407.657636 -49.262313) (xy 407.678636 -49.279556) (xy 407.683716 -49.28362)
			(xy 407.686002 -49.285398) (xy 407.698702 -49.287176) (xy 407.719784 -49.287176) (xy 407.725225 -49.287314)
			(xy 407.735861 -49.289611) (xy 407.740866 -49.291748) (xy 407.754836 -49.298098) (xy 407.760926 -49.30061)
			(xy 407.773913 -49.302799) (xy 407.78049 -49.302416) (xy 407.790142 -49.300638) (xy 407.79954 -49.292256)
			(xy 407.800302 -49.291748) (xy 407.800556 -49.291494) (xy 407.801826 -49.290224) (xy 407.823377 -49.27109)
			(xy 407.871084 -49.238761) (xy 407.923058 -49.213865) (xy 407.978149 -49.196953) (xy 408.03514 -49.188399)
			(xy 408.063954 -49.187862) (xy 408.091123 -49.188323) (xy 408.144924 -49.195942) (xy 408.197123 -49.211037)
			(xy 408.246687 -49.233307) (xy 408.292636 -49.262313) (xy 408.313636 -49.279556) (xy 408.318716 -49.28362)
			(xy 408.321002 -49.285398) (xy 408.333702 -49.287176) (xy 408.355292 -49.287176) (xy 408.365452 -49.288192)
			(xy 408.371548 -49.289462) (xy 408.424634 -49.289462) (xy 408.429045 -49.289375) (xy 408.437733 -49.287845)
			(xy 408.441906 -49.286414) (xy 408.44978 -49.28362) (xy 408.45105 -49.282604) (xy 408.456638 -49.278032)
			(xy 408.477229 -49.261809) (xy 408.522005 -49.234547) (xy 408.570079 -49.213646) (xy 408.620555 -49.199496)
			(xy 408.672489 -49.192362) (xy 408.6987 -49.191926) (xy 408.699462 -49.191926) (xy 408.728166 -49.192433)
			(xy 408.78493 -49.201008) (xy 408.83977 -49.217986) (xy 408.865832 -49.230026) (xy 408.870912 -49.232566)
			(xy 408.87777 -49.234344) (xy 408.887979 -49.236309) (xy 408.908443 -49.232772) (xy 408.917394 -49.227486)
			(xy 408.95651 -49.202086) (xy 408.957018 -49.202086) (xy 408.983434 -49.18456) (xy 408.985974 -49.182782)
			(xy 408.995046 -49.175232) (xy 409.005656 -49.15418) (xy 409.006294 -49.142396) (xy 409.006294 -48.984408)
			(xy 409.006294 -48.982376) (xy 408.922982 -46.85284) (xy 408.922982 -46.8503) (xy 407.986484 -39.919656)
			(xy 407.982721 -39.890264) (xy 407.978274 -39.83117) (xy 407.977594 -39.801546) (xy 407.97226 -39.470076)
			(xy 407.96972 -39.4589) (xy 407.96718 -39.454074) (xy 407.947933 -39.414111) (xy 407.915792 -39.331433)
			(xy 407.891124 -39.246225) (xy 407.874127 -39.159162) (xy 407.864934 -39.070933) (xy 407.863802 -39.026592)
			(xy 407.857198 -38.60165) (xy 407.857198 -38.601396) (xy 407.855928 -38.55212) (xy 407.855928 -38.551358)
			(xy 407.856182 -38.531038) (xy 407.856182 -38.528498) (xy 407.855928 -38.516052) (xy 407.855928 -38.515544)
			(xy 407.856047 -38.495518) (xy 407.857699 -38.455501) (xy 407.85923 -38.435534) (xy 407.862954 -38.394527)
			(xy 407.876305 -38.31327) (xy 407.8859 -38.273228) (xy 407.886916 -38.269164) (xy 407.882344 -38.24097)
			(xy 407.880312 -38.228016) (xy 407.871168 -38.172136) (xy 407.865326 -38.13048) (xy 407.862078 -38.101252)
			(xy 407.858644 -38.042539) (xy 407.858468 -38.013132) (xy 407.858468 -37.991542) (xy 407.858468 -37.99078)
			(xy 407.858722 -37.981636) (xy 407.85796 -37.97681) (xy 407.852491 -37.941044) (xy 407.846133 -37.868963)
			(xy 407.84526 -37.832792) (xy 407.83764 -37.338254) (xy 407.83764 -37.321998) (xy 407.83764 -37.32149)
			(xy 407.838158 -37.275693) (xy 407.846553 -37.184484) (xy 407.863269 -37.094428) (xy 407.875232 -37.050218)
			(xy 407.876248 -37.046916) (xy 407.876248 -37.046662) (xy 407.878026 -37.040312) (xy 407.878788 -37.010594)
			(xy 407.878788 -37.010086) (xy 407.87955 -36.971478) (xy 407.879563 -36.967616) (xy 407.878547 -36.95996)
			(xy 407.877518 -36.956238) (xy 407.875994 -36.952428) (xy 407.875994 -36.952174) (xy 407.875232 -36.950142)
			(xy 407.872184 -36.943284) (xy 407.87193 -36.94303) (xy 407.87066 -36.939728) (xy 407.867612 -36.932108)
			(xy 407.84653 -36.908232) (xy 407.838402 -36.902644) (xy 407.81859 -36.892738) (xy 407.813265 -36.890272)
			(xy 407.801849 -36.88757) (xy 407.795984 -36.887404) (xy 407.781506 -36.887404) (xy 407.77668 -36.88842)
			(xy 407.775664 -36.888674) (xy 407.77414 -36.889182) (xy 407.744676 -36.894008) (xy 407.74366 -36.894008)
			(xy 407.733415 -36.895259) (xy 407.712829 -36.896781) (xy 407.702512 -36.897056) (xy 407.696162 -36.897056)
			(xy 407.668911 -36.896568) (xy 407.614965 -36.888807) (xy 407.562672 -36.873449) (xy 407.513097 -36.850806)
			(xy 407.467248 -36.82134) (xy 407.426058 -36.785649) (xy 407.390366 -36.74446) (xy 407.360898 -36.698612)
			(xy 407.338254 -36.649037) (xy 407.322895 -36.596745) (xy 407.315133 -36.542799) (xy 407.314654 -36.515548)
			(xy 407.315136 -36.488305) (xy 407.32288 -36.434372) (xy 407.338218 -36.38209) (xy 407.360837 -36.332521)
			(xy 407.390278 -36.286674) (xy 407.425941 -36.245482) (xy 407.467102 -36.209782) (xy 407.512922 -36.1803)
			(xy 407.562471 -36.157637) (xy 407.61474 -36.142252) (xy 407.668665 -36.13446) (xy 407.695908 -36.13404)
			(xy 407.709624 -36.13404) (xy 407.718903 -36.133632) (xy 407.736225 -36.126978) (xy 407.743406 -36.121086)
			(xy 407.746454 -36.118546) (xy 407.746962 -36.118038) (xy 407.795222 -36.074604) (xy 407.798784 -36.071257)
			(xy 407.804674 -36.063458) (xy 407.806906 -36.05911) (xy 407.811224 -36.05022) (xy 407.811986 -36.040568)
			(xy 407.812494 -36.03498) (xy 407.812748 -36.032186) (xy 407.813002 -36.03117) (xy 407.813256 -36.027614)
			(xy 407.81478 -36.013898) (xy 407.815034 -36.012628) (xy 407.815034 -36.01212) (xy 407.820085 -35.972628)
			(xy 407.835723 -35.894554) (xy 407.846276 -35.856164) (xy 407.85288 -35.834066) (xy 407.85288 -35.833558)
			(xy 407.858368 -35.816415) (xy 407.870436 -35.782497) (xy 407.87701 -35.76574) (xy 407.895044 -35.723068)
			(xy 407.897838 -35.71367) (xy 407.898092 -35.712908) (xy 407.900632 -35.701478) (xy 407.897584 -35.689794)
			(xy 407.889456 -35.658806) (xy 407.886154 -35.64636) (xy 407.872438 -35.595052) (xy 407.86939 -35.583622)
			(xy 407.861262 -35.554412) (xy 407.859169 -35.548418) (xy 407.852476 -35.537633) (xy 407.848054 -35.533076)
			(xy 407.839926 -35.526726) (xy 407.807922 -35.507168) (xy 407.807414 -35.507168) (xy 407.778204 -35.489642)
			(xy 407.769822 -35.485578) (xy 407.750772 -35.490404) (xy 407.712326 -35.499569) (xy 407.634351 -35.512517)
			(xy 407.555595 -35.519245) (xy 407.516076 -35.519868) (xy 407.503122 -35.519868) (xy 407.456726 -35.518988)
			(xy 407.364393 -35.509669) (xy 407.273326 -35.491806) (xy 407.184314 -35.465555) (xy 407.098127 -35.431144)
			(xy 407.015512 -35.38887) (xy 406.976072 -35.36442) (xy 406.971754 -35.365182) (xy 406.969722 -35.36569)
			(xy 406.953478 -35.368457) (xy 406.920666 -35.371506) (xy 406.90419 -35.371786) (xy 406.900888 -35.371786)
			(xy 406.873808 -35.371312) (xy 406.820193 -35.363652) (xy 406.7682 -35.348489) (xy 406.718873 -35.326126)
			(xy 406.673203 -35.297013) (xy 406.632109 -35.261736) (xy 406.596416 -35.221002) (xy 406.566841 -35.17563)
			(xy 406.543978 -35.126533) (xy 406.528287 -35.074697) (xy 406.520083 -35.021162) (xy 406.51938 -34.994088)
			(xy 406.51938 -34.990024) (xy 406.519889 -34.96277) (xy 406.52768 -34.908821) (xy 406.543051 -34.856524)
			(xy 406.553924 -34.831528) (xy 406.55621 -34.826448) (xy 406.557988 -34.81832) (xy 406.552664 -34.800887)
			(xy 406.543138 -34.765699) (xy 406.538938 -34.747962) (xy 406.53081 -34.709608) (xy 406.522557 -34.663251)
			(xy 406.513783 -34.569494) (xy 406.513284 -34.52241) (xy 406.513718 -34.479823) (xy 406.520957 -34.394958)
			(xy 406.535409 -34.31102) (xy 406.556968 -34.228621) (xy 406.585478 -34.148361) (xy 406.602692 -34.109406)
			(xy 406.605878 -34.100273) (xy 406.605882 -34.080945) (xy 406.602692 -34.071814) (xy 406.585482 -34.032858)
			(xy 406.556986 -33.952595) (xy 406.535432 -33.870195) (xy 406.520978 -33.786259) (xy 406.513729 -33.701396)
			(xy 406.513284 -33.65881) (xy 406.513284 -33.657794) (xy 406.513912 -33.607927) (xy 406.523919 -33.508696)
			(xy 406.54379 -33.410961) (xy 406.557988 -33.363154) (xy 406.556972 -33.358582) (xy 406.553416 -33.348168)
			(xy 406.549606 -33.339532) (xy 406.549606 -33.339278) (xy 406.547574 -33.333944) (xy 406.536652 -33.304226)
			(xy 406.536652 -33.303972) (xy 406.535636 -33.301178) (xy 406.535128 -33.299146) (xy 406.534874 -33.298384)
			(xy 406.534874 -33.29813) (xy 406.530015 -33.280914) (xy 406.523145 -33.245804) (xy 406.521158 -33.228026)
			(xy 406.51938 -33.1978) (xy 406.51938 -33.188402) (xy 406.519988 -33.161234) (xy 406.527952 -33.107481)
			(xy 406.543462 -33.055401) (xy 406.566204 -33.006048) (xy 406.59572 -32.960422) (xy 406.63141 -32.919445)
			(xy 406.672553 -32.883947) (xy 406.718317 -32.854646) (xy 406.767775 -32.832135) (xy 406.819927 -32.816869)
			(xy 406.873718 -32.809157) (xy 406.900888 -32.808672) (xy 406.90546 -32.808672) (xy 406.921553 -32.80901)
			(xy 406.953601 -32.812059) (xy 406.969468 -32.814768) (xy 406.976834 -32.816038) (xy 407.016175 -32.791746)
			(xy 407.09854 -32.749723) (xy 407.184443 -32.715505) (xy 407.273144 -32.689387) (xy 407.363883 -32.671594)
			(xy 407.455879 -32.662277) (xy 407.502106 -32.661352) (xy 407.514298 -32.661352) (xy 407.560916 -32.66208)
			(xy 407.653714 -32.671157) (xy 407.745259 -32.688856) (xy 407.834752 -32.715025) (xy 407.921412 -32.749434)
			(xy 408.004481 -32.791782) (xy 408.044142 -32.816292) (xy 408.050492 -32.815022) (xy 408.053286 -32.814514)
			(xy 408.053794 -32.814514) (xy 408.059636 -32.813498) (xy 408.061668 -32.81299) (xy 408.065732 -32.812482)
			(xy 408.066748 -32.812482) (xy 408.080827 -32.810534) (xy 408.109178 -32.808496) (xy 408.12339 -32.808418)
			(xy 408.125168 -32.808418) (xy 408.162252 -32.810704) (xy 408.181166 -32.81301) (xy 408.218446 -32.820901)
			(xy 408.236674 -32.826452) (xy 408.237182 -32.826452) (xy 408.23769 -32.826706) (xy 408.239976 -32.827468)
			(xy 408.244802 -32.828992) (xy 408.254708 -32.830262) (xy 408.263132 -32.830583) (xy 408.279462 -32.826437)
			(xy 408.286712 -32.822134) (xy 408.326082 -32.79394) (xy 408.32659 -32.79394) (xy 408.3558 -32.772604)
			(xy 408.3558 -32.77235) (xy 408.359334 -32.769605) (xy 408.365468 -32.763091) (xy 408.367992 -32.759396)
			(xy 408.367484 -32.741108) (xy 408.367484 -32.722312) (xy 408.367918 -32.679725) (xy 408.375157 -32.59486)
			(xy 408.389609 -32.510922) (xy 408.411168 -32.428523) (xy 408.439677 -32.348263) (xy 408.456892 -32.309308)
			(xy 408.460079 -32.300175) (xy 408.460083 -32.280847) (xy 408.456892 -32.271716) (xy 408.439682 -32.23276)
			(xy 408.411186 -32.152497) (xy 408.389632 -32.070097) (xy 408.375178 -31.986161) (xy 408.367928 -31.901298)
			(xy 408.367484 -31.858712) (xy 408.367992 -31.822136) (xy 408.368754 -31.803848) (xy 408.36977 -31.783782)
			(xy 408.362912 -31.775654) (xy 408.345386 -31.754826) (xy 408.336496 -31.750254) (xy 408.327352 -31.745428)
			(xy 408.31262 -31.738062) (xy 408.303476 -31.737046) (xy 408.29357 -31.735776) (xy 408.272234 -31.740348)
			(xy 408.26944 -31.741364) (xy 408.267408 -31.74238) (xy 408.244461 -31.751545) (xy 408.19679 -31.764548)
			(xy 408.147839 -31.771283) (xy 408.123136 -31.771844) (xy 408.11958 -31.771844) (xy 408.103305 -31.771663)
			(xy 408.070875 -31.768866) (xy 408.05481 -31.766256) (xy 408.044904 -31.764478) (xy 408.004918 -31.789197)
			(xy 407.921142 -31.83186) (xy 407.833725 -31.866453) (xy 407.743441 -31.892669) (xy 407.651091 -31.910277)
			(xy 407.557495 -31.919119) (xy 407.510488 -31.919672) (xy 407.50109 -31.919926) (xy 407.457156 -31.919023)
			(xy 407.369694 -31.910448) (xy 407.283326 -31.894211) (xy 407.198722 -31.870437) (xy 407.116537 -31.839312)
			(xy 407.037409 -31.801077) (xy 406.99944 -31.778956) (xy 406.995884 -31.77667) (xy 406.99071 -31.774405)
			(xy 406.979686 -31.771961) (xy 406.97404 -31.771844) (xy 406.900888 -31.771844) (xy 406.87374 -31.771365)
			(xy 406.819993 -31.763666) (xy 406.76788 -31.748425) (xy 406.718454 -31.725951) (xy 406.672714 -31.696697)
			(xy 406.631582 -31.661254) (xy 406.59589 -31.620337) (xy 406.56636 -31.574775) (xy 406.543587 -31.525486)
			(xy 406.528031 -31.473466) (xy 406.520007 -31.419767) (xy 406.51938 -31.392622) (xy 406.51938 -31.389828)
			(xy 406.519873 -31.361597) (xy 406.52816 -31.305748) (xy 406.544588 -31.251731) (xy 406.55621 -31.225998)
			(xy 406.557988 -31.218632) (xy 406.54395 -31.171265) (xy 406.524186 -31.074463) (xy 406.514072 -30.976183)
			(xy 406.513284 -30.926786) (xy 406.513284 -30.922468) (xy 406.51372 -30.879882) (xy 406.520962 -30.795018)
			(xy 406.535418 -30.711081) (xy 406.55698 -30.628683) (xy 406.585492 -30.548425) (xy 406.602692 -30.509464)
			(xy 406.605871 -30.500331) (xy 406.605859 -30.48101) (xy 406.602692 -30.471872) (xy 406.58548 -30.432916)
			(xy 406.556979 -30.352654) (xy 406.535421 -30.270254) (xy 406.520962 -30.186318) (xy 406.513707 -30.101454)
			(xy 406.513284 -30.058868) (xy 406.513284 -30.05836) (xy 406.513928 -30.008319) (xy 406.524003 -29.908744)
			(xy 406.543986 -29.810676) (xy 406.558242 -29.762704) (xy 406.556464 -29.755084) (xy 406.554178 -29.750258)
			(xy 406.543171 -29.725168) (xy 406.527662 -29.672621) (xy 406.519841 -29.618394) (xy 406.51938 -29.591)
			(xy 406.51938 -29.590238) (xy 406.51984 -29.562983) (xy 406.527593 -29.509027) (xy 406.542945 -29.456724)
			(xy 406.565586 -29.407138) (xy 406.595052 -29.36128) (xy 406.630746 -29.320081) (xy 406.67194 -29.284382)
			(xy 406.717794 -29.25491) (xy 406.767377 -29.232263) (xy 406.819678 -29.216903) (xy 406.873633 -29.209144)
			(xy 406.900888 -29.20873) (xy 406.901904 -29.20873) (xy 406.918756 -29.208892) (xy 406.952334 -29.211814)
			(xy 406.96896 -29.214572) (xy 406.977088 -29.216096) (xy 407.017015 -29.191466) (xy 407.100653 -29.148958)
			(xy 407.187909 -29.114486) (xy 407.278016 -29.088351) (xy 407.370176 -29.070786) (xy 407.463578 -29.061946)
			(xy 407.510488 -29.06141) (xy 407.510742 -29.06141) (xy 407.557652 -29.061962) (xy 407.651054 -29.070797)
			(xy 407.743216 -29.088356) (xy 407.833324 -29.114484) (xy 407.920583 -29.148951) (xy 408.004223 -29.191453)
			(xy 408.044142 -29.216096) (xy 408.045158 -29.215842) (xy 408.050238 -29.214826) (xy 408.052016 -29.214572)
			(xy 408.068893 -29.21177) (xy 408.102981 -29.208845) (xy 408.120088 -29.20873) (xy 408.12085 -29.20873)
			(xy 408.149292 -29.209313) (xy 408.205533 -29.217854) (xy 408.232864 -29.225748) (xy 408.24023 -29.228034)
			(xy 408.263344 -29.228034) (xy 408.269082 -29.227826) (xy 408.28024 -29.225131) (xy 408.285442 -29.2227)
			(xy 408.286712 -29.222192) (xy 408.287982 -29.22143) (xy 408.289252 -29.220668) (xy 408.291538 -29.219398)
			(xy 408.312874 -29.20365) (xy 408.313636 -29.203142) (xy 408.33675 -29.186378) (xy 408.354022 -29.173932)
			(xy 408.356054 -29.172408) (xy 408.35707 -29.171646) (xy 408.360234 -29.169016) (xy 408.365721 -29.162886)
			(xy 408.367992 -29.159454) (xy 408.367484 -29.137356) (xy 408.367484 -29.12237) (xy 408.36792 -29.079784)
			(xy 408.375162 -28.99492) (xy 408.389617 -28.910983) (xy 408.411179 -28.828585) (xy 408.439692 -28.748327)
			(xy 408.456892 -28.709366) (xy 408.460071 -28.700233) (xy 408.46006 -28.680911) (xy 408.456892 -28.671774)
			(xy 408.43968 -28.632818) (xy 408.411179 -28.552556) (xy 408.38962 -28.470156) (xy 408.375161 -28.38622)
			(xy 408.367906 -28.301356) (xy 408.367484 -28.25877) (xy 408.367972 -28.211623) (xy 408.376746 -28.117738)
			(xy 408.38501 -28.071318) (xy 408.388657 -28.052831) (xy 408.397168 -28.016118) (xy 408.402028 -27.997912)
			(xy 408.412188 -27.96286) (xy 408.412188 -27.962606) (xy 408.41041 -27.954224) (xy 408.408124 -27.949144)
			(xy 408.40787 -27.948636) (xy 408.397326 -27.924428) (xy 408.382268 -27.873818) (xy 408.374349 -27.821614)
			(xy 408.37358 -27.79522) (xy 408.37358 -27.789886) (xy 408.37408 -27.762644) (xy 408.381862 -27.708719)
			(xy 408.397235 -27.656449) (xy 408.419888 -27.606898) (xy 408.44936 -27.561074) (xy 408.485051 -27.519908)
			(xy 408.526236 -27.484239) (xy 408.572076 -27.454791) (xy 408.621639 -27.432164) (xy 408.673917 -27.416819)
			(xy 408.727846 -27.409066) (xy 408.755088 -27.408632) (xy 408.756358 -27.408632) (xy 408.770702 -27.408766)
			(xy 408.799307 -27.41093) (xy 408.813508 -27.41295) (xy 408.822285 -27.413864) (xy 408.839569 -27.410363)
			(xy 408.84729 -27.406092) (xy 408.883104 -27.385264) (xy 408.883612 -27.385264) (xy 408.896058 -27.378152)
			(xy 408.899868 -27.368754) (xy 408.91968 -27.295348) (xy 408.919426 -27.281632) (xy 408.917648 -27.275028)
			(xy 408.91333 -27.259534) (xy 408.910282 -27.2542) (xy 408.898587 -27.232664) (xy 408.880168 -27.187249)
			(xy 408.867708 -27.139852) (xy 408.86141 -27.091251) (xy 408.861006 -27.066748) (xy 408.861006 -27.057604)
			(xy 408.86126 -27.054048) (xy 408.86126 -27.053032) (xy 408.862784 -27.030172) (xy 408.865531 -27.005455)
			(xy 408.876625 -26.956977) (xy 408.893933 -26.910355) (xy 408.905202 -26.888186) (xy 408.907234 -26.884122)
			(xy 408.90825 -26.882344) (xy 408.909266 -26.880566) (xy 408.909266 -26.880312) (xy 408.916143 -26.868282)
			(xy 408.931397 -26.845144) (xy 408.939746 -26.834084) (xy 408.940254 -26.833576) (xy 408.95016 -26.821638)
			(xy 408.951176 -26.820114) (xy 408.952954 -26.817828) (xy 408.954478 -26.816304) (xy 408.968702 -26.80081)
			(xy 408.996896 -26.774394) (xy 408.99715 -26.77414) (xy 409.000706 -26.771346) (xy 409.004008 -26.768552)
			(xy 409.005024 -26.76779) (xy 409.00731 -26.766012) (xy 409.009342 -26.76398) (xy 409.011882 -26.761948)
			(xy 409.016708 -26.757122) (xy 409.021788 -26.751026) (xy 409.022042 -26.750772) (xy 409.02255 -26.75001)
			(xy 409.027444 -26.743401) (xy 409.03315 -26.727987) (xy 409.033726 -26.719784) (xy 409.033726 -26.71572)
			(xy 409.029154 -26.630884) (xy 409.028402 -26.625381) (xy 409.02481 -26.614872) (xy 409.022042 -26.610056)
			(xy 409.018994 -26.60523) (xy 409.01112 -26.596848) (xy 409.00477 -26.593038) (xy 408.981059 -26.578116)
			(xy 408.937879 -26.542422) (xy 408.90038 -26.5008) (xy 408.869367 -26.454144) (xy 408.845504 -26.403457)
			(xy 408.829306 -26.349827) (xy 408.821119 -26.294405) (xy 408.82062 -26.266394) (xy 408.821106 -26.239143)
			(xy 408.828862 -26.185195) (xy 408.844217 -26.1329) (xy 408.866859 -26.083323) (xy 408.896325 -26.037473)
			(xy 408.932016 -25.996282) (xy 408.973207 -25.960591) (xy 409.019057 -25.931125) (xy 409.068634 -25.908483)
			(xy 409.120929 -25.893128) (xy 409.174877 -25.885372) (xy 409.229379 -25.885372) (xy 409.283327 -25.893128)
			(xy 409.335622 -25.908483) (xy 409.385199 -25.931125) (xy 409.431049 -25.960591) (xy 409.47224 -25.996282)
			(xy 409.507931 -26.037473) (xy 409.537397 -26.083323) (xy 409.560039 -26.1329) (xy 409.575394 -26.185195)
			(xy 409.58315 -26.239143) (xy 409.583636 -26.266394) (xy 409.583106 -26.295249) (xy 409.574411 -26.3523)
			(xy 409.557219 -26.407389) (xy 409.531922 -26.459259) (xy 409.499098 -26.506725) (xy 409.459497 -26.548703)
			(xy 409.437078 -26.566876) (xy 409.43657 -26.567384) (xy 409.432252 -26.57094) (xy 409.424378 -26.580338)
			(xy 409.42387 -26.5811) (xy 409.417366 -26.589039) (xy 409.410696 -26.60843) (xy 409.410916 -26.618692)
			(xy 409.411932 -26.637742) (xy 409.411932 -26.63825) (xy 409.415488 -26.707592) (xy 409.42006 -26.717498)
			(xy 409.42514 -26.72715) (xy 409.434792 -26.736548) (xy 409.439364 -26.739596) (xy 409.441396 -26.740866)
			(xy 409.443174 -26.741882) (xy 409.445714 -26.743406) (xy 409.468664 -26.758413) (xy 409.510412 -26.793965)
			(xy 409.546643 -26.835125) (xy 409.576609 -26.881047) (xy 409.599696 -26.930785) (xy 409.615426 -26.983314)
			(xy 409.623477 -27.037555) (xy 409.624022 -27.06497) (xy 409.624022 -27.070558) (xy 409.623777 -27.084974)
			(xy 409.621366 -27.113708) (xy 409.619196 -27.127962) (xy 409.617672 -27.136344) (xy 409.615063 -27.149689)
			(xy 409.608196 -27.176002) (xy 409.603956 -27.188922) (xy 409.601741 -27.196294) (xy 409.601344 -27.211676)
			(xy 409.603194 -27.219148) (xy 409.603702 -27.220926) (xy 409.605226 -27.225244) (xy 409.606242 -27.22753)
			(xy 409.608274 -27.231594) (xy 409.630626 -27.276044) (xy 409.634436 -27.28341) (xy 409.640532 -27.295602)
			(xy 409.644342 -27.30119) (xy 409.644596 -27.301444) (xy 409.663646 -27.307286) (xy 409.700866 -27.319384)
			(xy 409.759103 -27.342846) (xy 416.823652 -27.342846) (xy 416.823652 -26.479246) (xy 416.824142 -26.449278)
			(xy 416.831965 -26.389856) (xy 416.847478 -26.331963) (xy 416.870414 -26.27659) (xy 416.900381 -26.224684)
			(xy 416.936868 -26.177134) (xy 416.979248 -26.134754) (xy 417.026798 -26.098267) (xy 417.078704 -26.0683)
			(xy 417.134077 -26.045364) (xy 417.19197 -26.029851) (xy 417.251392 -26.022028) (xy 417.311328 -26.022028)
			(xy 417.37075 -26.029851) (xy 417.428643 -26.045364) (xy 417.484016 -26.0683) (xy 417.535922 -26.098267)
			(xy 417.583472 -26.134754) (xy 417.625852 -26.177134) (xy 417.662339 -26.224684) (xy 417.692306 -26.27659)
			(xy 417.715242 -26.331963) (xy 417.722991 -26.360882) (xy 419.389558 -26.360882) (xy 419.393629 -26.30526)
			(xy 419.405755 -26.250823) (xy 419.425678 -26.198732) (xy 419.452974 -26.150097) (xy 419.48706 -26.105954)
			(xy 419.527209 -26.067245) (xy 419.572567 -26.034794) (xy 419.622167 -26.009293) (xy 419.674951 -25.991286)
			(xy 419.729794 -25.981156) (xy 419.785528 -25.979119) (xy 419.840965 -25.985219) (xy 419.894922 -25.999325)
			(xy 419.946251 -26.021137) (xy 419.993857 -26.050191) (xy 420.036725 -26.085866) (xy 420.073942 -26.127403)
			(xy 420.104715 -26.173916) (xy 420.128387 -26.224413) (xy 420.144455 -26.27782) (xy 420.150623 -26.319734)
			(xy 425.141896 -26.319734) (xy 425.145967 -26.264112) (xy 425.158093 -26.209675) (xy 425.178016 -26.157584)
			(xy 425.205312 -26.108949) (xy 425.239398 -26.064806) (xy 425.279547 -26.026097) (xy 425.324905 -25.993646)
			(xy 425.374505 -25.968145) (xy 425.427289 -25.950138) (xy 425.482132 -25.940008) (xy 425.537866 -25.937971)
			(xy 425.593303 -25.944071) (xy 425.64726 -25.958177) (xy 425.698589 -25.979989) (xy 425.746195 -26.009043)
			(xy 425.77586 -26.03373) (xy 431.567842 -26.03373) (xy 431.571913 -25.978108) (xy 431.584039 -25.923671)
			(xy 431.603962 -25.87158) (xy 431.631258 -25.822945) (xy 431.665344 -25.778802) (xy 431.705493 -25.740093)
			(xy 431.750851 -25.707642) (xy 431.800451 -25.682141) (xy 431.853235 -25.664134) (xy 431.908078 -25.654004)
			(xy 431.963812 -25.651967) (xy 432.019249 -25.658067) (xy 432.073206 -25.672173) (xy 432.124535 -25.693985)
			(xy 432.172141 -25.723039) (xy 432.215009 -25.758714) (xy 432.252226 -25.800251) (xy 432.282999 -25.846764)
			(xy 432.306671 -25.897261) (xy 432.322739 -25.950668) (xy 432.330859 -26.005844) (xy 432.331368 -26.03373)
			(xy 432.330859 -26.061616) (xy 432.322739 -26.116792) (xy 432.306671 -26.170199) (xy 432.282999 -26.220696)
			(xy 432.252226 -26.267209) (xy 432.215009 -26.308746) (xy 432.172141 -26.344421) (xy 432.124535 -26.373475)
			(xy 432.073206 -26.395287) (xy 432.019249 -26.409393) (xy 431.963812 -26.415493) (xy 431.908078 -26.413456)
			(xy 431.853235 -26.403326) (xy 431.800451 -26.385319) (xy 431.750851 -26.359818) (xy 431.705493 -26.327367)
			(xy 431.665344 -26.288658) (xy 431.631258 -26.244515) (xy 431.603962 -26.19588) (xy 431.584039 -26.143789)
			(xy 431.571913 -26.089352) (xy 431.567842 -26.03373) (xy 425.77586 -26.03373) (xy 425.789063 -26.044718)
			(xy 425.82628 -26.086255) (xy 425.857053 -26.132768) (xy 425.880725 -26.183265) (xy 425.896793 -26.236672)
			(xy 425.904913 -26.291848) (xy 425.905422 -26.319734) (xy 425.904913 -26.34762) (xy 425.896793 -26.402796)
			(xy 425.880725 -26.456203) (xy 425.857053 -26.5067) (xy 425.82628 -26.553213) (xy 425.789063 -26.59475)
			(xy 425.746195 -26.630425) (xy 425.698589 -26.659479) (xy 425.64726 -26.681291) (xy 425.593303 -26.695397)
			(xy 425.537866 -26.701497) (xy 425.482132 -26.69946) (xy 425.427289 -26.68933) (xy 425.374505 -26.671323)
			(xy 425.324905 -26.645822) (xy 425.279547 -26.613371) (xy 425.239398 -26.574662) (xy 425.205312 -26.530519)
			(xy 425.178016 -26.481884) (xy 425.158093 -26.429793) (xy 425.145967 -26.375356) (xy 425.141896 -26.319734)
			(xy 420.150623 -26.319734) (xy 420.152575 -26.332996) (xy 420.153084 -26.360882) (xy 420.152575 -26.388768)
			(xy 420.144455 -26.443944) (xy 420.128387 -26.497351) (xy 420.104715 -26.547848) (xy 420.073942 -26.594361)
			(xy 420.036725 -26.635898) (xy 419.993857 -26.671573) (xy 419.946251 -26.700627) (xy 419.894922 -26.722439)
			(xy 419.840965 -26.736545) (xy 419.785528 -26.742645) (xy 419.729794 -26.740608) (xy 419.674951 -26.730478)
			(xy 419.622167 -26.712471) (xy 419.572567 -26.68697) (xy 419.527209 -26.654519) (xy 419.48706 -26.61581)
			(xy 419.452974 -26.571667) (xy 419.425678 -26.523032) (xy 419.405755 -26.470941) (xy 419.393629 -26.416504)
			(xy 419.389558 -26.360882) (xy 417.722991 -26.360882) (xy 417.730755 -26.389856) (xy 417.738578 -26.449278)
			(xy 417.739068 -26.479246) (xy 417.739068 -26.971244) (xy 421.151048 -26.971244) (xy 421.155119 -26.915622)
			(xy 421.167245 -26.861185) (xy 421.187168 -26.809094) (xy 421.214464 -26.760459) (xy 421.24855 -26.716316)
			(xy 421.288699 -26.677607) (xy 421.334057 -26.645156) (xy 421.383657 -26.619655) (xy 421.436441 -26.601648)
			(xy 421.491284 -26.591518) (xy 421.547018 -26.589481) (xy 421.602455 -26.595581) (xy 421.656412 -26.609687)
			(xy 421.707741 -26.631499) (xy 421.755347 -26.660553) (xy 421.798215 -26.696228) (xy 421.835432 -26.737765)
			(xy 421.866205 -26.784278) (xy 421.889877 -26.834775) (xy 421.905945 -26.888182) (xy 421.914065 -26.943358)
			(xy 421.914574 -26.971244) (xy 421.914065 -26.99913) (xy 421.905945 -27.054306) (xy 421.889877 -27.107713)
			(xy 421.866205 -27.15821) (xy 421.835432 -27.204723) (xy 421.798215 -27.24626) (xy 421.755347 -27.281935)
			(xy 421.707741 -27.310989) (xy 421.656412 -27.332801) (xy 421.602455 -27.346907) (xy 421.547018 -27.353007)
			(xy 421.491284 -27.35097) (xy 421.436441 -27.34084) (xy 421.383657 -27.322833) (xy 421.334057 -27.297332)
			(xy 421.288699 -27.264881) (xy 421.24855 -27.226172) (xy 421.214464 -27.182029) (xy 421.187168 -27.133394)
			(xy 421.167245 -27.081303) (xy 421.155119 -27.026866) (xy 421.151048 -26.971244) (xy 417.739068 -26.971244)
			(xy 417.739068 -27.342846) (xy 417.738578 -27.372814) (xy 417.730755 -27.432236) (xy 417.715242 -27.490129)
			(xy 417.692306 -27.545502) (xy 417.662339 -27.597408) (xy 417.625852 -27.644958) (xy 417.583472 -27.687338)
			(xy 417.535922 -27.723825) (xy 417.484016 -27.753792) (xy 417.428643 -27.776728) (xy 417.37075 -27.792241)
			(xy 417.311328 -27.800064) (xy 417.251392 -27.800064) (xy 417.19197 -27.792241) (xy 417.134077 -27.776728)
			(xy 417.078704 -27.753792) (xy 417.026798 -27.723825) (xy 416.979248 -27.687338) (xy 416.936868 -27.644958)
			(xy 416.900381 -27.597408) (xy 416.870414 -27.545502) (xy 416.847478 -27.490129) (xy 416.831965 -27.432236)
			(xy 416.824142 -27.372814) (xy 416.823652 -27.342846) (xy 409.759103 -27.342846) (xy 409.773465 -27.348632)
			(xy 409.80868 -27.365706) (xy 409.826273 -27.37457) (xy 409.860827 -27.393498) (xy 409.877768 -27.403552)
			(xy 409.883539 -27.406841) (xy 409.89628 -27.410584) (xy 409.902914 -27.410918) (xy 409.909772 -27.410664)
			(xy 409.919457 -27.409655) (xy 409.938898 -27.408512) (xy 409.948634 -27.408378) (xy 409.949142 -27.408378)
			(xy 409.968192 -27.408886) (xy 409.977844 -27.409648) (xy 410.004853 -27.41218) (xy 410.057815 -27.423911)
			(xy 410.108582 -27.443024) (xy 410.156132 -27.469132) (xy 410.199506 -27.50171) (xy 410.23783 -27.540101)
			(xy 410.25445 -27.56154) (xy 410.256482 -27.56408) (xy 410.300879 -27.571473) (xy 410.388219 -27.593233)
			(xy 410.473245 -27.622772) (xy 410.555263 -27.659851) (xy 410.633608 -27.704168) (xy 410.707642 -27.755362)
			(xy 410.776763 -27.813018) (xy 410.808932 -27.844496) (xy 412.078908 -29.114242) (xy 419.147244 -29.114242)
			(xy 419.147244 -28.250642) (xy 419.147734 -28.220658) (xy 419.155562 -28.161202) (xy 419.171083 -28.103277)
			(xy 419.194032 -28.047873) (xy 419.224016 -27.995939) (xy 419.260522 -27.948363) (xy 419.302927 -27.905958)
			(xy 419.350503 -27.869452) (xy 419.402437 -27.839468) (xy 419.457841 -27.816519) (xy 419.515766 -27.800998)
			(xy 419.575222 -27.79317) (xy 419.63519 -27.79317) (xy 419.694646 -27.800998) (xy 419.752571 -27.816519)
			(xy 419.807975 -27.839468) (xy 419.859909 -27.869452) (xy 419.907485 -27.905958) (xy 419.94989 -27.948363)
			(xy 419.986396 -27.995939) (xy 420.01638 -28.047873) (xy 420.039329 -28.103277) (xy 420.05485 -28.161202)
			(xy 420.062678 -28.220658) (xy 420.063168 -28.250642) (xy 420.063168 -28.469082) (xy 424.05249 -28.469082)
			(xy 424.056561 -28.41346) (xy 424.068687 -28.359023) (xy 424.08861 -28.306932) (xy 424.115906 -28.258297)
			(xy 424.149992 -28.214154) (xy 424.190141 -28.175445) (xy 424.235499 -28.142994) (xy 424.285099 -28.117493)
			(xy 424.337883 -28.099486) (xy 424.392726 -28.089356) (xy 424.44846 -28.087319) (xy 424.503897 -28.093419)
			(xy 424.557854 -28.107525) (xy 424.609183 -28.129337) (xy 424.625239 -28.139136) (xy 428.697896 -28.139136)
			(xy 428.701967 -28.083514) (xy 428.714093 -28.029077) (xy 428.734016 -27.976986) (xy 428.761312 -27.928351)
			(xy 428.795398 -27.884208) (xy 428.835547 -27.845499) (xy 428.880905 -27.813048) (xy 428.930505 -27.787547)
			(xy 428.983289 -27.76954) (xy 429.038132 -27.75941) (xy 429.093866 -27.757373) (xy 429.149303 -27.763473)
			(xy 429.20326 -27.777579) (xy 429.254589 -27.799391) (xy 429.302195 -27.828445) (xy 429.345063 -27.86412)
			(xy 429.38228 -27.905657) (xy 429.413053 -27.95217) (xy 429.436725 -28.002667) (xy 429.452793 -28.056074)
			(xy 429.460913 -28.11125) (xy 429.461422 -28.139136) (xy 429.967896 -28.139136) (xy 429.971967 -28.083514)
			(xy 429.984093 -28.029077) (xy 430.004016 -27.976986) (xy 430.031312 -27.928351) (xy 430.065398 -27.884208)
			(xy 430.105547 -27.845499) (xy 430.150905 -27.813048) (xy 430.200505 -27.787547) (xy 430.253289 -27.76954)
			(xy 430.308132 -27.75941) (xy 430.363866 -27.757373) (xy 430.419303 -27.763473) (xy 430.47326 -27.777579)
			(xy 430.524589 -27.799391) (xy 430.572195 -27.828445) (xy 430.615063 -27.86412) (xy 430.65228 -27.905657)
			(xy 430.683053 -27.95217) (xy 430.706725 -28.002667) (xy 430.722793 -28.056074) (xy 430.730913 -28.11125)
			(xy 430.731422 -28.139136) (xy 430.730913 -28.167022) (xy 430.722793 -28.222198) (xy 430.706725 -28.275605)
			(xy 430.683053 -28.326102) (xy 430.65228 -28.372615) (xy 430.615063 -28.414152) (xy 430.572195 -28.449827)
			(xy 430.524589 -28.478881) (xy 430.47326 -28.500693) (xy 430.419303 -28.514799) (xy 430.363866 -28.520899)
			(xy 430.308132 -28.518862) (xy 430.253289 -28.508732) (xy 430.200505 -28.490725) (xy 430.150905 -28.465224)
			(xy 430.105547 -28.432773) (xy 430.065398 -28.394064) (xy 430.031312 -28.349921) (xy 430.004016 -28.301286)
			(xy 429.984093 -28.249195) (xy 429.971967 -28.194758) (xy 429.967896 -28.139136) (xy 429.461422 -28.139136)
			(xy 429.460913 -28.167022) (xy 429.452793 -28.222198) (xy 429.436725 -28.275605) (xy 429.413053 -28.326102)
			(xy 429.38228 -28.372615) (xy 429.345063 -28.414152) (xy 429.302195 -28.449827) (xy 429.254589 -28.478881)
			(xy 429.20326 -28.500693) (xy 429.149303 -28.514799) (xy 429.093866 -28.520899) (xy 429.038132 -28.518862)
			(xy 428.983289 -28.508732) (xy 428.930505 -28.490725) (xy 428.880905 -28.465224) (xy 428.835547 -28.432773)
			(xy 428.795398 -28.394064) (xy 428.761312 -28.349921) (xy 428.734016 -28.301286) (xy 428.714093 -28.249195)
			(xy 428.701967 -28.194758) (xy 428.697896 -28.139136) (xy 424.625239 -28.139136) (xy 424.656789 -28.158391)
			(xy 424.699657 -28.194066) (xy 424.736874 -28.235603) (xy 424.767647 -28.282116) (xy 424.791319 -28.332613)
			(xy 424.807387 -28.38602) (xy 424.815507 -28.441196) (xy 424.816016 -28.469082) (xy 424.815507 -28.496968)
			(xy 424.807387 -28.552144) (xy 424.791319 -28.605551) (xy 424.767647 -28.656048) (xy 424.736874 -28.702561)
			(xy 424.699657 -28.744098) (xy 424.656789 -28.779773) (xy 424.609183 -28.808827) (xy 424.557854 -28.830639)
			(xy 424.503897 -28.844745) (xy 424.44846 -28.850845) (xy 424.392726 -28.848808) (xy 424.337883 -28.838678)
			(xy 424.285099 -28.820671) (xy 424.235499 -28.79517) (xy 424.190141 -28.762719) (xy 424.149992 -28.72401)
			(xy 424.115906 -28.679867) (xy 424.08861 -28.631232) (xy 424.068687 -28.579141) (xy 424.056561 -28.524704)
			(xy 424.05249 -28.469082) (xy 420.063168 -28.469082) (xy 420.063168 -29.114242) (xy 420.062678 -29.144226)
			(xy 420.05485 -29.203682) (xy 420.039329 -29.261607) (xy 420.01638 -29.317011) (xy 419.986396 -29.368945)
			(xy 419.94989 -29.416521) (xy 419.907485 -29.458926) (xy 419.859909 -29.495432) (xy 419.807975 -29.525416)
			(xy 419.752571 -29.548365) (xy 419.694646 -29.563886) (xy 419.63519 -29.571714) (xy 419.575222 -29.571714)
			(xy 419.515766 -29.563886) (xy 419.457841 -29.548365) (xy 419.402437 -29.525416) (xy 419.350503 -29.495432)
			(xy 419.302927 -29.458926) (xy 419.260522 -29.416521) (xy 419.224016 -29.368945) (xy 419.194032 -29.317011)
			(xy 419.171083 -29.261607) (xy 419.155562 -29.203682) (xy 419.147734 -29.144226) (xy 419.147244 -29.114242)
			(xy 412.078908 -29.114242) (xy 412.211012 -29.246322) (xy 412.21406 -29.247846) (xy 412.217108 -29.24937)
			(xy 412.218124 -29.249878) (xy 412.244612 -29.263995) (xy 412.293172 -29.299268) (xy 412.335614 -29.341707)
			(xy 412.370891 -29.390265) (xy 412.385002 -29.416756) (xy 412.38551 -29.417772) (xy 412.387034 -29.42082)
			(xy 412.388558 -29.423868) (xy 412.507938 -29.543248) (xy 413.707834 -30.743398) (xy 413.732494 -30.768433)
			(xy 413.778639 -30.821441) (xy 413.800036 -30.849316) (xy 413.815186 -30.869693) (xy 413.843649 -30.911749)
			(xy 413.849137 -30.92069) (xy 421.789352 -30.92069) (xy 421.789352 -30.05709) (xy 421.789842 -30.027106)
			(xy 421.79767 -29.96765) (xy 421.813191 -29.909725) (xy 421.83614 -29.854321) (xy 421.866124 -29.802387)
			(xy 421.90263 -29.754811) (xy 421.945035 -29.712406) (xy 421.992611 -29.6759) (xy 422.044545 -29.645916)
			(xy 422.099949 -29.622967) (xy 422.157874 -29.607446) (xy 422.21733 -29.599618) (xy 422.277298 -29.599618)
			(xy 422.336754 -29.607446) (xy 422.394679 -29.622967) (xy 422.450083 -29.645916) (xy 422.502017 -29.6759)
			(xy 422.549593 -29.712406) (xy 422.591998 -29.754811) (xy 422.628504 -29.802387) (xy 422.658488 -29.854321)
			(xy 422.681437 -29.909725) (xy 422.696958 -29.96765) (xy 422.704786 -30.027106) (xy 422.705276 -30.05709)
			(xy 422.705276 -30.376876) (xy 427.188884 -30.376876) (xy 427.189425 -30.34796) (xy 427.198145 -30.290788)
			(xy 427.215396 -30.235588) (xy 427.240784 -30.183626) (xy 427.273725 -30.136092) (xy 427.313465 -30.094076)
			(xy 427.33595 -30.075886) (xy 427.344762 -30.068284) (xy 427.354941 -30.047379) (xy 427.355508 -30.035754)
			(xy 427.355508 -29.955998) (xy 427.354953 -29.944368) (xy 427.344775 -29.923459) (xy 427.33595 -29.915866)
			(xy 427.31344 -29.897707) (xy 427.273709 -29.855679) (xy 427.240774 -29.808137) (xy 427.215391 -29.75617)
			(xy 427.19814 -29.700967) (xy 427.189416 -29.643794) (xy 427.188884 -29.614876) (xy 427.18937 -29.587625)
			(xy 427.197126 -29.533677) (xy 427.212481 -29.481382) (xy 427.235123 -29.431805) (xy 427.264589 -29.385955)
			(xy 427.30028 -29.344764) (xy 427.341471 -29.309073) (xy 427.387321 -29.279607) (xy 427.436898 -29.256965)
			(xy 427.489193 -29.24161) (xy 427.543141 -29.233854) (xy 427.597643 -29.233854) (xy 427.651591 -29.24161)
			(xy 427.703886 -29.256965) (xy 427.753463 -29.279607) (xy 427.799313 -29.309073) (xy 427.840504 -29.344764)
			(xy 427.876195 -29.385955) (xy 427.905661 -29.431805) (xy 427.928303 -29.481382) (xy 427.943658 -29.533677)
			(xy 427.951414 -29.587625) (xy 427.9519 -29.614876) (xy 427.951364 -29.643792) (xy 427.942639 -29.700963)
			(xy 427.925384 -29.756161) (xy 427.899996 -29.808123) (xy 427.867056 -29.855657) (xy 427.827318 -29.897675)
			(xy 427.804834 -29.915866) (xy 427.796041 -29.923486) (xy 427.785852 -29.944378) (xy 427.785276 -29.955998)
			(xy 427.785276 -30.035754) (xy 427.785772 -30.047392) (xy 427.795988 -30.068303) (xy 427.804834 -30.075886)
			(xy 427.827318 -30.094076) (xy 427.867051 -30.136097) (xy 427.899989 -30.183633) (xy 427.925377 -30.235594)
			(xy 427.942634 -30.290791) (xy 427.951364 -30.34796) (xy 427.9519 -30.376876) (xy 430.22901 -30.376876)
			(xy 430.229579 -30.347961) (xy 430.238297 -30.290792) (xy 430.255545 -30.235594) (xy 430.280927 -30.183632)
			(xy 430.313861 -30.136097) (xy 430.353594 -30.094078) (xy 430.376076 -30.075886) (xy 430.384892 -30.068288)
			(xy 430.395068 -30.04738) (xy 430.395634 -30.035754) (xy 430.395634 -29.955998) (xy 430.395105 -29.944364)
			(xy 430.384912 -29.923453) (xy 430.376076 -29.915866) (xy 430.353571 -29.8977) (xy 430.313838 -29.855675)
			(xy 430.280903 -29.808134) (xy 430.255518 -29.756168) (xy 430.238266 -29.700966) (xy 430.229542 -29.643793)
			(xy 430.22901 -29.614876) (xy 430.229496 -29.587625) (xy 430.237252 -29.533677) (xy 430.252607 -29.481382)
			(xy 430.275249 -29.431805) (xy 430.304715 -29.385955) (xy 430.340406 -29.344764) (xy 430.381597 -29.309073)
			(xy 430.427447 -29.279607) (xy 430.477024 -29.256965) (xy 430.529319 -29.24161) (xy 430.583267 -29.233854)
			(xy 430.637769 -29.233854) (xy 430.691717 -29.24161) (xy 430.744012 -29.256965) (xy 430.793589 -29.279607)
			(xy 430.839439 -29.309073) (xy 430.88063 -29.344764) (xy 430.916321 -29.385955) (xy 430.945787 -29.431805)
			(xy 430.968429 -29.481382) (xy 430.983784 -29.533677) (xy 430.99154 -29.587625) (xy 430.992026 -29.614876)
			(xy 430.991519 -29.643794) (xy 430.982791 -29.700967) (xy 430.965533 -29.756167) (xy 430.94014 -29.808129)
			(xy 430.907193 -29.855663) (xy 430.867448 -29.897678) (xy 430.84496 -29.915866) (xy 430.836172 -29.923491)
			(xy 430.825979 -29.944378) (xy 430.825402 -29.955998) (xy 430.825402 -30.035754) (xy 430.825924 -30.047388)
			(xy 430.836125 -30.068297) (xy 430.84496 -30.075886) (xy 430.867428 -30.094095) (xy 430.907166 -30.13611)
			(xy 430.940108 -30.183641) (xy 430.9655 -30.235599) (xy 430.982759 -30.290793) (xy 430.99149 -30.347961)
			(xy 430.992026 -30.376876) (xy 430.99154 -30.404127) (xy 430.983784 -30.458075) (xy 430.968429 -30.51037)
			(xy 430.945787 -30.559947) (xy 430.916321 -30.605797) (xy 430.88063 -30.646988) (xy 430.839439 -30.682679)
			(xy 430.793589 -30.712145) (xy 430.744012 -30.734787) (xy 430.691717 -30.750142) (xy 430.637769 -30.757898)
			(xy 430.583267 -30.757898) (xy 430.529319 -30.750142) (xy 430.477024 -30.734787) (xy 430.427447 -30.712145)
			(xy 430.381597 -30.682679) (xy 430.340406 -30.646988) (xy 430.304715 -30.605797) (xy 430.275249 -30.559947)
			(xy 430.252607 -30.51037) (xy 430.237252 -30.458075) (xy 430.229496 -30.404127) (xy 430.22901 -30.376876)
			(xy 427.9519 -30.376876) (xy 427.951414 -30.404127) (xy 427.943658 -30.458075) (xy 427.928303 -30.51037)
			(xy 427.905661 -30.559947) (xy 427.876195 -30.605797) (xy 427.840504 -30.646988) (xy 427.799313 -30.682679)
			(xy 427.753463 -30.712145) (xy 427.703886 -30.734787) (xy 427.651591 -30.750142) (xy 427.597643 -30.757898)
			(xy 427.543141 -30.757898) (xy 427.489193 -30.750142) (xy 427.436898 -30.734787) (xy 427.387321 -30.712145)
			(xy 427.341471 -30.682679) (xy 427.30028 -30.646988) (xy 427.264589 -30.605797) (xy 427.235123 -30.559947)
			(xy 427.212481 -30.51037) (xy 427.197126 -30.458075) (xy 427.18937 -30.404127) (xy 427.188884 -30.376876)
			(xy 422.705276 -30.376876) (xy 422.705276 -30.92069) (xy 422.704786 -30.950674) (xy 422.696958 -31.01013)
			(xy 422.681437 -31.068055) (xy 422.658488 -31.123459) (xy 422.628504 -31.175393) (xy 422.591998 -31.222969)
			(xy 422.549593 -31.265374) (xy 422.502017 -31.30188) (xy 422.450083 -31.331864) (xy 422.394679 -31.354813)
			(xy 422.336754 -31.370334) (xy 422.277298 -31.378162) (xy 422.21733 -31.378162) (xy 422.157874 -31.370334)
			(xy 422.099949 -31.354813) (xy 422.044545 -31.331864) (xy 421.992611 -31.30188) (xy 421.945035 -31.265374)
			(xy 421.90263 -31.222969) (xy 421.866124 -31.175393) (xy 421.83614 -31.123459) (xy 421.813191 -31.068055)
			(xy 421.79767 -31.01013) (xy 421.789842 -30.950674) (xy 421.789352 -30.92069) (xy 413.849137 -30.92069)
			(xy 413.856932 -30.93339) (xy 413.857948 -30.935168) (xy 413.864044 -30.94355) (xy 413.877881 -30.958748)
			(xy 413.904432 -30.990127) (xy 413.91713 -31.006288) (xy 413.930233 -31.023208) (xy 413.955133 -31.058018)
			(xy 413.966914 -31.075884) (xy 413.983424 -31.1023) (xy 413.98444 -31.104332) (xy 413.985964 -31.106618)
			(xy 413.99206 -31.116778) (xy 414.000188 -31.130748) (xy 414.000188 -31.131002) (xy 414.006284 -31.142178)
			(xy 414.0073 -31.14421) (xy 414.019256 -31.166691) (xy 414.04111 -31.212689) (xy 414.050988 -31.236158)
			(xy 414.656778 -32.69869) (xy 414.663231 -32.714184) (xy 419.147244 -32.714184) (xy 419.147244 -31.850584)
			(xy 419.147734 -31.8206) (xy 419.155562 -31.761144) (xy 419.171083 -31.703219) (xy 419.194032 -31.647815)
			(xy 419.224016 -31.595881) (xy 419.260522 -31.548305) (xy 419.302927 -31.5059) (xy 419.350503 -31.469394)
			(xy 419.402437 -31.43941) (xy 419.457841 -31.416461) (xy 419.515766 -31.40094) (xy 419.575222 -31.393112)
			(xy 419.63519 -31.393112) (xy 419.694646 -31.40094) (xy 419.752571 -31.416461) (xy 419.807975 -31.43941)
			(xy 419.859909 -31.469394) (xy 419.907485 -31.5059) (xy 419.94989 -31.548305) (xy 419.964912 -31.567882)
			(xy 427.29861 -31.567882) (xy 427.302681 -31.51226) (xy 427.314807 -31.457823) (xy 427.33473 -31.405732)
			(xy 427.362026 -31.357097) (xy 427.396112 -31.312954) (xy 427.436261 -31.274245) (xy 427.481619 -31.241794)
			(xy 427.531219 -31.216293) (xy 427.584003 -31.198286) (xy 427.638846 -31.188156) (xy 427.69458 -31.186119)
			(xy 427.750017 -31.192219) (xy 427.803974 -31.206325) (xy 427.855303 -31.228137) (xy 427.902909 -31.257191)
			(xy 427.945777 -31.292866) (xy 427.982994 -31.334403) (xy 428.013767 -31.380916) (xy 428.037439 -31.431413)
			(xy 428.053507 -31.48482) (xy 428.061627 -31.539996) (xy 428.062136 -31.567882) (xy 428.061627 -31.595768)
			(xy 428.053507 -31.650944) (xy 428.037439 -31.704351) (xy 428.030447 -31.719266) (xy 428.585374 -31.719266)
			(xy 428.589445 -31.663644) (xy 428.601571 -31.609207) (xy 428.621494 -31.557116) (xy 428.64879 -31.508481)
			(xy 428.682876 -31.464338) (xy 428.723025 -31.425629) (xy 428.768383 -31.393178) (xy 428.817983 -31.367677)
			(xy 428.870767 -31.34967) (xy 428.92561 -31.33954) (xy 428.981344 -31.337503) (xy 429.036781 -31.343603)
			(xy 429.090738 -31.357709) (xy 429.142067 -31.379521) (xy 429.189673 -31.408575) (xy 429.232541 -31.44425)
			(xy 429.269758 -31.485787) (xy 429.300531 -31.5323) (xy 429.324203 -31.582797) (xy 429.340271 -31.636204)
			(xy 429.344421 -31.664402) (xy 429.860962 -31.664402) (xy 429.865033 -31.60878) (xy 429.877159 -31.554343)
			(xy 429.897082 -31.502252) (xy 429.924378 -31.453617) (xy 429.958464 -31.409474) (xy 429.998613 -31.370765)
			(xy 430.043971 -31.338314) (xy 430.093571 -31.312813) (xy 430.146355 -31.294806) (xy 430.201198 -31.284676)
			(xy 430.256932 -31.282639) (xy 430.312369 -31.288739) (xy 430.366326 -31.302845) (xy 430.417655 -31.324657)
			(xy 430.465261 -31.353711) (xy 430.508129 -31.389386) (xy 430.545346 -31.430923) (xy 430.576119 -31.477436)
			(xy 430.599791 -31.527933) (xy 430.615859 -31.58134) (xy 430.623979 -31.636516) (xy 430.624488 -31.664402)
			(xy 430.623979 -31.692288) (xy 430.615859 -31.747464) (xy 430.606919 -31.777178) (xy 431.126136 -31.777178)
			(xy 431.130207 -31.721556) (xy 431.142333 -31.667119) (xy 431.162256 -31.615028) (xy 431.189552 -31.566393)
			(xy 431.223638 -31.52225) (xy 431.263787 -31.483541) (xy 431.309145 -31.45109) (xy 431.358745 -31.425589)
			(xy 431.411529 -31.407582) (xy 431.466372 -31.397452) (xy 431.522106 -31.395415) (xy 431.577543 -31.401515)
			(xy 431.6315 -31.415621) (xy 431.682829 -31.437433) (xy 431.730435 -31.466487) (xy 431.773303 -31.502162)
			(xy 431.81052 -31.543699) (xy 431.841293 -31.590212) (xy 431.864965 -31.640709) (xy 431.881033 -31.694116)
			(xy 431.889153 -31.749292) (xy 431.889662 -31.777178) (xy 431.889153 -31.805064) (xy 431.881033 -31.86024)
			(xy 431.864965 -31.913647) (xy 431.841293 -31.964144) (xy 431.81052 -32.010657) (xy 431.773303 -32.052194)
			(xy 431.730435 -32.087869) (xy 431.682829 -32.116923) (xy 431.6315 -32.138735) (xy 431.577543 -32.152841)
			(xy 431.522106 -32.158941) (xy 431.466372 -32.156904) (xy 431.411529 -32.146774) (xy 431.358745 -32.128767)
			(xy 431.309145 -32.103266) (xy 431.263787 -32.070815) (xy 431.223638 -32.032106) (xy 431.189552 -31.987963)
			(xy 431.162256 -31.939328) (xy 431.142333 -31.887237) (xy 431.130207 -31.8328) (xy 431.126136 -31.777178)
			(xy 430.606919 -31.777178) (xy 430.599791 -31.800871) (xy 430.576119 -31.851368) (xy 430.545346 -31.897881)
			(xy 430.508129 -31.939418) (xy 430.465261 -31.975093) (xy 430.417655 -32.004147) (xy 430.366326 -32.025959)
			(xy 430.312369 -32.040065) (xy 430.256932 -32.046165) (xy 430.201198 -32.044128) (xy 430.146355 -32.033998)
			(xy 430.093571 -32.015991) (xy 430.043971 -31.99049) (xy 429.998613 -31.958039) (xy 429.958464 -31.91933)
			(xy 429.924378 -31.875187) (xy 429.897082 -31.826552) (xy 429.877159 -31.774461) (xy 429.865033 -31.720024)
			(xy 429.860962 -31.664402) (xy 429.344421 -31.664402) (xy 429.348391 -31.69138) (xy 429.3489 -31.719266)
			(xy 429.348391 -31.747152) (xy 429.340271 -31.802328) (xy 429.324203 -31.855735) (xy 429.300531 -31.906232)
			(xy 429.269758 -31.952745) (xy 429.232541 -31.994282) (xy 429.189673 -32.029957) (xy 429.142067 -32.059011)
			(xy 429.090738 -32.080823) (xy 429.036781 -32.094929) (xy 428.981344 -32.101029) (xy 428.92561 -32.098992)
			(xy 428.870767 -32.088862) (xy 428.817983 -32.070855) (xy 428.768383 -32.045354) (xy 428.723025 -32.012903)
			(xy 428.682876 -31.974194) (xy 428.64879 -31.930051) (xy 428.621494 -31.881416) (xy 428.601571 -31.829325)
			(xy 428.589445 -31.774888) (xy 428.585374 -31.719266) (xy 428.030447 -31.719266) (xy 428.013767 -31.754848)
			(xy 427.982994 -31.801361) (xy 427.945777 -31.842898) (xy 427.902909 -31.878573) (xy 427.855303 -31.907627)
			(xy 427.803974 -31.929439) (xy 427.750017 -31.943545) (xy 427.69458 -31.949645) (xy 427.638846 -31.947608)
			(xy 427.584003 -31.937478) (xy 427.531219 -31.919471) (xy 427.481619 -31.89397) (xy 427.436261 -31.861519)
			(xy 427.396112 -31.82281) (xy 427.362026 -31.778667) (xy 427.33473 -31.730032) (xy 427.314807 -31.677941)
			(xy 427.302681 -31.623504) (xy 427.29861 -31.567882) (xy 419.964912 -31.567882) (xy 419.986396 -31.595881)
			(xy 420.01638 -31.647815) (xy 420.039329 -31.703219) (xy 420.05485 -31.761144) (xy 420.062678 -31.8206)
			(xy 420.063168 -31.850584) (xy 420.063168 -32.714184) (xy 420.062678 -32.744168) (xy 420.05485 -32.803624)
			(xy 420.039329 -32.861549) (xy 420.01638 -32.916953) (xy 419.986396 -32.968887) (xy 419.94989 -33.016463)
			(xy 419.907485 -33.058868) (xy 419.859909 -33.095374) (xy 419.807975 -33.125358) (xy 419.752571 -33.148307)
			(xy 419.694646 -33.163828) (xy 419.63519 -33.171656) (xy 419.575222 -33.171656) (xy 419.515766 -33.163828)
			(xy 419.457841 -33.148307) (xy 419.402437 -33.125358) (xy 419.350503 -33.095374) (xy 419.302927 -33.058868)
			(xy 419.260522 -33.016463) (xy 419.224016 -32.968887) (xy 419.194032 -32.916953) (xy 419.171083 -32.861549)
			(xy 419.155562 -32.803624) (xy 419.147734 -32.744168) (xy 419.147244 -32.714184) (xy 414.663231 -32.714184)
			(xy 414.700466 -32.803592) (xy 414.700466 -32.8041) (xy 414.714182 -32.836104) (xy 414.721294 -32.846518)
			(xy 414.726374 -32.85236) (xy 414.734502 -32.856932) (xy 414.759543 -32.871501) (xy 414.805303 -32.907026)
			(xy 414.845167 -32.949061) (xy 414.878217 -32.996639) (xy 414.903694 -33.048667) (xy 414.921013 -33.103949)
			(xy 414.929774 -33.161214) (xy 414.930336 -33.19018) (xy 414.930024 -33.216082) (xy 414.923274 -33.267441)
			(xy 414.916874 -33.292542) (xy 414.915604 -33.297114) (xy 414.914842 -33.306004) (xy 414.914842 -33.306766)
			(xy 414.913826 -33.318704) (xy 415.022792 -33.581594) (xy 415.411714 -34.520886) (xy 421.789352 -34.520886)
			(xy 421.789352 -33.657286) (xy 421.789842 -33.627302) (xy 421.79767 -33.567846) (xy 421.813191 -33.509921)
			(xy 421.83614 -33.454517) (xy 421.866124 -33.402583) (xy 421.90263 -33.355007) (xy 421.945035 -33.312602)
			(xy 421.992611 -33.276096) (xy 422.044545 -33.246112) (xy 422.099949 -33.223163) (xy 422.157874 -33.207642)
			(xy 422.21733 -33.199814) (xy 422.277298 -33.199814) (xy 422.336754 -33.207642) (xy 422.394679 -33.223163)
			(xy 422.450083 -33.246112) (xy 422.502017 -33.276096) (xy 422.549593 -33.312602) (xy 422.591998 -33.355007)
			(xy 422.628504 -33.402583) (xy 422.658488 -33.454517) (xy 422.681437 -33.509921) (xy 422.696958 -33.567846)
			(xy 422.704786 -33.627302) (xy 422.705276 -33.657286) (xy 422.705276 -34.520886) (xy 422.704786 -34.55087)
			(xy 422.696958 -34.610326) (xy 422.681437 -34.668251) (xy 422.658488 -34.723655) (xy 422.628504 -34.775589)
			(xy 422.591998 -34.823165) (xy 422.549593 -34.86557) (xy 422.502017 -34.902076) (xy 422.450083 -34.93206)
			(xy 422.394679 -34.955009) (xy 422.336754 -34.97053) (xy 422.277298 -34.978358) (xy 422.21733 -34.978358)
			(xy 422.157874 -34.97053) (xy 422.099949 -34.955009) (xy 422.044545 -34.93206) (xy 421.992611 -34.902076)
			(xy 421.945035 -34.86557) (xy 421.90263 -34.823165) (xy 421.866124 -34.775589) (xy 421.83614 -34.723655)
			(xy 421.813191 -34.668251) (xy 421.79767 -34.610326) (xy 421.789842 -34.55087) (xy 421.789352 -34.520886)
			(xy 415.411714 -34.520886) (xy 415.432748 -34.571686) (xy 415.719884 -35.264852) (xy 430.202338 -35.264852)
			(xy 430.206409 -35.20923) (xy 430.218535 -35.154793) (xy 430.238458 -35.102702) (xy 430.265754 -35.054067)
			(xy 430.29984 -35.009924) (xy 430.339989 -34.971215) (xy 430.385347 -34.938764) (xy 430.434947 -34.913263)
			(xy 430.487731 -34.895256) (xy 430.542574 -34.885126) (xy 430.598308 -34.883089) (xy 430.653745 -34.889189)
			(xy 430.707702 -34.903295) (xy 430.759031 -34.925107) (xy 430.806637 -34.954161) (xy 430.849505 -34.989836)
			(xy 430.886722 -35.031373) (xy 430.917495 -35.077886) (xy 430.941167 -35.128383) (xy 430.957235 -35.18179)
			(xy 430.965355 -35.236966) (xy 430.965864 -35.264852) (xy 430.965355 -35.292738) (xy 430.957235 -35.347914)
			(xy 430.941167 -35.401321) (xy 430.917495 -35.451818) (xy 430.886722 -35.498331) (xy 430.849505 -35.539868)
			(xy 430.806637 -35.575543) (xy 430.759031 -35.604597) (xy 430.707702 -35.626409) (xy 430.653745 -35.640515)
			(xy 430.598308 -35.646615) (xy 430.542574 -35.644578) (xy 430.487731 -35.634448) (xy 430.434947 -35.616441)
			(xy 430.385347 -35.59094) (xy 430.339989 -35.558489) (xy 430.29984 -35.51978) (xy 430.265754 -35.475637)
			(xy 430.238458 -35.427002) (xy 430.218535 -35.374911) (xy 430.206409 -35.320474) (xy 430.202338 -35.264852)
			(xy 415.719884 -35.264852) (xy 415.97335 -35.876738) (xy 419.017194 -35.876738) (xy 419.021265 -35.821116)
			(xy 419.033391 -35.766679) (xy 419.053314 -35.714588) (xy 419.08061 -35.665953) (xy 419.114696 -35.62181)
			(xy 419.154845 -35.583101) (xy 419.200203 -35.55065) (xy 419.249803 -35.525149) (xy 419.302587 -35.507142)
			(xy 419.35743 -35.497012) (xy 419.413164 -35.494975) (xy 419.468601 -35.501075) (xy 419.522558 -35.515181)
			(xy 419.573887 -35.536993) (xy 419.621493 -35.566047) (xy 419.664361 -35.601722) (xy 419.701578 -35.643259)
			(xy 419.732351 -35.689772) (xy 419.756023 -35.740269) (xy 419.772091 -35.793676) (xy 419.780211 -35.848852)
			(xy 419.78072 -35.876738) (xy 423.088814 -35.876738) (xy 423.092885 -35.821116) (xy 423.105011 -35.766679)
			(xy 423.124934 -35.714588) (xy 423.15223 -35.665953) (xy 423.186316 -35.62181) (xy 423.226465 -35.583101)
			(xy 423.271823 -35.55065) (xy 423.321423 -35.525149) (xy 423.374207 -35.507142) (xy 423.42905 -35.497012)
			(xy 423.484784 -35.494975) (xy 423.540221 -35.501075) (xy 423.594178 -35.515181) (xy 423.645507 -35.536993)
			(xy 423.693113 -35.566047) (xy 423.735981 -35.601722) (xy 423.773198 -35.643259) (xy 423.803971 -35.689772)
			(xy 423.827643 -35.740269) (xy 423.843711 -35.793676) (xy 423.851831 -35.848852) (xy 423.85234 -35.876738)
			(xy 423.851831 -35.904624) (xy 423.843711 -35.9598) (xy 423.827643 -36.013207) (xy 423.803971 -36.063704)
			(xy 423.773198 -36.110217) (xy 423.735981 -36.151754) (xy 423.693113 -36.187429) (xy 423.645507 -36.216483)
			(xy 423.594178 -36.238295) (xy 423.540221 -36.252401) (xy 423.484784 -36.258501) (xy 423.42905 -36.256464)
			(xy 423.374207 -36.246334) (xy 423.321423 -36.228327) (xy 423.271823 -36.202826) (xy 423.226465 -36.170375)
			(xy 423.186316 -36.131666) (xy 423.15223 -36.087523) (xy 423.124934 -36.038888) (xy 423.105011 -35.986797)
			(xy 423.092885 -35.93236) (xy 423.088814 -35.876738) (xy 419.78072 -35.876738) (xy 419.780211 -35.904624)
			(xy 419.772091 -35.9598) (xy 419.756023 -36.013207) (xy 419.732351 -36.063704) (xy 419.701578 -36.110217)
			(xy 419.664361 -36.151754) (xy 419.621493 -36.187429) (xy 419.573887 -36.216483) (xy 419.522558 -36.238295)
			(xy 419.468601 -36.252401) (xy 419.413164 -36.258501) (xy 419.35743 -36.256464) (xy 419.302587 -36.246334)
			(xy 419.249803 -36.228327) (xy 419.200203 -36.202826) (xy 419.154845 -36.170375) (xy 419.114696 -36.131666)
			(xy 419.08061 -36.087523) (xy 419.053314 -36.038888) (xy 419.033391 -35.986797) (xy 419.021265 -35.93236)
			(xy 419.017194 -35.876738) (xy 415.97335 -35.876738) (xy 416.235655 -36.50996) (xy 420.913812 -36.50996)
			(xy 420.917883 -36.454338) (xy 420.930009 -36.399901) (xy 420.949932 -36.34781) (xy 420.977228 -36.299175)
			(xy 421.011314 -36.255032) (xy 421.051463 -36.216323) (xy 421.096821 -36.183872) (xy 421.146421 -36.158371)
			(xy 421.199205 -36.140364) (xy 421.254048 -36.130234) (xy 421.309782 -36.128197) (xy 421.365219 -36.134297)
			(xy 421.419176 -36.148403) (xy 421.470505 -36.170215) (xy 421.518111 -36.199269) (xy 421.560979 -36.234944)
			(xy 421.598196 -36.276481) (xy 421.628969 -36.322994) (xy 421.652641 -36.373491) (xy 421.668709 -36.426898)
			(xy 421.672634 -36.453572) (xy 424.228512 -36.453572) (xy 424.232583 -36.39795) (xy 424.244709 -36.343513)
			(xy 424.264632 -36.291422) (xy 424.291928 -36.242787) (xy 424.326014 -36.198644) (xy 424.366163 -36.159935)
			(xy 424.411521 -36.127484) (xy 424.461121 -36.101983) (xy 424.513905 -36.083976) (xy 424.568748 -36.073846)
			(xy 424.624482 -36.071809) (xy 424.679919 -36.077909) (xy 424.733876 -36.092015) (xy 424.785205 -36.113827)
			(xy 424.832811 -36.142881) (xy 424.875679 -36.178556) (xy 424.912896 -36.220093) (xy 424.943669 -36.266606)
			(xy 424.953205 -36.286948) (xy 431.500278 -36.286948) (xy 431.504349 -36.231326) (xy 431.516475 -36.176889)
			(xy 431.536398 -36.124798) (xy 431.563694 -36.076163) (xy 431.59778 -36.03202) (xy 431.637929 -35.993311)
			(xy 431.683287 -35.96086) (xy 431.732887 -35.935359) (xy 431.785671 -35.917352) (xy 431.840514 -35.907222)
			(xy 431.896248 -35.905185) (xy 431.951685 -35.911285) (xy 432.005642 -35.925391) (xy 432.056971 -35.947203)
			(xy 432.104577 -35.976257) (xy 432.147445 -36.011932) (xy 432.184662 -36.053469) (xy 432.215435 -36.099982)
			(xy 432.239107 -36.150479) (xy 432.255175 -36.203886) (xy 432.263295 -36.259062) (xy 432.263804 -36.286948)
			(xy 432.263295 -36.314834) (xy 432.255175 -36.37001) (xy 432.239107 -36.423417) (xy 432.215435 -36.473914)
			(xy 432.184662 -36.520427) (xy 432.147445 -36.561964) (xy 432.104577 -36.597639) (xy 432.056971 -36.626693)
			(xy 432.005642 -36.648505) (xy 431.951685 -36.662611) (xy 431.896248 -36.668711) (xy 431.840514 -36.666674)
			(xy 431.785671 -36.656544) (xy 431.732887 -36.638537) (xy 431.683287 -36.613036) (xy 431.637929 -36.580585)
			(xy 431.59778 -36.541876) (xy 431.563694 -36.497733) (xy 431.536398 -36.449098) (xy 431.516475 -36.397007)
			(xy 431.504349 -36.34257) (xy 431.500278 -36.286948) (xy 424.953205 -36.286948) (xy 424.967341 -36.317103)
			(xy 424.983409 -36.37051) (xy 424.991529 -36.425686) (xy 424.992038 -36.453572) (xy 424.991529 -36.481458)
			(xy 424.983409 -36.536634) (xy 424.967341 -36.590041) (xy 424.943669 -36.640538) (xy 424.912896 -36.687051)
			(xy 424.875679 -36.728588) (xy 424.832811 -36.764263) (xy 424.785205 -36.793317) (xy 424.733876 -36.815129)
			(xy 424.679919 -36.829235) (xy 424.624482 -36.835335) (xy 424.568748 -36.833298) (xy 424.513905 -36.823168)
			(xy 424.461121 -36.805161) (xy 424.411521 -36.77966) (xy 424.366163 -36.747209) (xy 424.326014 -36.7085)
			(xy 424.291928 -36.664357) (xy 424.264632 -36.615722) (xy 424.244709 -36.563631) (xy 424.232583 -36.509194)
			(xy 424.228512 -36.453572) (xy 421.672634 -36.453572) (xy 421.676829 -36.482074) (xy 421.677338 -36.50996)
			(xy 421.676829 -36.537846) (xy 421.668709 -36.593022) (xy 421.652641 -36.646429) (xy 421.628969 -36.696926)
			(xy 421.598196 -36.743439) (xy 421.560979 -36.784976) (xy 421.518111 -36.820651) (xy 421.470505 -36.849705)
			(xy 421.419176 -36.871517) (xy 421.365219 -36.885623) (xy 421.309782 -36.891723) (xy 421.254048 -36.889686)
			(xy 421.199205 -36.879556) (xy 421.146421 -36.861549) (xy 421.096821 -36.836048) (xy 421.051463 -36.803597)
			(xy 421.011314 -36.764888) (xy 420.977228 -36.720745) (xy 420.949932 -36.67211) (xy 420.930009 -36.620019)
			(xy 420.917883 -36.565582) (xy 420.913812 -36.50996) (xy 416.235655 -36.50996) (xy 416.47618 -37.090604)
			(xy 416.490244 -37.125598) (xy 416.513635 -37.197305) (xy 416.522916 -37.23386) (xy 416.523678 -37.236654)
			(xy 416.52444 -37.239194) (xy 416.53333 -37.260022) (xy 416.53333 -37.26053) (xy 416.545014 -37.28847)
			(xy 416.545268 -37.28847) (xy 416.550348 -37.300662) (xy 416.550348 -37.30117) (xy 416.569059 -37.347187)
			(xy 416.598328 -37.442121) (xy 416.60501 -37.47516) (xy 418.059106 -37.47516) (xy 418.063177 -37.419538)
			(xy 418.075303 -37.365101) (xy 418.095226 -37.31301) (xy 418.122522 -37.264375) (xy 418.156608 -37.220232)
			(xy 418.196757 -37.181523) (xy 418.242115 -37.149072) (xy 418.291715 -37.123571) (xy 418.344499 -37.105564)
			(xy 418.399342 -37.095434) (xy 418.455076 -37.093397) (xy 418.510513 -37.099497) (xy 418.56447 -37.113603)
			(xy 418.615799 -37.135415) (xy 418.663405 -37.164469) (xy 418.706273 -37.200144) (xy 418.74349 -37.241681)
			(xy 418.774263 -37.288194) (xy 418.797935 -37.338691) (xy 418.814003 -37.392098) (xy 418.822123 -37.447274)
			(xy 418.822632 -37.47516) (xy 418.822123 -37.503046) (xy 418.814003 -37.558222) (xy 418.797935 -37.611629)
			(xy 418.774263 -37.662126) (xy 418.77411 -37.662358) (xy 420.248332 -37.662358) (xy 420.252403 -37.606736)
			(xy 420.264529 -37.552299) (xy 420.284452 -37.500208) (xy 420.311748 -37.451573) (xy 420.345834 -37.40743)
			(xy 420.385983 -37.368721) (xy 420.431341 -37.33627) (xy 420.480941 -37.310769) (xy 420.533725 -37.292762)
			(xy 420.588568 -37.282632) (xy 420.644302 -37.280595) (xy 420.699739 -37.286695) (xy 420.753696 -37.300801)
			(xy 420.805025 -37.322613) (xy 420.852631 -37.351667) (xy 420.895499 -37.387342) (xy 420.932716 -37.428879)
			(xy 420.963489 -37.475392) (xy 420.987161 -37.525889) (xy 421.003229 -37.579296) (xy 421.011349 -37.634472)
			(xy 421.011858 -37.662358) (xy 421.011349 -37.690244) (xy 421.003229 -37.74542) (xy 420.994595 -37.774118)
			(xy 431.764692 -37.774118) (xy 431.768763 -37.718496) (xy 431.780889 -37.664059) (xy 431.800812 -37.611968)
			(xy 431.828108 -37.563333) (xy 431.862194 -37.51919) (xy 431.902343 -37.480481) (xy 431.947701 -37.44803)
			(xy 431.997301 -37.422529) (xy 432.050085 -37.404522) (xy 432.104928 -37.394392) (xy 432.160662 -37.392355)
			(xy 432.216099 -37.398455) (xy 432.270056 -37.412561) (xy 432.321385 -37.434373) (xy 432.368991 -37.463427)
			(xy 432.411859 -37.499102) (xy 432.449076 -37.540639) (xy 432.479849 -37.587152) (xy 432.503521 -37.637649)
			(xy 432.519589 -37.691056) (xy 432.527709 -37.746232) (xy 432.528218 -37.774118) (xy 432.527709 -37.802004)
			(xy 432.519589 -37.85718) (xy 432.503521 -37.910587) (xy 432.479849 -37.961084) (xy 432.449076 -38.007597)
			(xy 432.411859 -38.049134) (xy 432.368991 -38.084809) (xy 432.321385 -38.113863) (xy 432.270056 -38.135675)
			(xy 432.216099 -38.149781) (xy 432.160662 -38.155881) (xy 432.104928 -38.153844) (xy 432.050085 -38.143714)
			(xy 431.997301 -38.125707) (xy 431.947701 -38.100206) (xy 431.902343 -38.067755) (xy 431.862194 -38.029046)
			(xy 431.828108 -37.984903) (xy 431.800812 -37.936268) (xy 431.780889 -37.884177) (xy 431.768763 -37.82974)
			(xy 431.764692 -37.774118) (xy 420.994595 -37.774118) (xy 420.987161 -37.798827) (xy 420.963489 -37.849324)
			(xy 420.932716 -37.895837) (xy 420.895499 -37.937374) (xy 420.852631 -37.973049) (xy 420.805025 -38.002103)
			(xy 420.753696 -38.023915) (xy 420.699739 -38.038021) (xy 420.644302 -38.044121) (xy 420.588568 -38.042084)
			(xy 420.533725 -38.031954) (xy 420.480941 -38.013947) (xy 420.431341 -37.988446) (xy 420.385983 -37.955995)
			(xy 420.345834 -37.917286) (xy 420.311748 -37.873143) (xy 420.284452 -37.824508) (xy 420.264529 -37.772417)
			(xy 420.252403 -37.71798) (xy 420.248332 -37.662358) (xy 418.77411 -37.662358) (xy 418.74349 -37.708639)
			(xy 418.706273 -37.750176) (xy 418.663405 -37.785851) (xy 418.615799 -37.814905) (xy 418.56447 -37.836717)
			(xy 418.510513 -37.850823) (xy 418.455076 -37.856923) (xy 418.399342 -37.854886) (xy 418.344499 -37.844756)
			(xy 418.291715 -37.826749) (xy 418.242115 -37.801248) (xy 418.196757 -37.768797) (xy 418.156608 -37.730088)
			(xy 418.122522 -37.685945) (xy 418.095226 -37.63731) (xy 418.075303 -37.585219) (xy 418.063177 -37.530782)
			(xy 418.059106 -37.47516) (xy 416.60501 -37.47516) (xy 416.61802 -37.539493) (xy 416.627939 -37.638341)
			(xy 416.62858 -37.688012) (xy 416.62858 -37.704522) (xy 416.62858 -37.705538) (xy 416.611584 -38.729951)
			(xy 424.000897 -38.729951) (xy 424.000897 -38.675449) (xy 424.008654 -38.621501) (xy 424.02401 -38.569207)
			(xy 424.046652 -38.51963) (xy 424.07612 -38.47378) (xy 424.111813 -38.432592) (xy 424.153005 -38.396902)
			(xy 424.198856 -38.367438) (xy 424.248435 -38.3448) (xy 424.300731 -38.329448) (xy 424.354679 -38.321695)
			(xy 424.38193 -38.321234) (xy 424.410233 -38.321763) (xy 424.46622 -38.330106) (xy 424.520359 -38.346633)
			(xy 424.571461 -38.370981) (xy 424.618401 -38.402616) (xy 424.660149 -38.440843) (xy 424.695788 -38.48482)
			(xy 424.710606 -38.50894) (xy 424.71823 -38.520957) (xy 424.738843 -38.540558) (xy 424.764069 -38.5537)
			(xy 424.791945 -38.559362) (xy 424.8203 -38.557101) (xy 424.846927 -38.547095) (xy 424.869752 -38.530121)
			(xy 424.878754 -38.5191) (xy 424.896914 -38.496202) (xy 424.939083 -38.45574) (xy 424.986924 -38.422175)
			(xy 425.039321 -38.396291) (xy 425.09505 -38.378694) (xy 425.152809 -38.369794) (xy 425.18203 -38.36924)
			(xy 425.209283 -38.369632) (xy 425.263235 -38.377393) (xy 425.315532 -38.392753) (xy 425.365112 -38.415398)
			(xy 425.410964 -38.444869) (xy 425.452156 -38.480565) (xy 425.487849 -38.52176) (xy 425.517316 -38.567614)
			(xy 425.539958 -38.617196) (xy 425.555313 -38.669495) (xy 425.56307 -38.723447) (xy 425.56307 -38.777953)
			(xy 425.555313 -38.831905) (xy 425.539958 -38.884204) (xy 425.517316 -38.933786) (xy 425.487849 -38.97964)
			(xy 425.452156 -39.020835) (xy 425.410964 -39.056531) (xy 425.365112 -39.086002) (xy 425.315532 -39.108647)
			(xy 425.263235 -39.124007) (xy 425.209283 -39.131768) (xy 425.18203 -39.132256) (xy 425.153726 -39.131763)
			(xy 425.097736 -39.123415) (xy 425.043596 -39.106882) (xy 424.992495 -39.082527) (xy 424.945555 -39.050886)
			(xy 424.903808 -39.012655) (xy 424.86817 -38.968672) (xy 424.853354 -38.94455) (xy 424.845783 -38.932498)
			(xy 424.825158 -38.912896) (xy 424.79992 -38.899756) (xy 424.772035 -38.894099) (xy 424.743671 -38.896366)
			(xy 424.717038 -38.906381) (xy 424.694209 -38.923364) (xy 424.685206 -38.93439) (xy 424.667009 -38.957257)
			(xy 424.624848 -38.997722) (xy 424.577015 -39.031291) (xy 424.524625 -39.057179) (xy 424.468903 -39.074783)
			(xy 424.411149 -39.083692) (xy 424.38193 -39.08425) (xy 424.354679 -39.083705) (xy 424.300731 -39.075952)
			(xy 424.248435 -39.0606) (xy 424.198856 -39.037962) (xy 424.153005 -39.008498) (xy 424.111813 -38.972808)
			(xy 424.07612 -38.93162) (xy 424.046652 -38.88577) (xy 424.02401 -38.836193) (xy 424.008654 -38.783899)
			(xy 424.000897 -38.729951) (xy 416.611584 -38.729951) (xy 416.609022 -38.884352) (xy 416.603942 -39.186104)
			(xy 416.602584 -39.233452) (xy 416.592024 -39.327591) (xy 416.58286 -39.374064) (xy 416.535108 -39.60241)
			(xy 416.457728 -39.97198) (xy 426.195742 -39.97198) (xy 426.199813 -39.916358) (xy 426.211939 -39.861921)
			(xy 426.231862 -39.80983) (xy 426.259158 -39.761195) (xy 426.293244 -39.717052) (xy 426.333393 -39.678343)
			(xy 426.378751 -39.645892) (xy 426.428351 -39.620391) (xy 426.481135 -39.602384) (xy 426.535978 -39.592254)
			(xy 426.591712 -39.590217) (xy 426.647149 -39.596317) (xy 426.701106 -39.610423) (xy 426.752435 -39.632235)
			(xy 426.800041 -39.661289) (xy 426.842909 -39.696964) (xy 426.880126 -39.738501) (xy 426.910899 -39.785014)
			(xy 426.934571 -39.835511) (xy 426.950639 -39.888918) (xy 426.958759 -39.944094) (xy 426.959268 -39.97198)
			(xy 426.958759 -39.999866) (xy 426.950639 -40.055042) (xy 426.934571 -40.108449) (xy 426.910899 -40.158946)
			(xy 426.880126 -40.205459) (xy 426.842909 -40.246996) (xy 426.800041 -40.282671) (xy 426.752435 -40.311725)
			(xy 426.701106 -40.333537) (xy 426.647149 -40.347643) (xy 426.591712 -40.353743) (xy 426.535978 -40.351706)
			(xy 426.481135 -40.341576) (xy 426.428351 -40.323569) (xy 426.378751 -40.298068) (xy 426.333393 -40.265617)
			(xy 426.293244 -40.226908) (xy 426.259158 -40.182765) (xy 426.231862 -40.13413) (xy 426.211939 -40.082039)
			(xy 426.199813 -40.027602) (xy 426.195742 -39.97198) (xy 416.457728 -39.97198) (xy 416.293554 -40.756078)
			(xy 416.29239 -40.762344) (xy 416.292901 -40.775074) (xy 416.29457 -40.781224) (xy 416.296476 -40.786865)
			(xy 416.302517 -40.797124) (xy 416.306508 -40.801544) (xy 416.37204 -40.862758) (xy 416.372548 -40.863266)
			(xy 416.379194 -40.868809) (xy 416.395145 -40.875492) (xy 416.412409 -40.876522) (xy 416.420808 -40.874442)
			(xy 416.44631 -40.867677) (xy 416.498568 -40.860418) (xy 416.524948 -40.859964) (xy 416.553688 -40.860481)
			(xy 416.610519 -40.869098) (xy 416.665413 -40.886145) (xy 416.717128 -40.911235) (xy 416.764493 -40.943801)
			(xy 416.785806 -40.963088) (xy 416.78606 -40.963342) (xy 416.790041 -40.966815) (xy 416.799133 -40.972192)
			(xy 416.804094 -40.97401) (xy 416.808101 -40.975293) (xy 416.816398 -40.976695) (xy 416.820604 -40.976804)
			(xy 416.889692 -40.976804) (xy 416.893901 -40.976724) (xy 416.902202 -40.975321) (xy 416.906202 -40.97401)
			(xy 416.911158 -40.972183) (xy 416.920241 -40.966798) (xy 416.924236 -40.963342) (xy 416.92449 -40.963088)
			(xy 416.945817 -40.943816) (xy 416.993179 -40.911247) (xy 417.04489 -40.886151) (xy 417.09978 -40.869095)
			(xy 417.156608 -40.860466) (xy 417.185348 -40.859964) (xy 417.212599 -40.860453) (xy 417.266545 -40.868216)
			(xy 417.318838 -40.883576) (xy 417.368413 -40.906222) (xy 417.414261 -40.935691) (xy 417.455448 -40.971386)
			(xy 417.491137 -41.012578) (xy 417.520601 -41.058429) (xy 417.543241 -41.108007) (xy 417.558594 -41.160301)
			(xy 417.56635 -41.214249) (xy 417.56635 -41.268751) (xy 417.558594 -41.322699) (xy 417.543241 -41.374993)
			(xy 417.520601 -41.424571) (xy 417.491137 -41.470422) (xy 417.455448 -41.511614) (xy 417.414261 -41.547309)
			(xy 417.368413 -41.576778) (xy 417.318838 -41.599424) (xy 417.266546 -41.614784) (xy 417.212599 -41.622547)
			(xy 417.185348 -41.62298) (xy 417.156608 -41.622463) (xy 417.099777 -41.613846) (xy 417.044882 -41.5968)
			(xy 416.993165 -41.571712) (xy 416.945798 -41.539149) (xy 416.92449 -41.519856) (xy 416.924236 -41.519602)
			(xy 416.920256 -41.516127) (xy 416.911165 -41.510746) (xy 416.906202 -41.508934) (xy 416.902194 -41.507653)
			(xy 416.893898 -41.506253) (xy 416.889692 -41.50614) (xy 416.820604 -41.50614) (xy 416.816395 -41.50622)
			(xy 416.808095 -41.507625) (xy 416.804094 -41.508934) (xy 416.799132 -41.510751) (xy 416.790033 -41.516119)
			(xy 416.78606 -41.519602) (xy 416.785806 -41.519856) (xy 416.764478 -41.539126) (xy 416.717115 -41.571691)
			(xy 416.665404 -41.596783) (xy 416.610514 -41.613836) (xy 416.553687 -41.622464) (xy 416.524948 -41.62298)
			(xy 416.499438 -41.622552) (xy 416.448873 -41.615751) (xy 416.399663 -41.602278) (xy 416.352686 -41.582373)
			(xy 416.308778 -41.556389) (xy 416.288474 -41.540938) (xy 416.28187 -41.535604) (xy 416.249612 -41.524174)
			(xy 416.245943 -41.524223) (xy 416.238677 -41.52525) (xy 416.235134 -41.526206) (xy 416.195002 -41.54043)
			(xy 416.15106 -41.555924) (xy 416.143026 -41.559182) (xy 416.129589 -41.570119) (xy 416.120518 -41.58488)
			(xy 416.118294 -41.593262) (xy 415.815018 -43.041062) (xy 415.759747 -43.305222) (xy 418.60724 -43.305222)
			(xy 418.607709 -43.277852) (xy 418.615525 -43.223672) (xy 418.631013 -43.171169) (xy 418.653854 -43.121422)
			(xy 418.683579 -43.075455) (xy 418.70122 -43.054524) (xy 418.701474 -43.05427) (xy 418.707046 -43.047174)
			(xy 418.7133 -43.030264) (xy 418.713666 -43.02125) (xy 418.713666 -42.954194) (xy 418.713319 -42.945176)
			(xy 418.707066 -42.928259) (xy 418.701474 -42.921174) (xy 418.70122 -42.921174) (xy 418.70122 -42.92092)
			(xy 418.68358 -42.899989) (xy 418.653868 -42.854016) (xy 418.631031 -42.804268) (xy 418.615541 -42.751767)
			(xy 418.607713 -42.697591) (xy 418.60724 -42.670222) (xy 418.607793 -42.641484) (xy 418.616411 -42.584659)
			(xy 418.633455 -42.529769) (xy 418.65854 -42.478057) (xy 418.691097 -42.430693) (xy 418.710364 -42.409364)
			(xy 418.716968 -42.402506) (xy 418.72408 -42.384472) (xy 418.72408 -42.295572) (xy 418.716968 -42.277538)
			(xy 418.710364 -42.27068) (xy 418.691113 -42.249335) (xy 418.658544 -42.201977) (xy 418.633448 -42.150268)
			(xy 418.616395 -42.09538) (xy 418.607769 -42.038554) (xy 418.607767 -41.981078) (xy 418.616388 -41.924251)
			(xy 418.633437 -41.869361) (xy 418.658528 -41.817651) (xy 418.691093 -41.77029) (xy 418.710364 -41.748964)
			(xy 418.716968 -41.742106) (xy 418.72408 -41.724072) (xy 418.72408 -41.635172) (xy 418.716968 -41.617138)
			(xy 418.710364 -41.61028) (xy 418.691108 -41.58894) (xy 418.658539 -41.541582) (xy 418.633443 -41.489874)
			(xy 418.616389 -41.434986) (xy 418.607763 -41.37816) (xy 418.60724 -41.349422) (xy 418.607726 -41.322171)
			(xy 418.615482 -41.268223) (xy 418.630837 -41.215928) (xy 418.653479 -41.166351) (xy 418.682945 -41.120501)
			(xy 418.718636 -41.07931) (xy 418.759827 -41.043619) (xy 418.805677 -41.014153) (xy 418.855254 -40.991511)
			(xy 418.907549 -40.976156) (xy 418.961497 -40.9684) (xy 419.015999 -40.9684) (xy 419.03912 -40.971724)
			(xy 426.893988 -40.971724) (xy 426.898059 -40.916102) (xy 426.910185 -40.861665) (xy 426.930108 -40.809574)
			(xy 426.957404 -40.760939) (xy 426.99149 -40.716796) (xy 427.031639 -40.678087) (xy 427.076997 -40.645636)
			(xy 427.126597 -40.620135) (xy 427.179381 -40.602128) (xy 427.234224 -40.591998) (xy 427.289958 -40.589961)
			(xy 427.345395 -40.596061) (xy 427.399352 -40.610167) (xy 427.450681 -40.631979) (xy 427.498287 -40.661033)
			(xy 427.541155 -40.696708) (xy 427.578372 -40.738245) (xy 427.609145 -40.784758) (xy 427.632817 -40.835255)
			(xy 427.648885 -40.888662) (xy 427.657005 -40.943838) (xy 427.657514 -40.971724) (xy 427.657005 -40.99961)
			(xy 427.648885 -41.054786) (xy 427.632817 -41.108193) (xy 427.609145 -41.15869) (xy 427.578372 -41.205203)
			(xy 427.541155 -41.24674) (xy 427.498287 -41.282415) (xy 427.450681 -41.311469) (xy 427.399352 -41.333281)
			(xy 427.345395 -41.347387) (xy 427.289958 -41.353487) (xy 427.234224 -41.35145) (xy 427.179381 -41.34132)
			(xy 427.126597 -41.323313) (xy 427.076997 -41.297812) (xy 427.031639 -41.265361) (xy 426.99149 -41.226652)
			(xy 426.957404 -41.182509) (xy 426.930108 -41.133874) (xy 426.910185 -41.081783) (xy 426.898059 -41.027346)
			(xy 426.893988 -40.971724) (xy 419.03912 -40.971724) (xy 419.069947 -40.976156) (xy 419.122242 -40.991511)
			(xy 419.171819 -41.014153) (xy 419.217669 -41.043619) (xy 419.25886 -41.07931) (xy 419.294551 -41.120501)
			(xy 419.324017 -41.166351) (xy 419.346659 -41.215928) (xy 419.362014 -41.268223) (xy 419.36977 -41.322171)
			(xy 419.370256 -41.349422) (xy 419.369731 -41.378161) (xy 419.361106 -41.434987) (xy 419.344056 -41.489877)
			(xy 419.318965 -41.541589) (xy 419.286402 -41.588952) (xy 419.267132 -41.61028) (xy 419.260528 -41.617138)
			(xy 419.253416 -41.635172) (xy 419.253416 -41.724072) (xy 419.260528 -41.742106) (xy 419.267132 -41.748964)
			(xy 419.286422 -41.770273) (xy 419.318982 -41.81764) (xy 419.344069 -41.869355) (xy 419.361114 -41.924248)
			(xy 419.369733 -41.981077) (xy 419.369731 -42.038555) (xy 419.361107 -42.095383) (xy 419.344057 -42.150275)
			(xy 419.318966 -42.201988) (xy 419.286402 -42.249352) (xy 419.267132 -42.27068) (xy 419.260528 -42.277538)
			(xy 419.253416 -42.295572) (xy 419.253416 -42.384472) (xy 419.260528 -42.402506) (xy 419.267132 -42.409364)
			(xy 419.286408 -42.430686) (xy 419.318975 -42.478049) (xy 419.344067 -42.529762) (xy 419.361116 -42.584654)
			(xy 419.369737 -42.641483) (xy 419.370256 -42.670222) (xy 419.369814 -42.697593) (xy 419.361992 -42.751774)
			(xy 419.346498 -42.804278) (xy 419.32594 -42.849038) (xy 421.191942 -42.849038) (xy 421.196013 -42.793416)
			(xy 421.208139 -42.738979) (xy 421.228062 -42.686888) (xy 421.255358 -42.638253) (xy 421.289444 -42.59411)
			(xy 421.329593 -42.555401) (xy 421.374951 -42.52295) (xy 421.424551 -42.497449) (xy 421.477335 -42.479442)
			(xy 421.532178 -42.469312) (xy 421.587912 -42.467275) (xy 421.643349 -42.473375) (xy 421.697306 -42.487481)
			(xy 421.748635 -42.509293) (xy 421.796241 -42.538347) (xy 421.839109 -42.574022) (xy 421.876326 -42.615559)
			(xy 421.907099 -42.662072) (xy 421.930771 -42.712569) (xy 421.946839 -42.765976) (xy 421.954959 -42.821152)
			(xy 421.95532 -42.84091) (xy 427.233078 -42.84091) (xy 427.237149 -42.785288) (xy 427.249275 -42.730851)
			(xy 427.269198 -42.67876) (xy 427.296494 -42.630125) (xy 427.33058 -42.585982) (xy 427.370729 -42.547273)
			(xy 427.416087 -42.514822) (xy 427.465687 -42.489321) (xy 427.518471 -42.471314) (xy 427.573314 -42.461184)
			(xy 427.629048 -42.459147) (xy 427.684485 -42.465247) (xy 427.738442 -42.479353) (xy 427.789771 -42.501165)
			(xy 427.837377 -42.530219) (xy 427.880245 -42.565894) (xy 427.917462 -42.607431) (xy 427.948235 -42.653944)
			(xy 427.971907 -42.704441) (xy 427.987975 -42.757848) (xy 427.996095 -42.813024) (xy 427.996604 -42.84091)
			(xy 427.996095 -42.868796) (xy 427.987975 -42.923972) (xy 427.971907 -42.977379) (xy 427.948235 -43.027876)
			(xy 427.917462 -43.074389) (xy 427.880245 -43.115926) (xy 427.837377 -43.151601) (xy 427.789771 -43.180655)
			(xy 427.738442 -43.202467) (xy 427.684485 -43.216573) (xy 427.629048 -43.222673) (xy 427.573314 -43.220636)
			(xy 427.518471 -43.210506) (xy 427.465687 -43.192499) (xy 427.416087 -43.166998) (xy 427.370729 -43.134547)
			(xy 427.33058 -43.095838) (xy 427.296494 -43.051695) (xy 427.269198 -43.00306) (xy 427.249275 -42.950969)
			(xy 427.237149 -42.896532) (xy 427.233078 -42.84091) (xy 421.95532 -42.84091) (xy 421.955468 -42.849038)
			(xy 421.954959 -42.876924) (xy 421.946839 -42.9321) (xy 421.930771 -42.985507) (xy 421.907099 -43.036004)
			(xy 421.876326 -43.082517) (xy 421.839109 -43.124054) (xy 421.796241 -43.159729) (xy 421.748635 -43.188783)
			(xy 421.697306 -43.210595) (xy 421.643349 -43.224701) (xy 421.587912 -43.230801) (xy 421.532178 -43.228764)
			(xy 421.477335 -43.218634) (xy 421.424551 -43.200627) (xy 421.374951 -43.175126) (xy 421.329593 -43.142675)
			(xy 421.289444 -43.103966) (xy 421.255358 -43.059823) (xy 421.228062 -43.011188) (xy 421.208139 -42.959097)
			(xy 421.196013 -42.90466) (xy 421.191942 -42.849038) (xy 419.32594 -42.849038) (xy 419.32365 -42.854024)
			(xy 419.29392 -42.899989) (xy 419.276276 -42.92092) (xy 419.276022 -42.921174) (xy 419.270431 -42.928257)
			(xy 419.264189 -42.945177) (xy 419.26383 -42.954194) (xy 419.26383 -43.02125) (xy 419.264204 -43.030265)
			(xy 419.270439 -43.047183) (xy 419.276022 -43.05427) (xy 419.276276 -43.05427) (xy 419.276276 -43.054524)
			(xy 419.293889 -43.075477) (xy 419.323606 -43.121444) (xy 419.346447 -43.171186) (xy 419.361944 -43.223682)
			(xy 419.369779 -43.277854) (xy 419.370256 -43.305222) (xy 419.36977 -43.332473) (xy 419.362014 -43.386421)
			(xy 419.346659 -43.438716) (xy 419.324017 -43.488293) (xy 419.294551 -43.534143) (xy 419.25886 -43.575334)
			(xy 419.217669 -43.611025) (xy 419.171819 -43.640491) (xy 419.122242 -43.663133) (xy 419.069947 -43.678488)
			(xy 419.015999 -43.686244) (xy 418.961497 -43.686244) (xy 418.907549 -43.678488) (xy 418.855254 -43.663133)
			(xy 418.805677 -43.640491) (xy 418.759827 -43.611025) (xy 418.718636 -43.575334) (xy 418.682945 -43.534143)
			(xy 418.653479 -43.488293) (xy 418.630837 -43.438716) (xy 418.615482 -43.386421) (xy 418.607726 -43.332473)
			(xy 418.60724 -43.305222) (xy 415.759747 -43.305222) (xy 415.66956 -43.73626) (xy 420.513 -43.73626)
			(xy 420.517071 -43.680638) (xy 420.529197 -43.626201) (xy 420.54912 -43.57411) (xy 420.576416 -43.525475)
			(xy 420.610502 -43.481332) (xy 420.650651 -43.442623) (xy 420.696009 -43.410172) (xy 420.745609 -43.384671)
			(xy 420.798393 -43.366664) (xy 420.853236 -43.356534) (xy 420.90897 -43.354497) (xy 420.964407 -43.360597)
			(xy 421.018364 -43.374703) (xy 421.069693 -43.396515) (xy 421.117299 -43.425569) (xy 421.160167 -43.461244)
			(xy 421.197384 -43.502781) (xy 421.228157 -43.549294) (xy 421.236383 -43.566842) (xy 423.63339 -43.566842)
			(xy 423.637461 -43.51122) (xy 423.649587 -43.456783) (xy 423.66951 -43.404692) (xy 423.696806 -43.356057)
			(xy 423.730892 -43.311914) (xy 423.771041 -43.273205) (xy 423.816399 -43.240754) (xy 423.865999 -43.215253)
			(xy 423.918783 -43.197246) (xy 423.973626 -43.187116) (xy 424.02936 -43.185079) (xy 424.084797 -43.191179)
			(xy 424.138754 -43.205285) (xy 424.190083 -43.227097) (xy 424.237689 -43.256151) (xy 424.280557 -43.291826)
			(xy 424.317774 -43.333363) (xy 424.348547 -43.379876) (xy 424.372219 -43.430373) (xy 424.388287 -43.48378)
			(xy 424.396407 -43.538956) (xy 424.396916 -43.566842) (xy 424.396407 -43.594728) (xy 424.388287 -43.649904)
			(xy 424.372219 -43.703311) (xy 424.348547 -43.753808) (xy 424.317774 -43.800321) (xy 424.280557 -43.841858)
			(xy 424.26247 -43.85691) (xy 425.019722 -43.85691) (xy 425.023793 -43.801288) (xy 425.035919 -43.746851)
			(xy 425.055842 -43.69476) (xy 425.083138 -43.646125) (xy 425.117224 -43.601982) (xy 425.157373 -43.563273)
			(xy 425.202731 -43.530822) (xy 425.252331 -43.505321) (xy 425.305115 -43.487314) (xy 425.359958 -43.477184)
			(xy 425.415692 -43.475147) (xy 425.471129 -43.481247) (xy 425.525086 -43.495353) (xy 425.576415 -43.517165)
			(xy 425.624021 -43.546219) (xy 425.666889 -43.581894) (xy 425.704106 -43.623431) (xy 425.734879 -43.669944)
			(xy 425.758551 -43.720441) (xy 425.774619 -43.773848) (xy 425.782739 -43.829024) (xy 425.783248 -43.85691)
			(xy 425.782739 -43.884796) (xy 425.774619 -43.939972) (xy 425.758551 -43.993379) (xy 425.734879 -44.043876)
			(xy 425.704106 -44.090389) (xy 425.666889 -44.131926) (xy 425.624021 -44.167601) (xy 425.576415 -44.196655)
			(xy 425.525086 -44.218467) (xy 425.471129 -44.232573) (xy 425.415692 -44.238673) (xy 425.359958 -44.236636)
			(xy 425.305115 -44.226506) (xy 425.252331 -44.208499) (xy 425.202731 -44.182998) (xy 425.157373 -44.150547)
			(xy 425.117224 -44.111838) (xy 425.083138 -44.067695) (xy 425.055842 -44.01906) (xy 425.035919 -43.966969)
			(xy 425.023793 -43.912532) (xy 425.019722 -43.85691) (xy 424.26247 -43.85691) (xy 424.237689 -43.877533)
			(xy 424.190083 -43.906587) (xy 424.138754 -43.928399) (xy 424.084797 -43.942505) (xy 424.02936 -43.948605)
			(xy 423.973626 -43.946568) (xy 423.918783 -43.936438) (xy 423.865999 -43.918431) (xy 423.816399 -43.89293)
			(xy 423.771041 -43.860479) (xy 423.730892 -43.82177) (xy 423.696806 -43.777627) (xy 423.66951 -43.728992)
			(xy 423.649587 -43.676901) (xy 423.637461 -43.622464) (xy 423.63339 -43.566842) (xy 421.236383 -43.566842)
			(xy 421.251829 -43.599791) (xy 421.267897 -43.653198) (xy 421.276017 -43.708374) (xy 421.276526 -43.73626)
			(xy 421.276017 -43.764146) (xy 421.267897 -43.819322) (xy 421.251829 -43.872729) (xy 421.228157 -43.923226)
			(xy 421.197384 -43.969739) (xy 421.160167 -44.011276) (xy 421.117299 -44.046951) (xy 421.069693 -44.076005)
			(xy 421.018364 -44.097817) (xy 420.964407 -44.111923) (xy 420.90897 -44.118023) (xy 420.853236 -44.115986)
			(xy 420.798393 -44.105856) (xy 420.745609 -44.087849) (xy 420.696009 -44.062348) (xy 420.650651 -44.029897)
			(xy 420.610502 -43.991188) (xy 420.576416 -43.947045) (xy 420.54912 -43.89841) (xy 420.529197 -43.846319)
			(xy 420.517071 -43.791882) (xy 420.513 -43.73626) (xy 415.66956 -43.73626) (xy 415.654998 -43.805856)
			(xy 415.381029 -45.114464) (xy 420.365426 -45.114464) (xy 420.369497 -45.058842) (xy 420.381623 -45.004405)
			(xy 420.401546 -44.952314) (xy 420.428842 -44.903679) (xy 420.462928 -44.859536) (xy 420.503077 -44.820827)
			(xy 420.548435 -44.788376) (xy 420.598035 -44.762875) (xy 420.650819 -44.744868) (xy 420.705662 -44.734738)
			(xy 420.761396 -44.732701) (xy 420.816833 -44.738801) (xy 420.87079 -44.752907) (xy 420.922119 -44.774719)
			(xy 420.969725 -44.803773) (xy 421.012593 -44.839448) (xy 421.042575 -44.87291) (xy 427.233078 -44.87291)
			(xy 427.237149 -44.817288) (xy 427.249275 -44.762851) (xy 427.269198 -44.71076) (xy 427.296494 -44.662125)
			(xy 427.33058 -44.617982) (xy 427.370729 -44.579273) (xy 427.416087 -44.546822) (xy 427.465687 -44.521321)
			(xy 427.518471 -44.503314) (xy 427.573314 -44.493184) (xy 427.629048 -44.491147) (xy 427.684485 -44.497247)
			(xy 427.738442 -44.511353) (xy 427.789771 -44.533165) (xy 427.837377 -44.562219) (xy 427.880245 -44.597894)
			(xy 427.917462 -44.639431) (xy 427.948235 -44.685944) (xy 427.971907 -44.736441) (xy 427.987975 -44.789848)
			(xy 427.996095 -44.845024) (xy 427.996604 -44.87291) (xy 427.996095 -44.900796) (xy 427.987975 -44.955972)
			(xy 427.971907 -45.009379) (xy 427.948235 -45.059876) (xy 427.917462 -45.106389) (xy 427.880245 -45.147926)
			(xy 427.837377 -45.183601) (xy 427.789771 -45.212655) (xy 427.738442 -45.234467) (xy 427.684485 -45.248573)
			(xy 427.629048 -45.254673) (xy 427.573314 -45.252636) (xy 427.518471 -45.242506) (xy 427.465687 -45.224499)
			(xy 427.416087 -45.198998) (xy 427.370729 -45.166547) (xy 427.33058 -45.127838) (xy 427.296494 -45.083695)
			(xy 427.269198 -45.03506) (xy 427.249275 -44.982969) (xy 427.237149 -44.928532) (xy 427.233078 -44.87291)
			(xy 421.042575 -44.87291) (xy 421.04981 -44.880985) (xy 421.080583 -44.927498) (xy 421.104255 -44.977995)
			(xy 421.120323 -45.031402) (xy 421.128443 -45.086578) (xy 421.128952 -45.114464) (xy 421.128443 -45.14235)
			(xy 421.120323 -45.197526) (xy 421.104255 -45.250933) (xy 421.080583 -45.30143) (xy 421.04981 -45.347943)
			(xy 421.044168 -45.35424) (xy 425.00372 -45.35424) (xy 425.007791 -45.298618) (xy 425.019917 -45.244181)
			(xy 425.03984 -45.19209) (xy 425.067136 -45.143455) (xy 425.101222 -45.099312) (xy 425.141371 -45.060603)
			(xy 425.186729 -45.028152) (xy 425.236329 -45.002651) (xy 425.289113 -44.984644) (xy 425.343956 -44.974514)
			(xy 425.39969 -44.972477) (xy 425.455127 -44.978577) (xy 425.509084 -44.992683) (xy 425.560413 -45.014495)
			(xy 425.608019 -45.043549) (xy 425.650887 -45.079224) (xy 425.688104 -45.120761) (xy 425.718877 -45.167274)
			(xy 425.742549 -45.217771) (xy 425.758617 -45.271178) (xy 425.766737 -45.326354) (xy 425.767246 -45.35424)
			(xy 425.766737 -45.382126) (xy 425.758617 -45.437302) (xy 425.742549 -45.490709) (xy 425.718877 -45.541206)
			(xy 425.688104 -45.587719) (xy 425.650887 -45.629256) (xy 425.608019 -45.664931) (xy 425.560413 -45.693985)
			(xy 425.509084 -45.715797) (xy 425.455127 -45.729903) (xy 425.39969 -45.736003) (xy 425.343956 -45.733966)
			(xy 425.289113 -45.723836) (xy 425.236329 -45.705829) (xy 425.186729 -45.680328) (xy 425.141371 -45.647877)
			(xy 425.101222 -45.609168) (xy 425.067136 -45.565025) (xy 425.03984 -45.51639) (xy 425.019917 -45.464299)
			(xy 425.007791 -45.409862) (xy 425.00372 -45.35424) (xy 421.044168 -45.35424) (xy 421.012593 -45.38948)
			(xy 420.969725 -45.425155) (xy 420.922119 -45.454209) (xy 420.87079 -45.476021) (xy 420.816833 -45.490127)
			(xy 420.761396 -45.496227) (xy 420.705662 -45.49419) (xy 420.650819 -45.48406) (xy 420.598035 -45.466053)
			(xy 420.548435 -45.440552) (xy 420.503077 -45.408101) (xy 420.462928 -45.369392) (xy 420.428842 -45.325249)
			(xy 420.401546 -45.276614) (xy 420.381623 -45.224523) (xy 420.369497 -45.170086) (xy 420.365426 -45.114464)
			(xy 415.381029 -45.114464) (xy 415.178423 -46.082204) (xy 418.352478 -46.082204) (xy 418.352981 -46.054953)
			(xy 418.360737 -46.001007) (xy 418.376091 -45.948714) (xy 418.398731 -45.899137) (xy 418.428195 -45.853288)
			(xy 418.463885 -45.812098) (xy 418.505073 -45.776406) (xy 418.550921 -45.746939) (xy 418.600497 -45.724297)
			(xy 418.65279 -45.708941) (xy 418.706736 -45.701183) (xy 418.733986 -45.700696) (xy 418.760888 -45.701169)
			(xy 418.814158 -45.708739) (xy 418.865836 -45.723716) (xy 418.914897 -45.745805) (xy 418.96037 -45.774565)
			(xy 419.001352 -45.809429) (xy 419.03703 -45.849703) (xy 419.052248 -45.871892) (xy 419.05936 -45.882814)
			(xy 419.08222 -45.894752) (xy 419.194488 -45.89272) (xy 419.21684 -45.879766) (xy 419.223698 -45.86859)
			(xy 419.238634 -45.844998) (xy 419.274311 -45.802047) (xy 419.315867 -45.764753) (xy 419.362414 -45.733915)
			(xy 419.412959 -45.71019) (xy 419.466422 -45.694085) (xy 419.521662 -45.685944) (xy 419.54958 -45.685456)
			(xy 419.576573 -45.685929) (xy 419.630021 -45.693532) (xy 419.681864 -45.708589) (xy 419.731069 -45.730801)
			(xy 419.776653 -45.759723) (xy 419.797484 -45.776896) (xy 419.805612 -45.784008) (xy 419.826186 -45.790104)
			(xy 419.91153 -45.779182) (xy 419.922081 -45.777432) (xy 419.940361 -45.76636) (xy 419.946836 -45.757846)
			(xy 419.962173 -45.736603) (xy 419.997763 -45.698151) (xy 420.038283 -45.664933) (xy 420.082969 -45.637576)
			(xy 420.130979 -45.616595) (xy 420.181411 -45.602384) (xy 420.233312 -45.595212) (xy 420.25951 -45.594778)
			(xy 420.28676 -45.595293) (xy 420.340704 -45.60305) (xy 420.392996 -45.618406) (xy 420.44257 -45.641047)
			(xy 420.488417 -45.670512) (xy 420.529605 -45.706202) (xy 420.565294 -45.747391) (xy 420.594758 -45.793239)
			(xy 420.617398 -45.842813) (xy 420.632752 -45.895105) (xy 420.640508 -45.94905) (xy 420.640508 -46.00355)
			(xy 420.632752 -46.057495) (xy 420.617398 -46.109787) (xy 420.594758 -46.159361) (xy 420.565294 -46.205209)
			(xy 420.529605 -46.246398) (xy 420.488417 -46.282088) (xy 420.44257 -46.311553) (xy 420.392996 -46.334194)
			(xy 420.340704 -46.34955) (xy 420.28676 -46.357307) (xy 420.25951 -46.357794) (xy 420.232517 -46.357315)
			(xy 420.179071 -46.349712) (xy 420.127228 -46.334655) (xy 420.078023 -46.312445) (xy 420.032437 -46.283526)
			(xy 420.011606 -46.266354) (xy 420.003478 -46.259242) (xy 419.982904 -46.253146) (xy 419.89756 -46.264068)
			(xy 419.887025 -46.26588) (xy 419.868739 -46.276909) (xy 419.862254 -46.285404) (xy 419.844644 -46.309707)
			(xy 419.803047 -46.352965) (xy 419.77945 -46.37151) (xy 419.771576 -46.377352) (xy 419.761162 -46.394878)
			(xy 419.747954 -46.485302) (xy 419.75278 -46.504606) (xy 419.758622 -46.51248) (xy 419.758622 -46.512734)
			(xy 419.776119 -46.537483) (xy 419.803924 -46.591333) (xy 419.822862 -46.648904) (xy 419.830066 -46.693836)
			(xy 424.97629 -46.693836) (xy 424.976776 -46.666585) (xy 424.984532 -46.612637) (xy 424.999887 -46.560342)
			(xy 425.022529 -46.510765) (xy 425.051995 -46.464915) (xy 425.087686 -46.423724) (xy 425.128877 -46.388033)
			(xy 425.174727 -46.358567) (xy 425.224304 -46.335925) (xy 425.276599 -46.32057) (xy 425.330547 -46.312814)
			(xy 425.385049 -46.312814) (xy 425.438997 -46.32057) (xy 425.491292 -46.335925) (xy 425.540869 -46.358567)
			(xy 425.586719 -46.388033) (xy 425.62791 -46.423724) (xy 425.663601 -46.464915) (xy 425.693067 -46.510765)
			(xy 425.715709 -46.560342) (xy 425.731064 -46.612637) (xy 425.73882 -46.666585) (xy 425.739306 -46.693836)
			(xy 425.738832 -46.720264) (xy 425.731523 -46.772611) (xy 425.71705 -46.823446) (xy 425.695691 -46.871793)
			(xy 425.682156 -46.894496) (xy 425.681902 -46.89475) (xy 425.676565 -46.904768) (xy 425.674306 -46.927319)
			(xy 425.677584 -46.938184) (xy 425.703746 -47.01286) (xy 425.708133 -47.023374) (xy 425.724219 -47.039463)
			(xy 425.734734 -47.043848) (xy 425.734988 -47.043848) (xy 425.759506 -47.052894) (xy 425.805957 -47.076841)
			(xy 425.848708 -47.106901) (xy 425.886958 -47.142512) (xy 425.919993 -47.183008) (xy 425.947196 -47.227631)
			(xy 425.968056 -47.275549) (xy 425.982186 -47.325864) (xy 425.989319 -47.377635) (xy 425.98975 -47.403766)
			(xy 425.989264 -47.431017) (xy 425.987741 -47.441612) (xy 427.26178 -47.441612) (xy 427.265851 -47.38599)
			(xy 427.277977 -47.331553) (xy 427.2979 -47.279462) (xy 427.325196 -47.230827) (xy 427.359282 -47.186684)
			(xy 427.399431 -47.147975) (xy 427.444789 -47.115524) (xy 427.494389 -47.090023) (xy 427.547173 -47.072016)
			(xy 427.602016 -47.061886) (xy 427.65775 -47.059849) (xy 427.713187 -47.065949) (xy 427.767144 -47.080055)
			(xy 427.818473 -47.101867) (xy 427.866079 -47.130921) (xy 427.908947 -47.166596) (xy 427.946164 -47.208133)
			(xy 427.976937 -47.254646) (xy 428.000609 -47.305143) (xy 428.016677 -47.35855) (xy 428.024797 -47.413726)
			(xy 428.025306 -47.441612) (xy 428.024797 -47.469498) (xy 428.016677 -47.524674) (xy 428.000609 -47.578081)
			(xy 427.976937 -47.628578) (xy 427.946164 -47.675091) (xy 427.908947 -47.716628) (xy 427.866079 -47.752303)
			(xy 427.818473 -47.781357) (xy 427.767144 -47.803169) (xy 427.713187 -47.817275) (xy 427.65775 -47.823375)
			(xy 427.602016 -47.821338) (xy 427.547173 -47.811208) (xy 427.494389 -47.793201) (xy 427.444789 -47.7677)
			(xy 427.399431 -47.735249) (xy 427.359282 -47.69654) (xy 427.325196 -47.652397) (xy 427.2979 -47.603762)
			(xy 427.277977 -47.551671) (xy 427.265851 -47.497234) (xy 427.26178 -47.441612) (xy 425.987741 -47.441612)
			(xy 425.981508 -47.484965) (xy 425.966153 -47.53726) (xy 425.943511 -47.586837) (xy 425.914045 -47.632687)
			(xy 425.878354 -47.673878) (xy 425.837163 -47.709569) (xy 425.791313 -47.739035) (xy 425.741736 -47.761677)
			(xy 425.689441 -47.777032) (xy 425.635493 -47.784788) (xy 425.580991 -47.784788) (xy 425.527043 -47.777032)
			(xy 425.474748 -47.761677) (xy 425.425171 -47.739035) (xy 425.379321 -47.709569) (xy 425.33813 -47.673878)
			(xy 425.302439 -47.632687) (xy 425.272973 -47.586837) (xy 425.250331 -47.53726) (xy 425.234976 -47.484965)
			(xy 425.22722 -47.431017) (xy 425.226734 -47.403766) (xy 425.227203 -47.377338) (xy 425.234513 -47.324991)
			(xy 425.248987 -47.274156) (xy 425.270349 -47.225809) (xy 425.283884 -47.203106) (xy 425.284138 -47.202852)
			(xy 425.289473 -47.192833) (xy 425.291732 -47.170283) (xy 425.288456 -47.159418) (xy 425.262294 -47.084742)
			(xy 425.257934 -47.074214) (xy 425.241829 -47.058131) (xy 425.231306 -47.053754) (xy 425.231052 -47.053754)
			(xy 425.206544 -47.044684) (xy 425.160091 -47.020741) (xy 425.117339 -46.990685) (xy 425.079087 -46.955078)
			(xy 425.046051 -46.914585) (xy 425.018847 -46.869964) (xy 424.997985 -46.822049) (xy 424.983855 -46.771736)
			(xy 424.976721 -46.719966) (xy 424.97629 -46.693836) (xy 419.830066 -46.693836) (xy 419.832456 -46.708745)
			(xy 419.833044 -46.739048) (xy 419.832567 -46.766299) (xy 419.824805 -46.820245) (xy 419.809445 -46.872538)
			(xy 419.786801 -46.922113) (xy 419.757333 -46.967961) (xy 419.721641 -47.00915) (xy 419.680451 -47.044841)
			(xy 419.634602 -47.074307) (xy 419.585026 -47.09695) (xy 419.532733 -47.112307) (xy 419.478787 -47.120068)
			(xy 419.451536 -47.120556) (xy 419.425503 -47.120081) (xy 419.373922 -47.113) (xy 419.323781 -47.098976)
			(xy 419.276009 -47.078272) (xy 419.231493 -47.051269) (xy 419.210998 -47.035212) (xy 419.203248 -47.029459)
			(xy 419.184832 -47.023725) (xy 419.175184 -47.024036) (xy 419.095428 -47.030386) (xy 419.077648 -47.039022)
			(xy 419.071298 -47.046388) (xy 419.053141 -47.066057) (xy 419.012228 -47.100577) (xy 418.966894 -47.129043)
			(xy 418.918028 -47.150897) (xy 418.866588 -47.165709) (xy 418.813583 -47.17319) (xy 418.786818 -47.173642)
			(xy 418.759569 -47.173105) (xy 418.705625 -47.165352) (xy 418.653333 -47.150001) (xy 418.603758 -47.127364)
			(xy 418.557909 -47.097903) (xy 418.51672 -47.062217) (xy 418.481028 -47.021032) (xy 418.451561 -46.975187)
			(xy 418.428917 -46.925616) (xy 418.413559 -46.873326) (xy 418.405799 -46.819383) (xy 418.40531 -46.792134)
			(xy 418.405832 -46.76336) (xy 418.414483 -46.706465) (xy 418.43158 -46.651515) (xy 418.456734 -46.599755)
			(xy 418.489375 -46.552359) (xy 418.508688 -46.531022) (xy 418.516054 -46.523148) (xy 418.523166 -46.503336)
			(xy 418.5158 -46.40707) (xy 418.505894 -46.388274) (xy 418.497512 -46.38167) (xy 418.475326 -46.363447)
			(xy 418.436116 -46.321511) (xy 418.403631 -46.274175) (xy 418.378603 -46.222507) (xy 418.361597 -46.167672)
			(xy 418.352996 -46.110909) (xy 418.352478 -46.082204) (xy 415.178423 -46.082204) (xy 415.177732 -46.085506)
			(xy 414.712508 -48.30699) (xy 424.85386 -48.30699) (xy 424.857931 -48.251368) (xy 424.870057 -48.196931)
			(xy 424.88998 -48.14484) (xy 424.917276 -48.096205) (xy 424.951362 -48.052062) (xy 424.991511 -48.013353)
			(xy 425.036869 -47.980902) (xy 425.086469 -47.955401) (xy 425.139253 -47.937394) (xy 425.194096 -47.927264)
			(xy 425.24983 -47.925227) (xy 425.305267 -47.931327) (xy 425.359224 -47.945433) (xy 425.410553 -47.967245)
			(xy 425.458159 -47.996299) (xy 425.501027 -48.031974) (xy 425.538244 -48.073511) (xy 425.569017 -48.120024)
			(xy 425.592689 -48.170521) (xy 425.608757 -48.223928) (xy 425.616877 -48.279104) (xy 425.617386 -48.30699)
			(xy 425.616877 -48.334876) (xy 425.608757 -48.390052) (xy 425.592689 -48.443459) (xy 425.569017 -48.493956)
			(xy 425.538244 -48.540469) (xy 425.501027 -48.582006) (xy 425.458159 -48.617681) (xy 425.410553 -48.646735)
			(xy 425.359224 -48.668547) (xy 425.305267 -48.682653) (xy 425.24983 -48.688753) (xy 425.194096 -48.686716)
			(xy 425.139253 -48.676586) (xy 425.086469 -48.658579) (xy 425.036869 -48.633078) (xy 424.991511 -48.600627)
			(xy 424.951362 -48.561918) (xy 424.917276 -48.517775) (xy 424.88998 -48.46914) (xy 424.870057 -48.417049)
			(xy 424.857931 -48.362612) (xy 424.85386 -48.30699) (xy 414.712508 -48.30699) (xy 414.619102 -48.753014)
			(xy 421.468294 -48.753014) (xy 421.472365 -48.697392) (xy 421.484491 -48.642955) (xy 421.504414 -48.590864)
			(xy 421.53171 -48.542229) (xy 421.565796 -48.498086) (xy 421.605945 -48.459377) (xy 421.651303 -48.426926)
			(xy 421.700903 -48.401425) (xy 421.753687 -48.383418) (xy 421.80853 -48.373288) (xy 421.864264 -48.371251)
			(xy 421.919701 -48.377351) (xy 421.973658 -48.391457) (xy 422.024987 -48.413269) (xy 422.072593 -48.442323)
			(xy 422.115461 -48.477998) (xy 422.152678 -48.519535) (xy 422.183451 -48.566048) (xy 422.207123 -48.616545)
			(xy 422.223191 -48.669952) (xy 422.231311 -48.725128) (xy 422.23182 -48.753014) (xy 422.231311 -48.7809)
			(xy 422.223191 -48.836076) (xy 422.220747 -48.8442) (xy 422.487342 -48.8442) (xy 422.491413 -48.788578)
			(xy 422.503539 -48.734141) (xy 422.523462 -48.68205) (xy 422.550758 -48.633415) (xy 422.584844 -48.589272)
			(xy 422.624993 -48.550563) (xy 422.670351 -48.518112) (xy 422.719951 -48.492611) (xy 422.772735 -48.474604)
			(xy 422.827578 -48.464474) (xy 422.883312 -48.462437) (xy 422.938749 -48.468537) (xy 422.992706 -48.482643)
			(xy 423.044035 -48.504455) (xy 423.091641 -48.533509) (xy 423.134509 -48.569184) (xy 423.171726 -48.610721)
			(xy 423.202499 -48.657234) (xy 423.226171 -48.707731) (xy 423.242239 -48.761138) (xy 423.250359 -48.816314)
			(xy 423.250868 -48.8442) (xy 423.250359 -48.872086) (xy 423.247361 -48.89246) (xy 423.51401 -48.89246)
			(xy 423.518081 -48.836838) (xy 423.530207 -48.782401) (xy 423.55013 -48.73031) (xy 423.577426 -48.681675)
			(xy 423.611512 -48.637532) (xy 423.651661 -48.598823) (xy 423.697019 -48.566372) (xy 423.746619 -48.540871)
			(xy 423.799403 -48.522864) (xy 423.854246 -48.512734) (xy 423.90998 -48.510697) (xy 423.965417 -48.516797)
			(xy 424.019374 -48.530903) (xy 424.070703 -48.552715) (xy 424.118309 -48.581769) (xy 424.161177 -48.617444)
			(xy 424.198394 -48.658981) (xy 424.229167 -48.705494) (xy 424.252839 -48.755991) (xy 424.268907 -48.809398)
			(xy 424.277027 -48.864574) (xy 424.277536 -48.89246) (xy 424.277027 -48.920346) (xy 424.274589 -48.93691)
			(xy 427.233078 -48.93691) (xy 427.237149 -48.881288) (xy 427.249275 -48.826851) (xy 427.269198 -48.77476)
			(xy 427.296494 -48.726125) (xy 427.33058 -48.681982) (xy 427.370729 -48.643273) (xy 427.416087 -48.610822)
			(xy 427.465687 -48.585321) (xy 427.518471 -48.567314) (xy 427.573314 -48.557184) (xy 427.629048 -48.555147)
			(xy 427.684485 -48.561247) (xy 427.738442 -48.575353) (xy 427.789771 -48.597165) (xy 427.837377 -48.626219)
			(xy 427.880245 -48.661894) (xy 427.917462 -48.703431) (xy 427.948235 -48.749944) (xy 427.971907 -48.800441)
			(xy 427.987975 -48.853848) (xy 427.996095 -48.909024) (xy 427.996604 -48.93691) (xy 427.996095 -48.964796)
			(xy 427.987975 -49.019972) (xy 427.971907 -49.073379) (xy 427.948235 -49.123876) (xy 427.917462 -49.170389)
			(xy 427.880245 -49.211926) (xy 427.837377 -49.247601) (xy 427.789771 -49.276655) (xy 427.738442 -49.298467)
			(xy 427.684485 -49.312573) (xy 427.629048 -49.318673) (xy 427.573314 -49.316636) (xy 427.518471 -49.306506)
			(xy 427.465687 -49.288499) (xy 427.416087 -49.262998) (xy 427.370729 -49.230547) (xy 427.33058 -49.191838)
			(xy 427.296494 -49.147695) (xy 427.269198 -49.09906) (xy 427.249275 -49.046969) (xy 427.237149 -48.992532)
			(xy 427.233078 -48.93691) (xy 424.274589 -48.93691) (xy 424.268907 -48.975522) (xy 424.252839 -49.028929)
			(xy 424.229167 -49.079426) (xy 424.198394 -49.125939) (xy 424.161177 -49.167476) (xy 424.118309 -49.203151)
			(xy 424.070703 -49.232205) (xy 424.019374 -49.254017) (xy 423.965417 -49.268123) (xy 423.90998 -49.274223)
			(xy 423.854246 -49.272186) (xy 423.799403 -49.262056) (xy 423.746619 -49.244049) (xy 423.697019 -49.218548)
			(xy 423.651661 -49.186097) (xy 423.611512 -49.147388) (xy 423.577426 -49.103245) (xy 423.55013 -49.05461)
			(xy 423.530207 -49.002519) (xy 423.518081 -48.948082) (xy 423.51401 -48.89246) (xy 423.247361 -48.89246)
			(xy 423.242239 -48.927262) (xy 423.226171 -48.980669) (xy 423.202499 -49.031166) (xy 423.171726 -49.077679)
			(xy 423.134509 -49.119216) (xy 423.091641 -49.154891) (xy 423.044035 -49.183945) (xy 422.992706 -49.205757)
			(xy 422.938749 -49.219863) (xy 422.883312 -49.225963) (xy 422.827578 -49.223926) (xy 422.772735 -49.213796)
			(xy 422.719951 -49.195789) (xy 422.670351 -49.170288) (xy 422.624993 -49.137837) (xy 422.584844 -49.099128)
			(xy 422.550758 -49.054985) (xy 422.523462 -49.00635) (xy 422.503539 -48.954259) (xy 422.491413 -48.899822)
			(xy 422.487342 -48.8442) (xy 422.220747 -48.8442) (xy 422.207123 -48.889483) (xy 422.183451 -48.93998)
			(xy 422.152678 -48.986493) (xy 422.115461 -49.02803) (xy 422.072593 -49.063705) (xy 422.024987 -49.092759)
			(xy 421.973658 -49.114571) (xy 421.919701 -49.128677) (xy 421.864264 -49.134777) (xy 421.80853 -49.13274)
			(xy 421.753687 -49.12261) (xy 421.700903 -49.104603) (xy 421.651303 -49.079102) (xy 421.605945 -49.046651)
			(xy 421.565796 -49.007942) (xy 421.53171 -48.963799) (xy 421.504414 -48.915164) (xy 421.484491 -48.863073)
			(xy 421.472365 -48.808636) (xy 421.468294 -48.753014) (xy 414.619102 -48.753014) (xy 414.580324 -48.93818)
			(xy 414.579308 -48.948086) (xy 414.572626 -49.601953) (xy 432.412859 -49.601953) (xy 432.412859 -49.547447)
			(xy 432.420616 -49.493497) (xy 432.435972 -49.441199) (xy 432.458615 -49.39162) (xy 432.488083 -49.345767)
			(xy 432.523776 -49.304575) (xy 432.564968 -49.268881) (xy 432.610821 -49.239414) (xy 432.660401 -49.216772)
			(xy 432.712699 -49.201416) (xy 432.766649 -49.193659) (xy 432.793902 -49.193196) (xy 432.821272 -49.193662)
			(xy 432.875451 -49.20148) (xy 432.927954 -49.216969) (xy 432.977701 -49.239811) (xy 433.023668 -49.269535)
			(xy 433.0446 -49.287176) (xy 433.044854 -49.28743) (xy 433.051947 -49.293007) (xy 433.068859 -49.299258)
			(xy 433.077874 -49.299622) (xy 433.14493 -49.299622) (xy 433.153948 -49.299275) (xy 433.170864 -49.29302)
			(xy 433.17795 -49.28743) (xy 433.17795 -49.287176) (xy 433.178204 -49.287176) (xy 433.199137 -49.269535)
			(xy 433.245105 -49.239811) (xy 433.294851 -49.216965) (xy 433.347353 -49.201469) (xy 433.401531 -49.19364)
			(xy 433.456273 -49.19364) (xy 433.510451 -49.201469) (xy 433.562953 -49.216965) (xy 433.612699 -49.239811)
			(xy 433.658667 -49.269535) (xy 433.6796 -49.287176) (xy 433.679854 -49.28743) (xy 433.686947 -49.293007)
			(xy 433.703859 -49.299258) (xy 433.712874 -49.299622) (xy 433.77993 -49.299622) (xy 433.788948 -49.299275)
			(xy 433.805864 -49.29302) (xy 433.81295 -49.28743) (xy 433.81295 -49.287176) (xy 433.813204 -49.287176)
			(xy 433.834137 -49.269535) (xy 433.880105 -49.239811) (xy 433.929851 -49.216965) (xy 433.982353 -49.201469)
			(xy 434.036531 -49.19364) (xy 434.091273 -49.19364) (xy 434.145451 -49.201469) (xy 434.197953 -49.216965)
			(xy 434.247699 -49.239811) (xy 434.293667 -49.269535) (xy 434.3146 -49.287176) (xy 434.314854 -49.28743)
			(xy 434.321947 -49.293007) (xy 434.338859 -49.299258) (xy 434.347874 -49.299622) (xy 434.41493 -49.299622)
			(xy 434.423948 -49.299275) (xy 434.440864 -49.29302) (xy 434.44795 -49.28743) (xy 434.44795 -49.287176)
			(xy 434.448204 -49.287176) (xy 434.469121 -49.269518) (xy 434.515098 -49.23981) (xy 434.56485 -49.216978)
			(xy 434.617353 -49.201491) (xy 434.671532 -49.193668) (xy 434.698902 -49.193196) (xy 434.726153 -49.193674)
			(xy 434.780102 -49.201431) (xy 434.832397 -49.216786) (xy 434.881974 -49.239428) (xy 434.927825 -49.268894)
			(xy 434.969015 -49.304586) (xy 435.004707 -49.345777) (xy 435.034173 -49.391628) (xy 435.056814 -49.441205)
			(xy 435.07217 -49.4935) (xy 435.079926 -49.547449) (xy 435.079926 -49.601951) (xy 435.07217 -49.6559)
			(xy 435.056814 -49.708195) (xy 435.034173 -49.757772) (xy 435.004707 -49.803623) (xy 434.969015 -49.844814)
			(xy 434.927825 -49.880506) (xy 434.881974 -49.909972) (xy 434.832397 -49.932614) (xy 434.780102 -49.947969)
			(xy 434.726153 -49.955726) (xy 434.698902 -49.956212) (xy 434.671532 -49.955742) (xy 434.617353 -49.947925)
			(xy 434.56485 -49.932436) (xy 434.515103 -49.909596) (xy 434.469136 -49.879872) (xy 434.448204 -49.862232)
			(xy 434.44795 -49.861978) (xy 434.440855 -49.856404) (xy 434.423945 -49.85015) (xy 434.41493 -49.849786)
			(xy 434.347874 -49.849786) (xy 434.338856 -49.850134) (xy 434.32194 -49.856388) (xy 434.314854 -49.861978)
			(xy 434.3146 -49.862232) (xy 434.293667 -49.879873) (xy 434.247699 -49.909597) (xy 434.197953 -49.932443)
			(xy 434.145451 -49.947939) (xy 434.091273 -49.955768) (xy 434.036531 -49.955768) (xy 433.982353 -49.947939)
			(xy 433.929851 -49.932443) (xy 433.880105 -49.909597) (xy 433.834137 -49.879873) (xy 433.813204 -49.862232)
			(xy 433.81295 -49.861978) (xy 433.805855 -49.856404) (xy 433.788945 -49.85015) (xy 433.77993 -49.849786)
			(xy 433.712874 -49.849786) (xy 433.703856 -49.850134) (xy 433.68694 -49.856388) (xy 433.679854 -49.861978)
			(xy 433.679854 -49.862232) (xy 433.6796 -49.862232) (xy 433.658667 -49.879873) (xy 433.612699 -49.909597)
			(xy 433.562953 -49.932443) (xy 433.510451 -49.947939) (xy 433.456273 -49.955768) (xy 433.401531 -49.955768)
			(xy 433.347353 -49.947939) (xy 433.294851 -49.932443) (xy 433.245105 -49.909597) (xy 433.199137 -49.879873)
			(xy 433.178204 -49.862232) (xy 433.17795 -49.861978) (xy 433.170855 -49.856404) (xy 433.153945 -49.85015)
			(xy 433.14493 -49.849786) (xy 433.077874 -49.849786) (xy 433.068856 -49.850134) (xy 433.05194 -49.856388)
			(xy 433.044854 -49.861978) (xy 433.044854 -49.862232) (xy 433.0446 -49.862232) (xy 433.023683 -49.87989)
			(xy 432.977705 -49.909598) (xy 432.927954 -49.932429) (xy 432.87545 -49.947916) (xy 432.821272 -49.95574)
			(xy 432.793902 -49.956212) (xy 432.766649 -49.955741) (xy 432.712699 -49.947984) (xy 432.660401 -49.932628)
			(xy 432.610821 -49.909986) (xy 432.564968 -49.880519) (xy 432.523776 -49.844825) (xy 432.488083 -49.803633)
			(xy 432.458615 -49.75778) (xy 432.435972 -49.708201) (xy 432.420616 -49.655903) (xy 432.412859 -49.601953)
			(xy 414.572626 -49.601953) (xy 414.563426 -50.502312) (xy 423.116754 -50.502312) (xy 423.120825 -50.44669)
			(xy 423.132951 -50.392253) (xy 423.152874 -50.340162) (xy 423.18017 -50.291527) (xy 423.214256 -50.247384)
			(xy 423.254405 -50.208675) (xy 423.299763 -50.176224) (xy 423.349363 -50.150723) (xy 423.402147 -50.132716)
			(xy 423.45699 -50.122586) (xy 423.512724 -50.120549) (xy 423.568161 -50.126649) (xy 423.622118 -50.140755)
			(xy 423.673447 -50.162567) (xy 423.721053 -50.191621) (xy 423.763921 -50.227296) (xy 423.801138 -50.268833)
			(xy 423.831911 -50.315346) (xy 423.855583 -50.365843) (xy 423.871651 -50.41925) (xy 423.879771 -50.474426)
			(xy 423.88028 -50.502312) (xy 423.879771 -50.530198) (xy 423.871651 -50.585374) (xy 423.855583 -50.638781)
			(xy 423.831911 -50.689278) (xy 423.801138 -50.735791) (xy 423.763921 -50.777328) (xy 423.721053 -50.813003)
			(xy 423.673447 -50.842057) (xy 423.622118 -50.863869) (xy 423.568161 -50.877975) (xy 423.512724 -50.884075)
			(xy 423.45699 -50.882038) (xy 423.402147 -50.871908) (xy 423.349363 -50.853901) (xy 423.299763 -50.8284)
			(xy 423.254405 -50.795949) (xy 423.214256 -50.75724) (xy 423.18017 -50.713097) (xy 423.152874 -50.664462)
			(xy 423.132951 -50.612371) (xy 423.120825 -50.557934) (xy 423.116754 -50.502312) (xy 414.563426 -50.502312)
			(xy 414.558141 -51.019456) (xy 425.04944 -51.019456) (xy 425.053511 -50.963834) (xy 425.065637 -50.909397)
			(xy 425.08556 -50.857306) (xy 425.112856 -50.808671) (xy 425.146942 -50.764528) (xy 425.187091 -50.725819)
			(xy 425.232449 -50.693368) (xy 425.282049 -50.667867) (xy 425.334833 -50.64986) (xy 425.389676 -50.63973)
			(xy 425.44541 -50.637693) (xy 425.500847 -50.643793) (xy 425.554804 -50.657899) (xy 425.606133 -50.679711)
			(xy 425.653739 -50.708765) (xy 425.696607 -50.74444) (xy 425.733824 -50.785977) (xy 425.764597 -50.83249)
			(xy 425.788269 -50.882987) (xy 425.804337 -50.936394) (xy 425.812457 -50.99157) (xy 425.812966 -51.019456)
			(xy 425.812457 -51.047342) (xy 425.804337 -51.102518) (xy 425.788269 -51.155925) (xy 425.764597 -51.206422)
			(xy 425.739741 -51.243992) (xy 433.432966 -51.243992) (xy 433.433411 -51.216621) (xy 433.441232 -51.16244)
			(xy 433.456725 -51.109936) (xy 433.479571 -51.06019) (xy 433.509302 -51.014224) (xy 433.526946 -50.993294)
			(xy 433.5272 -50.99304) (xy 433.532776 -50.985946) (xy 433.539029 -50.969035) (xy 433.539392 -50.96002)
			(xy 433.539392 -50.892964) (xy 433.539054 -50.883945) (xy 433.532793 -50.867028) (xy 433.5272 -50.859944)
			(xy 433.526946 -50.859944) (xy 433.526946 -50.85969) (xy 433.509296 -50.838767) (xy 433.479584 -50.792792)
			(xy 433.45675 -50.743043) (xy 433.441261 -50.69054) (xy 433.433437 -50.636362) (xy 433.432966 -50.608992)
			(xy 433.43347 -50.581742) (xy 433.441227 -50.527796) (xy 433.456582 -50.475503) (xy 433.479222 -50.425928)
			(xy 433.508687 -50.380079) (xy 433.544376 -50.338889) (xy 433.585564 -50.303198) (xy 433.631412 -50.273731)
			(xy 433.680986 -50.251088) (xy 433.733278 -50.235731) (xy 433.787224 -50.227972) (xy 433.814474 -50.227484)
			(xy 433.843392 -50.227989) (xy 433.900565 -50.236716) (xy 433.955766 -50.253975) (xy 434.007728 -50.279369)
			(xy 434.055261 -50.312316) (xy 434.097276 -50.352062) (xy 434.115464 -50.37455) (xy 434.123088 -50.383339)
			(xy 434.143976 -50.393531) (xy 434.155596 -50.394108) (xy 434.235352 -50.394108) (xy 434.246985 -50.393582)
			(xy 434.267894 -50.383383) (xy 434.275484 -50.37455) (xy 434.293671 -50.352064) (xy 434.335693 -50.312331)
			(xy 434.38323 -50.279394) (xy 434.435191 -50.254006) (xy 434.490389 -50.23675) (xy 434.547558 -50.22802)
			(xy 434.576474 -50.227484) (xy 434.603726 -50.227979) (xy 434.657675 -50.235733) (xy 434.709972 -50.251085)
			(xy 434.759551 -50.273724) (xy 434.805404 -50.303188) (xy 434.846597 -50.338879) (xy 434.882291 -50.380068)
			(xy 434.91176 -50.425919) (xy 434.934403 -50.475496) (xy 434.94976 -50.527792) (xy 434.957518 -50.58174)
			(xy 434.957982 -50.608992) (xy 434.957515 -50.635306) (xy 434.950281 -50.687435) (xy 434.935962 -50.738078)
			(xy 434.91483 -50.786277) (xy 434.887283 -50.83112) (xy 434.853844 -50.87176) (xy 434.834792 -50.889916)
			(xy 434.82738 -50.897429) (xy 434.818862 -50.916716) (xy 434.818282 -50.927254) (xy 434.818282 -51.00193)
			(xy 434.818841 -51.012476) (xy 434.827356 -51.031772) (xy 434.834792 -51.039268) (xy 434.853872 -51.057399)
			(xy 434.887327 -51.098034) (xy 434.914883 -51.142879) (xy 434.936017 -51.191085) (xy 434.950329 -51.241737)
			(xy 434.957547 -51.293874) (xy 434.957982 -51.320192) (xy 434.957537 -51.347446) (xy 434.949781 -51.401399)
			(xy 434.934424 -51.453699) (xy 434.911781 -51.50328) (xy 434.882311 -51.549135) (xy 434.846615 -51.590328)
			(xy 434.80542 -51.626022) (xy 434.759565 -51.655489) (xy 434.709982 -51.678131) (xy 434.657681 -51.693484)
			(xy 434.603728 -51.701238) (xy 434.576474 -51.7017) (xy 434.548808 -51.701208) (xy 434.494058 -51.693205)
			(xy 434.441036 -51.677385) (xy 434.390852 -51.654079) (xy 434.344557 -51.623774) (xy 434.303119 -51.587106)
			(xy 434.267407 -51.544842) (xy 434.25237 -51.521614) (xy 434.245757 -51.511918) (xy 434.225878 -51.499485)
			(xy 434.21427 -51.497738) (xy 434.13426 -51.489864) (xy 434.122621 -51.489211) (xy 434.100782 -51.497305)
			(xy 434.09235 -51.505358) (xy 434.092096 -51.505612) (xy 434.074002 -51.52418) (xy 434.033672 -51.556759)
			(xy 433.989301 -51.583573) (xy 433.941705 -51.604128) (xy 433.891763 -51.618045) (xy 433.840396 -51.625066)
			(xy 433.814474 -51.6255) (xy 433.787222 -51.625046) (xy 433.733272 -51.617286) (xy 433.680977 -51.601927)
			(xy 433.631399 -51.579283) (xy 433.585548 -51.549813) (xy 433.544358 -51.514118) (xy 433.508667 -51.472925)
			(xy 433.479201 -51.427071) (xy 433.456561 -51.377491) (xy 433.441207 -51.325194) (xy 433.433451 -51.271244)
			(xy 433.432966 -51.243992) (xy 425.739741 -51.243992) (xy 425.733824 -51.252935) (xy 425.696607 -51.294472)
			(xy 425.653739 -51.330147) (xy 425.606133 -51.359201) (xy 425.554804 -51.381013) (xy 425.500847 -51.395119)
			(xy 425.44541 -51.401219) (xy 425.389676 -51.399182) (xy 425.334833 -51.389052) (xy 425.282049 -51.371045)
			(xy 425.232449 -51.345544) (xy 425.187091 -51.313093) (xy 425.146942 -51.274384) (xy 425.112856 -51.230241)
			(xy 425.08556 -51.181606) (xy 425.065637 -51.129515) (xy 425.053511 -51.075078) (xy 425.04944 -51.019456)
			(xy 414.558141 -51.019456) (xy 414.547759 -52.035456) (xy 427.241206 -52.035456) (xy 427.245277 -51.979834)
			(xy 427.257403 -51.925397) (xy 427.277326 -51.873306) (xy 427.304622 -51.824671) (xy 427.338708 -51.780528)
			(xy 427.378857 -51.741819) (xy 427.424215 -51.709368) (xy 427.473815 -51.683867) (xy 427.526599 -51.66586)
			(xy 427.581442 -51.65573) (xy 427.637176 -51.653693) (xy 427.692613 -51.659793) (xy 427.74657 -51.673899)
			(xy 427.797899 -51.695711) (xy 427.845505 -51.724765) (xy 427.888373 -51.76044) (xy 427.92559 -51.801977)
			(xy 427.956363 -51.84849) (xy 427.980035 -51.898987) (xy 427.996103 -51.952394) (xy 428.004223 -52.00757)
			(xy 428.004732 -52.035456) (xy 428.004223 -52.063342) (xy 427.996103 -52.118518) (xy 427.980035 -52.171925)
			(xy 427.956363 -52.222422) (xy 427.92559 -52.268935) (xy 427.888373 -52.310472) (xy 427.845505 -52.346147)
			(xy 427.797899 -52.375201) (xy 427.74657 -52.397013) (xy 427.692613 -52.411119) (xy 427.637176 -52.417219)
			(xy 427.581442 -52.415182) (xy 427.526599 -52.405052) (xy 427.473815 -52.387045) (xy 427.424215 -52.361544)
			(xy 427.378857 -52.329093) (xy 427.338708 -52.290384) (xy 427.304622 -52.246241) (xy 427.277326 -52.197606)
			(xy 427.257403 -52.145515) (xy 427.245277 -52.091078) (xy 427.241206 -52.035456) (xy 414.547759 -52.035456)
			(xy 414.541462 -52.65166) (xy 414.543748 -52.656486) (xy 414.556284 -52.682862) (xy 414.574016 -52.738502)
			(xy 414.583043 -52.796198) (xy 414.583626 -52.825396) (xy 414.583626 -52.827174) (xy 414.583626 -52.832)
			(xy 414.581594 -52.866544) (xy 414.577287 -52.900695) (xy 414.557988 -52.96676) (xy 414.54324 -52.997862)
			(xy 414.540446 -53.00345) (xy 414.537906 -53.014118) (xy 414.53689 -53.100224) (xy 414.53689 -53.109368)
			(xy 414.535112 -53.274468) (xy 414.537652 -53.279294) (xy 414.552214 -53.307417) (xy 414.572832 -53.367292)
			(xy 414.583284 -53.429749) (xy 414.58388 -53.461412) (xy 414.58388 -53.46192) (xy 414.583216 -53.493592)
			(xy 414.572689 -53.556056) (xy 414.55201 -53.615931) (xy 414.537398 -53.644038) (xy 414.537144 -53.644546)
			(xy 414.53478 -53.649255) (xy 414.531833 -53.65937) (xy 414.531302 -53.664612) (xy 414.529016 -53.86705)
			(xy 414.530794 -53.88102) (xy 414.532572 -53.887116) (xy 414.536636 -53.893466) (xy 414.550072 -53.916517)
			(xy 414.571262 -53.965483) (xy 414.585605 -54.016873) (xy 414.592836 -54.069735) (xy 414.593278 -54.096412)
			(xy 414.593278 -54.09692) (xy 414.592805 -54.123936) (xy 414.585347 -54.177452) (xy 414.570617 -54.229438)
			(xy 414.548893 -54.278911) (xy 414.535112 -54.302152) (xy 414.532318 -54.306724) (xy 414.526476 -54.325266)
			(xy 414.525511 -54.328807) (xy 414.524491 -54.336074) (xy 414.524444 -54.339744) (xy 414.522412 -54.520846)
			(xy 414.522412 -54.522624) (xy 414.52673 -54.52999) (xy 414.527238 -54.530752) (xy 414.54068 -54.553451)
			(xy 414.561878 -54.60176) (xy 414.57623 -54.652524) (xy 414.583464 -54.704781) (xy 414.58388 -54.731158)
			(xy 414.58388 -54.731666) (xy 414.582864 -54.761384) (xy 414.581086 -54.77637) (xy 414.579055 -54.791102)
			(xy 416.476434 -54.791102) (xy 416.476893 -54.763731) (xy 416.484711 -54.709552) (xy 416.500202 -54.657048)
			(xy 416.523045 -54.607301) (xy 416.552772 -54.561335) (xy 416.570414 -54.540404) (xy 416.570668 -54.54015)
			(xy 416.576248 -54.533059) (xy 416.582497 -54.516145) (xy 416.58286 -54.50713) (xy 416.58286 -54.440074)
			(xy 416.582524 -54.431055) (xy 416.576263 -54.414137) (xy 416.570668 -54.407054) (xy 416.570414 -54.407054)
			(xy 416.570414 -54.4068) (xy 416.552776 -54.385865) (xy 416.523052 -54.339898) (xy 416.500207 -54.290152)
			(xy 416.484711 -54.23765) (xy 416.476883 -54.183472) (xy 416.476883 -54.128731) (xy 416.484711 -54.074553)
			(xy 416.500206 -54.022051) (xy 416.52305 -53.972305) (xy 416.552774 -53.926337) (xy 416.570414 -53.905404)
			(xy 416.570668 -53.90515) (xy 416.576248 -53.898059) (xy 416.582497 -53.881145) (xy 416.58286 -53.87213)
			(xy 416.58286 -53.805074) (xy 416.582524 -53.796055) (xy 416.576263 -53.779137) (xy 416.570668 -53.772054)
			(xy 416.570414 -53.772054) (xy 416.570414 -53.7718) (xy 416.552776 -53.750865) (xy 416.523052 -53.704898)
			(xy 416.500207 -53.655152) (xy 416.484711 -53.60265) (xy 416.476883 -53.548472) (xy 416.476883 -53.493731)
			(xy 416.484711 -53.439553) (xy 416.500206 -53.387051) (xy 416.52305 -53.337305) (xy 416.552774 -53.291337)
			(xy 416.570414 -53.270404) (xy 416.570668 -53.27015) (xy 416.576248 -53.263059) (xy 416.582497 -53.246145)
			(xy 416.58286 -53.23713) (xy 416.58286 -53.170074) (xy 416.582524 -53.161055) (xy 416.576263 -53.144137)
			(xy 416.570668 -53.137054) (xy 416.570414 -53.137054) (xy 416.570414 -53.1368) (xy 416.552764 -53.115877)
			(xy 416.523053 -53.069902) (xy 416.500219 -53.020152) (xy 416.484731 -52.967649) (xy 416.476906 -52.913472)
			(xy 416.476434 -52.886102) (xy 416.47692 -52.858851) (xy 416.484676 -52.804903) (xy 416.500031 -52.752608)
			(xy 416.522673 -52.703031) (xy 416.552139 -52.657181) (xy 416.58783 -52.61599) (xy 416.629021 -52.580299)
			(xy 416.674871 -52.550833) (xy 416.724448 -52.528191) (xy 416.776743 -52.512836) (xy 416.830691 -52.50508)
			(xy 416.885193 -52.50508) (xy 416.939141 -52.512836) (xy 416.991436 -52.528191) (xy 417.03054 -52.54605)
			(xy 421.979596 -52.54605) (xy 421.979596 -52.49155) (xy 421.987352 -52.437605) (xy 422.002707 -52.385313)
			(xy 422.025347 -52.335738) (xy 422.054811 -52.28989) (xy 422.090501 -52.248702) (xy 422.131689 -52.213012)
			(xy 422.177537 -52.183547) (xy 422.227111 -52.160907) (xy 422.279403 -52.145553) (xy 422.333348 -52.137796)
			(xy 422.360598 -52.13731) (xy 422.387968 -52.137775) (xy 422.442148 -52.145593) (xy 422.494651 -52.161082)
			(xy 422.544398 -52.183924) (xy 422.590364 -52.213649) (xy 422.611296 -52.23129) (xy 422.61155 -52.231544)
			(xy 422.618643 -52.237121) (xy 422.635555 -52.243372) (xy 422.64457 -52.243736) (xy 422.711626 -52.243736)
			(xy 422.720643 -52.243384) (xy 422.73756 -52.237132) (xy 422.744646 -52.231544) (xy 422.744646 -52.23129)
			(xy 422.7449 -52.23129) (xy 422.765833 -52.213649) (xy 422.811801 -52.183925) (xy 422.861547 -52.161079)
			(xy 422.914049 -52.145583) (xy 422.968227 -52.137754) (xy 423.022969 -52.137754) (xy 423.077147 -52.145583)
			(xy 423.129649 -52.161079) (xy 423.179395 -52.183925) (xy 423.225363 -52.213649) (xy 423.246296 -52.23129)
			(xy 423.24655 -52.231544) (xy 423.253643 -52.237121) (xy 423.270555 -52.243372) (xy 423.27957 -52.243736)
			(xy 423.346626 -52.243736) (xy 423.355643 -52.243384) (xy 423.37256 -52.237132) (xy 423.379646 -52.231544)
			(xy 423.379646 -52.23129) (xy 423.3799 -52.23129) (xy 423.40082 -52.213636) (xy 423.446796 -52.183927)
			(xy 423.496547 -52.161094) (xy 423.54905 -52.145606) (xy 423.603228 -52.137782) (xy 423.630598 -52.13731)
			(xy 423.657852 -52.137737) (xy 423.711806 -52.145494) (xy 423.764107 -52.16085) (xy 423.813689 -52.183494)
			(xy 423.859545 -52.212963) (xy 423.90074 -52.248659) (xy 423.936435 -52.289853) (xy 423.965905 -52.335709)
			(xy 423.988549 -52.385292) (xy 424.003906 -52.437592) (xy 424.011663 -52.491546) (xy 424.011663 -52.546054)
			(xy 424.005719 -52.587398) (xy 425.055282 -52.587398) (xy 425.059353 -52.531776) (xy 425.071479 -52.477339)
			(xy 425.091402 -52.425248) (xy 425.118698 -52.376613) (xy 425.152784 -52.33247) (xy 425.192933 -52.293761)
			(xy 425.238291 -52.26131) (xy 425.287891 -52.235809) (xy 425.340675 -52.217802) (xy 425.395518 -52.207672)
			(xy 425.451252 -52.205635) (xy 425.506689 -52.211735) (xy 425.560646 -52.225841) (xy 425.611975 -52.247653)
			(xy 425.659581 -52.276707) (xy 425.702449 -52.312382) (xy 425.739666 -52.353919) (xy 425.770439 -52.400432)
			(xy 425.794111 -52.450929) (xy 425.810179 -52.504336) (xy 425.817775 -52.555952) (xy 432.883779 -52.555952)
			(xy 432.883779 -52.501448) (xy 432.891536 -52.447499) (xy 432.906892 -52.395203) (xy 432.929535 -52.345625)
			(xy 432.959002 -52.299774) (xy 432.994696 -52.258583) (xy 433.035888 -52.222892) (xy 433.081741 -52.193426)
			(xy 433.13132 -52.170786) (xy 433.183617 -52.155432) (xy 433.237566 -52.147678) (xy 433.264818 -52.147216)
			(xy 433.292189 -52.147668) (xy 433.346369 -52.155488) (xy 433.398872 -52.170981) (xy 433.448619 -52.193826)
			(xy 433.494585 -52.223553) (xy 433.515516 -52.241196) (xy 433.51577 -52.24145) (xy 433.522857 -52.247036)
			(xy 433.539774 -52.253282) (xy 433.54879 -52.253642) (xy 433.615846 -52.253642) (xy 433.624862 -52.253272)
			(xy 433.64178 -52.247035) (xy 433.648866 -52.24145) (xy 433.648866 -52.241196) (xy 433.64912 -52.241196)
			(xy 433.670071 -52.22358) (xy 433.716039 -52.193865) (xy 433.765781 -52.171025) (xy 433.818278 -52.155528)
			(xy 433.87245 -52.147694) (xy 433.899818 -52.147216) (xy 433.92707 -52.147655) (xy 433.981019 -52.155414)
			(xy 434.033315 -52.170772) (xy 434.082893 -52.193415) (xy 434.128744 -52.222884) (xy 434.169935 -52.258578)
			(xy 434.205627 -52.29977) (xy 434.235093 -52.345623) (xy 434.257734 -52.395202) (xy 434.27309 -52.447498)
			(xy 434.280846 -52.501448) (xy 434.280846 -52.555952) (xy 434.27309 -52.609902) (xy 434.257734 -52.662198)
			(xy 434.235093 -52.711777) (xy 434.205627 -52.75763) (xy 434.169935 -52.798822) (xy 434.128744 -52.834516)
			(xy 434.082893 -52.863985) (xy 434.033315 -52.886628) (xy 433.981019 -52.901986) (xy 433.92707 -52.909745)
			(xy 433.899818 -52.910232) (xy 433.872447 -52.909772) (xy 433.818267 -52.901955) (xy 433.765764 -52.886466)
			(xy 433.716017 -52.863622) (xy 433.670051 -52.833895) (xy 433.64912 -52.816252) (xy 433.648866 -52.815998)
			(xy 433.641765 -52.810433) (xy 433.624859 -52.804173) (xy 433.615846 -52.803806) (xy 433.54879 -52.803806)
			(xy 433.539772 -52.804157) (xy 433.522856 -52.810409) (xy 433.51577 -52.815998) (xy 433.51577 -52.816252)
			(xy 433.515516 -52.816252) (xy 433.494583 -52.83389) (xy 433.448611 -52.863603) (xy 433.398864 -52.88644)
			(xy 433.346363 -52.901932) (xy 433.292187 -52.909759) (xy 433.264818 -52.910232) (xy 433.237566 -52.909722)
			(xy 433.183617 -52.901968) (xy 433.13132 -52.886614) (xy 433.081741 -52.863974) (xy 433.035888 -52.834508)
			(xy 432.994696 -52.798817) (xy 432.959002 -52.757626) (xy 432.929535 -52.711775) (xy 432.906892 -52.662197)
			(xy 432.891536 -52.609901) (xy 432.883779 -52.555952) (xy 425.817775 -52.555952) (xy 425.818299 -52.559512)
			(xy 425.818808 -52.587398) (xy 425.818299 -52.615284) (xy 425.810179 -52.67046) (xy 425.794111 -52.723867)
			(xy 425.770439 -52.774364) (xy 425.739666 -52.820877) (xy 425.702449 -52.862414) (xy 425.659581 -52.898089)
			(xy 425.611975 -52.927143) (xy 425.560646 -52.948955) (xy 425.506689 -52.963061) (xy 425.451252 -52.969161)
			(xy 425.395518 -52.967124) (xy 425.340675 -52.956994) (xy 425.287891 -52.938987) (xy 425.238291 -52.913486)
			(xy 425.192933 -52.881035) (xy 425.152784 -52.842326) (xy 425.118698 -52.798183) (xy 425.091402 -52.749548)
			(xy 425.071479 -52.697457) (xy 425.059353 -52.64302) (xy 425.055282 -52.587398) (xy 424.005719 -52.587398)
			(xy 424.003906 -52.600008) (xy 423.988549 -52.652308) (xy 423.965905 -52.701891) (xy 423.936435 -52.747747)
			(xy 423.90074 -52.788941) (xy 423.859545 -52.824637) (xy 423.813689 -52.854106) (xy 423.764107 -52.87675)
			(xy 423.711806 -52.892106) (xy 423.657852 -52.899863) (xy 423.630598 -52.900326) (xy 423.603227 -52.899879)
			(xy 423.549046 -52.892059) (xy 423.496542 -52.876567) (xy 423.446796 -52.85372) (xy 423.40083 -52.82399)
			(xy 423.3799 -52.806346) (xy 423.379646 -52.806092) (xy 423.372551 -52.800518) (xy 423.355641 -52.794264)
			(xy 423.346626 -52.7939) (xy 423.27957 -52.7939) (xy 423.270552 -52.794243) (xy 423.253635 -52.8005)
			(xy 423.24655 -52.806092) (xy 423.246296 -52.806346) (xy 423.225363 -52.823987) (xy 423.179395 -52.853711)
			(xy 423.129649 -52.876557) (xy 423.077147 -52.892053) (xy 423.022969 -52.899882) (xy 422.968227 -52.899882)
			(xy 422.914049 -52.892053) (xy 422.861547 -52.876557) (xy 422.811801 -52.853711) (xy 422.765833 -52.823987)
			(xy 422.7449 -52.806346) (xy 422.744646 -52.806092) (xy 422.737551 -52.800518) (xy 422.720641 -52.794264)
			(xy 422.711626 -52.7939) (xy 422.64457 -52.7939) (xy 422.635552 -52.794243) (xy 422.618635 -52.8005)
			(xy 422.61155 -52.806092) (xy 422.61155 -52.806346) (xy 422.611296 -52.806346) (xy 422.590369 -52.823992)
			(xy 422.544396 -52.853705) (xy 422.494647 -52.87654) (xy 422.442145 -52.892029) (xy 422.387968 -52.899854)
			(xy 422.360598 -52.900326) (xy 422.333348 -52.899804) (xy 422.279403 -52.892047) (xy 422.227111 -52.876693)
			(xy 422.177537 -52.854053) (xy 422.131689 -52.824588) (xy 422.090501 -52.788898) (xy 422.054811 -52.74771)
			(xy 422.025347 -52.701862) (xy 422.002707 -52.652287) (xy 421.987352 -52.599995) (xy 421.979596 -52.54605)
			(xy 417.03054 -52.54605) (xy 417.041013 -52.550833) (xy 417.086863 -52.580299) (xy 417.128054 -52.61599)
			(xy 417.163745 -52.657181) (xy 417.193211 -52.703031) (xy 417.215853 -52.752608) (xy 417.231208 -52.804903)
			(xy 417.238964 -52.858851) (xy 417.23945 -52.886102) (xy 417.238997 -52.913473) (xy 417.231178 -52.967653)
			(xy 417.215687 -53.020157) (xy 417.192842 -53.069903) (xy 417.163113 -53.115869) (xy 417.14547 -53.1368)
			(xy 417.145216 -53.137054) (xy 417.139644 -53.144151) (xy 417.133388 -53.16106) (xy 417.133024 -53.170074)
			(xy 417.133024 -53.23713) (xy 417.133361 -53.246149) (xy 417.139622 -53.263066) (xy 417.145216 -53.27015)
			(xy 417.14547 -53.27015) (xy 417.14547 -53.270404) (xy 417.163113 -53.291335) (xy 417.192838 -53.337303)
			(xy 417.215683 -53.38705) (xy 417.231179 -53.439552) (xy 417.239008 -53.493731) (xy 417.239008 -53.548472)
			(xy 417.231179 -53.602651) (xy 417.215682 -53.655153) (xy 417.192836 -53.7049) (xy 417.163111 -53.750867)
			(xy 417.14654 -53.77053) (xy 417.510722 -53.77053) (xy 417.511254 -53.741613) (xy 417.519979 -53.684443)
			(xy 417.537233 -53.629244) (xy 417.562623 -53.577282) (xy 417.595564 -53.529747) (xy 417.635303 -53.48773)
			(xy 417.657788 -53.46954) (xy 417.666565 -53.461904) (xy 417.676766 -53.441025) (xy 417.677346 -53.429408)
			(xy 417.677346 -53.349652) (xy 417.676839 -53.338016) (xy 417.666629 -53.317105) (xy 417.657788 -53.30952)
			(xy 417.635312 -53.291321) (xy 417.595577 -53.249302) (xy 417.562637 -53.201769) (xy 417.537248 -53.149809)
			(xy 417.51999 -53.094614) (xy 417.511258 -53.037445) (xy 417.510722 -53.00853) (xy 417.511183 -52.981277)
			(xy 417.518937 -52.927324) (xy 417.534291 -52.875024) (xy 417.556932 -52.825442) (xy 417.5864 -52.779587)
			(xy 417.622094 -52.738394) (xy 417.663287 -52.7027) (xy 417.709142 -52.673232) (xy 417.758724 -52.650591)
			(xy 417.811024 -52.635237) (xy 417.864977 -52.627483) (xy 417.89223 -52.627022) (xy 417.918545 -52.627462)
			(xy 417.970675 -52.634702) (xy 418.021318 -52.649026) (xy 418.069517 -52.670163) (xy 418.11436 -52.697714)
			(xy 418.154998 -52.731158) (xy 418.173154 -52.750212) (xy 418.180652 -52.757641) (xy 418.19995 -52.76615)
			(xy 418.210492 -52.766722) (xy 418.285168 -52.766722) (xy 418.295716 -52.766182) (xy 418.315011 -52.757654)
			(xy 418.322506 -52.750212) (xy 418.340668 -52.731163) (xy 418.381296 -52.697705) (xy 418.426135 -52.670144)
			(xy 418.474334 -52.649005) (xy 418.524981 -52.634686) (xy 418.577114 -52.627461) (xy 418.60343 -52.627022)
			(xy 418.630683 -52.62745) (xy 418.684635 -52.635211) (xy 418.736932 -52.650572) (xy 418.786512 -52.673219)
			(xy 418.832363 -52.702691) (xy 418.873554 -52.738388) (xy 418.909245 -52.779585) (xy 418.93871 -52.825441)
			(xy 418.961349 -52.875024) (xy 418.976701 -52.927324) (xy 418.984454 -52.981277) (xy 418.984938 -53.00853)
			(xy 418.984478 -53.036197) (xy 418.982247 -53.051456) (xy 427.241206 -53.051456) (xy 427.245277 -52.995834)
			(xy 427.257403 -52.941397) (xy 427.277326 -52.889306) (xy 427.304622 -52.840671) (xy 427.338708 -52.796528)
			(xy 427.378857 -52.757819) (xy 427.424215 -52.725368) (xy 427.473815 -52.699867) (xy 427.526599 -52.68186)
			(xy 427.581442 -52.67173) (xy 427.637176 -52.669693) (xy 427.692613 -52.675793) (xy 427.74657 -52.689899)
			(xy 427.797899 -52.711711) (xy 427.845505 -52.740765) (xy 427.888373 -52.77644) (xy 427.92559 -52.817977)
			(xy 427.956363 -52.86449) (xy 427.980035 -52.914987) (xy 427.996103 -52.968394) (xy 428.004223 -53.02357)
			(xy 428.004732 -53.051456) (xy 428.004223 -53.079342) (xy 427.996103 -53.134518) (xy 427.980035 -53.187925)
			(xy 427.956363 -53.238422) (xy 427.92559 -53.284935) (xy 427.888373 -53.326472) (xy 427.845505 -53.362147)
			(xy 427.797899 -53.391201) (xy 427.74657 -53.413013) (xy 427.692613 -53.427119) (xy 427.637176 -53.433219)
			(xy 427.581442 -53.431182) (xy 427.526599 -53.421052) (xy 427.473815 -53.403045) (xy 427.424215 -53.377544)
			(xy 427.378857 -53.345093) (xy 427.338708 -53.306384) (xy 427.304622 -53.262241) (xy 427.277326 -53.213606)
			(xy 427.257403 -53.161515) (xy 427.245277 -53.107078) (xy 427.241206 -53.051456) (xy 418.982247 -53.051456)
			(xy 418.976473 -53.09095) (xy 418.960649 -53.143974) (xy 418.937338 -53.194159) (xy 418.907028 -53.240455)
			(xy 418.870354 -53.28189) (xy 418.828083 -53.317599) (xy 418.804852 -53.332634) (xy 418.795162 -53.339255)
			(xy 418.782724 -53.359128) (xy 418.780976 -53.370734) (xy 418.773102 -53.450744) (xy 418.772465 -53.462382)
			(xy 418.78055 -53.484219) (xy 418.788596 -53.492654) (xy 418.78885 -53.492908) (xy 418.807408 -53.511012)
			(xy 418.83999 -53.551338) (xy 418.866808 -53.595707) (xy 418.887365 -53.643301) (xy 418.901283 -53.693242)
			(xy 418.908304 -53.744608) (xy 418.908738 -53.77053) (xy 418.90825 -53.797781) (xy 418.90049 -53.851727)
			(xy 418.885133 -53.90402) (xy 418.862491 -53.953595) (xy 418.833024 -53.999444) (xy 418.797333 -54.040633)
			(xy 418.756144 -54.076324) (xy 418.710295 -54.105791) (xy 418.66072 -54.128433) (xy 418.608427 -54.14379)
			(xy 418.554481 -54.15155) (xy 418.52723 -54.152038) (xy 418.49986 -54.151569) (xy 418.44568 -54.143755)
			(xy 418.393176 -54.128267) (xy 418.343429 -54.105425) (xy 418.297463 -54.0757) (xy 418.276532 -54.058058)
			(xy 418.276278 -54.057804) (xy 418.269202 -54.052203) (xy 418.252277 -54.045965) (xy 418.243258 -54.045612)
			(xy 418.176202 -54.045612) (xy 418.167185 -54.045967) (xy 418.150268 -54.052216) (xy 418.143182 -54.057804)
			(xy 418.143182 -54.058058) (xy 418.142928 -54.058058) (xy 418.121991 -54.075691) (xy 418.07602 -54.105405)
			(xy 418.026274 -54.128243) (xy 417.973774 -54.143735) (xy 417.919599 -54.151564) (xy 417.89223 -54.152038)
			(xy 417.864981 -54.151494) (xy 417.811037 -54.143742) (xy 417.758745 -54.128392) (xy 417.70917 -54.105757)
			(xy 417.663321 -54.076297) (xy 417.622131 -54.040611) (xy 417.586439 -53.999427) (xy 417.556972 -53.953583)
			(xy 417.534328 -53.904011) (xy 417.51897 -53.851722) (xy 417.51121 -53.797779) (xy 417.510722 -53.77053)
			(xy 417.14654 -53.77053) (xy 417.14547 -53.7718) (xy 417.145216 -53.772054) (xy 417.139644 -53.779151)
			(xy 417.133388 -53.79606) (xy 417.133024 -53.805074) (xy 417.133024 -53.87213) (xy 417.133361 -53.881149)
			(xy 417.139622 -53.898066) (xy 417.145216 -53.90515) (xy 417.14547 -53.90515) (xy 417.14547 -53.905404)
			(xy 417.163113 -53.926335) (xy 417.192838 -53.972303) (xy 417.215683 -54.02205) (xy 417.231179 -54.074552)
			(xy 417.239008 -54.128731) (xy 417.239008 -54.183472) (xy 417.231179 -54.237651) (xy 417.215682 -54.290153)
			(xy 417.20189 -54.320186) (xy 419.430454 -54.320186) (xy 419.430899 -54.292815) (xy 419.43872 -54.238634)
			(xy 419.454213 -54.18613) (xy 419.47706 -54.136384) (xy 419.50679 -54.090418) (xy 419.524434 -54.069488)
			(xy 419.524688 -54.069234) (xy 419.530265 -54.062141) (xy 419.536518 -54.045229) (xy 419.53688 -54.036214)
			(xy 419.53688 -53.969158) (xy 419.536499 -53.960143) (xy 419.530269 -53.943226) (xy 419.524688 -53.936138)
			(xy 419.524434 -53.936138) (xy 419.524434 -53.935884) (xy 419.506826 -53.914927) (xy 419.477108 -53.868961)
			(xy 419.454266 -53.81922) (xy 419.438768 -53.766725) (xy 419.430932 -53.712554) (xy 419.430454 -53.685186)
			(xy 419.43094 -53.657935) (xy 419.438696 -53.603987) (xy 419.454051 -53.551692) (xy 419.476693 -53.502115)
			(xy 419.506159 -53.456265) (xy 419.54185 -53.415074) (xy 419.583041 -53.379383) (xy 419.628891 -53.349917)
			(xy 419.678468 -53.327275) (xy 419.730763 -53.31192) (xy 419.784711 -53.304164) (xy 419.839213 -53.304164)
			(xy 419.893161 -53.31192) (xy 419.945456 -53.327275) (xy 419.995033 -53.349917) (xy 420.040883 -53.379383)
			(xy 420.082074 -53.415074) (xy 420.117765 -53.456265) (xy 420.143655 -53.496551) (xy 432.433464 -53.496551)
			(xy 432.433464 -53.442049) (xy 432.44122 -53.388101) (xy 432.456574 -53.335806) (xy 432.479215 -53.286229)
			(xy 432.50868 -53.240378) (xy 432.54437 -53.199187) (xy 432.585559 -53.163494) (xy 432.631408 -53.134026)
			(xy 432.680984 -53.111383) (xy 432.733278 -53.096025) (xy 432.787225 -53.088265) (xy 432.814476 -53.087778)
			(xy 432.841847 -53.088239) (xy 432.896027 -53.096055) (xy 432.948531 -53.111544) (xy 432.998277 -53.134388)
			(xy 433.044243 -53.164115) (xy 433.065174 -53.181758) (xy 433.065428 -53.182012) (xy 433.07253 -53.187576)
			(xy 433.089435 -53.193836) (xy 433.098448 -53.194204) (xy 433.165504 -53.194204) (xy 433.174521 -53.193848)
			(xy 433.191438 -53.1876) (xy 433.198524 -53.182012) (xy 433.198524 -53.181758) (xy 433.198778 -53.181758)
			(xy 433.219702 -53.164109) (xy 433.265678 -53.1344) (xy 433.315427 -53.111566) (xy 433.367929 -53.096077)
			(xy 433.422106 -53.088251) (xy 433.449476 -53.087778) (xy 433.476729 -53.088268) (xy 433.530681 -53.096022)
			(xy 433.582979 -53.111375) (xy 433.632561 -53.134015) (xy 433.678415 -53.163482) (xy 433.719609 -53.199174)
			(xy 433.755304 -53.240366) (xy 433.784773 -53.286218) (xy 433.807417 -53.335798) (xy 433.822773 -53.388096)
			(xy 433.830531 -53.442047) (xy 433.830531 -53.496553) (xy 433.822773 -53.550504) (xy 433.807417 -53.602802)
			(xy 433.784773 -53.652382) (xy 433.755304 -53.698234) (xy 433.719609 -53.739426) (xy 433.678415 -53.775118)
			(xy 433.632561 -53.804585) (xy 433.582979 -53.827225) (xy 433.530681 -53.842578) (xy 433.476729 -53.850332)
			(xy 433.449476 -53.850794) (xy 433.422105 -53.850343) (xy 433.367925 -53.842522) (xy 433.315422 -53.827029)
			(xy 433.265675 -53.804184) (xy 433.219709 -53.774457) (xy 433.198778 -53.756814) (xy 433.198524 -53.75656)
			(xy 433.191438 -53.750972) (xy 433.174521 -53.744727) (xy 433.165504 -53.744368) (xy 433.098448 -53.744368)
			(xy 433.089434 -53.744755) (xy 433.072517 -53.750982) (xy 433.065428 -53.75656) (xy 433.065428 -53.756814)
			(xy 433.065174 -53.756814) (xy 433.044227 -53.774434) (xy 432.998258 -53.804148) (xy 432.948514 -53.826988)
			(xy 432.896017 -53.842483) (xy 432.841844 -53.850317) (xy 432.814476 -53.850794) (xy 432.787225 -53.850335)
			(xy 432.733278 -53.842575) (xy 432.680984 -53.827217) (xy 432.631408 -53.804574) (xy 432.585559 -53.775106)
			(xy 432.54437 -53.739413) (xy 432.50868 -53.698222) (xy 432.479215 -53.652371) (xy 432.456574 -53.602794)
			(xy 432.44122 -53.550499) (xy 432.433464 -53.496551) (xy 420.143655 -53.496551) (xy 420.147231 -53.502115)
			(xy 420.169873 -53.551692) (xy 420.185228 -53.603987) (xy 420.192984 -53.657935) (xy 420.19347 -53.685186)
			(xy 420.193003 -53.712556) (xy 420.185187 -53.766736) (xy 420.169698 -53.819239) (xy 420.146856 -53.868986)
			(xy 420.117132 -53.914953) (xy 420.09949 -53.935884) (xy 420.099236 -53.936138) (xy 420.093662 -53.943233)
			(xy 420.087409 -53.960143) (xy 420.087044 -53.969158) (xy 420.087044 -54.036214) (xy 420.087385 -54.045233)
			(xy 420.093642 -54.06215) (xy 420.099236 -54.069234) (xy 420.09949 -54.069234) (xy 420.09949 -54.069488)
			(xy 420.117135 -54.090415) (xy 420.146847 -54.136389) (xy 420.169682 -54.186138) (xy 420.185171 -54.23864)
			(xy 420.192997 -54.292816) (xy 420.19347 -54.320186) (xy 420.192984 -54.347437) (xy 420.185228 -54.401385)
			(xy 420.169873 -54.45368) (xy 420.147231 -54.503257) (xy 420.117765 -54.549107) (xy 420.082074 -54.590298)
			(xy 420.040883 -54.625989) (xy 419.995033 -54.655455) (xy 419.945456 -54.678097) (xy 419.893161 -54.693452)
			(xy 419.839213 -54.701208) (xy 419.784711 -54.701208) (xy 419.730763 -54.693452) (xy 419.678468 -54.678097)
			(xy 419.628891 -54.655455) (xy 419.583041 -54.625989) (xy 419.54185 -54.590298) (xy 419.506159 -54.549107)
			(xy 419.476693 -54.503257) (xy 419.454051 -54.45368) (xy 419.438696 -54.401385) (xy 419.43094 -54.347437)
			(xy 419.430454 -54.320186) (xy 417.20189 -54.320186) (xy 417.192836 -54.3399) (xy 417.163111 -54.385867)
			(xy 417.14547 -54.4068) (xy 417.145216 -54.407054) (xy 417.139644 -54.414151) (xy 417.133388 -54.43106)
			(xy 417.133024 -54.440074) (xy 417.133024 -54.50713) (xy 417.133361 -54.516149) (xy 417.139622 -54.533066)
			(xy 417.145216 -54.54015) (xy 417.14547 -54.54015) (xy 417.14547 -54.540404) (xy 417.16312 -54.561328)
			(xy 417.192831 -54.607302) (xy 417.215665 -54.657052) (xy 417.231154 -54.709555) (xy 417.238978 -54.763732)
			(xy 417.239095 -54.770528) (xy 420.371016 -54.770528) (xy 420.371495 -54.743158) (xy 420.379309 -54.688979)
			(xy 420.394795 -54.636476) (xy 420.417634 -54.586729) (xy 420.447356 -54.540762) (xy 420.464996 -54.51983)
			(xy 420.46525 -54.519576) (xy 420.470859 -54.512505) (xy 420.477091 -54.495576) (xy 420.477442 -54.486556)
			(xy 420.477442 -54.4195) (xy 420.477097 -54.410482) (xy 420.470843 -54.393564) (xy 420.46525 -54.38648)
			(xy 420.464996 -54.38648) (xy 420.464996 -54.386226) (xy 420.447355 -54.365295) (xy 420.417644 -54.319322)
			(xy 420.394808 -54.269574) (xy 420.379317 -54.217073) (xy 420.37149 -54.162897) (xy 420.371016 -54.135528)
			(xy 420.371502 -54.108277) (xy 420.379258 -54.054329) (xy 420.394613 -54.002034) (xy 420.417255 -53.952457)
			(xy 420.446721 -53.906607) (xy 420.482412 -53.865416) (xy 420.523603 -53.829725) (xy 420.569453 -53.800259)
			(xy 420.61903 -53.777617) (xy 420.671325 -53.762262) (xy 420.725273 -53.754506) (xy 420.779775 -53.754506)
			(xy 420.833723 -53.762262) (xy 420.886018 -53.777617) (xy 420.935595 -53.800259) (xy 420.981445 -53.829725)
			(xy 421.022636 -53.865416) (xy 421.058327 -53.906607) (xy 421.087793 -53.952457) (xy 421.092868 -53.96357)
			(xy 425.072046 -53.96357) (xy 425.076117 -53.907948) (xy 425.088243 -53.853511) (xy 425.108166 -53.80142)
			(xy 425.135462 -53.752785) (xy 425.169548 -53.708642) (xy 425.209697 -53.669933) (xy 425.255055 -53.637482)
			(xy 425.304655 -53.611981) (xy 425.357439 -53.593974) (xy 425.412282 -53.583844) (xy 425.468016 -53.581807)
			(xy 425.523453 -53.587907) (xy 425.57741 -53.602013) (xy 425.628739 -53.623825) (xy 425.676345 -53.652879)
			(xy 425.719213 -53.688554) (xy 425.75643 -53.730091) (xy 425.787203 -53.776604) (xy 425.810875 -53.827101)
			(xy 425.826943 -53.880508) (xy 425.835063 -53.935684) (xy 425.835572 -53.96357) (xy 425.835063 -53.991456)
			(xy 425.826943 -54.046632) (xy 425.810875 -54.100039) (xy 425.787203 -54.150536) (xy 425.75643 -54.197049)
			(xy 425.719213 -54.238586) (xy 425.676345 -54.274261) (xy 425.628739 -54.303315) (xy 425.57741 -54.325127)
			(xy 425.523453 -54.339233) (xy 425.468016 -54.345333) (xy 425.412282 -54.343296) (xy 425.357439 -54.333166)
			(xy 425.304655 -54.315159) (xy 425.255055 -54.289658) (xy 425.209697 -54.257207) (xy 425.169548 -54.218498)
			(xy 425.135462 -54.174355) (xy 425.108166 -54.12572) (xy 425.088243 -54.073629) (xy 425.076117 -54.019192)
			(xy 425.072046 -53.96357) (xy 421.092868 -53.96357) (xy 421.110435 -54.002034) (xy 421.12579 -54.054329)
			(xy 421.133546 -54.108277) (xy 421.134032 -54.135528) (xy 421.133599 -54.1629) (xy 421.125776 -54.217081)
			(xy 421.11028 -54.269585) (xy 421.08743 -54.319331) (xy 421.057697 -54.365296) (xy 421.040052 -54.386226)
			(xy 421.039798 -54.38648) (xy 421.034213 -54.393568) (xy 421.027966 -54.410484) (xy 421.027606 -54.4195)
			(xy 421.027606 -54.486556) (xy 421.027983 -54.495571) (xy 421.034217 -54.512488) (xy 421.039798 -54.519576)
			(xy 421.040052 -54.519576) (xy 421.040052 -54.51983) (xy 421.057664 -54.540784) (xy 421.087382 -54.58675)
			(xy 421.110224 -54.636492) (xy 421.125721 -54.688988) (xy 421.133555 -54.74316) (xy 421.134032 -54.770528)
			(xy 421.133546 -54.797779) (xy 421.12579 -54.851727) (xy 421.110435 -54.904022) (xy 421.087793 -54.953599)
			(xy 421.065009 -54.989051) (xy 430.201068 -54.989051) (xy 430.201068 -54.934549) (xy 430.208824 -54.880603)
			(xy 430.224178 -54.828309) (xy 430.246817 -54.778733) (xy 430.276281 -54.732882) (xy 430.311971 -54.691692)
			(xy 430.353158 -54.655999) (xy 430.399006 -54.626532) (xy 430.448581 -54.603888) (xy 430.500874 -54.58853)
			(xy 430.554819 -54.58077) (xy 430.58207 -54.580282) (xy 430.610161 -54.580801) (xy 430.665737 -54.589023)
			(xy 430.719505 -54.60531) (xy 430.770303 -54.629309) (xy 430.81703 -54.6605) (xy 430.858675 -54.698209)
			(xy 430.894339 -54.741619) (xy 430.909222 -54.765448) (xy 430.914556 -54.774338) (xy 430.931574 -54.78653)
			(xy 431.024792 -54.80685) (xy 431.045366 -54.802532) (xy 431.054002 -54.79669) (xy 431.078063 -54.780686)
			(xy 431.129996 -54.755344) (xy 431.185154 -54.73812) (xy 431.242279 -54.729406) (xy 431.271172 -54.728872)
			(xy 431.298423 -54.729381) (xy 431.352371 -54.737134) (xy 431.404667 -54.752485) (xy 431.454246 -54.775123)
			(xy 431.500098 -54.804586) (xy 431.541291 -54.840275) (xy 431.576985 -54.881463) (xy 431.606454 -54.927312)
			(xy 431.629098 -54.976888) (xy 431.644456 -55.029182) (xy 431.652215 -55.083129) (xy 431.65268 -55.11038)
			(xy 431.652207 -55.13775) (xy 431.644392 -55.191929) (xy 431.628904 -55.244432) (xy 431.606064 -55.294179)
			(xy 431.576341 -55.340146) (xy 431.5587 -55.361078) (xy 431.558446 -55.361332) (xy 431.552875 -55.368429)
			(xy 431.54662 -55.385338) (xy 431.546254 -55.394352) (xy 431.546254 -55.461408) (xy 431.546596 -55.470427)
			(xy 431.552853 -55.487344) (xy 431.558446 -55.494428) (xy 431.5587 -55.494428) (xy 431.5587 -55.494682)
			(xy 431.57632 -55.515631) (xy 431.606044 -55.561597) (xy 431.628888 -55.61134) (xy 431.644385 -55.66384)
			(xy 431.652215 -55.718016) (xy 431.652217 -55.772754) (xy 431.644392 -55.826931) (xy 431.628899 -55.879431)
			(xy 431.606058 -55.929177) (xy 431.576338 -55.975145) (xy 431.5587 -55.996078) (xy 431.558446 -55.996332)
			(xy 431.552875 -56.003429) (xy 431.54662 -56.020338) (xy 431.546254 -56.029352) (xy 431.546254 -56.096408)
			(xy 431.546596 -56.105427) (xy 431.552853 -56.122344) (xy 431.558446 -56.129428) (xy 431.5587 -56.129428)
			(xy 431.5587 -56.129682) (xy 431.576344 -56.15061) (xy 431.606055 -56.196584) (xy 431.62889 -56.246332)
			(xy 431.64438 -56.298834) (xy 431.652207 -56.353011) (xy 431.65268 -56.38038) (xy 431.652194 -56.407631)
			(xy 431.644438 -56.461579) (xy 431.629083 -56.513874) (xy 431.606441 -56.563451) (xy 431.576975 -56.609301)
			(xy 431.541284 -56.650492) (xy 431.500093 -56.686183) (xy 431.454243 -56.715649) (xy 431.404666 -56.738291)
			(xy 431.352371 -56.753646) (xy 431.298423 -56.761402) (xy 431.243921 -56.761402) (xy 431.189973 -56.753646)
			(xy 431.137678 -56.738291) (xy 431.088101 -56.715649) (xy 431.042251 -56.686183) (xy 431.00106 -56.650492)
			(xy 430.965369 -56.609301) (xy 430.935903 -56.563451) (xy 430.913261 -56.513874) (xy 430.897906 -56.461579)
			(xy 430.89015 -56.407631) (xy 430.889664 -56.38038) (xy 430.890103 -56.353009) (xy 430.897925 -56.298828)
			(xy 430.913419 -56.246324) (xy 430.936268 -56.196577) (xy 430.965999 -56.150612) (xy 430.983644 -56.129682)
			(xy 430.983898 -56.129428) (xy 430.989479 -56.122337) (xy 430.995729 -56.105424) (xy 430.99609 -56.096408)
			(xy 430.99609 -56.029352) (xy 430.99571 -56.020337) (xy 430.989479 -56.00342) (xy 430.983898 -55.996332)
			(xy 430.983644 -55.996332) (xy 430.983644 -55.996078) (xy 430.965983 -55.975161) (xy 430.936258 -55.929191)
			(xy 430.913412 -55.879442) (xy 430.897917 -55.826938) (xy 430.89009 -55.772757) (xy 430.890092 -55.718013)
			(xy 430.897923 -55.663833) (xy 430.913423 -55.611329) (xy 430.936272 -55.561582) (xy 430.966001 -55.515614)
			(xy 430.983644 -55.494682) (xy 430.983898 -55.494428) (xy 430.989479 -55.487337) (xy 430.995729 -55.470424)
			(xy 430.99609 -55.461408) (xy 430.99609 -55.394352) (xy 430.99571 -55.385337) (xy 430.989479 -55.36842)
			(xy 430.983898 -55.361332) (xy 430.983644 -55.360824) (xy 430.972697 -55.348092) (xy 430.952858 -55.320999)
			(xy 430.94402 -55.306722) (xy 430.938686 -55.297832) (xy 430.921668 -55.28564) (xy 430.82845 -55.26532)
			(xy 430.807876 -55.269638) (xy 430.79924 -55.27548) (xy 430.775165 -55.291463) (xy 430.723238 -55.31681)
			(xy 430.668083 -55.334041) (xy 430.610962 -55.342761) (xy 430.58207 -55.343298) (xy 430.554819 -55.34283)
			(xy 430.500874 -55.33507) (xy 430.448581 -55.319712) (xy 430.399006 -55.297068) (xy 430.353158 -55.267601)
			(xy 430.311971 -55.231908) (xy 430.276281 -55.190718) (xy 430.246817 -55.144867) (xy 430.224178 -55.095291)
			(xy 430.208824 -55.042997) (xy 430.201068 -54.989051) (xy 421.065009 -54.989051) (xy 421.058327 -54.999449)
			(xy 421.022636 -55.04064) (xy 420.981445 -55.076331) (xy 420.935595 -55.105797) (xy 420.886018 -55.128439)
			(xy 420.833723 -55.143794) (xy 420.779775 -55.15155) (xy 420.725273 -55.15155) (xy 420.671325 -55.143794)
			(xy 420.61903 -55.128439) (xy 420.569453 -55.105797) (xy 420.523603 -55.076331) (xy 420.482412 -55.04064)
			(xy 420.446721 -54.999449) (xy 420.417255 -54.953599) (xy 420.394613 -54.904022) (xy 420.379258 -54.851727)
			(xy 420.371502 -54.797779) (xy 420.371016 -54.770528) (xy 417.239095 -54.770528) (xy 417.23945 -54.791102)
			(xy 417.238964 -54.818353) (xy 417.231208 -54.872301) (xy 417.215853 -54.924596) (xy 417.193211 -54.974173)
			(xy 417.163745 -55.020023) (xy 417.128054 -55.061214) (xy 417.086863 -55.096905) (xy 417.041013 -55.126371)
			(xy 416.991436 -55.149013) (xy 416.939141 -55.164368) (xy 416.885193 -55.172124) (xy 416.830691 -55.172124)
			(xy 416.776743 -55.164368) (xy 416.724448 -55.149013) (xy 416.674871 -55.126371) (xy 416.629021 -55.096905)
			(xy 416.58783 -55.061214) (xy 416.552139 -55.020023) (xy 416.522673 -54.974173) (xy 416.500031 -54.924596)
			(xy 416.484676 -54.872301) (xy 416.47692 -54.818353) (xy 416.476434 -54.791102) (xy 414.579055 -54.791102)
			(xy 414.57715 -54.804926) (xy 414.561809 -54.860491) (xy 414.538308 -54.913126) (xy 414.523174 -54.93766)
			(xy 414.518094 -54.945788) (xy 414.511236 -55.622444) (xy 414.511236 -55.722266) (xy 426.13402 -55.722266)
			(xy 426.138091 -55.666644) (xy 426.150217 -55.612207) (xy 426.17014 -55.560116) (xy 426.197436 -55.511481)
			(xy 426.231522 -55.467338) (xy 426.271671 -55.428629) (xy 426.317029 -55.396178) (xy 426.366629 -55.370677)
			(xy 426.419413 -55.35267) (xy 426.474256 -55.34254) (xy 426.52999 -55.340503) (xy 426.585427 -55.346603)
			(xy 426.639384 -55.360709) (xy 426.690713 -55.382521) (xy 426.738319 -55.411575) (xy 426.749465 -55.420851)
			(xy 428.524668 -55.420851) (xy 428.524668 -55.366349) (xy 428.532424 -55.312403) (xy 428.547778 -55.260109)
			(xy 428.570417 -55.210533) (xy 428.599881 -55.164682) (xy 428.635571 -55.123492) (xy 428.676758 -55.087799)
			(xy 428.722606 -55.058332) (xy 428.772181 -55.035688) (xy 428.824474 -55.02033) (xy 428.878419 -55.01257)
			(xy 428.90567 -55.012082) (xy 428.931985 -55.012509) (xy 428.984115 -55.019753) (xy 429.034759 -55.03408)
			(xy 429.082957 -55.05522) (xy 429.1278 -55.082773) (xy 429.168438 -55.116218) (xy 429.186594 -55.135272)
			(xy 429.19412 -55.142669) (xy 429.213396 -55.151197) (xy 429.223932 -55.151782) (xy 429.298608 -55.151782)
			(xy 429.30916 -55.151276) (xy 429.328456 -55.142725) (xy 429.335946 -55.135272) (xy 429.354081 -55.116196)
			(xy 429.394716 -55.082742) (xy 429.43956 -55.055186) (xy 429.487765 -55.034051) (xy 429.538416 -55.019738)
			(xy 429.590553 -55.012518) (xy 429.61687 -55.012082) (xy 429.644124 -55.012563) (xy 429.698076 -55.020317)
			(xy 429.750376 -55.03567) (xy 429.799959 -55.05831) (xy 429.845815 -55.087776) (xy 429.88701 -55.123469)
			(xy 429.922706 -55.164661) (xy 429.952176 -55.210515) (xy 429.97482 -55.260095) (xy 429.990177 -55.312394)
			(xy 429.997935 -55.366347) (xy 429.997935 -55.420854) (xy 429.990177 -55.474806) (xy 429.97482 -55.527105)
			(xy 429.952176 -55.576685) (xy 429.922706 -55.622539) (xy 429.88701 -55.663731) (xy 429.845815 -55.699424)
			(xy 429.799959 -55.72889) (xy 429.750376 -55.75153) (xy 429.698076 -55.766883) (xy 429.644124 -55.774637)
			(xy 429.61687 -55.775098) (xy 429.590555 -55.774651) (xy 429.538426 -55.767412) (xy 429.487783 -55.753089)
			(xy 429.439584 -55.731953) (xy 429.394741 -55.704403) (xy 429.354102 -55.670961) (xy 429.335946 -55.651908)
			(xy 429.328445 -55.644482) (xy 429.309149 -55.635971) (xy 429.298608 -55.635398) (xy 429.223932 -55.635398)
			(xy 429.213383 -55.635932) (xy 429.194087 -55.644464) (xy 429.186594 -55.651908) (xy 429.168436 -55.670961)
			(xy 429.127807 -55.704418) (xy 429.082967 -55.731977) (xy 429.034767 -55.753116) (xy 428.98412 -55.767434)
			(xy 428.931986 -55.774659) (xy 428.90567 -55.775098) (xy 428.878419 -55.77463) (xy 428.824474 -55.76687)
			(xy 428.772181 -55.751512) (xy 428.722606 -55.728868) (xy 428.676758 -55.699401) (xy 428.635571 -55.663708)
			(xy 428.599881 -55.622518) (xy 428.570417 -55.576667) (xy 428.547778 -55.527091) (xy 428.532424 -55.474797)
			(xy 428.524668 -55.420851) (xy 426.749465 -55.420851) (xy 426.781187 -55.44725) (xy 426.818404 -55.488787)
			(xy 426.849177 -55.5353) (xy 426.872849 -55.585797) (xy 426.888917 -55.639204) (xy 426.897037 -55.69438)
			(xy 426.897546 -55.722266) (xy 426.897037 -55.750152) (xy 426.888917 -55.805328) (xy 426.872849 -55.858735)
			(xy 426.849177 -55.909232) (xy 426.818404 -55.955745) (xy 426.781187 -55.997282) (xy 426.738319 -56.032957)
			(xy 426.690713 -56.062011) (xy 426.639384 -56.083823) (xy 426.585427 -56.097929) (xy 426.52999 -56.104029)
			(xy 426.474256 -56.101992) (xy 426.419413 -56.091862) (xy 426.366629 -56.073855) (xy 426.317029 -56.048354)
			(xy 426.271671 -56.015903) (xy 426.231522 -55.977194) (xy 426.197436 -55.933051) (xy 426.17014 -55.884416)
			(xy 426.150217 -55.832325) (xy 426.138091 -55.777888) (xy 426.13402 -55.722266) (xy 414.511236 -55.722266)
			(xy 414.511236 -56.586628) (xy 414.511463 -56.594132) (xy 414.515851 -56.608482) (xy 414.519872 -56.614822)
			(xy 414.534367 -56.637446) (xy 414.55755 -56.685916) (xy 414.573709 -56.737158) (xy 414.582522 -56.79016)
			(xy 414.583626 -56.817006) (xy 414.583626 -56.84012) (xy 414.582029 -56.86926) (xy 414.571084 -56.926582)
			(xy 414.551534 -56.981567) (xy 414.540012 -57.002934) (xy 421.86352 -57.002934) (xy 421.864023 -56.974843)
			(xy 421.872247 -56.919265) (xy 421.888535 -56.865495) (xy 421.912536 -56.814697) (xy 421.94373 -56.76797)
			(xy 421.981442 -56.726325) (xy 422.024855 -56.690664) (xy 422.048686 -56.675782) (xy 422.057576 -56.670448)
			(xy 422.069768 -56.65343) (xy 422.090088 -56.560212) (xy 422.08577 -56.539638) (xy 422.079928 -56.531002)
			(xy 422.06393 -56.506937) (xy 422.038586 -56.455006) (xy 422.02136 -56.399849) (xy 422.012644 -56.342724)
			(xy 422.01211 -56.313832) (xy 422.012585 -56.286579) (xy 422.020338 -56.232628) (xy 422.035691 -56.180329)
			(xy 422.058331 -56.130748) (xy 422.087798 -56.084894) (xy 422.12349 -56.0437) (xy 422.164682 -56.008006)
			(xy 422.210535 -55.978538) (xy 422.260116 -55.955896) (xy 422.312414 -55.940541) (xy 422.366365 -55.932786)
			(xy 422.393618 -55.932324) (xy 422.420989 -55.932774) (xy 422.475169 -55.940595) (xy 422.527672 -55.956087)
			(xy 422.577419 -55.978933) (xy 422.623385 -56.008661) (xy 422.644316 -56.026304) (xy 422.64457 -56.026558)
			(xy 422.651656 -56.032145) (xy 422.668573 -56.03839) (xy 422.67759 -56.03875) (xy 422.744646 -56.03875)
			(xy 422.753662 -56.038378) (xy 422.770579 -56.032142) (xy 422.777666 -56.026558) (xy 422.777666 -56.026304)
			(xy 422.77792 -56.026304) (xy 422.798853 -56.008663) (xy 422.844821 -55.978939) (xy 422.894567 -55.956093)
			(xy 422.947069 -55.940597) (xy 423.001247 -55.932768) (xy 423.055989 -55.932768) (xy 423.110167 -55.940597)
			(xy 423.162669 -55.956093) (xy 423.212415 -55.978939) (xy 423.258383 -56.008663) (xy 423.279316 -56.026304)
			(xy 423.27957 -56.026558) (xy 423.286656 -56.032145) (xy 423.303573 -56.03839) (xy 423.31259 -56.03875)
			(xy 423.379646 -56.03875) (xy 423.388662 -56.038378) (xy 423.405579 -56.032142) (xy 423.412666 -56.026558)
			(xy 423.412666 -56.026304) (xy 423.41292 -56.026304) (xy 423.433872 -56.00869) (xy 423.479839 -55.978974)
			(xy 423.529582 -55.956133) (xy 423.582078 -55.940636) (xy 423.63625 -55.932802) (xy 423.663618 -55.932324)
			(xy 423.690871 -55.932747) (xy 423.744821 -55.940506) (xy 423.797118 -55.955864) (xy 423.846697 -55.978508)
			(xy 423.892549 -56.007978) (xy 423.933741 -56.043672) (xy 423.969433 -56.084865) (xy 423.9989 -56.130719)
			(xy 424.021542 -56.180299) (xy 424.036897 -56.232597) (xy 424.044654 -56.286547) (xy 424.044654 -56.297068)
			(xy 424.3865 -56.297068) (xy 424.390571 -56.241446) (xy 424.402697 -56.187009) (xy 424.42262 -56.134918)
			(xy 424.449916 -56.086283) (xy 424.484002 -56.04214) (xy 424.524151 -56.003431) (xy 424.569509 -55.97098)
			(xy 424.619109 -55.945479) (xy 424.671893 -55.927472) (xy 424.726736 -55.917342) (xy 424.78247 -55.915305)
			(xy 424.837907 -55.921405) (xy 424.891864 -55.935511) (xy 424.943193 -55.957323) (xy 424.990799 -55.986377)
			(xy 425.033667 -56.022052) (xy 425.070884 -56.063589) (xy 425.101657 -56.110102) (xy 425.125329 -56.160599)
			(xy 425.141397 -56.214006) (xy 425.149517 -56.269182) (xy 425.150026 -56.297068) (xy 425.149517 -56.324954)
			(xy 425.141397 -56.38013) (xy 425.125329 -56.433537) (xy 425.101657 -56.484034) (xy 425.070884 -56.530547)
			(xy 425.033667 -56.572084) (xy 424.990799 -56.607759) (xy 424.943193 -56.636813) (xy 424.891864 -56.658625)
			(xy 424.837907 -56.672731) (xy 424.78247 -56.678831) (xy 424.726736 -56.676794) (xy 424.671893 -56.666664)
			(xy 424.619109 -56.648657) (xy 424.569509 -56.623156) (xy 424.524151 -56.590705) (xy 424.484002 -56.551996)
			(xy 424.449916 -56.507853) (xy 424.42262 -56.459218) (xy 424.402697 -56.407127) (xy 424.390571 -56.35269)
			(xy 424.3865 -56.297068) (xy 424.044654 -56.297068) (xy 424.044654 -56.341053) (xy 424.036897 -56.395003)
			(xy 424.021542 -56.447301) (xy 423.9989 -56.496881) (xy 423.969433 -56.542735) (xy 423.933741 -56.583928)
			(xy 423.892549 -56.619622) (xy 423.846697 -56.649092) (xy 423.797118 -56.671736) (xy 423.744821 -56.687094)
			(xy 423.690871 -56.694853) (xy 423.663618 -56.69534) (xy 423.636247 -56.694878) (xy 423.582068 -56.687061)
			(xy 423.529564 -56.671572) (xy 423.479817 -56.648729) (xy 423.433851 -56.619003) (xy 423.41292 -56.60136)
			(xy 423.412666 -56.601106) (xy 423.405564 -56.595542) (xy 423.388659 -56.589281) (xy 423.379646 -56.588914)
			(xy 423.31259 -56.588914) (xy 423.303572 -56.589263) (xy 423.286655 -56.595516) (xy 423.27957 -56.601106)
			(xy 423.27957 -56.60136) (xy 423.279316 -56.60136) (xy 423.258383 -56.619001) (xy 423.212415 -56.648725)
			(xy 423.162669 -56.671571) (xy 423.110167 -56.687067) (xy 423.055989 -56.694896) (xy 423.001247 -56.694896)
			(xy 422.947069 -56.687067) (xy 422.894567 -56.671571) (xy 422.844821 -56.648725) (xy 422.798853 -56.619001)
			(xy 422.77792 -56.60136) (xy 422.777666 -56.601106) (xy 422.770564 -56.595542) (xy 422.753659 -56.589281)
			(xy 422.744646 -56.588914) (xy 422.67759 -56.588914) (xy 422.668572 -56.589263) (xy 422.651655 -56.595516)
			(xy 422.64457 -56.601106) (xy 422.644062 -56.60136) (xy 422.631328 -56.612304) (xy 422.604236 -56.632145)
			(xy 422.58996 -56.640984) (xy 422.58107 -56.646318) (xy 422.568878 -56.663336) (xy 422.548558 -56.756554)
			(xy 422.552876 -56.777128) (xy 422.558718 -56.785764) (xy 422.574707 -56.809835) (xy 422.600052 -56.861764)
			(xy 422.61728 -56.91692) (xy 422.625999 -56.974042) (xy 422.626536 -57.002934) (xy 422.62605 -57.030185)
			(xy 422.618294 -57.084133) (xy 422.602939 -57.136428) (xy 422.580297 -57.186005) (xy 422.550831 -57.231855)
			(xy 422.51514 -57.273046) (xy 422.473949 -57.308737) (xy 422.428099 -57.338203) (xy 422.378522 -57.360845)
			(xy 422.326227 -57.3762) (xy 422.272279 -57.383956) (xy 422.217777 -57.383956) (xy 422.163829 -57.3762)
			(xy 422.111534 -57.360845) (xy 422.061957 -57.338203) (xy 422.016107 -57.308737) (xy 421.974916 -57.273046)
			(xy 421.939225 -57.231855) (xy 421.909759 -57.186005) (xy 421.887117 -57.136428) (xy 421.871762 -57.084133)
			(xy 421.864006 -57.030185) (xy 421.86352 -57.002934) (xy 414.540012 -57.002934) (xy 414.523836 -57.032931)
			(xy 414.506664 -57.056528) (xy 414.50641 -57.057036) (xy 414.502128 -57.063191) (xy 414.496957 -57.077258)
			(xy 414.49625 -57.084722) (xy 414.49625 -57.096914) (xy 414.495234 -57.195466) (xy 414.495234 -57.199276)
			(xy 414.505648 -57.230264) (xy 414.51149 -57.237884) (xy 414.512252 -57.238646) (xy 414.524228 -57.255899)
			(xy 414.544722 -57.292559) (xy 414.553146 -57.311798) (xy 414.562847 -57.335534) (xy 414.576517 -57.384957)
			(xy 414.58344 -57.435765) (xy 414.58388 -57.461404) (xy 414.583626 -57.473596) (xy 414.583038 -57.48528)
			(xy 430.905918 -57.48528) (xy 430.909989 -57.429658) (xy 430.922115 -57.375221) (xy 430.942038 -57.32313)
			(xy 430.969334 -57.274495) (xy 431.00342 -57.230352) (xy 431.043569 -57.191643) (xy 431.088927 -57.159192)
			(xy 431.138527 -57.133691) (xy 431.191311 -57.115684) (xy 431.246154 -57.105554) (xy 431.301888 -57.103517)
			(xy 431.357325 -57.109617) (xy 431.411282 -57.123723) (xy 431.462611 -57.145535) (xy 431.510217 -57.174589)
			(xy 431.553085 -57.210264) (xy 431.590302 -57.251801) (xy 431.621075 -57.298314) (xy 431.644747 -57.348811)
			(xy 431.660815 -57.402218) (xy 431.668935 -57.457394) (xy 431.669444 -57.48528) (xy 431.668935 -57.513166)
			(xy 431.660815 -57.568342) (xy 431.644747 -57.621749) (xy 431.621075 -57.672246) (xy 431.590302 -57.718759)
			(xy 431.553085 -57.760296) (xy 431.510217 -57.795971) (xy 431.462611 -57.825025) (xy 431.411282 -57.846837)
			(xy 431.357325 -57.860943) (xy 431.301888 -57.867043) (xy 431.246154 -57.865006) (xy 431.191311 -57.854876)
			(xy 431.138527 -57.836869) (xy 431.088927 -57.811368) (xy 431.043569 -57.778917) (xy 431.00342 -57.740208)
			(xy 430.969334 -57.696065) (xy 430.942038 -57.64743) (xy 430.922115 -57.595339) (xy 430.909989 -57.540902)
			(xy 430.905918 -57.48528) (xy 414.583038 -57.48528) (xy 414.582149 -57.502931) (xy 414.571306 -57.560656)
			(xy 414.55175 -57.61604) (xy 414.523943 -57.667776) (xy 414.506664 -57.691528) (xy 414.499806 -57.700672)
			(xy 414.495692 -57.706684) (xy 414.49067 -57.720352) (xy 414.4899 -57.727596) (xy 414.489138 -57.795922)
			(xy 414.48863 -57.83453) (xy 414.494472 -57.851294) (xy 414.500314 -57.858152) (xy 414.505648 -57.864756)
			(xy 414.505648 -57.865264) (xy 414.511744 -57.873138) (xy 414.512252 -57.873646) (xy 414.524228 -57.890899)
			(xy 414.544722 -57.927559) (xy 414.553146 -57.946798) (xy 414.562847 -57.970534) (xy 414.576517 -58.019957)
			(xy 414.58344 -58.070765) (xy 414.58388 -58.096404) (xy 414.583626 -58.108342) (xy 414.58241 -58.133712)
			(xy 414.574098 -58.183818) (xy 414.559221 -58.232381) (xy 414.538042 -58.278545) (xy 414.510934 -58.321497)
			(xy 414.49498 -58.34126) (xy 414.486598 -58.35142) (xy 414.48482 -58.354214) (xy 414.483804 -58.355738)
			(xy 414.483296 -58.3565) (xy 414.483296 -58.36031) (xy 414.483042 -58.392822) (xy 414.48228 -58.46953)
			(xy 414.486598 -58.476388) (xy 414.492948 -58.484262) (xy 414.507934 -58.503058) (xy 414.508442 -58.503566)
			(xy 414.526183 -58.528425) (xy 414.554362 -58.582605) (xy 414.573556 -58.640579) (xy 414.579805 -58.679334)
			(xy 422.29532 -58.679334) (xy 422.295737 -58.653018) (xy 422.302981 -58.600887) (xy 422.31731 -58.550243)
			(xy 422.338452 -58.502044) (xy 422.366007 -58.457202) (xy 422.399454 -58.416565) (xy 422.41851 -58.39841)
			(xy 422.425911 -58.390888) (xy 422.434435 -58.371608) (xy 422.43502 -58.361072) (xy 422.43502 -58.286396)
			(xy 422.434501 -58.275845) (xy 422.425958 -58.25655) (xy 422.41851 -58.249058) (xy 422.399443 -58.230914)
			(xy 422.365986 -58.190282) (xy 422.338429 -58.145439) (xy 422.317292 -58.097236) (xy 422.302978 -58.046587)
			(xy 422.295756 -57.994451) (xy 422.29532 -57.968134) (xy 422.295806 -57.940883) (xy 422.303562 -57.886935)
			(xy 422.318917 -57.83464) (xy 422.341559 -57.785063) (xy 422.371025 -57.739213) (xy 422.406716 -57.698022)
			(xy 422.447907 -57.662331) (xy 422.493757 -57.632865) (xy 422.543334 -57.610223) (xy 422.595629 -57.594868)
			(xy 422.649577 -57.587112) (xy 422.704079 -57.587112) (xy 422.758027 -57.594868) (xy 422.810322 -57.610223)
			(xy 422.859899 -57.632865) (xy 422.905749 -57.662331) (xy 422.94694 -57.698022) (xy 422.982631 -57.739213)
			(xy 423.012097 -57.785063) (xy 423.034739 -57.83464) (xy 423.050094 -57.886935) (xy 423.05785 -57.940883)
			(xy 423.058336 -57.968134) (xy 423.05788 -57.994448) (xy 423.050641 -58.046577) (xy 423.043374 -58.072274)
			(xy 426.293532 -58.072274) (xy 426.297603 -58.016652) (xy 426.309729 -57.962215) (xy 426.329652 -57.910124)
			(xy 426.356948 -57.861489) (xy 426.391034 -57.817346) (xy 426.431183 -57.778637) (xy 426.476541 -57.746186)
			(xy 426.526141 -57.720685) (xy 426.578925 -57.702678) (xy 426.633768 -57.692548) (xy 426.689502 -57.690511)
			(xy 426.744939 -57.696611) (xy 426.798896 -57.710717) (xy 426.850225 -57.732529) (xy 426.897831 -57.761583)
			(xy 426.940699 -57.797258) (xy 426.977916 -57.838795) (xy 427.008689 -57.885308) (xy 427.032361 -57.935805)
			(xy 427.048429 -57.989212) (xy 427.056549 -58.044388) (xy 427.057058 -58.072274) (xy 427.056988 -58.076084)
			(xy 431.658012 -58.076084) (xy 431.662083 -58.020462) (xy 431.674209 -57.966025) (xy 431.694132 -57.913934)
			(xy 431.721428 -57.865299) (xy 431.755514 -57.821156) (xy 431.795663 -57.782447) (xy 431.841021 -57.749996)
			(xy 431.890621 -57.724495) (xy 431.943405 -57.706488) (xy 431.998248 -57.696358) (xy 432.053982 -57.694321)
			(xy 432.109419 -57.700421) (xy 432.163376 -57.714527) (xy 432.214705 -57.736339) (xy 432.262311 -57.765393)
			(xy 432.305179 -57.801068) (xy 432.342396 -57.842605) (xy 432.373169 -57.889118) (xy 432.396841 -57.939615)
			(xy 432.412909 -57.993022) (xy 432.421029 -58.048198) (xy 432.421538 -58.076084) (xy 432.42107 -58.101738)
			(xy 433.942996 -58.101738) (xy 433.947067 -58.046116) (xy 433.959193 -57.991679) (xy 433.979116 -57.939588)
			(xy 434.006412 -57.890953) (xy 434.040498 -57.84681) (xy 434.080647 -57.808101) (xy 434.126005 -57.77565)
			(xy 434.175605 -57.750149) (xy 434.228389 -57.732142) (xy 434.283232 -57.722012) (xy 434.338966 -57.719975)
			(xy 434.394403 -57.726075) (xy 434.44836 -57.740181) (xy 434.499689 -57.761993) (xy 434.547295 -57.791047)
			(xy 434.590163 -57.826722) (xy 434.62738 -57.868259) (xy 434.658153 -57.914772) (xy 434.681825 -57.965269)
			(xy 434.697893 -58.018676) (xy 434.706013 -58.073852) (xy 434.706522 -58.101738) (xy 434.706013 -58.129624)
			(xy 434.697893 -58.1848) (xy 434.681825 -58.238207) (xy 434.658153 -58.288704) (xy 434.62738 -58.335217)
			(xy 434.590163 -58.376754) (xy 434.547295 -58.412429) (xy 434.499689 -58.441483) (xy 434.44836 -58.463295)
			(xy 434.394403 -58.477401) (xy 434.338966 -58.483501) (xy 434.283232 -58.481464) (xy 434.228389 -58.471334)
			(xy 434.175605 -58.453327) (xy 434.126005 -58.427826) (xy 434.080647 -58.395375) (xy 434.040498 -58.356666)
			(xy 434.006412 -58.312523) (xy 433.979116 -58.263888) (xy 433.959193 -58.211797) (xy 433.947067 -58.15736)
			(xy 433.942996 -58.101738) (xy 432.42107 -58.101738) (xy 432.421029 -58.10397) (xy 432.412909 -58.159146)
			(xy 432.396841 -58.212553) (xy 432.373169 -58.26305) (xy 432.342396 -58.309563) (xy 432.305179 -58.3511)
			(xy 432.262311 -58.386775) (xy 432.214705 -58.415829) (xy 432.163376 -58.437641) (xy 432.109419 -58.451747)
			(xy 432.053982 -58.457847) (xy 431.998248 -58.45581) (xy 431.943405 -58.44568) (xy 431.890621 -58.427673)
			(xy 431.841021 -58.402172) (xy 431.795663 -58.369721) (xy 431.755514 -58.331012) (xy 431.721428 -58.286869)
			(xy 431.694132 -58.238234) (xy 431.674209 -58.186143) (xy 431.662083 -58.131706) (xy 431.658012 -58.076084)
			(xy 427.056988 -58.076084) (xy 427.056549 -58.10016) (xy 427.048429 -58.155336) (xy 427.032361 -58.208743)
			(xy 427.008689 -58.25924) (xy 426.977916 -58.305753) (xy 426.940699 -58.34729) (xy 426.897831 -58.382965)
			(xy 426.850225 -58.412019) (xy 426.798896 -58.433831) (xy 426.744939 -58.447937) (xy 426.689502 -58.454037)
			(xy 426.633768 -58.452) (xy 426.578925 -58.44187) (xy 426.526141 -58.423863) (xy 426.476541 -58.398362)
			(xy 426.431183 -58.365911) (xy 426.391034 -58.327202) (xy 426.356948 -58.283059) (xy 426.329652 -58.234424)
			(xy 426.309729 -58.182333) (xy 426.297603 -58.127896) (xy 426.293532 -58.072274) (xy 423.043374 -58.072274)
			(xy 423.036319 -58.097219) (xy 423.015184 -58.145418) (xy 422.987637 -58.190261) (xy 422.954198 -58.230901)
			(xy 422.935146 -58.249058) (xy 422.927768 -58.2566) (xy 422.919229 -58.275864) (xy 422.918636 -58.286396)
			(xy 422.918636 -58.361072) (xy 422.919156 -58.371623) (xy 422.927697 -58.390919) (xy 422.935146 -58.39841)
			(xy 422.954208 -58.416559) (xy 422.987663 -58.457191) (xy 423.01522 -58.502033) (xy 423.036357 -58.550235)
			(xy 423.039463 -58.561224) (xy 432.862226 -58.561224) (xy 432.866297 -58.505602) (xy 432.878423 -58.451165)
			(xy 432.898346 -58.399074) (xy 432.925642 -58.350439) (xy 432.959728 -58.306296) (xy 432.999877 -58.267587)
			(xy 433.045235 -58.235136) (xy 433.094835 -58.209635) (xy 433.147619 -58.191628) (xy 433.202462 -58.181498)
			(xy 433.258196 -58.179461) (xy 433.313633 -58.185561) (xy 433.36759 -58.199667) (xy 433.418919 -58.221479)
			(xy 433.466525 -58.250533) (xy 433.509393 -58.286208) (xy 433.54661 -58.327745) (xy 433.577383 -58.374258)
			(xy 433.601055 -58.424755) (xy 433.617123 -58.478162) (xy 433.625243 -58.533338) (xy 433.625752 -58.561224)
			(xy 433.625243 -58.58911) (xy 433.617123 -58.644286) (xy 433.601055 -58.697693) (xy 433.577383 -58.74819)
			(xy 433.54661 -58.794703) (xy 433.509393 -58.83624) (xy 433.466525 -58.871915) (xy 433.418919 -58.900969)
			(xy 433.36759 -58.922781) (xy 433.313633 -58.936887) (xy 433.258196 -58.942987) (xy 433.202462 -58.94095)
			(xy 433.147619 -58.93082) (xy 433.094835 -58.912813) (xy 433.045235 -58.887312) (xy 432.999877 -58.854861)
			(xy 432.959728 -58.816152) (xy 432.925642 -58.772009) (xy 432.898346 -58.723374) (xy 432.878423 -58.671283)
			(xy 432.866297 -58.616846) (xy 432.862226 -58.561224) (xy 423.039463 -58.561224) (xy 423.050673 -58.600883)
			(xy 423.057898 -58.653018) (xy 423.058336 -58.679334) (xy 423.05785 -58.706585) (xy 423.050094 -58.760533)
			(xy 423.034739 -58.812828) (xy 423.012097 -58.862405) (xy 422.982631 -58.908255) (xy 422.94694 -58.949446)
			(xy 422.905749 -58.985137) (xy 422.859899 -59.014603) (xy 422.810322 -59.037245) (xy 422.758027 -59.0526)
			(xy 422.704079 -59.060356) (xy 422.649577 -59.060356) (xy 422.595629 -59.0526) (xy 422.543334 -59.037245)
			(xy 422.493757 -59.014603) (xy 422.447907 -58.985137) (xy 422.406716 -58.949446) (xy 422.371025 -58.908255)
			(xy 422.341559 -58.862405) (xy 422.318917 -58.812828) (xy 422.303562 -58.760533) (xy 422.295806 -58.706585)
			(xy 422.29532 -58.679334) (xy 414.579805 -58.679334) (xy 414.583277 -58.700869) (xy 414.58388 -58.731404)
			(xy 414.583362 -58.759727) (xy 414.574981 -58.815748) (xy 414.558404 -58.869914) (xy 414.533995 -58.92103)
			(xy 414.502293 -58.967973) (xy 414.48355 -58.989214) (xy 414.476692 -58.997088) (xy 414.474884 -59.174634)
			(xy 431.39309 -59.174634) (xy 431.397161 -59.119012) (xy 431.409287 -59.064575) (xy 431.42921 -59.012484)
			(xy 431.456506 -58.963849) (xy 431.490592 -58.919706) (xy 431.530741 -58.880997) (xy 431.576099 -58.848546)
			(xy 431.625699 -58.823045) (xy 431.678483 -58.805038) (xy 431.733326 -58.794908) (xy 431.78906 -58.792871)
			(xy 431.844497 -58.798971) (xy 431.898454 -58.813077) (xy 431.949783 -58.834889) (xy 431.997389 -58.863943)
			(xy 432.040257 -58.899618) (xy 432.077474 -58.941155) (xy 432.108247 -58.987668) (xy 432.131919 -59.038165)
			(xy 432.147987 -59.091572) (xy 432.156107 -59.146748) (xy 432.156616 -59.174634) (xy 432.156107 -59.20252)
			(xy 432.147987 -59.257696) (xy 432.131919 -59.311103) (xy 432.108247 -59.3616) (xy 432.077474 -59.408113)
			(xy 432.040257 -59.44965) (xy 431.997389 -59.485325) (xy 431.949783 -59.514379) (xy 431.898454 -59.536191)
			(xy 431.844497 -59.550297) (xy 431.78906 -59.556397) (xy 431.733326 -59.55436) (xy 431.678483 -59.54423)
			(xy 431.625699 -59.526223) (xy 431.576099 -59.500722) (xy 431.530741 -59.468271) (xy 431.490592 -59.429562)
			(xy 431.456506 -59.385419) (xy 431.42921 -59.336784) (xy 431.409287 -59.284693) (xy 431.397161 -59.230256)
			(xy 431.39309 -59.174634) (xy 414.474884 -59.174634) (xy 414.466281 -60.01925) (xy 422.435784 -60.01925)
			(xy 422.435784 -59.96475) (xy 422.44354 -59.910805) (xy 422.458894 -59.858512) (xy 422.481533 -59.808937)
			(xy 422.510997 -59.763088) (xy 422.546686 -59.721899) (xy 422.587874 -59.686208) (xy 422.633721 -59.656742)
			(xy 422.683295 -59.6341) (xy 422.735587 -59.618743) (xy 422.789532 -59.610985) (xy 422.816782 -59.610498)
			(xy 422.844152 -59.610975) (xy 422.89833 -59.61879) (xy 422.950833 -59.634277) (xy 423.00058 -59.657116)
			(xy 423.046548 -59.686838) (xy 423.06748 -59.704478) (xy 423.067734 -59.704732) (xy 423.074833 -59.710301)
			(xy 423.09174 -59.716557) (xy 423.100754 -59.716924) (xy 423.16781 -59.716924) (xy 423.176827 -59.716566)
			(xy 423.193743 -59.710319) (xy 423.20083 -59.704732) (xy 423.20083 -59.704478) (xy 423.201084 -59.704478)
			(xy 423.222017 -59.686837) (xy 423.267985 -59.657113) (xy 423.317731 -59.634267) (xy 423.370233 -59.618771)
			(xy 423.424411 -59.610942) (xy 423.479153 -59.610942) (xy 423.533331 -59.618771) (xy 423.585833 -59.634267)
			(xy 423.635579 -59.657113) (xy 423.681547 -59.686837) (xy 423.70248 -59.704478) (xy 423.702734 -59.704732)
			(xy 423.709833 -59.710301) (xy 423.72674 -59.716557) (xy 423.735754 -59.716924) (xy 423.80281 -59.716924)
			(xy 423.811827 -59.716566) (xy 423.828743 -59.710319) (xy 423.83583 -59.704732) (xy 423.83583 -59.704478)
			(xy 423.836084 -59.704478) (xy 423.857008 -59.68683) (xy 423.902984 -59.65712) (xy 423.952733 -59.634286)
			(xy 424.005235 -59.618797) (xy 424.059412 -59.610971) (xy 424.086782 -59.610498) (xy 424.114036 -59.610948)
			(xy 424.16799 -59.618703) (xy 424.220291 -59.634058) (xy 424.269874 -59.6567) (xy 424.31573 -59.686168)
			(xy 424.356925 -59.721862) (xy 424.392622 -59.763056) (xy 424.422092 -59.80891) (xy 424.444736 -59.858492)
			(xy 424.460093 -59.910793) (xy 424.467851 -59.964746) (xy 424.467851 -60.019254) (xy 424.460093 -60.073207)
			(xy 424.444736 -60.125508) (xy 424.422092 -60.17509) (xy 424.392622 -60.220944) (xy 424.356925 -60.262138)
			(xy 424.31573 -60.297832) (xy 424.269874 -60.3273) (xy 424.220291 -60.349942) (xy 424.16799 -60.365297)
			(xy 424.114036 -60.373052) (xy 424.086782 -60.373514) (xy 424.059412 -60.373055) (xy 424.005232 -60.365235)
			(xy 423.952729 -60.349744) (xy 423.902983 -60.326901) (xy 423.857016 -60.297175) (xy 423.836084 -60.279534)
			(xy 423.83583 -60.27928) (xy 423.828741 -60.273698) (xy 423.811826 -60.267449) (xy 423.80281 -60.267088)
			(xy 423.735754 -60.267088) (xy 423.72674 -60.267473) (xy 423.709823 -60.273701) (xy 423.702734 -60.27928)
			(xy 423.70248 -60.279534) (xy 423.681547 -60.297175) (xy 423.635579 -60.326899) (xy 423.585833 -60.349745)
			(xy 423.533331 -60.365241) (xy 423.479153 -60.37307) (xy 423.424411 -60.37307) (xy 423.370233 -60.365241)
			(xy 423.317731 -60.349745) (xy 423.267985 -60.326899) (xy 423.222017 -60.297175) (xy 423.201084 -60.279534)
			(xy 423.20083 -60.27928) (xy 423.193741 -60.273698) (xy 423.176826 -60.267449) (xy 423.16781 -60.267088)
			(xy 423.100754 -60.267088) (xy 423.09174 -60.267473) (xy 423.074823 -60.273701) (xy 423.067734 -60.27928)
			(xy 423.067734 -60.279534) (xy 423.06748 -60.279534) (xy 423.046533 -60.297154) (xy 423.000564 -60.326868)
			(xy 422.95082 -60.349707) (xy 422.898323 -60.365202) (xy 422.84415 -60.373037) (xy 422.816782 -60.373514)
			(xy 422.789532 -60.373015) (xy 422.735587 -60.365257) (xy 422.683295 -60.3499) (xy 422.633721 -60.327258)
			(xy 422.587874 -60.297792) (xy 422.546686 -60.262101) (xy 422.510997 -60.220912) (xy 422.481533 -60.175063)
			(xy 422.458894 -60.125488) (xy 422.44354 -60.073195) (xy 422.435784 -60.01925) (xy 414.466281 -60.01925)
			(xy 414.460026 -60.633356) (xy 434.09692 -60.633356) (xy 434.100991 -60.577734) (xy 434.113117 -60.523297)
			(xy 434.13304 -60.471206) (xy 434.160336 -60.422571) (xy 434.194422 -60.378428) (xy 434.234571 -60.339719)
			(xy 434.279929 -60.307268) (xy 434.329529 -60.281767) (xy 434.382313 -60.26376) (xy 434.437156 -60.25363)
			(xy 434.49289 -60.251593) (xy 434.548327 -60.257693) (xy 434.602284 -60.271799) (xy 434.653613 -60.293611)
			(xy 434.701219 -60.322665) (xy 434.744087 -60.35834) (xy 434.781304 -60.399877) (xy 434.812077 -60.44639)
			(xy 434.835749 -60.496887) (xy 434.851817 -60.550294) (xy 434.859937 -60.60547) (xy 434.860446 -60.633356)
			(xy 434.859937 -60.661242) (xy 434.851817 -60.716418) (xy 434.835749 -60.769825) (xy 434.812077 -60.820322)
			(xy 434.781304 -60.866835) (xy 434.744087 -60.908372) (xy 434.701219 -60.944047) (xy 434.653613 -60.973101)
			(xy 434.602284 -60.994913) (xy 434.548327 -61.009019) (xy 434.49289 -61.015119) (xy 434.437156 -61.013082)
			(xy 434.382313 -61.002952) (xy 434.329529 -60.984945) (xy 434.279929 -60.959444) (xy 434.234571 -60.926993)
			(xy 434.194422 -60.888284) (xy 434.160336 -60.844141) (xy 434.13304 -60.795506) (xy 434.113117 -60.743415)
			(xy 434.100991 -60.688978) (xy 434.09692 -60.633356) (xy 414.460026 -60.633356) (xy 414.451323 -61.487812)
			(xy 432.604416 -61.487812) (xy 432.608487 -61.43219) (xy 432.620613 -61.377753) (xy 432.640536 -61.325662)
			(xy 432.667832 -61.277027) (xy 432.701918 -61.232884) (xy 432.742067 -61.194175) (xy 432.787425 -61.161724)
			(xy 432.837025 -61.136223) (xy 432.889809 -61.118216) (xy 432.944652 -61.108086) (xy 433.000386 -61.106049)
			(xy 433.055823 -61.112149) (xy 433.10978 -61.126255) (xy 433.161109 -61.148067) (xy 433.208715 -61.177121)
			(xy 433.251583 -61.212796) (xy 433.2888 -61.254333) (xy 433.319573 -61.300846) (xy 433.343245 -61.351343)
			(xy 433.359313 -61.40475) (xy 433.367433 -61.459926) (xy 433.367942 -61.487812) (xy 433.367433 -61.515698)
			(xy 433.359313 -61.570874) (xy 433.343245 -61.624281) (xy 433.319573 -61.674778) (xy 433.2888 -61.721291)
			(xy 433.251583 -61.762828) (xy 433.208715 -61.798503) (xy 433.161109 -61.827557) (xy 433.10978 -61.849369)
			(xy 433.055823 -61.863475) (xy 433.000386 -61.869575) (xy 432.944652 -61.867538) (xy 432.889809 -61.857408)
			(xy 432.837025 -61.839401) (xy 432.787425 -61.8139) (xy 432.742067 -61.781449) (xy 432.701918 -61.74274)
			(xy 432.667832 -61.698597) (xy 432.640536 -61.649962) (xy 432.620613 -61.597871) (xy 432.608487 -61.543434)
			(xy 432.604416 -61.487812) (xy 414.451323 -61.487812) (xy 414.444874 -62.121034) (xy 430.54219 -62.121034)
			(xy 430.546261 -62.065412) (xy 430.558387 -62.010975) (xy 430.57831 -61.958884) (xy 430.605606 -61.910249)
			(xy 430.639692 -61.866106) (xy 430.679841 -61.827397) (xy 430.725199 -61.794946) (xy 430.774799 -61.769445)
			(xy 430.827583 -61.751438) (xy 430.882426 -61.741308) (xy 430.93816 -61.739271) (xy 430.993597 -61.745371)
			(xy 431.047554 -61.759477) (xy 431.098883 -61.781289) (xy 431.146489 -61.810343) (xy 431.189357 -61.846018)
			(xy 431.226574 -61.887555) (xy 431.257347 -61.934068) (xy 431.281019 -61.984565) (xy 431.297087 -62.037972)
			(xy 431.305207 -62.093148) (xy 431.305716 -62.121034) (xy 431.305207 -62.14892) (xy 431.297087 -62.204096)
			(xy 431.281019 -62.257503) (xy 431.257347 -62.308) (xy 431.226574 -62.354513) (xy 431.189357 -62.39605)
			(xy 431.146489 -62.431725) (xy 431.098883 -62.460779) (xy 431.047554 -62.482591) (xy 430.993597 -62.496697)
			(xy 430.93816 -62.502797) (xy 430.882426 -62.50076) (xy 430.827583 -62.49063) (xy 430.774799 -62.472623)
			(xy 430.725199 -62.447122) (xy 430.679841 -62.414671) (xy 430.639692 -62.375962) (xy 430.605606 -62.331819)
			(xy 430.57831 -62.283184) (xy 430.558387 -62.231093) (xy 430.546261 -62.176656) (xy 430.54219 -62.121034)
			(xy 414.444874 -62.121034) (xy 414.433747 -63.21355) (xy 422.420788 -63.21355) (xy 422.420788 -63.15905)
			(xy 422.428544 -63.105104) (xy 422.443899 -63.052811) (xy 422.466539 -63.003235) (xy 422.496004 -62.957386)
			(xy 422.531694 -62.916197) (xy 422.572883 -62.880507) (xy 422.618732 -62.851041) (xy 422.668307 -62.8284)
			(xy 422.7206 -62.813045) (xy 422.774546 -62.805289) (xy 422.801796 -62.804802) (xy 422.829166 -62.80527)
			(xy 422.883345 -62.813087) (xy 422.935848 -62.828576) (xy 422.985595 -62.851417) (xy 423.031562 -62.881141)
			(xy 423.052494 -62.898782) (xy 423.052748 -62.899036) (xy 423.059842 -62.904611) (xy 423.076753 -62.910864)
			(xy 423.085768 -62.911228) (xy 423.152824 -62.911228) (xy 423.161841 -62.910877) (xy 423.178758 -62.904625)
			(xy 423.185844 -62.899036) (xy 423.185844 -62.898782) (xy 423.186098 -62.898782) (xy 423.207031 -62.881141)
			(xy 423.252999 -62.851417) (xy 423.302745 -62.828571) (xy 423.355247 -62.813075) (xy 423.409425 -62.805246)
			(xy 423.464167 -62.805246) (xy 423.518345 -62.813075) (xy 423.570847 -62.828571) (xy 423.620593 -62.851417)
			(xy 423.666561 -62.881141) (xy 423.687494 -62.898782) (xy 423.687748 -62.899036) (xy 423.694842 -62.904611)
			(xy 423.711753 -62.910864) (xy 423.720768 -62.911228) (xy 423.787824 -62.911228) (xy 423.796841 -62.910877)
			(xy 423.813758 -62.904625) (xy 423.820844 -62.899036) (xy 423.820844 -62.898782) (xy 423.821098 -62.898782)
			(xy 423.842018 -62.881128) (xy 423.887994 -62.851419) (xy 423.937745 -62.828586) (xy 423.990248 -62.813098)
			(xy 424.044426 -62.805274) (xy 424.071796 -62.804802) (xy 424.09905 -62.805245) (xy 424.153003 -62.813001)
			(xy 424.205302 -62.828357) (xy 424.254884 -62.851) (xy 424.300739 -62.880469) (xy 424.341934 -62.916164)
			(xy 424.377629 -62.957358) (xy 424.407098 -63.003212) (xy 424.429741 -63.052794) (xy 424.43956 -63.086234)
			(xy 427.687484 -63.086234) (xy 427.691555 -63.030612) (xy 427.703681 -62.976175) (xy 427.723604 -62.924084)
			(xy 427.7509 -62.875449) (xy 427.784986 -62.831306) (xy 427.825135 -62.792597) (xy 427.870493 -62.760146)
			(xy 427.920093 -62.734645) (xy 427.972877 -62.716638) (xy 428.02772 -62.706508) (xy 428.083454 -62.704471)
			(xy 428.138891 -62.710571) (xy 428.192848 -62.724677) (xy 428.244177 -62.746489) (xy 428.291783 -62.775543)
			(xy 428.334651 -62.811218) (xy 428.371868 -62.852755) (xy 428.402641 -62.899268) (xy 428.426313 -62.949765)
			(xy 428.442381 -63.003172) (xy 428.450501 -63.058348) (xy 428.45101 -63.086234) (xy 428.450501 -63.11412)
			(xy 428.442381 -63.169296) (xy 428.426313 -63.222703) (xy 428.402641 -63.2732) (xy 428.402488 -63.273432)
			(xy 429.87671 -63.273432) (xy 429.880781 -63.21781) (xy 429.892907 -63.163373) (xy 429.91283 -63.111282)
			(xy 429.940126 -63.062647) (xy 429.974212 -63.018504) (xy 430.014361 -62.979795) (xy 430.059719 -62.947344)
			(xy 430.109319 -62.921843) (xy 430.162103 -62.903836) (xy 430.216946 -62.893706) (xy 430.27268 -62.891669)
			(xy 430.328117 -62.897769) (xy 430.382074 -62.911875) (xy 430.433403 -62.933687) (xy 430.481009 -62.962741)
			(xy 430.523877 -62.998416) (xy 430.561094 -63.039953) (xy 430.591867 -63.086466) (xy 430.615539 -63.136963)
			(xy 430.631607 -63.19037) (xy 430.639727 -63.245546) (xy 430.640236 -63.273432) (xy 430.639727 -63.301318)
			(xy 430.631607 -63.356494) (xy 430.615539 -63.409901) (xy 430.591867 -63.460398) (xy 430.561094 -63.506911)
			(xy 430.523877 -63.548448) (xy 430.481009 -63.584123) (xy 430.433403 -63.613177) (xy 430.382074 -63.634989)
			(xy 430.328117 -63.649095) (xy 430.27268 -63.655195) (xy 430.216946 -63.653158) (xy 430.162103 -63.643028)
			(xy 430.109319 -63.625021) (xy 430.059719 -63.59952) (xy 430.014361 -63.567069) (xy 429.974212 -63.52836)
			(xy 429.940126 -63.484217) (xy 429.91283 -63.435582) (xy 429.892907 -63.383491) (xy 429.880781 -63.329054)
			(xy 429.87671 -63.273432) (xy 428.402488 -63.273432) (xy 428.371868 -63.319713) (xy 428.334651 -63.36125)
			(xy 428.291783 -63.396925) (xy 428.244177 -63.425979) (xy 428.192848 -63.447791) (xy 428.138891 -63.461897)
			(xy 428.083454 -63.467997) (xy 428.02772 -63.46596) (xy 427.972877 -63.45583) (xy 427.920093 -63.437823)
			(xy 427.870493 -63.412322) (xy 427.825135 -63.379871) (xy 427.784986 -63.341162) (xy 427.7509 -63.297019)
			(xy 427.723604 -63.248384) (xy 427.703681 -63.196293) (xy 427.691555 -63.141856) (xy 427.687484 -63.086234)
			(xy 424.43956 -63.086234) (xy 424.445098 -63.105093) (xy 424.452855 -63.159046) (xy 424.452855 -63.213554)
			(xy 424.445098 -63.267507) (xy 424.429741 -63.319806) (xy 424.407098 -63.369388) (xy 424.377629 -63.415242)
			(xy 424.341934 -63.456436) (xy 424.300739 -63.492131) (xy 424.254884 -63.5216) (xy 424.205302 -63.544243)
			(xy 424.153003 -63.559599) (xy 424.09905 -63.567355) (xy 424.071796 -63.567818) (xy 424.044425 -63.567374)
			(xy 423.990244 -63.559554) (xy 423.93774 -63.544061) (xy 423.887993 -63.521214) (xy 423.842028 -63.491483)
			(xy 423.821098 -63.473838) (xy 423.820844 -63.473584) (xy 423.81375 -63.468008) (xy 423.796839 -63.461755)
			(xy 423.787824 -63.461392) (xy 423.720768 -63.461392) (xy 423.71175 -63.461736) (xy 423.694833 -63.467993)
			(xy 423.687748 -63.473584) (xy 423.687494 -63.473838) (xy 423.666561 -63.491479) (xy 423.620593 -63.521203)
			(xy 423.570847 -63.544049) (xy 423.518345 -63.559545) (xy 423.464167 -63.567374) (xy 423.409425 -63.567374)
			(xy 423.355247 -63.559545) (xy 423.302745 -63.544049) (xy 423.252999 -63.521203) (xy 423.207031 -63.491479)
			(xy 423.186098 -63.473838) (xy 423.185844 -63.473584) (xy 423.17875 -63.468008) (xy 423.161839 -63.461755)
			(xy 423.152824 -63.461392) (xy 423.085768 -63.461392) (xy 423.07675 -63.461736) (xy 423.059833 -63.467993)
			(xy 423.052748 -63.473584) (xy 423.052748 -63.473838) (xy 423.052494 -63.473838) (xy 423.03158 -63.4915)
			(xy 422.985602 -63.521207) (xy 422.93585 -63.544038) (xy 422.883345 -63.559524) (xy 422.829166 -63.567347)
			(xy 422.801796 -63.567818) (xy 422.774546 -63.567311) (xy 422.7206 -63.559555) (xy 422.668307 -63.5442)
			(xy 422.618732 -63.521559) (xy 422.572883 -63.492093) (xy 422.531694 -63.456403) (xy 422.496004 -63.415214)
			(xy 422.466539 -63.369365) (xy 422.443899 -63.319789) (xy 422.428544 -63.267496) (xy 422.420788 -63.21355)
			(xy 414.433747 -63.21355) (xy 414.419796 -64.58331) (xy 414.419796 -65.100962) (xy 420.432482 -65.100962)
			(xy 420.436553 -65.04534) (xy 420.448679 -64.990903) (xy 420.468602 -64.938812) (xy 420.495898 -64.890177)
			(xy 420.529984 -64.846034) (xy 420.570133 -64.807325) (xy 420.615491 -64.774874) (xy 420.665091 -64.749373)
			(xy 420.717875 -64.731366) (xy 420.772718 -64.721236) (xy 420.828452 -64.719199) (xy 420.883889 -64.725299)
			(xy 420.937846 -64.739405) (xy 420.989175 -64.761217) (xy 421.036781 -64.790271) (xy 421.079649 -64.825946)
			(xy 421.116866 -64.867483) (xy 421.147639 -64.913996) (xy 421.171311 -64.964493) (xy 421.187379 -65.0179)
			(xy 421.195499 -65.073076) (xy 421.196008 -65.100962) (xy 421.195586 -65.124076) (xy 432.407312 -65.124076)
			(xy 432.411383 -65.068454) (xy 432.423509 -65.014017) (xy 432.443432 -64.961926) (xy 432.470728 -64.913291)
			(xy 432.504814 -64.869148) (xy 432.544963 -64.830439) (xy 432.590321 -64.797988) (xy 432.639921 -64.772487)
			(xy 432.692705 -64.75448) (xy 432.747548 -64.74435) (xy 432.803282 -64.742313) (xy 432.858719 -64.748413)
			(xy 432.912676 -64.762519) (xy 432.964005 -64.784331) (xy 433.011611 -64.813385) (xy 433.054479 -64.84906)
			(xy 433.091696 -64.890597) (xy 433.122469 -64.93711) (xy 433.146141 -64.987607) (xy 433.162209 -65.041014)
			(xy 433.170329 -65.09619) (xy 433.170838 -65.124076) (xy 433.170329 -65.151962) (xy 433.162209 -65.207138)
			(xy 433.146141 -65.260545) (xy 433.122469 -65.311042) (xy 433.091696 -65.357555) (xy 433.054479 -65.399092)
			(xy 433.011611 -65.434767) (xy 432.964005 -65.463821) (xy 432.912676 -65.485633) (xy 432.858719 -65.499739)
			(xy 432.803282 -65.505839) (xy 432.747548 -65.503802) (xy 432.692705 -65.493672) (xy 432.639921 -65.475665)
			(xy 432.590321 -65.450164) (xy 432.544963 -65.417713) (xy 432.504814 -65.379004) (xy 432.470728 -65.334861)
			(xy 432.443432 -65.286226) (xy 432.423509 -65.234135) (xy 432.411383 -65.179698) (xy 432.407312 -65.124076)
			(xy 421.195586 -65.124076) (xy 421.195499 -65.128848) (xy 421.187379 -65.184024) (xy 421.171311 -65.237431)
			(xy 421.147639 -65.287928) (xy 421.116866 -65.334441) (xy 421.079649 -65.375978) (xy 421.036781 -65.411653)
			(xy 420.989175 -65.440707) (xy 420.937846 -65.462519) (xy 420.883889 -65.476625) (xy 420.828452 -65.482725)
			(xy 420.772718 -65.480688) (xy 420.717875 -65.470558) (xy 420.665091 -65.452551) (xy 420.615491 -65.42705)
			(xy 420.570133 -65.394599) (xy 420.529984 -65.35589) (xy 420.495898 -65.311747) (xy 420.468602 -65.263112)
			(xy 420.448679 -65.211021) (xy 420.436553 -65.156584) (xy 420.432482 -65.100962) (xy 414.419796 -65.100962)
			(xy 414.419796 -65.75552) (xy 414.646616 -65.75552) (xy 414.650687 -65.699898) (xy 414.662813 -65.645461)
			(xy 414.682736 -65.59337) (xy 414.710032 -65.544735) (xy 414.744118 -65.500592) (xy 414.784267 -65.461883)
			(xy 414.829625 -65.429432) (xy 414.879225 -65.403931) (xy 414.932009 -65.385924) (xy 414.986852 -65.375794)
			(xy 415.042586 -65.373757) (xy 415.098023 -65.379857) (xy 415.15198 -65.393963) (xy 415.203309 -65.415775)
			(xy 415.250915 -65.444829) (xy 415.293783 -65.480504) (xy 415.331 -65.522041) (xy 415.361773 -65.568554)
			(xy 415.385445 -65.619051) (xy 415.401513 -65.672458) (xy 415.409633 -65.727634) (xy 415.410142 -65.75552)
			(xy 415.409633 -65.783406) (xy 415.401513 -65.838582) (xy 415.385445 -65.891989) (xy 415.361773 -65.942486)
			(xy 415.331 -65.988999) (xy 415.293783 -66.030536) (xy 415.250915 -66.066211) (xy 415.203309 -66.095265)
			(xy 415.15198 -66.117077) (xy 415.098023 -66.131183) (xy 415.042586 -66.137283) (xy 414.986852 -66.135246)
			(xy 414.932009 -66.125116) (xy 414.879225 -66.107109) (xy 414.829625 -66.081608) (xy 414.784267 -66.049157)
			(xy 414.744118 -66.010448) (xy 414.710032 -65.966305) (xy 414.682736 -65.91767) (xy 414.662813 -65.865579)
			(xy 414.650687 -65.811142) (xy 414.646616 -65.75552) (xy 414.419796 -65.75552) (xy 414.419796 -67.128949)
			(xy 414.666698 -67.128949) (xy 414.666698 -67.074451) (xy 414.674454 -67.020508) (xy 414.689807 -66.968217)
			(xy 414.712446 -66.918643) (xy 414.741909 -66.872796) (xy 414.777597 -66.831609) (xy 414.818783 -66.795919)
			(xy 414.864629 -66.766454) (xy 414.914202 -66.743813) (xy 414.966492 -66.728457) (xy 415.020435 -66.720699)
			(xy 415.047684 -66.720212) (xy 415.075054 -66.720685) (xy 415.129233 -66.7285) (xy 415.181736 -66.743988)
			(xy 415.231483 -66.766828) (xy 415.27745 -66.796551) (xy 415.298382 -66.814192) (xy 415.298636 -66.814446)
			(xy 415.305733 -66.820017) (xy 415.322642 -66.826272) (xy 415.331656 -66.826638) (xy 415.398712 -66.826638)
			(xy 415.407728 -66.826279) (xy 415.424645 -66.820032) (xy 415.431732 -66.814446) (xy 415.431732 -66.814192)
			(xy 415.431986 -66.814192) (xy 415.452911 -66.796545) (xy 415.498886 -66.766834) (xy 415.548635 -66.744)
			(xy 415.601138 -66.728511) (xy 415.655314 -66.720685) (xy 415.682684 -66.720212) (xy 415.709939 -66.720634)
			(xy 415.763895 -66.728389) (xy 415.816197 -66.743745) (xy 415.865782 -66.766388) (xy 415.91164 -66.795857)
			(xy 415.952836 -66.831552) (xy 415.988534 -66.872748) (xy 416.018005 -66.918604) (xy 416.04065 -66.968188)
			(xy 416.056007 -67.02049) (xy 416.063765 -67.074445) (xy 416.063765 -67.128955) (xy 416.056007 -67.18291)
			(xy 416.04065 -67.235212) (xy 416.018005 -67.284796) (xy 415.988534 -67.330652) (xy 415.952836 -67.371848)
			(xy 415.91164 -67.407543) (xy 415.865782 -67.437012) (xy 415.816197 -67.459655) (xy 415.763895 -67.475011)
			(xy 415.709939 -67.482766) (xy 415.682684 -67.483228) (xy 415.655313 -67.482789) (xy 415.601132 -67.474967)
			(xy 415.548628 -67.459473) (xy 415.498881 -67.436625) (xy 415.452916 -67.406893) (xy 415.431986 -67.389248)
			(xy 415.431732 -67.388994) (xy 415.424641 -67.383414) (xy 415.407728 -67.377164) (xy 415.398712 -67.376802)
			(xy 415.331656 -67.376802) (xy 415.322642 -67.377186) (xy 415.305725 -67.383415) (xy 415.298636 -67.388994)
			(xy 415.298636 -67.389248) (xy 415.298382 -67.389248) (xy 415.277423 -67.406854) (xy 415.231459 -67.436573)
			(xy 415.181718 -67.459416) (xy 415.129223 -67.474914) (xy 415.075051 -67.48275) (xy 415.047684 -67.483228)
			(xy 415.020435 -67.482701) (xy 414.966492 -67.474943) (xy 414.914202 -67.459587) (xy 414.864629 -67.436946)
			(xy 414.818783 -67.407481) (xy 414.777597 -67.371791) (xy 414.741909 -67.330604) (xy 414.712446 -67.284757)
			(xy 414.689807 -67.235183) (xy 414.674454 -67.182892) (xy 414.666698 -67.128949) (xy 414.419796 -67.128949)
			(xy 414.419796 -67.488054) (xy 419.07917 -67.488054) (xy 419.083241 -67.432432) (xy 419.095367 -67.377995)
			(xy 419.11529 -67.325904) (xy 419.142586 -67.277269) (xy 419.176672 -67.233126) (xy 419.216821 -67.194417)
			(xy 419.262179 -67.161966) (xy 419.311779 -67.136465) (xy 419.364563 -67.118458) (xy 419.419406 -67.108328)
			(xy 419.47514 -67.106291) (xy 419.530577 -67.112391) (xy 419.584534 -67.126497) (xy 419.635863 -67.148309)
			(xy 419.683469 -67.177363) (xy 419.726337 -67.213038) (xy 419.763554 -67.254575) (xy 419.794327 -67.301088)
			(xy 419.817999 -67.351585) (xy 419.834067 -67.404992) (xy 419.842187 -67.460168) (xy 419.842696 -67.488054)
			(xy 419.842187 -67.51594) (xy 419.839002 -67.537584) (xy 420.371268 -67.537584) (xy 420.375339 -67.481962)
			(xy 420.387465 -67.427525) (xy 420.407388 -67.375434) (xy 420.434684 -67.326799) (xy 420.46877 -67.282656)
			(xy 420.508919 -67.243947) (xy 420.554277 -67.211496) (xy 420.603877 -67.185995) (xy 420.656661 -67.167988)
			(xy 420.711504 -67.157858) (xy 420.767238 -67.155821) (xy 420.822675 -67.161921) (xy 420.876632 -67.176027)
			(xy 420.927961 -67.197839) (xy 420.975567 -67.226893) (xy 421.018435 -67.262568) (xy 421.055652 -67.304105)
			(xy 421.086425 -67.350618) (xy 421.110097 -67.401115) (xy 421.126165 -67.454522) (xy 421.134285 -67.509698)
			(xy 421.134794 -67.537584) (xy 421.134285 -67.56547) (xy 421.13024 -67.592956) (xy 421.645332 -67.592956)
			(xy 421.649403 -67.537334) (xy 421.661529 -67.482897) (xy 421.681452 -67.430806) (xy 421.708748 -67.382171)
			(xy 421.742834 -67.338028) (xy 421.782983 -67.299319) (xy 421.828341 -67.266868) (xy 421.877941 -67.241367)
			(xy 421.930725 -67.22336) (xy 421.985568 -67.21323) (xy 422.041302 -67.211193) (xy 422.096739 -67.217293)
			(xy 422.150696 -67.231399) (xy 422.202025 -67.253211) (xy 422.249631 -67.282265) (xy 422.292499 -67.31794)
			(xy 422.329716 -67.359477) (xy 422.360489 -67.40599) (xy 422.384161 -67.456487) (xy 422.400229 -67.509894)
			(xy 422.408346 -67.565047) (xy 424.746716 -67.565047) (xy 424.746716 -67.510553) (xy 424.754471 -67.456613)
			(xy 424.769823 -67.404325) (xy 424.79246 -67.354755) (xy 424.821921 -67.30891) (xy 424.857606 -67.267725)
			(xy 424.898789 -67.232037) (xy 424.944632 -67.202573) (xy 424.994201 -67.179933) (xy 425.046487 -67.164577)
			(xy 425.100427 -67.156818) (xy 425.127674 -67.15633) (xy 425.155044 -67.156804) (xy 425.209223 -67.164619)
			(xy 425.261726 -67.180106) (xy 425.311473 -67.202946) (xy 425.35744 -67.232669) (xy 425.378372 -67.25031)
			(xy 425.378626 -67.250564) (xy 425.385724 -67.256133) (xy 425.402632 -67.262389) (xy 425.411646 -67.262756)
			(xy 425.478702 -67.262756) (xy 425.48772 -67.262409) (xy 425.504637 -67.256155) (xy 425.511722 -67.250564)
			(xy 425.511722 -67.25031) (xy 425.511976 -67.25031) (xy 425.532908 -67.23267) (xy 425.57888 -67.202958)
			(xy 425.628628 -67.180122) (xy 425.681129 -67.164631) (xy 425.735305 -67.156804) (xy 425.762674 -67.15633)
			(xy 425.789931 -67.156715) (xy 425.84389 -67.16447) (xy 425.896196 -67.179825) (xy 425.945785 -67.202469)
			(xy 425.991646 -67.231939) (xy 426.032846 -67.267636) (xy 426.068546 -67.308834) (xy 426.098019 -67.354693)
			(xy 426.120666 -67.404279) (xy 426.136025 -67.456585) (xy 426.143783 -67.510543) (xy 426.143783 -67.565057)
			(xy 426.136025 -67.619015) (xy 426.120666 -67.671321) (xy 426.098019 -67.720907) (xy 426.068546 -67.766766)
			(xy 426.032846 -67.807964) (xy 425.991646 -67.843661) (xy 425.945785 -67.873131) (xy 425.896196 -67.895775)
			(xy 425.84389 -67.91113) (xy 425.789931 -67.918885) (xy 425.762674 -67.919346) (xy 425.735303 -67.918908)
			(xy 425.681122 -67.911086) (xy 425.628618 -67.895591) (xy 425.578871 -67.872742) (xy 425.532906 -67.843011)
			(xy 425.511976 -67.825366) (xy 425.511722 -67.825112) (xy 425.504632 -67.81953) (xy 425.487718 -67.81328)
			(xy 425.478702 -67.81292) (xy 425.411646 -67.81292) (xy 425.402631 -67.813295) (xy 425.385714 -67.81953)
			(xy 425.378626 -67.825112) (xy 425.378626 -67.825366) (xy 425.378372 -67.825366) (xy 425.357419 -67.84298)
			(xy 425.311453 -67.872696) (xy 425.26171 -67.895538) (xy 425.209214 -67.911035) (xy 425.155042 -67.918869)
			(xy 425.127674 -67.919346) (xy 425.100427 -67.918782) (xy 425.046487 -67.911023) (xy 424.994201 -67.895667)
			(xy 424.944632 -67.873027) (xy 424.898789 -67.843563) (xy 424.857606 -67.807875) (xy 424.821921 -67.76669)
			(xy 424.79246 -67.720845) (xy 424.769823 -67.671275) (xy 424.754471 -67.618987) (xy 424.746716 -67.565047)
			(xy 422.408346 -67.565047) (xy 422.408349 -67.56507) (xy 422.408858 -67.592956) (xy 422.408349 -67.620842)
			(xy 422.400229 -67.676018) (xy 422.384161 -67.729425) (xy 422.360489 -67.779922) (xy 422.329716 -67.826435)
			(xy 422.292499 -67.867972) (xy 422.249631 -67.903647) (xy 422.202025 -67.932701) (xy 422.150696 -67.954513)
			(xy 422.096739 -67.968619) (xy 422.041302 -67.974719) (xy 421.985568 -67.972682) (xy 421.930725 -67.962552)
			(xy 421.877941 -67.944545) (xy 421.828341 -67.919044) (xy 421.782983 -67.886593) (xy 421.742834 -67.847884)
			(xy 421.708748 -67.803741) (xy 421.681452 -67.755106) (xy 421.661529 -67.703015) (xy 421.649403 -67.648578)
			(xy 421.645332 -67.592956) (xy 421.13024 -67.592956) (xy 421.126165 -67.620646) (xy 421.110097 -67.674053)
			(xy 421.086425 -67.72455) (xy 421.055652 -67.771063) (xy 421.018435 -67.8126) (xy 420.975567 -67.848275)
			(xy 420.927961 -67.877329) (xy 420.876632 -67.899141) (xy 420.822675 -67.913247) (xy 420.767238 -67.919347)
			(xy 420.711504 -67.91731) (xy 420.656661 -67.90718) (xy 420.603877 -67.889173) (xy 420.554277 -67.863672)
			(xy 420.508919 -67.831221) (xy 420.46877 -67.792512) (xy 420.434684 -67.748369) (xy 420.407388 -67.699734)
			(xy 420.387465 -67.647643) (xy 420.375339 -67.593206) (xy 420.371268 -67.537584) (xy 419.839002 -67.537584)
			(xy 419.834067 -67.571116) (xy 419.817999 -67.624523) (xy 419.794327 -67.67502) (xy 419.763554 -67.721533)
			(xy 419.726337 -67.76307) (xy 419.683469 -67.798745) (xy 419.635863 -67.827799) (xy 419.584534 -67.849611)
			(xy 419.530577 -67.863717) (xy 419.47514 -67.869817) (xy 419.419406 -67.86778) (xy 419.364563 -67.85765)
			(xy 419.311779 -67.839643) (xy 419.262179 -67.814142) (xy 419.216821 -67.781691) (xy 419.176672 -67.742982)
			(xy 419.142586 -67.698839) (xy 419.11529 -67.650204) (xy 419.095367 -67.598113) (xy 419.083241 -67.543676)
			(xy 419.07917 -67.488054) (xy 414.419796 -67.488054) (xy 414.419796 -68.36791) (xy 414.418526 -68.419218)
			(xy 414.409831 -68.586604) (xy 416.925252 -68.586604) (xy 416.925708 -68.559233) (xy 416.933526 -68.505053)
			(xy 416.949017 -68.45255) (xy 416.971861 -68.402803) (xy 417.001589 -68.356837) (xy 417.019232 -68.335906)
			(xy 417.019486 -68.335652) (xy 417.025055 -68.328554) (xy 417.031313 -68.311646) (xy 417.031678 -68.302632)
			(xy 417.031678 -68.235576) (xy 417.031337 -68.226557) (xy 417.025079 -68.20964) (xy 417.019486 -68.202556)
			(xy 417.019232 -68.202556) (xy 417.019232 -68.202302) (xy 417.001585 -68.181376) (xy 416.971874 -68.135402)
			(xy 416.949039 -68.085653) (xy 416.933549 -68.033151) (xy 416.925724 -67.978974) (xy 416.925252 -67.951604)
			(xy 416.925781 -67.924355) (xy 416.933536 -67.870411) (xy 416.948889 -67.818119) (xy 416.971527 -67.768545)
			(xy 417.000989 -67.722696) (xy 417.036676 -67.681507) (xy 417.077861 -67.645815) (xy 417.123706 -67.616348)
			(xy 417.173278 -67.593704) (xy 417.225568 -67.578346) (xy 417.279511 -67.570585) (xy 417.30676 -67.570096)
			(xy 417.333075 -67.570525) (xy 417.385205 -67.577768) (xy 417.435849 -67.592094) (xy 417.484048 -67.613234)
			(xy 417.52889 -67.640787) (xy 417.569528 -67.674232) (xy 417.587684 -67.693286) (xy 417.595212 -67.70068)
			(xy 417.614487 -67.709209) (xy 417.625022 -67.709796) (xy 417.699698 -67.709796) (xy 417.710249 -67.70928)
			(xy 417.729544 -67.700736) (xy 417.737036 -67.693286) (xy 417.755178 -67.674217) (xy 417.795811 -67.640762)
			(xy 417.840654 -67.613205) (xy 417.888858 -67.592069) (xy 417.939507 -67.577754) (xy 417.991643 -67.570533)
			(xy 418.01796 -67.570096) (xy 418.045329 -67.570586) (xy 418.099507 -67.578399) (xy 418.15201 -67.593882)
			(xy 418.201757 -67.616718) (xy 418.247725 -67.646437) (xy 418.268658 -67.664076) (xy 418.268912 -67.66433)
			(xy 418.275988 -67.669931) (xy 418.292913 -67.676168) (xy 418.301932 -67.676522) (xy 418.368988 -67.676522)
			(xy 418.378004 -67.676154) (xy 418.39492 -67.669914) (xy 418.402008 -67.66433) (xy 418.402008 -67.664076)
			(xy 418.402262 -67.664076) (xy 418.423194 -67.646438) (xy 418.469168 -67.616726) (xy 418.518915 -67.593891)
			(xy 418.571415 -67.578399) (xy 418.625591 -67.570571) (xy 418.65296 -67.570096) (xy 418.680212 -67.570593)
			(xy 418.734162 -67.578344) (xy 418.786459 -67.593695) (xy 418.83604 -67.616333) (xy 418.881893 -67.645798)
			(xy 418.923086 -67.681488) (xy 418.958781 -67.722678) (xy 418.988249 -67.768529) (xy 419.010892 -67.818107)
			(xy 419.026248 -67.870403) (xy 419.034005 -67.924352) (xy 419.034468 -67.951604) (xy 419.034012 -67.978975)
			(xy 419.026193 -68.033155) (xy 419.010702 -68.085658) (xy 418.987858 -68.135405) (xy 418.958131 -68.181371)
			(xy 418.940488 -68.202302) (xy 418.940234 -68.202556) (xy 418.934652 -68.209645) (xy 418.928404 -68.22656)
			(xy 418.928042 -68.235576) (xy 418.928042 -68.302632) (xy 418.928375 -68.311652) (xy 418.934638 -68.328569)
			(xy 418.940234 -68.335652) (xy 418.940488 -68.335652) (xy 418.940488 -68.335906) (xy 418.958141 -68.356827)
			(xy 418.987852 -68.402802) (xy 419.010685 -68.452553) (xy 419.026173 -68.505056) (xy 419.033996 -68.559234)
			(xy 419.034468 -68.586604) (xy 419.034048 -68.613859) (xy 419.02629 -68.667813) (xy 419.010931 -68.720114)
			(xy 418.994299 -68.75653) (xy 422.470326 -68.75653) (xy 422.470803 -68.72916) (xy 422.478617 -68.674981)
			(xy 422.494104 -68.622478) (xy 422.516943 -68.572731) (xy 422.546666 -68.526764) (xy 422.564306 -68.505832)
			(xy 422.56456 -68.505578) (xy 422.570169 -68.498507) (xy 422.576401 -68.481578) (xy 422.576752 -68.472558)
			(xy 422.576752 -68.405502) (xy 422.576404 -68.396484) (xy 422.570151 -68.379567) (xy 422.56456 -68.372482)
			(xy 422.564306 -68.372482) (xy 422.564306 -68.372228) (xy 422.546668 -68.351295) (xy 422.516955 -68.305323)
			(xy 422.494119 -68.255575) (xy 422.478628 -68.203075) (xy 422.4708 -68.148899) (xy 422.470326 -68.12153)
			(xy 422.470783 -68.094276) (xy 422.478537 -68.040323) (xy 422.493891 -67.988023) (xy 422.516533 -67.938441)
			(xy 422.546001 -67.892586) (xy 422.581695 -67.851392) (xy 422.622889 -67.815698) (xy 422.668745 -67.786231)
			(xy 422.718327 -67.76359) (xy 422.770627 -67.748236) (xy 422.82458 -67.740483) (xy 422.851834 -67.740022)
			(xy 422.879205 -67.740463) (xy 422.933386 -67.748286) (xy 422.985889 -67.763781) (xy 423.035636 -67.786628)
			(xy 423.081601 -67.816358) (xy 423.102532 -67.834002) (xy 423.102786 -67.834256) (xy 423.109868 -67.83985)
			(xy 423.126788 -67.846091) (xy 423.135806 -67.846448) (xy 423.202862 -67.846448) (xy 423.211878 -67.846084)
			(xy 423.228796 -67.839843) (xy 423.235882 -67.834256) (xy 423.235882 -67.834002) (xy 423.236136 -67.834002)
			(xy 423.257082 -67.81638) (xy 423.303051 -67.786665) (xy 423.352795 -67.763826) (xy 423.405292 -67.748331)
			(xy 423.459466 -67.740498) (xy 423.486834 -67.740022) (xy 423.513149 -67.74046) (xy 423.565279 -67.7477)
			(xy 423.615923 -67.762024) (xy 423.664122 -67.783162) (xy 423.708964 -67.810714) (xy 423.749603 -67.844158)
			(xy 423.767758 -67.863212) (xy 423.775292 -67.870599) (xy 423.794563 -67.879131) (xy 423.805096 -67.879722)
			(xy 423.879772 -67.879722) (xy 423.890321 -67.879185) (xy 423.909615 -67.870654) (xy 423.91711 -67.863212)
			(xy 423.93527 -67.844161) (xy 423.975899 -67.810703) (xy 424.020738 -67.783143) (xy 424.068938 -67.762004)
			(xy 424.119585 -67.747686) (xy 424.171718 -67.740461) (xy 424.198034 -67.740022) (xy 424.225287 -67.740446)
			(xy 424.279239 -67.748208) (xy 424.331537 -67.763569) (xy 424.381116 -67.786216) (xy 424.426968 -67.815689)
			(xy 424.468158 -67.851387) (xy 424.503849 -67.892584) (xy 424.533314 -67.93844) (xy 424.555953 -67.988023)
			(xy 424.571305 -68.040324) (xy 424.579058 -68.094276) (xy 424.579542 -68.12153) (xy 424.579108 -68.148902)
			(xy 424.571284 -68.203083) (xy 424.555789 -68.255587) (xy 424.532939 -68.305333) (xy 424.503207 -68.351298)
			(xy 424.485562 -68.372228) (xy 424.485308 -68.372482) (xy 424.479724 -68.37957) (xy 424.473475 -68.396486)
			(xy 424.473116 -68.405502) (xy 424.473116 -68.472558) (xy 424.47349 -68.481573) (xy 424.479725 -68.49849)
			(xy 424.485308 -68.505578) (xy 424.485562 -68.505578) (xy 424.485562 -68.505832) (xy 424.503177 -68.526784)
			(xy 424.532894 -68.572751) (xy 424.555735 -68.622493) (xy 424.571231 -68.67499) (xy 424.579065 -68.729162)
			(xy 424.579542 -68.75653) (xy 424.57905 -68.78378) (xy 424.57129 -68.837726) (xy 424.555933 -68.890019)
			(xy 424.533291 -68.939594) (xy 424.503825 -68.985442) (xy 424.468134 -69.026631) (xy 424.426946 -69.062322)
			(xy 424.381097 -69.091789) (xy 424.331522 -69.114432) (xy 424.27923 -69.12979) (xy 424.225284 -69.13755)
			(xy 424.198034 -69.138038) (xy 424.171718 -69.137634) (xy 424.119586 -69.130389) (xy 424.068941 -69.116059)
			(xy 424.020742 -69.094915) (xy 423.9759 -69.067356) (xy 423.935264 -69.033906) (xy 423.91711 -69.014848)
			(xy 423.90958 -69.007456) (xy 423.890307 -68.998925) (xy 423.879772 -68.998338) (xy 423.805096 -68.998338)
			(xy 423.794543 -68.99884) (xy 423.775247 -69.007393) (xy 423.767758 -69.014848) (xy 423.749625 -69.033926)
			(xy 423.70899 -69.067379) (xy 423.664144 -69.094934) (xy 423.615939 -69.116068) (xy 423.565288 -69.130381)
			(xy 423.513151 -69.137602) (xy 423.486834 -69.138038) (xy 423.459464 -69.137567) (xy 423.405284 -69.129753)
			(xy 423.352781 -69.114266) (xy 423.303034 -69.091425) (xy 423.257067 -69.0617) (xy 423.236136 -69.044058)
			(xy 423.235882 -69.043804) (xy 423.228804 -69.038204) (xy 423.211881 -69.031965) (xy 423.202862 -69.031612)
			(xy 423.135806 -69.031612) (xy 423.126789 -69.031969) (xy 423.109872 -69.038216) (xy 423.102786 -69.043804)
			(xy 423.102786 -69.044058) (xy 423.102532 -69.044058) (xy 423.081593 -69.061689) (xy 423.035623 -69.091404)
			(xy 422.985877 -69.114242) (xy 422.933378 -69.129734) (xy 422.879203 -69.137564) (xy 422.851834 -69.138038)
			(xy 422.824583 -69.137513) (xy 422.770636 -69.129762) (xy 422.718341 -69.114411) (xy 422.668763 -69.091775)
			(xy 422.622911 -69.062313) (xy 422.581719 -69.026626) (xy 422.546025 -68.98544) (xy 422.516556 -68.939593)
			(xy 422.493911 -68.890019) (xy 422.478552 -68.837726) (xy 422.470791 -68.783781) (xy 422.470326 -68.75653)
			(xy 418.994299 -68.75653) (xy 418.988285 -68.769697) (xy 418.958813 -68.815552) (xy 418.923115 -68.856746)
			(xy 418.881917 -68.89244) (xy 418.836059 -68.921906) (xy 418.786473 -68.944547) (xy 418.73417 -68.959899)
			(xy 418.680215 -68.967651) (xy 418.65296 -68.968112) (xy 418.625591 -68.967608) (xy 418.571414 -68.959799)
			(xy 418.518911 -68.944318) (xy 418.469164 -68.921485) (xy 418.423195 -68.891769) (xy 418.402262 -68.874132)
			(xy 418.402008 -68.873878) (xy 418.394925 -68.868286) (xy 418.378005 -68.862043) (xy 418.368988 -68.861686)
			(xy 418.301932 -68.861686) (xy 418.292917 -68.862061) (xy 418.276 -68.868296) (xy 418.268912 -68.873878)
			(xy 418.268912 -68.874132) (xy 418.268658 -68.874132) (xy 418.247719 -68.891762) (xy 418.201748 -68.921474)
			(xy 418.152002 -68.944312) (xy 418.099503 -68.959805) (xy 418.045329 -68.967636) (xy 418.01796 -68.968112)
			(xy 417.991645 -68.967667) (xy 417.939516 -68.960427) (xy 417.888873 -68.946104) (xy 417.840674 -68.924967)
			(xy 417.795831 -68.897417) (xy 417.755192 -68.863975) (xy 417.737036 -68.844922) (xy 417.7295 -68.837537)
			(xy 417.710231 -68.829003) (xy 417.699698 -68.828412) (xy 417.625022 -68.828412) (xy 417.614472 -68.828936)
			(xy 417.595176 -68.837474) (xy 417.587684 -68.844922) (xy 417.569534 -68.863983) (xy 417.528902 -68.897438)
			(xy 417.484061 -68.924996) (xy 417.435859 -68.946134) (xy 417.385211 -68.96045) (xy 417.333076 -68.967674)
			(xy 417.30676 -68.968112) (xy 417.279508 -68.967659) (xy 417.225559 -68.959898) (xy 417.173264 -68.944538)
			(xy 417.123687 -68.921892) (xy 417.077837 -68.892422) (xy 417.036647 -68.856727) (xy 417.000956 -68.815534)
			(xy 416.971491 -68.769681) (xy 416.94885 -68.720102) (xy 416.933495 -68.667806) (xy 416.925738 -68.613856)
			(xy 416.925252 -68.586604) (xy 414.409831 -68.586604) (xy 414.34385 -69.856858) (xy 414.340548 -69.918834)
			(xy 414.25542 -71.555864) (xy 419.49446 -71.555864) (xy 419.498531 -71.500242) (xy 419.510657 -71.445805)
			(xy 419.53058 -71.393714) (xy 419.557876 -71.345079) (xy 419.591962 -71.300936) (xy 419.632111 -71.262227)
			(xy 419.677469 -71.229776) (xy 419.727069 -71.204275) (xy 419.779853 -71.186268) (xy 419.834696 -71.176138)
			(xy 419.89043 -71.174101) (xy 419.945867 -71.180201) (xy 419.999824 -71.194307) (xy 420.051153 -71.216119)
			(xy 420.098759 -71.245173) (xy 420.141627 -71.280848) (xy 420.178844 -71.322385) (xy 420.209617 -71.368898)
			(xy 420.233289 -71.419395) (xy 420.249357 -71.472802) (xy 420.257477 -71.527978) (xy 420.257986 -71.555864)
			(xy 420.257477 -71.58375) (xy 420.251638 -71.623428) (xy 421.003474 -71.623428) (xy 421.007545 -71.567806)
			(xy 421.019671 -71.513369) (xy 421.039594 -71.461278) (xy 421.06689 -71.412643) (xy 421.100976 -71.3685)
			(xy 421.141125 -71.329791) (xy 421.186483 -71.29734) (xy 421.236083 -71.271839) (xy 421.288867 -71.253832)
			(xy 421.34371 -71.243702) (xy 421.399444 -71.241665) (xy 421.454881 -71.247765) (xy 421.508838 -71.261871)
			(xy 421.560167 -71.283683) (xy 421.607773 -71.312737) (xy 421.650641 -71.348412) (xy 421.687858 -71.389949)
			(xy 421.718631 -71.436462) (xy 421.742303 -71.486959) (xy 421.758371 -71.540366) (xy 421.766491 -71.595542)
			(xy 421.767 -71.623428) (xy 421.766491 -71.651314) (xy 421.758371 -71.70649) (xy 421.742303 -71.759897)
			(xy 421.718631 -71.810394) (xy 421.687858 -71.856907) (xy 421.650641 -71.898444) (xy 421.607773 -71.934119)
			(xy 421.560167 -71.963173) (xy 421.508838 -71.984985) (xy 421.454881 -71.999091) (xy 421.399444 -72.005191)
			(xy 421.34371 -72.003154) (xy 421.288867 -71.993024) (xy 421.236083 -71.975017) (xy 421.186483 -71.949516)
			(xy 421.141125 -71.917065) (xy 421.100976 -71.878356) (xy 421.06689 -71.834213) (xy 421.039594 -71.785578)
			(xy 421.019671 -71.733487) (xy 421.007545 -71.67905) (xy 421.003474 -71.623428) (xy 420.251638 -71.623428)
			(xy 420.249357 -71.638926) (xy 420.233289 -71.692333) (xy 420.209617 -71.74283) (xy 420.178844 -71.789343)
			(xy 420.141627 -71.83088) (xy 420.098759 -71.866555) (xy 420.051153 -71.895609) (xy 419.999824 -71.917421)
			(xy 419.945867 -71.931527) (xy 419.89043 -71.937627) (xy 419.834696 -71.93559) (xy 419.779853 -71.92546)
			(xy 419.727069 -71.907453) (xy 419.677469 -71.881952) (xy 419.632111 -71.849501) (xy 419.591962 -71.810792)
			(xy 419.557876 -71.766649) (xy 419.53058 -71.718014) (xy 419.510657 -71.665923) (xy 419.498531 -71.611486)
			(xy 419.49446 -71.555864) (xy 414.25542 -71.555864) (xy 414.205928 -72.507602) (xy 414.117809 -74.203814)
			(xy 431.474624 -74.203814) (xy 431.478695 -74.148192) (xy 431.490821 -74.093755) (xy 431.510744 -74.041664)
			(xy 431.53804 -73.993029) (xy 431.572126 -73.948886) (xy 431.612275 -73.910177) (xy 431.657633 -73.877726)
			(xy 431.707233 -73.852225) (xy 431.760017 -73.834218) (xy 431.81486 -73.824088) (xy 431.870594 -73.822051)
			(xy 431.926031 -73.828151) (xy 431.979988 -73.842257) (xy 432.031317 -73.864069) (xy 432.078923 -73.893123)
			(xy 432.121791 -73.928798) (xy 432.159008 -73.970335) (xy 432.189781 -74.016848) (xy 432.213453 -74.067345)
			(xy 432.229521 -74.120752) (xy 432.237641 -74.175928) (xy 432.23815 -74.203814) (xy 432.237641 -74.2317)
			(xy 432.229521 -74.286876) (xy 432.213453 -74.340283) (xy 432.189781 -74.39078) (xy 432.159008 -74.437293)
			(xy 432.121791 -74.47883) (xy 432.078923 -74.514505) (xy 432.031317 -74.543559) (xy 431.979988 -74.565371)
			(xy 431.926031 -74.579477) (xy 431.870594 -74.585577) (xy 431.81486 -74.58354) (xy 431.760017 -74.57341)
			(xy 431.707233 -74.555403) (xy 431.657633 -74.529902) (xy 431.612275 -74.497451) (xy 431.572126 -74.458742)
			(xy 431.53804 -74.414599) (xy 431.510744 -74.365964) (xy 431.490821 -74.313873) (xy 431.478695 -74.259436)
			(xy 431.474624 -74.203814) (xy 414.117809 -74.203814) (xy 413.961827 -77.206348) (xy 430.98415 -77.206348)
			(xy 430.988221 -77.150726) (xy 431.000347 -77.096289) (xy 431.02027 -77.044198) (xy 431.047566 -76.995563)
			(xy 431.081652 -76.95142) (xy 431.121801 -76.912711) (xy 431.167159 -76.88026) (xy 431.216759 -76.854759)
			(xy 431.269543 -76.836752) (xy 431.324386 -76.826622) (xy 431.38012 -76.824585) (xy 431.435557 -76.830685)
			(xy 431.489514 -76.844791) (xy 431.540843 -76.866603) (xy 431.588449 -76.895657) (xy 431.631317 -76.931332)
			(xy 431.668534 -76.972869) (xy 431.699307 -77.019382) (xy 431.722979 -77.069879) (xy 431.739047 -77.123286)
			(xy 431.747167 -77.178462) (xy 431.747676 -77.206348) (xy 431.747167 -77.234234) (xy 431.739047 -77.28941)
			(xy 431.722979 -77.342817) (xy 431.699307 -77.393314) (xy 431.668534 -77.439827) (xy 431.631317 -77.481364)
			(xy 431.588449 -77.517039) (xy 431.540843 -77.546093) (xy 431.489514 -77.567905) (xy 431.435557 -77.582011)
			(xy 431.38012 -77.588111) (xy 431.324386 -77.586074) (xy 431.269543 -77.575944) (xy 431.216759 -77.557937)
			(xy 431.167159 -77.532436) (xy 431.121801 -77.499985) (xy 431.081652 -77.461276) (xy 431.047566 -77.417133)
			(xy 431.02027 -77.368498) (xy 431.000347 -77.316407) (xy 430.988221 -77.26197) (xy 430.98415 -77.206348)
			(xy 413.961827 -77.206348) (xy 413.859193 -79.18196) (xy 427.891702 -79.18196) (xy 427.892188 -79.154709)
			(xy 427.899944 -79.100761) (xy 427.915299 -79.048466) (xy 427.937941 -78.998889) (xy 427.967407 -78.953039)
			(xy 428.003098 -78.911848) (xy 428.044289 -78.876157) (xy 428.090139 -78.846691) (xy 428.139716 -78.824049)
			(xy 428.192011 -78.808694) (xy 428.245959 -78.800938) (xy 428.300461 -78.800938) (xy 428.354409 -78.808694)
			(xy 428.406704 -78.824049) (xy 428.456281 -78.846691) (xy 428.502131 -78.876157) (xy 428.543322 -78.911848)
			(xy 428.579013 -78.953039) (xy 428.608479 -78.998889) (xy 428.631121 -79.048466) (xy 428.646476 -79.100761)
			(xy 428.654232 -79.154709) (xy 428.654718 -79.18196) (xy 428.654155 -79.210843) (xy 428.645439 -79.267948)
			(xy 428.628216 -79.323087) (xy 428.602877 -79.375) (xy 428.570004 -79.422501) (xy 428.530347 -79.464504)
			(xy 428.507906 -79.482696) (xy 428.496983 -79.491859) (xy 428.48023 -79.514911) (xy 428.470491 -79.541691)
			(xy 428.468522 -79.57012) (xy 428.474477 -79.597987) (xy 428.487892 -79.623128) (xy 428.507725 -79.64359)
			(xy 428.519844 -79.651098) (xy 428.544444 -79.665765) (xy 428.589317 -79.701352) (xy 428.628365 -79.743248)
			(xy 428.660711 -79.790512) (xy 428.685626 -79.842081) (xy 428.702551 -79.896794) (xy 428.711105 -79.953424)
			(xy 428.711614 -79.98206) (xy 428.711128 -80.009311) (xy 428.703372 -80.063259) (xy 428.688017 -80.115554)
			(xy 428.665375 -80.165131) (xy 428.635909 -80.210981) (xy 428.600218 -80.252172) (xy 428.559027 -80.287863)
			(xy 428.513177 -80.317329) (xy 428.4636 -80.339971) (xy 428.411305 -80.355326) (xy 428.357357 -80.363082)
			(xy 428.302855 -80.363082) (xy 428.248907 -80.355326) (xy 428.196612 -80.339971) (xy 428.147035 -80.317329)
			(xy 428.101185 -80.287863) (xy 428.059994 -80.252172) (xy 428.024303 -80.210981) (xy 427.994837 -80.165131)
			(xy 427.972195 -80.115554) (xy 427.95684 -80.063259) (xy 427.949084 -80.009311) (xy 427.948598 -79.98206)
			(xy 427.949097 -79.953174) (xy 427.957826 -79.896066) (xy 427.975062 -79.840926) (xy 428.000412 -79.789013)
			(xy 428.033296 -79.741514) (xy 428.072964 -79.699514) (xy 428.09541 -79.681324) (xy 428.106309 -79.672136)
			(xy 428.123059 -79.649089) (xy 428.132798 -79.622315) (xy 428.134769 -79.593893) (xy 428.12882 -79.566031)
			(xy 428.115412 -79.540892) (xy 428.095587 -79.520431) (xy 428.083472 -79.512922) (xy 428.058862 -79.498273)
			(xy 428.013992 -79.462679) (xy 427.974948 -79.420778) (xy 427.942605 -79.373512) (xy 427.917692 -79.321941)
			(xy 427.900768 -79.267227) (xy 427.892212 -79.210596) (xy 427.891702 -79.18196) (xy 413.859193 -79.18196)
			(xy 413.815662 -80.019906) (xy 420.800782 -80.019906) (xy 420.804853 -79.964284) (xy 420.816979 -79.909847)
			(xy 420.836902 -79.857756) (xy 420.864198 -79.809121) (xy 420.898284 -79.764978) (xy 420.938433 -79.726269)
			(xy 420.983791 -79.693818) (xy 421.033391 -79.668317) (xy 421.086175 -79.65031) (xy 421.141018 -79.64018)
			(xy 421.196752 -79.638143) (xy 421.252189 -79.644243) (xy 421.306146 -79.658349) (xy 421.357475 -79.680161)
			(xy 421.405081 -79.709215) (xy 421.447949 -79.74489) (xy 421.485166 -79.786427) (xy 421.515939 -79.83294)
			(xy 421.539611 -79.883437) (xy 421.555679 -79.936844) (xy 421.563799 -79.99202) (xy 421.564308 -80.019906)
			(xy 421.563799 -80.047792) (xy 421.555679 -80.102968) (xy 421.539611 -80.156375) (xy 421.515939 -80.206872)
			(xy 421.485166 -80.253385) (xy 421.447949 -80.294922) (xy 421.405081 -80.330597) (xy 421.357475 -80.359651)
			(xy 421.306146 -80.381463) (xy 421.252189 -80.395569) (xy 421.196752 -80.401669) (xy 421.141018 -80.399632)
			(xy 421.086175 -80.389502) (xy 421.033391 -80.371495) (xy 420.983791 -80.345994) (xy 420.938433 -80.313543)
			(xy 420.898284 -80.274834) (xy 420.864198 -80.230691) (xy 420.836902 -80.182056) (xy 420.816979 -80.129965)
			(xy 420.804853 -80.075528) (xy 420.800782 -80.019906) (xy 413.815662 -80.019906) (xy 413.691269 -82.414364)
			(xy 425.781722 -82.414364) (xy 425.785793 -82.358742) (xy 425.797919 -82.304305) (xy 425.817842 -82.252214)
			(xy 425.845138 -82.203579) (xy 425.879224 -82.159436) (xy 425.919373 -82.120727) (xy 425.964731 -82.088276)
			(xy 426.014331 -82.062775) (xy 426.067115 -82.044768) (xy 426.121958 -82.034638) (xy 426.177692 -82.032601)
			(xy 426.233129 -82.038701) (xy 426.287086 -82.052807) (xy 426.338415 -82.074619) (xy 426.386021 -82.103673)
			(xy 426.428889 -82.139348) (xy 426.466106 -82.180885) (xy 426.496879 -82.227398) (xy 426.520551 -82.277895)
			(xy 426.536619 -82.331302) (xy 426.544739 -82.386478) (xy 426.545248 -82.414364) (xy 426.545007 -82.427572)
			(xy 427.232824 -82.427572) (xy 427.236895 -82.37195) (xy 427.249021 -82.317513) (xy 427.268944 -82.265422)
			(xy 427.29624 -82.216787) (xy 427.330326 -82.172644) (xy 427.370475 -82.133935) (xy 427.415833 -82.101484)
			(xy 427.465433 -82.075983) (xy 427.518217 -82.057976) (xy 427.57306 -82.047846) (xy 427.628794 -82.045809)
			(xy 427.684231 -82.051909) (xy 427.738188 -82.066015) (xy 427.789517 -82.087827) (xy 427.837123 -82.116881)
			(xy 427.879991 -82.152556) (xy 427.917208 -82.194093) (xy 427.947981 -82.240606) (xy 427.971653 -82.291103)
			(xy 427.987721 -82.34451) (xy 427.995841 -82.399686) (xy 427.99635 -82.427572) (xy 427.995841 -82.455458)
			(xy 427.987721 -82.510634) (xy 427.971653 -82.564041) (xy 427.947981 -82.614538) (xy 427.917208 -82.661051)
			(xy 427.879991 -82.702588) (xy 427.837123 -82.738263) (xy 427.789517 -82.767317) (xy 427.738188 -82.789129)
			(xy 427.684231 -82.803235) (xy 427.628794 -82.809335) (xy 427.57306 -82.807298) (xy 427.518217 -82.797168)
			(xy 427.465433 -82.779161) (xy 427.415833 -82.75366) (xy 427.370475 -82.721209) (xy 427.330326 -82.6825)
			(xy 427.29624 -82.638357) (xy 427.268944 -82.589722) (xy 427.249021 -82.537631) (xy 427.236895 -82.483194)
			(xy 427.232824 -82.427572) (xy 426.545007 -82.427572) (xy 426.544739 -82.44225) (xy 426.536619 -82.497426)
			(xy 426.520551 -82.550833) (xy 426.496879 -82.60133) (xy 426.466106 -82.647843) (xy 426.428889 -82.68938)
			(xy 426.386021 -82.725055) (xy 426.338415 -82.754109) (xy 426.287086 -82.775921) (xy 426.233129 -82.790027)
			(xy 426.177692 -82.796127) (xy 426.121958 -82.79409) (xy 426.067115 -82.78396) (xy 426.014331 -82.765953)
			(xy 425.964731 -82.740452) (xy 425.919373 -82.708001) (xy 425.879224 -82.669292) (xy 425.845138 -82.625149)
			(xy 425.817842 -82.576514) (xy 425.797919 -82.524423) (xy 425.785793 -82.469986) (xy 425.781722 -82.414364)
			(xy 413.691269 -82.414364) (xy 413.654494 -83.122262) (xy 413.654995 -83.132855) (xy 413.663676 -83.152185)
			(xy 413.671258 -83.1596) (xy 413.74949 -83.220306) (xy 413.76219 -83.222338) (xy 413.770826 -83.223862)
			(xy 413.783526 -83.221576) (xy 413.78886 -83.219798) (xy 413.817308 -83.211238) (xy 413.875997 -83.202051)
			(xy 413.9057 -83.20151) (xy 413.906462 -83.20151) (xy 413.933716 -83.201971) (xy 413.98767 -83.209723)
			(xy 414.039972 -83.225076) (xy 414.089555 -83.247717) (xy 414.135412 -83.277184) (xy 414.176608 -83.312878)
			(xy 414.212304 -83.354072) (xy 414.241773 -83.399927) (xy 414.264417 -83.44951) (xy 414.279772 -83.50181)
			(xy 414.284143 -83.532218) (xy 424.611544 -83.532218) (xy 424.615615 -83.476596) (xy 424.627741 -83.422159)
			(xy 424.647664 -83.370068) (xy 424.67496 -83.321433) (xy 424.709046 -83.27729) (xy 424.749195 -83.238581)
			(xy 424.794553 -83.20613) (xy 424.844153 -83.180629) (xy 424.896937 -83.162622) (xy 424.95178 -83.152492)
			(xy 425.007514 -83.150455) (xy 425.062951 -83.156555) (xy 425.116908 -83.170661) (xy 425.168237 -83.192473)
			(xy 425.215843 -83.221527) (xy 425.258711 -83.257202) (xy 425.295928 -83.298739) (xy 425.326701 -83.345252)
			(xy 425.350373 -83.395749) (xy 425.366441 -83.449156) (xy 425.374561 -83.504332) (xy 425.37507 -83.532218)
			(xy 425.374561 -83.560104) (xy 425.366441 -83.61528) (xy 425.350373 -83.668687) (xy 425.326701 -83.719184)
			(xy 425.295928 -83.765697) (xy 425.258711 -83.807234) (xy 425.215843 -83.842909) (xy 425.168237 -83.871963)
			(xy 425.116908 -83.893775) (xy 425.062951 -83.907881) (xy 425.007514 -83.913981) (xy 424.95178 -83.911944)
			(xy 424.896937 -83.901814) (xy 424.844153 -83.883807) (xy 424.794553 -83.858306) (xy 424.749195 -83.825855)
			(xy 424.709046 -83.787146) (xy 424.67496 -83.743003) (xy 424.647664 -83.694368) (xy 424.627741 -83.642277)
			(xy 424.615615 -83.58784) (xy 424.611544 -83.532218) (xy 414.284143 -83.532218) (xy 414.287528 -83.555764)
			(xy 414.28797 -83.583018) (xy 414.287399 -83.613141) (xy 414.277924 -83.672638) (xy 414.259213 -83.729905)
			(xy 414.23173 -83.783518) (xy 414.196159 -83.832143) (xy 414.175194 -83.853782) (xy 414.17494 -83.854036)
			(xy 414.168359 -83.861285) (xy 414.160771 -83.879314) (xy 414.160208 -83.889088) (xy 414.159192 -83.95843)
			(xy 414.159192 -83.959954) (xy 414.159554 -83.967168) (xy 414.163816 -83.980963) (xy 414.167574 -83.987132)
			(xy 414.17367 -83.996022) (xy 414.176464 -83.99907) (xy 414.195422 -84.020352) (xy 414.227471 -84.067481)
			(xy 414.252171 -84.118844) (xy 414.268977 -84.173304) (xy 414.277515 -84.229654) (xy 414.278064 -84.25815)
			(xy 414.278064 -84.258912) (xy 414.277661 -84.284115) (xy 414.271019 -84.334081) (xy 414.257838 -84.382733)
			(xy 414.23835 -84.42922) (xy 414.225994 -84.45119) (xy 414.211004 -84.475838) (xy 414.210602 -84.476336)
			(xy 427.965614 -84.476336) (xy 427.969685 -84.420714) (xy 427.981811 -84.366277) (xy 428.001734 -84.314186)
			(xy 428.02903 -84.265551) (xy 428.063116 -84.221408) (xy 428.103265 -84.182699) (xy 428.148623 -84.150248)
			(xy 428.198223 -84.124747) (xy 428.251007 -84.10674) (xy 428.30585 -84.09661) (xy 428.361584 -84.094573)
			(xy 428.417021 -84.100673) (xy 428.470978 -84.114779) (xy 428.522307 -84.136591) (xy 428.569913 -84.165645)
			(xy 428.612781 -84.20132) (xy 428.649998 -84.242857) (xy 428.680771 -84.28937) (xy 428.704443 -84.339867)
			(xy 428.720511 -84.393274) (xy 428.728631 -84.44845) (xy 428.72914 -84.476336) (xy 428.728631 -84.504222)
			(xy 428.720511 -84.559398) (xy 428.704443 -84.612805) (xy 428.680771 -84.663302) (xy 428.649998 -84.709815)
			(xy 428.612781 -84.751352) (xy 428.569913 -84.787027) (xy 428.522307 -84.816081) (xy 428.470978 -84.837893)
			(xy 428.417021 -84.851999) (xy 428.361584 -84.858099) (xy 428.30585 -84.856062) (xy 428.251007 -84.845932)
			(xy 428.198223 -84.827925) (xy 428.148623 -84.802424) (xy 428.103265 -84.769973) (xy 428.063116 -84.731264)
			(xy 428.02903 -84.687121) (xy 428.001734 -84.638486) (xy 427.981811 -84.586395) (xy 427.969685 -84.531958)
			(xy 427.965614 -84.476336) (xy 414.210602 -84.476336) (xy 414.174778 -84.520733) (xy 414.153858 -84.540598)
			(xy 414.150556 -84.543646) (xy 414.143698 -84.552536) (xy 414.138364 -84.560918) (xy 414.132014 -84.573364)
			(xy 414.129866 -84.577794) (xy 414.127179 -84.587263) (xy 414.12668 -84.59216) (xy 414.126172 -84.598002)
			(xy 414.1216 -84.655406) (xy 414.121395 -84.663369) (xy 414.125421 -84.678773) (xy 414.129474 -84.685632)
			(xy 414.135316 -84.693252) (xy 414.15202 -84.71395) (xy 414.180141 -84.759096) (xy 414.201725 -84.807707)
			(xy 414.216355 -84.858843) (xy 414.223748 -84.911514) (xy 414.224216 -84.938108) (xy 414.22373 -84.965359)
			(xy 414.215972 -85.019306) (xy 414.200617 -85.071601) (xy 414.177975 -85.121177) (xy 414.148509 -85.167027)
			(xy 414.112817 -85.208217) (xy 414.088025 -85.2297) (xy 416.185602 -85.2297) (xy 416.189673 -85.174078)
			(xy 416.201799 -85.119641) (xy 416.221722 -85.06755) (xy 416.249018 -85.018915) (xy 416.283104 -84.974772)
			(xy 416.323253 -84.936063) (xy 416.368611 -84.903612) (xy 416.418211 -84.878111) (xy 416.470995 -84.860104)
			(xy 416.525838 -84.849974) (xy 416.581572 -84.847937) (xy 416.637009 -84.854037) (xy 416.690966 -84.868143)
			(xy 416.742295 -84.889955) (xy 416.789901 -84.919009) (xy 416.832769 -84.954684) (xy 416.869986 -84.996221)
			(xy 416.900759 -85.042734) (xy 416.924431 -85.093231) (xy 416.940499 -85.146638) (xy 416.948619 -85.201814)
			(xy 416.949128 -85.2297) (xy 416.948619 -85.257586) (xy 416.940499 -85.312762) (xy 416.924431 -85.366169)
			(xy 416.900759 -85.416666) (xy 416.869986 -85.463179) (xy 416.832769 -85.504716) (xy 416.789901 -85.540391)
			(xy 416.742295 -85.569445) (xy 416.690966 -85.591257) (xy 416.637009 -85.605363) (xy 416.581572 -85.611463)
			(xy 416.525838 -85.609426) (xy 416.470995 -85.599296) (xy 416.418211 -85.581289) (xy 416.368611 -85.555788)
			(xy 416.323253 -85.523337) (xy 416.283104 -85.484628) (xy 416.249018 -85.440485) (xy 416.221722 -85.39185)
			(xy 416.201799 -85.339759) (xy 416.189673 -85.285322) (xy 416.185602 -85.2297) (xy 414.088025 -85.2297)
			(xy 414.071627 -85.243909) (xy 414.025777 -85.273375) (xy 413.976201 -85.296017) (xy 413.923906 -85.311372)
			(xy 413.869959 -85.31913) (xy 413.842708 -85.319616) (xy 413.839914 -85.319616) (xy 413.839406 -85.319616)
			(xy 413.839152 -85.319616) (xy 413.812969 -85.319207) (xy 413.761089 -85.312087) (xy 413.710672 -85.297933)
			(xy 413.686498 -85.287866) (xy 413.676846 -85.283548) (xy 413.633158 -85.283548) (xy 413.625792 -85.290914)
			(xy 413.625538 -85.290914) (xy 413.607758 -85.301582) (xy 413.60725 -85.301582) (xy 413.557212 -85.332062)
			(xy 413.552877 -85.335352) (xy 413.545582 -85.343426) (xy 413.542734 -85.348064) (xy 413.540399 -85.352461)
			(xy 413.53733 -85.36193) (xy 413.536638 -85.36686) (xy 413.533336 -85.429344) (xy 413.517588 -85.73389)
			(xy 413.508444 -85.909658) (xy 413.490828 -86.247986) (xy 423.538648 -86.247986) (xy 423.542719 -86.192364)
			(xy 423.554845 -86.137927) (xy 423.574768 -86.085836) (xy 423.602064 -86.037201) (xy 423.63615 -85.993058)
			(xy 423.676299 -85.954349) (xy 423.721657 -85.921898) (xy 423.771257 -85.896397) (xy 423.824041 -85.87839)
			(xy 423.878884 -85.86826) (xy 423.934618 -85.866223) (xy 423.990055 -85.872323) (xy 424.044012 -85.886429)
			(xy 424.095341 -85.908241) (xy 424.142947 -85.937295) (xy 424.185815 -85.97297) (xy 424.223032 -86.014507)
			(xy 424.253805 -86.06102) (xy 424.277477 -86.111517) (xy 424.293545 -86.164924) (xy 424.301665 -86.2201)
			(xy 424.302174 -86.247986) (xy 424.301665 -86.275872) (xy 424.293545 -86.331048) (xy 424.277477 -86.384455)
			(xy 424.253805 -86.434952) (xy 424.223032 -86.481465) (xy 424.185815 -86.523002) (xy 424.142947 -86.558677)
			(xy 424.095341 -86.587731) (xy 424.044012 -86.609543) (xy 423.990055 -86.623649) (xy 423.934618 -86.629749)
			(xy 423.878884 -86.627712) (xy 423.824041 -86.617582) (xy 423.771257 -86.599575) (xy 423.721657 -86.574074)
			(xy 423.676299 -86.541623) (xy 423.63615 -86.502914) (xy 423.602064 -86.458771) (xy 423.574768 -86.410136)
			(xy 423.554845 -86.358045) (xy 423.542719 -86.303608) (xy 423.538648 -86.247986) (xy 413.490828 -86.247986)
			(xy 413.444366 -87.140288) (xy 415.304476 -87.140288) (xy 415.308547 -87.084666) (xy 415.320673 -87.030229)
			(xy 415.340596 -86.978138) (xy 415.367892 -86.929503) (xy 415.401978 -86.88536) (xy 415.442127 -86.846651)
			(xy 415.487485 -86.8142) (xy 415.537085 -86.788699) (xy 415.589869 -86.770692) (xy 415.644712 -86.760562)
			(xy 415.700446 -86.758525) (xy 415.755883 -86.764625) (xy 415.80984 -86.778731) (xy 415.861169 -86.800543)
			(xy 415.908775 -86.829597) (xy 415.951643 -86.865272) (xy 415.98886 -86.906809) (xy 416.019633 -86.953322)
			(xy 416.043305 -87.003819) (xy 416.059373 -87.057226) (xy 416.067493 -87.112402) (xy 416.068002 -87.140288)
			(xy 416.067493 -87.168174) (xy 416.059373 -87.22335) (xy 416.043305 -87.276757) (xy 416.019633 -87.327254)
			(xy 415.98886 -87.373767) (xy 415.951643 -87.415304) (xy 415.908775 -87.450979) (xy 415.861169 -87.480033)
			(xy 415.80984 -87.501845) (xy 415.755883 -87.515951) (xy 415.700446 -87.522051) (xy 415.644712 -87.520014)
			(xy 415.589869 -87.509884) (xy 415.537085 -87.491877) (xy 415.487485 -87.466376) (xy 415.442127 -87.433925)
			(xy 415.401978 -87.395216) (xy 415.367892 -87.351073) (xy 415.340596 -87.302438) (xy 415.320673 -87.250347)
			(xy 415.308547 -87.19591) (xy 415.304476 -87.140288) (xy 413.444366 -87.140288) (xy 413.430466 -87.407242)
			(xy 413.386751 -88.247728) (xy 413.813496 -88.247728) (xy 413.817567 -88.192106) (xy 413.829693 -88.137669)
			(xy 413.849616 -88.085578) (xy 413.876912 -88.036943) (xy 413.910998 -87.9928) (xy 413.951147 -87.954091)
			(xy 413.996505 -87.92164) (xy 414.046105 -87.896139) (xy 414.098889 -87.878132) (xy 414.153732 -87.868002)
			(xy 414.209466 -87.865965) (xy 414.264903 -87.872065) (xy 414.31886 -87.886171) (xy 414.370189 -87.907983)
			(xy 414.417795 -87.937037) (xy 414.460663 -87.972712) (xy 414.49788 -88.014249) (xy 414.528653 -88.060762)
			(xy 414.552325 -88.111259) (xy 414.568393 -88.164666) (xy 414.576513 -88.219842) (xy 414.577022 -88.247728)
			(xy 414.576513 -88.275614) (xy 414.568393 -88.33079) (xy 414.554792 -88.375998) (xy 428.223678 -88.375998)
			(xy 428.227749 -88.320376) (xy 428.239875 -88.265939) (xy 428.259798 -88.213848) (xy 428.287094 -88.165213)
			(xy 428.32118 -88.12107) (xy 428.361329 -88.082361) (xy 428.406687 -88.04991) (xy 428.456287 -88.024409)
			(xy 428.509071 -88.006402) (xy 428.563914 -87.996272) (xy 428.619648 -87.994235) (xy 428.675085 -88.000335)
			(xy 428.729042 -88.014441) (xy 428.780371 -88.036253) (xy 428.827977 -88.065307) (xy 428.870845 -88.100982)
			(xy 428.908062 -88.142519) (xy 428.938835 -88.189032) (xy 428.962507 -88.239529) (xy 428.978575 -88.292936)
			(xy 428.986695 -88.348112) (xy 428.987204 -88.375998) (xy 428.986695 -88.403884) (xy 428.978575 -88.45906)
			(xy 428.962507 -88.512467) (xy 428.938835 -88.562964) (xy 428.908062 -88.609477) (xy 428.870845 -88.651014)
			(xy 428.827977 -88.686689) (xy 428.780371 -88.715743) (xy 428.729042 -88.737555) (xy 428.675085 -88.751661)
			(xy 428.619648 -88.757761) (xy 428.563914 -88.755724) (xy 428.509071 -88.745594) (xy 428.456287 -88.727587)
			(xy 428.406687 -88.702086) (xy 428.361329 -88.669635) (xy 428.32118 -88.630926) (xy 428.287094 -88.586783)
			(xy 428.259798 -88.538148) (xy 428.239875 -88.486057) (xy 428.227749 -88.43162) (xy 428.223678 -88.375998)
			(xy 414.554792 -88.375998) (xy 414.552325 -88.384197) (xy 414.528653 -88.434694) (xy 414.49788 -88.481207)
			(xy 414.460663 -88.522744) (xy 414.417795 -88.558419) (xy 414.370189 -88.587473) (xy 414.31886 -88.609285)
			(xy 414.264903 -88.623391) (xy 414.209466 -88.629491) (xy 414.153732 -88.627454) (xy 414.098889 -88.617324)
			(xy 414.046105 -88.599317) (xy 413.996505 -88.573816) (xy 413.951147 -88.541365) (xy 413.910998 -88.502656)
			(xy 413.876912 -88.458513) (xy 413.849616 -88.409878) (xy 413.829693 -88.357787) (xy 413.817567 -88.30335)
			(xy 413.813496 -88.247728) (xy 413.386751 -88.247728) (xy 413.35198 -88.916256) (xy 413.351726 -88.925654)
			(xy 413.358584 -88.94699) (xy 413.362902 -88.956642) (xy 413.36849 -88.965786) (xy 413.37103 -88.970104)
			(xy 413.383378 -88.992076) (xy 413.402829 -89.038573) (xy 413.416001 -89.087223) (xy 413.422666 -89.137182)
			(xy 413.4231 -89.162382) (xy 413.4231 -89.16543) (xy 413.422592 -89.180162) (xy 413.419544 -89.213182)
			(xy 413.415753 -89.238368) (xy 413.402361 -89.287507) (xy 413.382566 -89.334435) (xy 413.356716 -89.378319)
			(xy 413.341312 -89.398602) (xy 413.336232 -89.404952) (xy 413.326342 -89.430352) (xy 419.929816 -89.430352)
			(xy 419.933887 -89.37473) (xy 419.946013 -89.320293) (xy 419.965936 -89.268202) (xy 419.993232 -89.219567)
			(xy 420.027318 -89.175424) (xy 420.067467 -89.136715) (xy 420.112825 -89.104264) (xy 420.162425 -89.078763)
			(xy 420.215209 -89.060756) (xy 420.270052 -89.050626) (xy 420.325786 -89.048589) (xy 420.381223 -89.054689)
			(xy 420.43518 -89.068795) (xy 420.486509 -89.090607) (xy 420.534115 -89.119661) (xy 420.576983 -89.155336)
			(xy 420.6142 -89.196873) (xy 420.644973 -89.243386) (xy 420.668645 -89.293883) (xy 420.684713 -89.34729)
			(xy 420.692833 -89.402466) (xy 420.693342 -89.430352) (xy 420.692833 -89.458238) (xy 420.684713 -89.513414)
			(xy 420.668645 -89.566821) (xy 420.644973 -89.617318) (xy 420.6142 -89.663831) (xy 420.576983 -89.705368)
			(xy 420.534115 -89.741043) (xy 420.501164 -89.761153) (xy 422.18606 -89.761153) (xy 422.18606 -89.706647)
			(xy 422.193817 -89.652697) (xy 422.209173 -89.6004) (xy 422.231815 -89.55082) (xy 422.261282 -89.504968)
			(xy 422.296976 -89.463776) (xy 422.338168 -89.428082) (xy 422.38402 -89.398615) (xy 422.4336 -89.375973)
			(xy 422.485897 -89.360617) (xy 422.539847 -89.35286) (xy 422.5671 -89.352374) (xy 422.594118 -89.352881)
			(xy 422.64761 -89.360518) (xy 422.699491 -89.375624) (xy 422.748722 -89.397899) (xy 422.794318 -89.426895)
			(xy 422.835368 -89.462034) (xy 422.87105 -89.502612) (xy 422.900651 -89.547818) (xy 422.91254 -89.572084)
			(xy 422.919278 -89.585231) (xy 422.938949 -89.607253) (xy 422.964097 -89.622728) (xy 422.992621 -89.630364)
			(xy 423.022138 -89.629523) (xy 423.050181 -89.620275) (xy 423.074407 -89.603392) (xy 423.08399 -89.59215)
			(xy 423.102187 -89.570117) (xy 423.144068 -89.531242) (xy 423.191278 -89.499046) (xy 423.24276 -89.474249)
			(xy 423.297364 -89.457405) (xy 423.353869 -89.448891) (xy 423.38244 -89.448386) (xy 423.409689 -89.448886)
			(xy 423.463632 -89.456648) (xy 423.515921 -89.472006) (xy 423.565492 -89.494649) (xy 423.611337 -89.524116)
			(xy 423.652522 -89.559807) (xy 423.688208 -89.600995) (xy 423.71767 -89.646843) (xy 423.740308 -89.696417)
			(xy 423.755661 -89.748708) (xy 423.762695 -89.797636) (xy 423.880024 -89.797636) (xy 423.884095 -89.742014)
			(xy 423.896221 -89.687577) (xy 423.916144 -89.635486) (xy 423.94344 -89.586851) (xy 423.977526 -89.542708)
			(xy 424.017675 -89.503999) (xy 424.063033 -89.471548) (xy 424.112633 -89.446047) (xy 424.165417 -89.42804)
			(xy 424.22026 -89.41791) (xy 424.275994 -89.415873) (xy 424.331431 -89.421973) (xy 424.385388 -89.436079)
			(xy 424.436717 -89.457891) (xy 424.484323 -89.486945) (xy 424.527191 -89.52262) (xy 424.564408 -89.564157)
			(xy 424.595181 -89.61067) (xy 424.618853 -89.661167) (xy 424.634921 -89.714574) (xy 424.643041 -89.76975)
			(xy 424.64355 -89.797636) (xy 424.643041 -89.825522) (xy 424.634921 -89.880698) (xy 424.633394 -89.885774)
			(xy 424.743624 -89.885774) (xy 424.747695 -89.830152) (xy 424.759821 -89.775715) (xy 424.779744 -89.723624)
			(xy 424.80704 -89.674989) (xy 424.841126 -89.630846) (xy 424.881275 -89.592137) (xy 424.926633 -89.559686)
			(xy 424.976233 -89.534185) (xy 425.029017 -89.516178) (xy 425.08386 -89.506048) (xy 425.139594 -89.504011)
			(xy 425.195031 -89.510111) (xy 425.248988 -89.524217) (xy 425.300317 -89.546029) (xy 425.347923 -89.575083)
			(xy 425.390791 -89.610758) (xy 425.428008 -89.652295) (xy 425.458781 -89.698808) (xy 425.482453 -89.749305)
			(xy 425.498521 -89.802712) (xy 425.506641 -89.857888) (xy 425.50715 -89.885774) (xy 425.506641 -89.91366)
			(xy 425.498521 -89.968836) (xy 425.482453 -90.022243) (xy 425.458781 -90.07274) (xy 425.428008 -90.119253)
			(xy 425.390791 -90.16079) (xy 425.347923 -90.196465) (xy 425.300317 -90.225519) (xy 425.248988 -90.247331)
			(xy 425.195031 -90.261437) (xy 425.139594 -90.267537) (xy 425.08386 -90.2655) (xy 425.029017 -90.25537)
			(xy 424.976233 -90.237363) (xy 424.926633 -90.211862) (xy 424.881275 -90.179411) (xy 424.841126 -90.140702)
			(xy 424.80704 -90.096559) (xy 424.779744 -90.047924) (xy 424.759821 -89.995833) (xy 424.747695 -89.941396)
			(xy 424.743624 -89.885774) (xy 424.633394 -89.885774) (xy 424.618853 -89.934105) (xy 424.595181 -89.984602)
			(xy 424.564408 -90.031115) (xy 424.527191 -90.072652) (xy 424.484323 -90.108327) (xy 424.436717 -90.137381)
			(xy 424.385388 -90.159193) (xy 424.331431 -90.173299) (xy 424.275994 -90.179399) (xy 424.22026 -90.177362)
			(xy 424.165417 -90.167232) (xy 424.112633 -90.149225) (xy 424.063033 -90.123724) (xy 424.017675 -90.091273)
			(xy 423.977526 -90.052564) (xy 423.94344 -90.008421) (xy 423.916144 -89.959786) (xy 423.896221 -89.907695)
			(xy 423.884095 -89.853258) (xy 423.880024 -89.797636) (xy 423.762695 -89.797636) (xy 423.763416 -89.802651)
			(xy 423.763416 -89.857149) (xy 423.755661 -89.911092) (xy 423.740308 -89.963383) (xy 423.71767 -90.012957)
			(xy 423.688208 -90.058805) (xy 423.652522 -90.099993) (xy 423.611337 -90.135684) (xy 423.565492 -90.165151)
			(xy 423.515921 -90.187794) (xy 423.463632 -90.203152) (xy 423.409689 -90.210914) (xy 423.38244 -90.211402)
			(xy 423.35542 -90.210959) (xy 423.301924 -90.203313) (xy 423.250041 -90.188198) (xy 423.200809 -90.165914)
			(xy 423.155213 -90.136909) (xy 423.114165 -90.101762) (xy 423.078485 -90.061175) (xy 423.048887 -90.015961)
			(xy 423.037 -89.991692) (xy 423.030208 -89.978577) (xy 423.010545 -89.956563) (xy 422.985408 -89.941092)
			(xy 422.956896 -89.933454) (xy 422.927391 -89.934289) (xy 422.899357 -89.943525) (xy 422.875134 -89.960392)
			(xy 422.86555 -89.971626) (xy 422.847325 -89.993634) (xy 422.80545 -90.032512) (xy 422.758247 -90.064712)
			(xy 422.70677 -90.089513) (xy 422.652171 -90.106362) (xy 422.59567 -90.114882) (xy 422.5671 -90.11539)
			(xy 422.539847 -90.11494) (xy 422.485897 -90.107183) (xy 422.4336 -90.091827) (xy 422.38402 -90.069185)
			(xy 422.338168 -90.039718) (xy 422.296976 -90.004024) (xy 422.261282 -89.962832) (xy 422.231815 -89.91698)
			(xy 422.209173 -89.8674) (xy 422.193817 -89.815103) (xy 422.18606 -89.761153) (xy 420.501164 -89.761153)
			(xy 420.486509 -89.770097) (xy 420.43518 -89.791909) (xy 420.381223 -89.806015) (xy 420.325786 -89.812115)
			(xy 420.270052 -89.810078) (xy 420.215209 -89.799948) (xy 420.162425 -89.781941) (xy 420.112825 -89.75644)
			(xy 420.067467 -89.723989) (xy 420.027318 -89.68528) (xy 419.993232 -89.641137) (xy 419.965936 -89.592502)
			(xy 419.946013 -89.540411) (xy 419.933887 -89.485974) (xy 419.929816 -89.430352) (xy 413.326342 -89.430352)
			(xy 413.325056 -89.433654) (xy 413.324548 -89.442036) (xy 413.225996 -91.337384) (xy 413.191706 -91.996006)
			(xy 413.180022 -92.219526) (xy 413.172402 -92.363798) (xy 413.026269 -95.17126) (xy 416.22802 -95.17126)
			(xy 416.232091 -95.115638) (xy 416.244217 -95.061201) (xy 416.26414 -95.00911) (xy 416.291436 -94.960475)
			(xy 416.325522 -94.916332) (xy 416.365671 -94.877623) (xy 416.411029 -94.845172) (xy 416.460629 -94.819671)
			(xy 416.513413 -94.801664) (xy 416.568256 -94.791534) (xy 416.62399 -94.789497) (xy 416.679427 -94.795597)
			(xy 416.733384 -94.809703) (xy 416.784713 -94.831515) (xy 416.832319 -94.860569) (xy 416.875187 -94.896244)
			(xy 416.912404 -94.937781) (xy 416.943177 -94.984294) (xy 416.966849 -95.034791) (xy 416.982917 -95.088198)
			(xy 416.991037 -95.143374) (xy 416.991546 -95.17126) (xy 416.991037 -95.199146) (xy 416.988711 -95.214948)
			(xy 419.939229 -95.214948) (xy 419.943184 -95.123111) (xy 419.955019 -95.031954) (xy 419.974646 -94.942151)
			(xy 420.00192 -94.854369) (xy 420.03664 -94.769255) (xy 420.078548 -94.687442) (xy 420.127334 -94.609534)
			(xy 420.182637 -94.536109) (xy 420.244047 -94.467709) (xy 420.311109 -94.404842) (xy 420.383328 -94.347972)
			(xy 420.460168 -94.297521) (xy 420.541061 -94.253862) (xy 420.625407 -94.217319) (xy 420.712583 -94.188162)
			(xy 420.801942 -94.166608) (xy 420.892823 -94.152814) (xy 420.984554 -94.146884) (xy 421.076455 -94.148862)
			(xy 421.167846 -94.158733) (xy 421.25805 -94.176423) (xy 421.346399 -94.201803) (xy 421.432239 -94.234683)
			(xy 421.514935 -94.274821) (xy 421.593875 -94.32192) (xy 421.668473 -94.37563) (xy 421.738179 -94.435554)
			(xy 421.802474 -94.501248) (xy 421.860885 -94.572226) (xy 421.912977 -94.647963) (xy 421.958366 -94.727898)
			(xy 421.996716 -94.811438) (xy 422.027741 -94.897966) (xy 422.051214 -94.986841) (xy 422.06696 -95.077405)
			(xy 422.074862 -95.168987) (xy 422.075356 -95.214948) (xy 422.074862 -95.260909) (xy 422.06696 -95.352491)
			(xy 422.051214 -95.443055) (xy 422.027741 -95.53193) (xy 421.996716 -95.618458) (xy 421.958366 -95.701998)
			(xy 421.912977 -95.781933) (xy 421.860885 -95.85767) (xy 421.802474 -95.928648) (xy 421.742773 -95.989648)
			(xy 423.864022 -95.989648) (xy 423.868093 -95.934026) (xy 423.880219 -95.879589) (xy 423.900142 -95.827498)
			(xy 423.927438 -95.778863) (xy 423.961524 -95.73472) (xy 424.001673 -95.696011) (xy 424.047031 -95.66356)
			(xy 424.096631 -95.638059) (xy 424.149415 -95.620052) (xy 424.204258 -95.609922) (xy 424.259992 -95.607885)
			(xy 424.315429 -95.613985) (xy 424.369386 -95.628091) (xy 424.420715 -95.649903) (xy 424.468321 -95.678957)
			(xy 424.511189 -95.714632) (xy 424.548406 -95.756169) (xy 424.579179 -95.802682) (xy 424.602851 -95.853179)
			(xy 424.618919 -95.906586) (xy 424.627039 -95.961762) (xy 424.627548 -95.989648) (xy 426.469554 -95.989648)
			(xy 426.473625 -95.934026) (xy 426.485751 -95.879589) (xy 426.505674 -95.827498) (xy 426.53297 -95.778863)
			(xy 426.567056 -95.73472) (xy 426.607205 -95.696011) (xy 426.652563 -95.66356) (xy 426.702163 -95.638059)
			(xy 426.754947 -95.620052) (xy 426.80979 -95.609922) (xy 426.865524 -95.607885) (xy 426.920961 -95.613985)
			(xy 426.974918 -95.628091) (xy 427.026247 -95.649903) (xy 427.073853 -95.678957) (xy 427.116721 -95.714632)
			(xy 427.153938 -95.756169) (xy 427.184711 -95.802682) (xy 427.208383 -95.853179) (xy 427.224451 -95.906586)
			(xy 427.232571 -95.961762) (xy 427.23308 -95.989648) (xy 427.232571 -96.017534) (xy 427.224451 -96.07271)
			(xy 427.208383 -96.126117) (xy 427.184711 -96.176614) (xy 427.153938 -96.223127) (xy 427.116721 -96.264664)
			(xy 427.073853 -96.300339) (xy 427.026247 -96.329393) (xy 426.974918 -96.351205) (xy 426.920961 -96.365311)
			(xy 426.865524 -96.371411) (xy 426.80979 -96.369374) (xy 426.754947 -96.359244) (xy 426.702163 -96.341237)
			(xy 426.652563 -96.315736) (xy 426.607205 -96.283285) (xy 426.567056 -96.244576) (xy 426.53297 -96.200433)
			(xy 426.505674 -96.151798) (xy 426.485751 -96.099707) (xy 426.473625 -96.04527) (xy 426.469554 -95.989648)
			(xy 424.627548 -95.989648) (xy 424.627039 -96.017534) (xy 424.618919 -96.07271) (xy 424.602851 -96.126117)
			(xy 424.579179 -96.176614) (xy 424.548406 -96.223127) (xy 424.511189 -96.264664) (xy 424.468321 -96.300339)
			(xy 424.420715 -96.329393) (xy 424.369386 -96.351205) (xy 424.315429 -96.365311) (xy 424.259992 -96.371411)
			(xy 424.204258 -96.369374) (xy 424.149415 -96.359244) (xy 424.096631 -96.341237) (xy 424.047031 -96.315736)
			(xy 424.001673 -96.283285) (xy 423.961524 -96.244576) (xy 423.927438 -96.200433) (xy 423.900142 -96.151798)
			(xy 423.880219 -96.099707) (xy 423.868093 -96.04527) (xy 423.864022 -95.989648) (xy 421.742773 -95.989648)
			(xy 421.738179 -95.994342) (xy 421.668473 -96.054266) (xy 421.593875 -96.107976) (xy 421.514935 -96.155075)
			(xy 421.432239 -96.195213) (xy 421.346399 -96.228093) (xy 421.25805 -96.253473) (xy 421.167846 -96.271163)
			(xy 421.076455 -96.281034) (xy 420.984554 -96.283012) (xy 420.892823 -96.277082) (xy 420.801942 -96.263288)
			(xy 420.712583 -96.241734) (xy 420.625407 -96.212577) (xy 420.541061 -96.176034) (xy 420.460168 -96.132375)
			(xy 420.383328 -96.081924) (xy 420.311109 -96.025054) (xy 420.244047 -95.962187) (xy 420.182637 -95.893787)
			(xy 420.127334 -95.820362) (xy 420.078548 -95.742454) (xy 420.03664 -95.660641) (xy 420.00192 -95.575527)
			(xy 419.974646 -95.487745) (xy 419.955019 -95.397942) (xy 419.943184 -95.306785) (xy 419.939229 -95.214948)
			(xy 416.988711 -95.214948) (xy 416.982917 -95.254322) (xy 416.966849 -95.307729) (xy 416.943177 -95.358226)
			(xy 416.912404 -95.404739) (xy 416.875187 -95.446276) (xy 416.832319 -95.481951) (xy 416.784713 -95.511005)
			(xy 416.733384 -95.532817) (xy 416.679427 -95.546923) (xy 416.62399 -95.553023) (xy 416.568256 -95.550986)
			(xy 416.513413 -95.540856) (xy 416.460629 -95.522849) (xy 416.411029 -95.497348) (xy 416.365671 -95.464897)
			(xy 416.325522 -95.426188) (xy 416.291436 -95.382045) (xy 416.26414 -95.33341) (xy 416.244217 -95.281319)
			(xy 416.232091 -95.226882) (xy 416.22802 -95.17126) (xy 413.026269 -95.17126) (xy 412.960783 -96.429346)
			(xy 415.757422 -96.429346) (xy 415.757422 -96.374854) (xy 415.765177 -96.320916) (xy 415.780528 -96.26863)
			(xy 415.803164 -96.219062) (xy 415.832623 -96.173218) (xy 415.868306 -96.132034) (xy 415.909486 -96.096347)
			(xy 415.955326 -96.066883) (xy 416.004893 -96.044242) (xy 416.057177 -96.028885) (xy 416.111114 -96.021125)
			(xy 416.13836 -96.020636) (xy 416.167179 -96.021157) (xy 416.224159 -96.029847) (xy 416.279184 -96.047006)
			(xy 416.331003 -96.072244) (xy 416.378439 -96.104986) (xy 416.420412 -96.144489) (xy 416.455968 -96.189853)
			(xy 416.470592 -96.214692) (xy 416.47853 -96.227544) (xy 416.500395 -96.248359) (xy 416.527391 -96.261871)
			(xy 416.557157 -96.266901) (xy 416.587093 -96.263007) (xy 416.614583 -96.250532) (xy 416.637224 -96.230564)
			(xy 416.645598 -96.217994) (xy 416.660612 -96.194657) (xy 416.696287 -96.152155) (xy 416.737744 -96.115272)
			(xy 416.784109 -96.084786) (xy 416.834402 -96.06134) (xy 416.887561 -96.04543) (xy 416.942465 -96.03739)
			(xy 416.97021 -96.036892) (xy 416.997461 -96.037378) (xy 417.051407 -96.045136) (xy 417.103701 -96.060492)
			(xy 417.153277 -96.083134) (xy 417.199126 -96.1126) (xy 417.240315 -96.148292) (xy 417.276006 -96.189482)
			(xy 417.305471 -96.235332) (xy 417.328111 -96.284908) (xy 417.343466 -96.337202) (xy 417.351222 -96.391149)
			(xy 417.351222 -96.445651) (xy 417.343466 -96.499598) (xy 417.328111 -96.551892) (xy 417.305471 -96.601468)
			(xy 417.276006 -96.647318) (xy 417.240315 -96.688508) (xy 417.199126 -96.7242) (xy 417.153277 -96.753666)
			(xy 417.103701 -96.776308) (xy 417.051407 -96.791664) (xy 416.997461 -96.799422) (xy 416.97021 -96.799908)
			(xy 416.941392 -96.79936) (xy 416.884412 -96.790679) (xy 416.829386 -96.773526) (xy 416.777566 -96.748294)
			(xy 416.730129 -96.715555) (xy 416.688156 -96.676054) (xy 416.652601 -96.630691) (xy 416.637978 -96.605852)
			(xy 416.630083 -96.592969) (xy 416.608212 -96.572143) (xy 416.581206 -96.558625) (xy 416.551428 -96.553597)
			(xy 416.521481 -96.557497) (xy 416.493985 -96.569986) (xy 416.471343 -96.589971) (xy 416.462972 -96.60255)
			(xy 416.447994 -96.625911) (xy 416.412311 -96.66841) (xy 416.370847 -96.70529) (xy 416.324476 -96.735773)
			(xy 416.274178 -96.759214) (xy 416.221014 -96.775121) (xy 416.166106 -96.783156) (xy 416.13836 -96.783652)
			(xy 416.111114 -96.783075) (xy 416.057177 -96.775315) (xy 416.004893 -96.759958) (xy 415.955326 -96.737317)
			(xy 415.909486 -96.707853) (xy 415.868306 -96.672166) (xy 415.832623 -96.630982) (xy 415.803164 -96.585138)
			(xy 415.780528 -96.53557) (xy 415.765177 -96.483284) (xy 415.757422 -96.429346) (xy 412.960783 -96.429346)
			(xy 412.936233 -96.901) (xy 417.621972 -96.901) (xy 417.626043 -96.845378) (xy 417.638169 -96.790941)
			(xy 417.658092 -96.73885) (xy 417.685388 -96.690215) (xy 417.719474 -96.646072) (xy 417.759623 -96.607363)
			(xy 417.804981 -96.574912) (xy 417.854581 -96.549411) (xy 417.907365 -96.531404) (xy 417.962208 -96.521274)
			(xy 418.017942 -96.519237) (xy 418.073379 -96.525337) (xy 418.127336 -96.539443) (xy 418.178665 -96.561255)
			(xy 418.226271 -96.590309) (xy 418.269139 -96.625984) (xy 418.306356 -96.667521) (xy 418.337129 -96.714034)
			(xy 418.360801 -96.764531) (xy 418.376869 -96.817938) (xy 418.384989 -96.873114) (xy 418.385498 -96.901)
			(xy 418.384989 -96.928886) (xy 418.376869 -96.984062) (xy 418.360801 -97.037469) (xy 418.359644 -97.039938)
			(xy 423.025568 -97.039938) (xy 423.029639 -96.984316) (xy 423.041765 -96.929879) (xy 423.061688 -96.877788)
			(xy 423.088984 -96.829153) (xy 423.12307 -96.78501) (xy 423.163219 -96.746301) (xy 423.208577 -96.71385)
			(xy 423.258177 -96.688349) (xy 423.310961 -96.670342) (xy 423.365804 -96.660212) (xy 423.421538 -96.658175)
			(xy 423.476975 -96.664275) (xy 423.530932 -96.678381) (xy 423.582261 -96.700193) (xy 423.629867 -96.729247)
			(xy 423.672735 -96.764922) (xy 423.709952 -96.806459) (xy 423.740725 -96.852972) (xy 423.764397 -96.903469)
			(xy 423.780465 -96.956876) (xy 423.787643 -97.005648) (xy 426.469554 -97.005648) (xy 426.473625 -96.950026)
			(xy 426.485751 -96.895589) (xy 426.505674 -96.843498) (xy 426.53297 -96.794863) (xy 426.567056 -96.75072)
			(xy 426.607205 -96.712011) (xy 426.652563 -96.67956) (xy 426.702163 -96.654059) (xy 426.754947 -96.636052)
			(xy 426.80979 -96.625922) (xy 426.865524 -96.623885) (xy 426.920961 -96.629985) (xy 426.974918 -96.644091)
			(xy 427.026247 -96.665903) (xy 427.073853 -96.694957) (xy 427.116721 -96.730632) (xy 427.153938 -96.772169)
			(xy 427.184711 -96.818682) (xy 427.208383 -96.869179) (xy 427.224451 -96.922586) (xy 427.232571 -96.977762)
			(xy 427.23308 -97.005648) (xy 427.232571 -97.033534) (xy 427.224451 -97.08871) (xy 427.208383 -97.142117)
			(xy 427.184711 -97.192614) (xy 427.153938 -97.239127) (xy 427.116721 -97.280664) (xy 427.073853 -97.316339)
			(xy 427.026247 -97.345393) (xy 426.974918 -97.367205) (xy 426.920961 -97.381311) (xy 426.865524 -97.387411)
			(xy 426.80979 -97.385374) (xy 426.754947 -97.375244) (xy 426.702163 -97.357237) (xy 426.652563 -97.331736)
			(xy 426.607205 -97.299285) (xy 426.567056 -97.260576) (xy 426.53297 -97.216433) (xy 426.505674 -97.167798)
			(xy 426.485751 -97.115707) (xy 426.473625 -97.06127) (xy 426.469554 -97.005648) (xy 423.787643 -97.005648)
			(xy 423.788585 -97.012052) (xy 423.789094 -97.039938) (xy 423.788585 -97.067824) (xy 423.780465 -97.123)
			(xy 423.764397 -97.176407) (xy 423.740725 -97.226904) (xy 423.709952 -97.273417) (xy 423.672735 -97.314954)
			(xy 423.629867 -97.350629) (xy 423.582261 -97.379683) (xy 423.530932 -97.401495) (xy 423.476975 -97.415601)
			(xy 423.421538 -97.421701) (xy 423.365804 -97.419664) (xy 423.310961 -97.409534) (xy 423.258177 -97.391527)
			(xy 423.208577 -97.366026) (xy 423.163219 -97.333575) (xy 423.12307 -97.294866) (xy 423.088984 -97.250723)
			(xy 423.061688 -97.202088) (xy 423.041765 -97.149997) (xy 423.029639 -97.09556) (xy 423.025568 -97.039938)
			(xy 418.359644 -97.039938) (xy 418.337129 -97.087966) (xy 418.306356 -97.134479) (xy 418.269139 -97.176016)
			(xy 418.226271 -97.211691) (xy 418.178665 -97.240745) (xy 418.127336 -97.262557) (xy 418.073379 -97.276663)
			(xy 418.017942 -97.282763) (xy 417.962208 -97.280726) (xy 417.907365 -97.270596) (xy 417.854581 -97.252589)
			(xy 417.804981 -97.227088) (xy 417.759623 -97.194637) (xy 417.719474 -97.155928) (xy 417.685388 -97.111785)
			(xy 417.658092 -97.06315) (xy 417.638169 -97.011059) (xy 417.626043 -96.956622) (xy 417.621972 -96.901)
			(xy 412.936233 -96.901) (xy 412.897759 -97.64014) (xy 422.218102 -97.64014) (xy 422.222173 -97.584518)
			(xy 422.234299 -97.530081) (xy 422.254222 -97.47799) (xy 422.281518 -97.429355) (xy 422.315604 -97.385212)
			(xy 422.355753 -97.346503) (xy 422.401111 -97.314052) (xy 422.450711 -97.288551) (xy 422.503495 -97.270544)
			(xy 422.558338 -97.260414) (xy 422.614072 -97.258377) (xy 422.669509 -97.264477) (xy 422.723466 -97.278583)
			(xy 422.774795 -97.300395) (xy 422.822401 -97.329449) (xy 422.865269 -97.365124) (xy 422.902486 -97.406661)
			(xy 422.933259 -97.453174) (xy 422.956931 -97.503671) (xy 422.972999 -97.557078) (xy 422.981119 -97.612254)
			(xy 422.981628 -97.64014) (xy 422.981119 -97.668026) (xy 422.972999 -97.723202) (xy 422.956931 -97.776609)
			(xy 422.933259 -97.827106) (xy 422.902486 -97.873619) (xy 422.865269 -97.915156) (xy 422.822401 -97.950831)
			(xy 422.774795 -97.979885) (xy 422.723466 -98.001697) (xy 422.669509 -98.015803) (xy 422.614072 -98.021903)
			(xy 422.558338 -98.019866) (xy 422.503495 -98.009736) (xy 422.450711 -97.991729) (xy 422.401111 -97.966228)
			(xy 422.355753 -97.933777) (xy 422.315604 -97.895068) (xy 422.281518 -97.850925) (xy 422.254222 -97.80229)
			(xy 422.234299 -97.750199) (xy 422.222173 -97.695762) (xy 422.218102 -97.64014) (xy 412.897759 -97.64014)
			(xy 412.870127 -98.171) (xy 423.864022 -98.171) (xy 423.868093 -98.115378) (xy 423.880219 -98.060941)
			(xy 423.900142 -98.00885) (xy 423.927438 -97.960215) (xy 423.961524 -97.916072) (xy 424.001673 -97.877363)
			(xy 424.047031 -97.844912) (xy 424.096631 -97.819411) (xy 424.149415 -97.801404) (xy 424.204258 -97.791274)
			(xy 424.259992 -97.789237) (xy 424.315429 -97.795337) (xy 424.369386 -97.809443) (xy 424.420715 -97.831255)
			(xy 424.468321 -97.860309) (xy 424.511189 -97.895984) (xy 424.548406 -97.937521) (xy 424.579179 -97.984034)
			(xy 424.602851 -98.034531) (xy 424.618919 -98.087938) (xy 424.627039 -98.143114) (xy 424.627548 -98.171)
			(xy 424.627039 -98.198886) (xy 424.618919 -98.254062) (xy 424.602851 -98.307469) (xy 424.579179 -98.357966)
			(xy 424.548406 -98.404479) (xy 424.511189 -98.446016) (xy 424.468321 -98.481691) (xy 424.420715 -98.510745)
			(xy 424.369386 -98.532557) (xy 424.315429 -98.546663) (xy 424.259992 -98.552763) (xy 424.204258 -98.550726)
			(xy 424.149415 -98.540596) (xy 424.096631 -98.522589) (xy 424.047031 -98.497088) (xy 424.001673 -98.464637)
			(xy 423.961524 -98.425928) (xy 423.927438 -98.381785) (xy 423.900142 -98.33315) (xy 423.880219 -98.281059)
			(xy 423.868093 -98.226622) (xy 423.864022 -98.171) (xy 412.870127 -98.171) (xy 412.817242 -99.187)
			(xy 418.422072 -99.187) (xy 418.426143 -99.131378) (xy 418.438269 -99.076941) (xy 418.458192 -99.02485)
			(xy 418.485488 -98.976215) (xy 418.519574 -98.932072) (xy 418.559723 -98.893363) (xy 418.605081 -98.860912)
			(xy 418.654681 -98.835411) (xy 418.707465 -98.817404) (xy 418.762308 -98.807274) (xy 418.818042 -98.805237)
			(xy 418.873479 -98.811337) (xy 418.927436 -98.825443) (xy 418.978765 -98.847255) (xy 419.026371 -98.876309)
			(xy 419.069239 -98.911984) (xy 419.106456 -98.953521) (xy 419.137229 -99.000034) (xy 419.160901 -99.050531)
			(xy 419.176969 -99.103938) (xy 419.185089 -99.159114) (xy 419.185598 -99.187) (xy 419.185089 -99.214886)
			(xy 419.176969 -99.270062) (xy 419.160901 -99.323469) (xy 419.137229 -99.373966) (xy 419.106456 -99.420479)
			(xy 419.08898 -99.439984) (xy 423.610022 -99.439984) (xy 423.614093 -99.384362) (xy 423.626219 -99.329925)
			(xy 423.646142 -99.277834) (xy 423.673438 -99.229199) (xy 423.707524 -99.185056) (xy 423.747673 -99.146347)
			(xy 423.793031 -99.113896) (xy 423.842631 -99.088395) (xy 423.895415 -99.070388) (xy 423.950258 -99.060258)
			(xy 424.005992 -99.058221) (xy 424.061429 -99.064321) (xy 424.115386 -99.078427) (xy 424.166715 -99.100239)
			(xy 424.214321 -99.129293) (xy 424.257189 -99.164968) (xy 424.294406 -99.206505) (xy 424.325179 -99.253018)
			(xy 424.348851 -99.303515) (xy 424.364919 -99.356922) (xy 424.373039 -99.412098) (xy 424.373548 -99.439984)
			(xy 424.373039 -99.46787) (xy 424.364919 -99.523046) (xy 424.348851 -99.576453) (xy 424.325179 -99.62695)
			(xy 424.294406 -99.673463) (xy 424.257189 -99.715) (xy 424.214321 -99.750675) (xy 424.166715 -99.779729)
			(xy 424.115386 -99.801541) (xy 424.061429 -99.815647) (xy 424.005992 -99.821747) (xy 423.950258 -99.81971)
			(xy 423.895415 -99.80958) (xy 423.842631 -99.791573) (xy 423.793031 -99.766072) (xy 423.747673 -99.733621)
			(xy 423.707524 -99.694912) (xy 423.673438 -99.650769) (xy 423.646142 -99.602134) (xy 423.626219 -99.550043)
			(xy 423.614093 -99.495606) (xy 423.610022 -99.439984) (xy 419.08898 -99.439984) (xy 419.069239 -99.462016)
			(xy 419.026371 -99.497691) (xy 418.978765 -99.526745) (xy 418.927436 -99.548557) (xy 418.873479 -99.562663)
			(xy 418.818042 -99.568763) (xy 418.762308 -99.566726) (xy 418.707465 -99.556596) (xy 418.654681 -99.538589)
			(xy 418.605081 -99.513088) (xy 418.559723 -99.480637) (xy 418.519574 -99.441928) (xy 418.485488 -99.397785)
			(xy 418.458192 -99.34915) (xy 418.438269 -99.297059) (xy 418.426143 -99.242622) (xy 418.422072 -99.187)
			(xy 412.817242 -99.187) (xy 412.772845 -100.039932) (xy 422.176954 -100.039932) (xy 422.181025 -99.98431)
			(xy 422.193151 -99.929873) (xy 422.213074 -99.877782) (xy 422.24037 -99.829147) (xy 422.274456 -99.785004)
			(xy 422.314605 -99.746295) (xy 422.359963 -99.713844) (xy 422.409563 -99.688343) (xy 422.462347 -99.670336)
			(xy 422.51719 -99.660206) (xy 422.572924 -99.658169) (xy 422.628361 -99.664269) (xy 422.682318 -99.678375)
			(xy 422.733647 -99.700187) (xy 422.781253 -99.729241) (xy 422.824121 -99.764916) (xy 422.861338 -99.806453)
			(xy 422.892111 -99.852966) (xy 422.915783 -99.903463) (xy 422.931851 -99.95687) (xy 422.939971 -100.012046)
			(xy 422.94048 -100.039932) (xy 422.939971 -100.067818) (xy 422.931851 -100.122994) (xy 422.915783 -100.176401)
			(xy 422.892111 -100.226898) (xy 422.861338 -100.273411) (xy 422.824121 -100.314948) (xy 422.781253 -100.350623)
			(xy 422.733647 -100.379677) (xy 422.682318 -100.401489) (xy 422.628361 -100.415595) (xy 422.572924 -100.421695)
			(xy 422.51719 -100.419658) (xy 422.462347 -100.409528) (xy 422.409563 -100.391521) (xy 422.359963 -100.36602)
			(xy 422.314605 -100.333569) (xy 422.274456 -100.29486) (xy 422.24037 -100.250717) (xy 422.213074 -100.202082)
			(xy 422.193151 -100.149991) (xy 422.181025 -100.095554) (xy 422.176954 -100.039932) (xy 412.772845 -100.039932)
			(xy 412.710375 -101.240082) (xy 422.594022 -101.240082) (xy 422.598093 -101.18446) (xy 422.610219 -101.130023)
			(xy 422.630142 -101.077932) (xy 422.657438 -101.029297) (xy 422.691524 -100.985154) (xy 422.731673 -100.946445)
			(xy 422.777031 -100.913994) (xy 422.826631 -100.888493) (xy 422.879415 -100.870486) (xy 422.934258 -100.860356)
			(xy 422.989992 -100.858319) (xy 423.045429 -100.864419) (xy 423.099386 -100.878525) (xy 423.150715 -100.900337)
			(xy 423.198321 -100.929391) (xy 423.241189 -100.965066) (xy 423.278406 -101.006603) (xy 423.309179 -101.053116)
			(xy 423.316929 -101.069648) (xy 423.886374 -101.069648) (xy 423.890445 -101.014026) (xy 423.902571 -100.959589)
			(xy 423.922494 -100.907498) (xy 423.94979 -100.858863) (xy 423.983876 -100.81472) (xy 424.024025 -100.776011)
			(xy 424.069383 -100.74356) (xy 424.118983 -100.718059) (xy 424.171767 -100.700052) (xy 424.22661 -100.689922)
			(xy 424.282344 -100.687885) (xy 424.337781 -100.693985) (xy 424.391738 -100.708091) (xy 424.443067 -100.729903)
			(xy 424.490673 -100.758957) (xy 424.533541 -100.794632) (xy 424.570758 -100.836169) (xy 424.601531 -100.882682)
			(xy 424.625203 -100.933179) (xy 424.641271 -100.986586) (xy 424.649391 -101.041762) (xy 424.6499 -101.069648)
			(xy 424.649391 -101.097534) (xy 424.641271 -101.15271) (xy 424.625203 -101.206117) (xy 424.601531 -101.256614)
			(xy 424.570758 -101.303127) (xy 424.533541 -101.344664) (xy 424.490673 -101.380339) (xy 424.443067 -101.409393)
			(xy 424.391738 -101.431205) (xy 424.337781 -101.445311) (xy 424.282344 -101.451411) (xy 424.22661 -101.449374)
			(xy 424.171767 -101.439244) (xy 424.118983 -101.421237) (xy 424.069383 -101.395736) (xy 424.024025 -101.363285)
			(xy 423.983876 -101.324576) (xy 423.94979 -101.280433) (xy 423.922494 -101.231798) (xy 423.902571 -101.179707)
			(xy 423.890445 -101.12527) (xy 423.886374 -101.069648) (xy 423.316929 -101.069648) (xy 423.332851 -101.103613)
			(xy 423.348919 -101.15702) (xy 423.357039 -101.212196) (xy 423.357548 -101.240082) (xy 423.357039 -101.267968)
			(xy 423.348919 -101.323144) (xy 423.332851 -101.376551) (xy 423.309179 -101.427048) (xy 423.278406 -101.473561)
			(xy 423.241189 -101.515098) (xy 423.198321 -101.550773) (xy 423.150715 -101.579827) (xy 423.099386 -101.601639)
			(xy 423.045429 -101.615745) (xy 422.989992 -101.621845) (xy 422.934258 -101.619808) (xy 422.879415 -101.609678)
			(xy 422.826631 -101.591671) (xy 422.777031 -101.56617) (xy 422.731673 -101.533719) (xy 422.691524 -101.49501)
			(xy 422.657438 -101.450867) (xy 422.630142 -101.402232) (xy 422.610219 -101.350141) (xy 422.598093 -101.295704)
			(xy 422.594022 -101.240082) (xy 412.710375 -101.240082) (xy 412.645366 -102.489) (xy 423.102022 -102.489)
			(xy 423.106093 -102.433378) (xy 423.118219 -102.378941) (xy 423.138142 -102.32685) (xy 423.165438 -102.278215)
			(xy 423.199524 -102.234072) (xy 423.239673 -102.195363) (xy 423.285031 -102.162912) (xy 423.334631 -102.137411)
			(xy 423.387415 -102.119404) (xy 423.442258 -102.109274) (xy 423.497992 -102.107237) (xy 423.553429 -102.113337)
			(xy 423.607386 -102.127443) (xy 423.658715 -102.149255) (xy 423.706321 -102.178309) (xy 423.749189 -102.213984)
			(xy 423.786406 -102.255521) (xy 423.817179 -102.302034) (xy 423.840851 -102.352531) (xy 423.856919 -102.405938)
			(xy 423.865039 -102.461114) (xy 423.865548 -102.489) (xy 423.865039 -102.516886) (xy 423.856919 -102.572062)
			(xy 423.840851 -102.625469) (xy 423.817179 -102.675966) (xy 423.786406 -102.722479) (xy 423.749189 -102.764016)
			(xy 423.706321 -102.799691) (xy 423.658715 -102.828745) (xy 423.607386 -102.850557) (xy 423.553429 -102.864663)
			(xy 423.497992 -102.870763) (xy 423.442258 -102.868726) (xy 423.387415 -102.858596) (xy 423.334631 -102.840589)
			(xy 423.285031 -102.815088) (xy 423.239673 -102.782637) (xy 423.199524 -102.743928) (xy 423.165438 -102.699785)
			(xy 423.138142 -102.65115) (xy 423.118219 -102.599059) (xy 423.106093 -102.544622) (xy 423.102022 -102.489)
			(xy 412.645366 -102.489) (xy 412.57265 -103.886) (xy 423.610022 -103.886) (xy 423.614093 -103.830378)
			(xy 423.626219 -103.775941) (xy 423.646142 -103.72385) (xy 423.673438 -103.675215) (xy 423.707524 -103.631072)
			(xy 423.747673 -103.592363) (xy 423.793031 -103.559912) (xy 423.842631 -103.534411) (xy 423.895415 -103.516404)
			(xy 423.950258 -103.506274) (xy 424.005992 -103.504237) (xy 424.061429 -103.510337) (xy 424.115386 -103.524443)
			(xy 424.166715 -103.546255) (xy 424.214321 -103.575309) (xy 424.257189 -103.610984) (xy 424.294406 -103.652521)
			(xy 424.325179 -103.699034) (xy 424.348851 -103.749531) (xy 424.364919 -103.802938) (xy 424.373039 -103.858114)
			(xy 424.373548 -103.886) (xy 424.373039 -103.913886) (xy 424.364919 -103.969062) (xy 424.348851 -104.022469)
			(xy 424.325179 -104.072966) (xy 424.294406 -104.119479) (xy 424.257189 -104.161016) (xy 424.214321 -104.196691)
			(xy 424.166715 -104.225745) (xy 424.115386 -104.247557) (xy 424.061429 -104.261663) (xy 424.005992 -104.267763)
			(xy 423.950258 -104.265726) (xy 423.895415 -104.255596) (xy 423.842631 -104.237589) (xy 423.793031 -104.212088)
			(xy 423.747673 -104.179637) (xy 423.707524 -104.140928) (xy 423.673438 -104.096785) (xy 423.646142 -104.04815)
			(xy 423.626219 -103.996059) (xy 423.614093 -103.941622) (xy 423.610022 -103.886) (xy 412.57265 -103.886)
			(xy 412.399611 -107.210352) (xy 413.291526 -107.210352) (xy 413.295597 -107.15473) (xy 413.307723 -107.100293)
			(xy 413.327646 -107.048202) (xy 413.354942 -106.999567) (xy 413.389028 -106.955424) (xy 413.429177 -106.916715)
			(xy 413.474535 -106.884264) (xy 413.524135 -106.858763) (xy 413.576919 -106.840756) (xy 413.631762 -106.830626)
			(xy 413.687496 -106.828589) (xy 413.742933 -106.834689) (xy 413.79689 -106.848795) (xy 413.848219 -106.870607)
			(xy 413.895825 -106.899661) (xy 413.938693 -106.935336) (xy 413.97591 -106.976873) (xy 414.006683 -107.023386)
			(xy 414.030355 -107.073883) (xy 414.046423 -107.12729) (xy 414.054543 -107.182466) (xy 414.055052 -107.210352)
			(xy 414.054543 -107.238238) (xy 414.046423 -107.293414) (xy 414.030355 -107.346821) (xy 414.006683 -107.397318)
			(xy 413.97591 -107.443831) (xy 413.938693 -107.485368) (xy 413.895825 -107.521043) (xy 413.848219 -107.550097)
			(xy 413.79689 -107.571909) (xy 413.742933 -107.586015) (xy 413.687496 -107.592115) (xy 413.631762 -107.590078)
			(xy 413.576919 -107.579948) (xy 413.524135 -107.561941) (xy 413.474535 -107.53644) (xy 413.429177 -107.503989)
			(xy 413.389028 -107.46528) (xy 413.354942 -107.421137) (xy 413.327646 -107.372502) (xy 413.307723 -107.320411)
			(xy 413.295597 -107.265974) (xy 413.291526 -107.210352) (xy 412.399611 -107.210352) (xy 412.22681 -110.530132)
			(xy 418.729158 -110.530132) (xy 418.733229 -110.47451) (xy 418.745355 -110.420073) (xy 418.765278 -110.367982)
			(xy 418.792574 -110.319347) (xy 418.82666 -110.275204) (xy 418.866809 -110.236495) (xy 418.912167 -110.204044)
			(xy 418.961767 -110.178543) (xy 419.014551 -110.160536) (xy 419.069394 -110.150406) (xy 419.125128 -110.148369)
			(xy 419.180565 -110.154469) (xy 419.234522 -110.168575) (xy 419.285851 -110.190387) (xy 419.333457 -110.219441)
			(xy 419.376325 -110.255116) (xy 419.413542 -110.296653) (xy 419.444315 -110.343166) (xy 419.467987 -110.393663)
			(xy 419.484055 -110.44707) (xy 419.492175 -110.502246) (xy 419.492684 -110.530132) (xy 419.492175 -110.558018)
			(xy 419.484055 -110.613194) (xy 419.467987 -110.666601) (xy 419.444315 -110.717098) (xy 419.413542 -110.763611)
			(xy 419.376325 -110.805148) (xy 419.333457 -110.840823) (xy 419.285851 -110.869877) (xy 419.234522 -110.891689)
			(xy 419.180565 -110.905795) (xy 419.125128 -110.911895) (xy 419.069394 -110.909858) (xy 419.014551 -110.899728)
			(xy 418.961767 -110.881721) (xy 418.912167 -110.85622) (xy 418.866809 -110.823769) (xy 418.82666 -110.78506)
			(xy 418.792574 -110.740917) (xy 418.765278 -110.692282) (xy 418.745355 -110.640191) (xy 418.733229 -110.585754)
			(xy 418.729158 -110.530132) (xy 412.22681 -110.530132) (xy 412.184965 -111.334042) (xy 412.56407 -111.334042)
			(xy 412.568141 -111.27842) (xy 412.580267 -111.223983) (xy 412.60019 -111.171892) (xy 412.627486 -111.123257)
			(xy 412.661572 -111.079114) (xy 412.701721 -111.040405) (xy 412.747079 -111.007954) (xy 412.796679 -110.982453)
			(xy 412.849463 -110.964446) (xy 412.904306 -110.954316) (xy 412.96004 -110.952279) (xy 413.015477 -110.958379)
			(xy 413.069434 -110.972485) (xy 413.120763 -110.994297) (xy 413.168369 -111.023351) (xy 413.211237 -111.059026)
			(xy 413.248454 -111.100563) (xy 413.279227 -111.147076) (xy 413.302899 -111.197573) (xy 413.318967 -111.25098)
			(xy 413.327087 -111.306156) (xy 413.327596 -111.334042) (xy 413.327087 -111.361928) (xy 413.318967 -111.417104)
			(xy 413.302899 -111.470511) (xy 413.279227 -111.521008) (xy 413.248454 -111.567521) (xy 413.211237 -111.609058)
			(xy 413.168369 -111.644733) (xy 413.120763 -111.673787) (xy 413.069434 -111.695599) (xy 413.015477 -111.709705)
			(xy 412.96004 -111.715805) (xy 412.904306 -111.713768) (xy 412.849463 -111.703638) (xy 412.796679 -111.685631)
			(xy 412.747079 -111.66013) (xy 412.701721 -111.627679) (xy 412.661572 -111.58897) (xy 412.627486 -111.544827)
			(xy 412.60019 -111.496192) (xy 412.580267 -111.444101) (xy 412.568141 -111.389664) (xy 412.56407 -111.334042)
			(xy 412.184965 -111.334042) (xy 412.156328 -111.884206) (xy 418.664388 -111.884206) (xy 418.668459 -111.828584)
			(xy 418.680585 -111.774147) (xy 418.700508 -111.722056) (xy 418.727804 -111.673421) (xy 418.76189 -111.629278)
			(xy 418.802039 -111.590569) (xy 418.847397 -111.558118) (xy 418.896997 -111.532617) (xy 418.949781 -111.51461)
			(xy 419.004624 -111.50448) (xy 419.060358 -111.502443) (xy 419.115795 -111.508543) (xy 419.169752 -111.522649)
			(xy 419.221081 -111.544461) (xy 419.268687 -111.573515) (xy 419.311555 -111.60919) (xy 419.348772 -111.650727)
			(xy 419.379545 -111.69724) (xy 419.403217 -111.747737) (xy 419.419285 -111.801144) (xy 419.427405 -111.85632)
			(xy 419.427914 -111.884206) (xy 419.427405 -111.912092) (xy 419.419285 -111.967268) (xy 419.415236 -111.980726)
			(xy 422.201594 -111.980726) (xy 422.202135 -111.951988) (xy 422.210754 -111.895161) (xy 422.2278 -111.840271)
			(xy 422.252887 -111.788559) (xy 422.285449 -111.741195) (xy 422.304718 -111.719868) (xy 422.311322 -111.71301)
			(xy 422.318434 -111.694976) (xy 422.318434 -111.606076) (xy 422.311322 -111.588042) (xy 422.304718 -111.581184)
			(xy 422.285473 -111.559835) (xy 422.252908 -111.512476) (xy 422.227815 -111.460768) (xy 422.210763 -111.405881)
			(xy 422.202139 -111.349056) (xy 422.202136 -111.291581) (xy 422.210755 -111.234756) (xy 422.227801 -111.179868)
			(xy 422.252889 -111.128157) (xy 422.285449 -111.080795) (xy 422.304718 -111.059468) (xy 422.311322 -111.05261)
			(xy 422.318434 -111.034576) (xy 422.318434 -110.945676) (xy 422.311322 -110.927642) (xy 422.304718 -110.920784)
			(xy 422.285473 -110.899435) (xy 422.252908 -110.852076) (xy 422.227815 -110.800368) (xy 422.210763 -110.745481)
			(xy 422.202139 -110.688656) (xy 422.202136 -110.631181) (xy 422.210755 -110.574356) (xy 422.227801 -110.519468)
			(xy 422.252889 -110.467757) (xy 422.285449 -110.420395) (xy 422.304718 -110.399068) (xy 422.311322 -110.39221)
			(xy 422.318434 -110.374176) (xy 422.318434 -110.285276) (xy 422.311322 -110.267242) (xy 422.304718 -110.260384)
			(xy 422.285473 -110.239035) (xy 422.252908 -110.191676) (xy 422.227815 -110.139968) (xy 422.210763 -110.085081)
			(xy 422.202139 -110.028256) (xy 422.202136 -109.970781) (xy 422.210755 -109.913956) (xy 422.227801 -109.859068)
			(xy 422.252889 -109.807357) (xy 422.285449 -109.759995) (xy 422.304718 -109.738668) (xy 422.311322 -109.73181)
			(xy 422.318434 -109.713776) (xy 422.318434 -109.624876) (xy 422.311322 -109.606842) (xy 422.304718 -109.599984)
			(xy 422.285456 -109.578649) (xy 422.252889 -109.531289) (xy 422.227796 -109.479579) (xy 422.210743 -109.42469)
			(xy 422.202117 -109.367864) (xy 422.201594 -109.339126) (xy 422.20208 -109.311874) (xy 422.209833 -109.257923)
			(xy 422.225186 -109.205626) (xy 422.247825 -109.156046) (xy 422.277291 -109.110192) (xy 422.312982 -109.068999)
			(xy 422.354173 -109.033305) (xy 422.400025 -109.003837) (xy 422.449603 -108.981194) (xy 422.5019 -108.965838)
			(xy 422.55585 -108.958081) (xy 422.583102 -108.957618) (xy 422.609416 -108.958078) (xy 422.661545 -108.965314)
			(xy 422.712188 -108.979634) (xy 422.760388 -109.000768) (xy 422.805231 -109.028315) (xy 422.84587 -109.061756)
			(xy 422.864026 -109.080808) (xy 422.871535 -109.088224) (xy 422.890825 -109.09674) (xy 422.901364 -109.097318)
			(xy 422.97604 -109.097318) (xy 422.986587 -109.096765) (xy 423.005882 -109.088246) (xy 423.013378 -109.080808)
			(xy 423.031553 -109.061772) (xy 423.072178 -109.028312) (xy 423.117014 -109.000751) (xy 423.165211 -108.979609)
			(xy 423.215856 -108.965288) (xy 423.267987 -108.958059) (xy 423.294302 -108.957618) (xy 423.321556 -108.958054)
			(xy 423.375509 -108.965811) (xy 423.427809 -108.981169) (xy 423.477391 -109.003814) (xy 423.523246 -109.033284)
			(xy 423.564439 -109.068981) (xy 423.600132 -109.110177) (xy 423.6296 -109.156033) (xy 423.652241 -109.205617)
			(xy 423.667594 -109.257918) (xy 423.675348 -109.311872) (xy 423.67581 -109.339126) (xy 423.675299 -109.367865)
			(xy 423.666673 -109.424693) (xy 423.64962 -109.479584) (xy 423.624526 -109.531295) (xy 423.591958 -109.578657)
			(xy 423.572686 -109.599984) (xy 423.566082 -109.606842) (xy 423.55897 -109.624876) (xy 423.55897 -109.713776)
			(xy 423.566082 -109.73181) (xy 423.572686 -109.738668) (xy 423.591982 -109.759973) (xy 423.624546 -109.807339)
			(xy 423.649635 -109.859055) (xy 423.666683 -109.913949) (xy 423.675303 -109.970779) (xy 423.6753 -110.028259)
			(xy 423.666674 -110.085088) (xy 423.649621 -110.139981) (xy 423.624527 -110.191694) (xy 423.591958 -110.239057)
			(xy 423.572686 -110.260384) (xy 423.566082 -110.267242) (xy 423.55897 -110.285276) (xy 423.55897 -110.374176)
			(xy 423.566082 -110.39221) (xy 423.572686 -110.399068) (xy 423.591982 -110.420373) (xy 423.624546 -110.467739)
			(xy 423.649635 -110.519455) (xy 423.666683 -110.574349) (xy 423.675303 -110.631179) (xy 423.6753 -110.688659)
			(xy 423.666674 -110.745488) (xy 423.649621 -110.800381) (xy 423.624527 -110.852094) (xy 423.591958 -110.899457)
			(xy 423.572686 -110.920784) (xy 423.566082 -110.927642) (xy 423.55897 -110.945676) (xy 423.55897 -111.034576)
			(xy 423.566082 -111.05261) (xy 423.572686 -111.059468) (xy 423.591982 -111.080773) (xy 423.624546 -111.128139)
			(xy 423.649635 -111.179855) (xy 423.666683 -111.234749) (xy 423.675303 -111.291579) (xy 423.6753 -111.349059)
			(xy 423.666674 -111.405888) (xy 423.649621 -111.460781) (xy 423.624527 -111.512494) (xy 423.591958 -111.559857)
			(xy 423.572686 -111.581184) (xy 423.566082 -111.588042) (xy 423.55897 -111.606076) (xy 423.55897 -111.694976)
			(xy 423.566082 -111.71301) (xy 423.572686 -111.719868) (xy 423.591973 -111.741181) (xy 423.624536 -111.788547)
			(xy 423.649625 -111.840262) (xy 423.666672 -111.895156) (xy 423.675291 -111.951986) (xy 423.67581 -111.980726)
			(xy 423.675346 -112.007978) (xy 423.667586 -112.061926) (xy 423.652228 -112.114221) (xy 423.629584 -112.163798)
			(xy 423.600115 -112.209649) (xy 423.564421 -112.250838) (xy 423.523229 -112.28653) (xy 423.477377 -112.315996)
			(xy 423.427799 -112.338636) (xy 423.375503 -112.353991) (xy 423.321554 -112.361748) (xy 423.294302 -112.362234)
			(xy 423.267989 -112.361754) (xy 423.215861 -112.35452) (xy 423.165219 -112.340203) (xy 423.11702 -112.319073)
			(xy 423.072176 -112.291529) (xy 423.031536 -112.258094) (xy 423.013378 -112.239044) (xy 423.005861 -112.231637)
			(xy 422.986578 -112.223114) (xy 422.97604 -112.222534) (xy 422.901364 -112.222534) (xy 422.890815 -112.223074)
			(xy 422.871519 -112.2316) (xy 422.864026 -112.239044) (xy 422.845859 -112.258088) (xy 422.805231 -112.291545)
			(xy 422.760393 -112.319104) (xy 422.712194 -112.340244) (xy 422.661549 -112.354564) (xy 422.609417 -112.361793)
			(xy 422.583102 -112.362234) (xy 422.555852 -112.36172) (xy 422.501907 -112.353965) (xy 422.449614 -112.338611)
			(xy 422.400038 -112.315972) (xy 422.354189 -112.286509) (xy 422.313 -112.25082) (xy 422.277308 -112.209633)
			(xy 422.247841 -112.163786) (xy 422.225198 -112.114212) (xy 422.209841 -112.061921) (xy 422.202082 -112.007976)
			(xy 422.201594 -111.980726) (xy 419.415236 -111.980726) (xy 419.403217 -112.020675) (xy 419.379545 -112.071172)
			(xy 419.348772 -112.117685) (xy 419.311555 -112.159222) (xy 419.268687 -112.194897) (xy 419.221081 -112.223951)
			(xy 419.169752 -112.245763) (xy 419.115795 -112.259869) (xy 419.060358 -112.265969) (xy 419.004624 -112.263932)
			(xy 418.949781 -112.253802) (xy 418.896997 -112.235795) (xy 418.847397 -112.210294) (xy 418.802039 -112.177843)
			(xy 418.76189 -112.139134) (xy 418.727804 -112.094991) (xy 418.700508 -112.046356) (xy 418.680585 -111.994265)
			(xy 418.668459 -111.939828) (xy 418.664388 -111.884206) (xy 412.156328 -111.884206) (xy 412.152084 -111.96574)
			(xy 412.152084 -112.090962) (xy 412.152427 -112.099696) (xy 412.158298 -112.116146) (xy 412.169392 -112.129636)
			(xy 412.176722 -112.134396) (xy 412.191708 -112.14354) (xy 412.19247 -112.144302) (xy 412.24708 -112.17783)
			(xy 412.256147 -112.182415) (xy 412.276313 -112.184764) (xy 412.286196 -112.182402) (xy 412.294578 -112.179608)
			(xy 412.298896 -112.177322) (xy 412.300928 -112.176306) (xy 412.302452 -112.175544) (xy 412.302706 -112.17529)
			(xy 412.316819 -112.167809) (xy 412.346067 -112.154963) (xy 412.361126 -112.149636) (xy 412.370895 -112.146376)
			(xy 412.390718 -112.140786) (xy 412.40075 -112.13846) (xy 412.404814 -112.137444) (xy 412.424088 -112.133668)
			(xy 412.463154 -112.129601) (xy 412.482792 -112.129316) (xy 412.488634 -112.129316) (xy 412.515696 -112.130075)
			(xy 412.569207 -112.138295) (xy 412.621018 -112.153997) (xy 412.670089 -112.176865) (xy 412.715434 -112.206441)
			(xy 412.756142 -112.242131) (xy 412.791397 -112.283217) (xy 412.820489 -112.328874) (xy 412.842834 -112.378185)
			(xy 412.857984 -112.43016) (xy 412.865634 -112.483755) (xy 412.865661 -112.485424) (xy 414.951162 -112.485424)
			(xy 414.955233 -112.429802) (xy 414.967359 -112.375365) (xy 414.987282 -112.323274) (xy 415.014578 -112.274639)
			(xy 415.048664 -112.230496) (xy 415.088813 -112.191787) (xy 415.134171 -112.159336) (xy 415.183771 -112.133835)
			(xy 415.236555 -112.115828) (xy 415.291398 -112.105698) (xy 415.347132 -112.103661) (xy 415.402569 -112.109761)
			(xy 415.456526 -112.123867) (xy 415.507855 -112.145679) (xy 415.555461 -112.174733) (xy 415.598329 -112.210408)
			(xy 415.635546 -112.251945) (xy 415.666319 -112.298458) (xy 415.689991 -112.348955) (xy 415.706059 -112.402362)
			(xy 415.708938 -112.421924) (xy 417.755068 -112.421924) (xy 417.759139 -112.366302) (xy 417.771265 -112.311865)
			(xy 417.791188 -112.259774) (xy 417.818484 -112.211139) (xy 417.85257 -112.166996) (xy 417.892719 -112.128287)
			(xy 417.938077 -112.095836) (xy 417.987677 -112.070335) (xy 418.040461 -112.052328) (xy 418.095304 -112.042198)
			(xy 418.151038 -112.040161) (xy 418.206475 -112.046261) (xy 418.260432 -112.060367) (xy 418.311761 -112.082179)
			(xy 418.359367 -112.111233) (xy 418.402235 -112.146908) (xy 418.439452 -112.188445) (xy 418.470225 -112.234958)
			(xy 418.493897 -112.285455) (xy 418.509965 -112.338862) (xy 418.518085 -112.394038) (xy 418.518594 -112.421924)
			(xy 418.518085 -112.44981) (xy 418.509965 -112.504986) (xy 418.493897 -112.558393) (xy 418.470225 -112.60889)
			(xy 418.439452 -112.655403) (xy 418.402235 -112.69694) (xy 418.359367 -112.732615) (xy 418.311761 -112.761669)
			(xy 418.260432 -112.783481) (xy 418.206475 -112.797587) (xy 418.151038 -112.803687) (xy 418.095304 -112.80165)
			(xy 418.040461 -112.79152) (xy 417.987677 -112.773513) (xy 417.938077 -112.748012) (xy 417.892719 -112.715561)
			(xy 417.85257 -112.676852) (xy 417.818484 -112.632709) (xy 417.791188 -112.584074) (xy 417.771265 -112.531983)
			(xy 417.759139 -112.477546) (xy 417.755068 -112.421924) (xy 415.708938 -112.421924) (xy 415.714179 -112.457538)
			(xy 415.714688 -112.485424) (xy 415.714179 -112.51331) (xy 415.706059 -112.568486) (xy 415.689991 -112.621893)
			(xy 415.666319 -112.67239) (xy 415.635546 -112.718903) (xy 415.598329 -112.76044) (xy 415.555461 -112.796115)
			(xy 415.507855 -112.825169) (xy 415.456526 -112.846981) (xy 415.402569 -112.861087) (xy 415.347132 -112.867187)
			(xy 415.291398 -112.86515) (xy 415.236555 -112.85502) (xy 415.183771 -112.837013) (xy 415.134171 -112.811512)
			(xy 415.088813 -112.779061) (xy 415.048664 -112.740352) (xy 415.014578 -112.696209) (xy 414.987282 -112.647574)
			(xy 414.967359 -112.595483) (xy 414.955233 -112.541046) (xy 414.951162 -112.485424) (xy 412.865661 -112.485424)
			(xy 412.866078 -112.510824) (xy 412.865613 -112.538075) (xy 412.857853 -112.592022) (xy 412.842495 -112.644315)
			(xy 412.81985 -112.69389) (xy 412.790381 -112.739738) (xy 412.754687 -112.780925) (xy 412.713495 -112.816614)
			(xy 412.667643 -112.846076) (xy 412.618064 -112.868714) (xy 412.565769 -112.884065) (xy 412.511821 -112.891817)
			(xy 412.48457 -112.892332) (xy 412.455605 -112.891795) (xy 412.39834 -112.883046) (xy 412.343051 -112.865754)
			(xy 412.291006 -112.840316) (xy 412.266892 -112.82426) (xy 412.26613 -112.823752) (xy 412.264098 -112.822482)
			(xy 412.253938 -112.816894) (xy 412.249857 -112.815284) (xy 412.241298 -112.813364) (xy 412.23692 -112.813084)
			(xy 412.230977 -112.812941) (xy 412.219292 -112.815114) (xy 412.213806 -112.817402) (xy 412.192978 -112.827308)
			(xy 412.19247 -112.827308) (xy 412.136844 -112.854486) (xy 412.13659 -112.85474) (xy 412.13532 -112.854994)
			(xy 412.131298 -112.856765) (xy 412.123887 -112.861488) (xy 412.120588 -112.864392) (xy 412.12008 -112.8649)
			(xy 412.112968 -112.872774) (xy 412.109158 -112.878362) (xy 412.106872 -112.884712) (xy 412.103824 -112.89792)
			(xy 412.085402 -113.251742) (xy 412.606234 -113.251742) (xy 412.610305 -113.19612) (xy 412.622431 -113.141683)
			(xy 412.642354 -113.089592) (xy 412.66965 -113.040957) (xy 412.703736 -112.996814) (xy 412.743885 -112.958105)
			(xy 412.789243 -112.925654) (xy 412.838843 -112.900153) (xy 412.891627 -112.882146) (xy 412.94647 -112.872016)
			(xy 413.002204 -112.869979) (xy 413.057641 -112.876079) (xy 413.111598 -112.890185) (xy 413.162927 -112.911997)
			(xy 413.210533 -112.941051) (xy 413.253401 -112.976726) (xy 413.264949 -112.989614) (xy 418.74008 -112.989614)
			(xy 418.744151 -112.933992) (xy 418.756277 -112.879555) (xy 418.7762 -112.827464) (xy 418.803496 -112.778829)
			(xy 418.837582 -112.734686) (xy 418.877731 -112.695977) (xy 418.923089 -112.663526) (xy 418.972689 -112.638025)
			(xy 419.025473 -112.620018) (xy 419.080316 -112.609888) (xy 419.13605 -112.607851) (xy 419.191487 -112.613951)
			(xy 419.245444 -112.628057) (xy 419.296773 -112.649869) (xy 419.344379 -112.678923) (xy 419.387247 -112.714598)
			(xy 419.424464 -112.756135) (xy 419.455237 -112.802648) (xy 419.478909 -112.853145) (xy 419.494977 -112.906552)
			(xy 419.503097 -112.961728) (xy 419.503606 -112.989614) (xy 419.503097 -113.0175) (xy 419.494977 -113.072676)
			(xy 419.478909 -113.126083) (xy 419.455237 -113.17658) (xy 419.424464 -113.223093) (xy 419.387247 -113.26463)
			(xy 419.344379 -113.300305) (xy 419.296773 -113.329359) (xy 419.245444 -113.351171) (xy 419.191487 -113.365277)
			(xy 419.13605 -113.371377) (xy 419.080316 -113.36934) (xy 419.025473 -113.35921) (xy 418.972689 -113.341203)
			(xy 418.923089 -113.315702) (xy 418.877731 -113.283251) (xy 418.837582 -113.244542) (xy 418.803496 -113.200399)
			(xy 418.7762 -113.151764) (xy 418.756277 -113.099673) (xy 418.744151 -113.045236) (xy 418.74008 -112.989614)
			(xy 413.264949 -112.989614) (xy 413.290618 -113.018263) (xy 413.321391 -113.064776) (xy 413.345063 -113.115273)
			(xy 413.361131 -113.16868) (xy 413.369251 -113.223856) (xy 413.36976 -113.251742) (xy 413.369251 -113.279628)
			(xy 413.361131 -113.334804) (xy 413.345063 -113.388211) (xy 413.323068 -113.43513) (xy 414.954972 -113.43513)
			(xy 414.959043 -113.379508) (xy 414.971169 -113.325071) (xy 414.991092 -113.27298) (xy 415.018388 -113.224345)
			(xy 415.052474 -113.180202) (xy 415.092623 -113.141493) (xy 415.137981 -113.109042) (xy 415.187581 -113.083541)
			(xy 415.240365 -113.065534) (xy 415.295208 -113.055404) (xy 415.350942 -113.053367) (xy 415.406379 -113.059467)
			(xy 415.460336 -113.073573) (xy 415.511665 -113.095385) (xy 415.559271 -113.124439) (xy 415.602139 -113.160114)
			(xy 415.639356 -113.201651) (xy 415.670129 -113.248164) (xy 415.693801 -113.298661) (xy 415.709869 -113.352068)
			(xy 415.717989 -113.407244) (xy 415.718498 -113.43513) (xy 415.718447 -113.437924) (xy 417.657786 -113.437924)
			(xy 417.661857 -113.382302) (xy 417.673983 -113.327865) (xy 417.693906 -113.275774) (xy 417.721202 -113.227139)
			(xy 417.755288 -113.182996) (xy 417.795437 -113.144287) (xy 417.840795 -113.111836) (xy 417.890395 -113.086335)
			(xy 417.943179 -113.068328) (xy 417.998022 -113.058198) (xy 418.053756 -113.056161) (xy 418.109193 -113.062261)
			(xy 418.16315 -113.076367) (xy 418.214479 -113.098179) (xy 418.262085 -113.127233) (xy 418.304953 -113.162908)
			(xy 418.34217 -113.204445) (xy 418.372943 -113.250958) (xy 418.396615 -113.301455) (xy 418.412683 -113.354862)
			(xy 418.420803 -113.410038) (xy 418.421312 -113.437924) (xy 418.420803 -113.46581) (xy 418.412683 -113.520986)
			(xy 418.396615 -113.574393) (xy 418.372943 -113.62489) (xy 418.34217 -113.671403) (xy 418.304953 -113.71294)
			(xy 418.262085 -113.748615) (xy 418.214479 -113.777669) (xy 418.16315 -113.799481) (xy 418.109193 -113.813587)
			(xy 418.053756 -113.819687) (xy 417.998022 -113.81765) (xy 417.943179 -113.80752) (xy 417.890395 -113.789513)
			(xy 417.840795 -113.764012) (xy 417.795437 -113.731561) (xy 417.755288 -113.692852) (xy 417.721202 -113.648709)
			(xy 417.693906 -113.600074) (xy 417.673983 -113.547983) (xy 417.661857 -113.493546) (xy 417.657786 -113.437924)
			(xy 415.718447 -113.437924) (xy 415.717989 -113.463016) (xy 415.709869 -113.518192) (xy 415.693801 -113.571599)
			(xy 415.670129 -113.622096) (xy 415.639356 -113.668609) (xy 415.602139 -113.710146) (xy 415.559271 -113.745821)
			(xy 415.511665 -113.774875) (xy 415.460336 -113.796687) (xy 415.406379 -113.810793) (xy 415.350942 -113.816893)
			(xy 415.295208 -113.814856) (xy 415.240365 -113.804726) (xy 415.187581 -113.786719) (xy 415.137981 -113.761218)
			(xy 415.092623 -113.728767) (xy 415.052474 -113.690058) (xy 415.018388 -113.645915) (xy 414.991092 -113.59728)
			(xy 414.971169 -113.545189) (xy 414.959043 -113.490752) (xy 414.954972 -113.43513) (xy 413.323068 -113.43513)
			(xy 413.321391 -113.438708) (xy 413.290618 -113.485221) (xy 413.253401 -113.526758) (xy 413.210533 -113.562433)
			(xy 413.162927 -113.591487) (xy 413.111598 -113.613299) (xy 413.057641 -113.627405) (xy 413.002204 -113.633505)
			(xy 412.94647 -113.631468) (xy 412.891627 -113.621338) (xy 412.838843 -113.603331) (xy 412.789243 -113.57783)
			(xy 412.743885 -113.545379) (xy 412.703736 -113.50667) (xy 412.66965 -113.462527) (xy 412.642354 -113.413892)
			(xy 412.622431 -113.361801) (xy 412.610305 -113.307364) (xy 412.606234 -113.251742) (xy 412.085402 -113.251742)
			(xy 412.050992 -113.91265) (xy 412.038546 -114.152426) (xy 412.031376 -114.290094) (xy 418.660324 -114.290094)
			(xy 418.664395 -114.234472) (xy 418.676521 -114.180035) (xy 418.696444 -114.127944) (xy 418.72374 -114.079309)
			(xy 418.757826 -114.035166) (xy 418.797975 -113.996457) (xy 418.843333 -113.964006) (xy 418.892933 -113.938505)
			(xy 418.945717 -113.920498) (xy 419.00056 -113.910368) (xy 419.056294 -113.908331) (xy 419.111731 -113.914431)
			(xy 419.165688 -113.928537) (xy 419.217017 -113.950349) (xy 419.264623 -113.979403) (xy 419.307491 -114.015078)
			(xy 419.344708 -114.056615) (xy 419.375481 -114.103128) (xy 419.399153 -114.153625) (xy 419.415221 -114.207032)
			(xy 419.423341 -114.262208) (xy 419.42385 -114.290094) (xy 419.423341 -114.31798) (xy 419.415221 -114.373156)
			(xy 419.399153 -114.426563) (xy 419.375481 -114.47706) (xy 419.344708 -114.523573) (xy 419.307491 -114.56511)
			(xy 419.264623 -114.600785) (xy 419.217017 -114.629839) (xy 419.165688 -114.651651) (xy 419.111731 -114.665757)
			(xy 419.056294 -114.671857) (xy 419.00056 -114.66982) (xy 418.945717 -114.65969) (xy 418.892933 -114.641683)
			(xy 418.843333 -114.616182) (xy 418.797975 -114.583731) (xy 418.757826 -114.545022) (xy 418.72374 -114.500879)
			(xy 418.696444 -114.452244) (xy 418.676521 -114.400153) (xy 418.664395 -114.345716) (xy 418.660324 -114.290094)
			(xy 412.031376 -114.290094) (xy 412.000896 -114.87531) (xy 414.257488 -114.87531) (xy 414.261559 -114.819688)
			(xy 414.273685 -114.765251) (xy 414.293608 -114.71316) (xy 414.320904 -114.664525) (xy 414.35499 -114.620382)
			(xy 414.395139 -114.581673) (xy 414.440497 -114.549222) (xy 414.490097 -114.523721) (xy 414.542881 -114.505714)
			(xy 414.597724 -114.495584) (xy 414.653458 -114.493547) (xy 414.708895 -114.499647) (xy 414.762852 -114.513753)
			(xy 414.814181 -114.535565) (xy 414.861787 -114.564619) (xy 414.904655 -114.600294) (xy 414.941872 -114.641831)
			(xy 414.972645 -114.688344) (xy 414.996317 -114.738841) (xy 415.012385 -114.792248) (xy 415.020505 -114.847424)
			(xy 415.021014 -114.87531) (xy 415.020505 -114.903196) (xy 415.012385 -114.958372) (xy 414.996317 -115.011779)
			(xy 414.972645 -115.062276) (xy 414.941872 -115.108789) (xy 414.904655 -115.150326) (xy 414.861787 -115.186001)
			(xy 414.814181 -115.215055) (xy 414.762852 -115.236867) (xy 414.708895 -115.250973) (xy 414.653458 -115.257073)
			(xy 414.597724 -115.255036) (xy 414.542881 -115.244906) (xy 414.490097 -115.226899) (xy 414.440497 -115.201398)
			(xy 414.395139 -115.168947) (xy 414.35499 -115.130238) (xy 414.320904 -115.086095) (xy 414.293608 -115.03746)
			(xy 414.273685 -114.985369) (xy 414.261559 -114.930932) (xy 414.257488 -114.87531) (xy 412.000896 -114.87531)
			(xy 411.982666 -115.225322) (xy 411.981142 -115.254532) (xy 411.979476 -115.285774) (xy 415.230816 -115.285774)
			(xy 415.234887 -115.230152) (xy 415.247013 -115.175715) (xy 415.266936 -115.123624) (xy 415.294232 -115.074989)
			(xy 415.328318 -115.030846) (xy 415.368467 -114.992137) (xy 415.413825 -114.959686) (xy 415.463425 -114.934185)
			(xy 415.516209 -114.916178) (xy 415.571052 -114.906048) (xy 415.626786 -114.904011) (xy 415.682223 -114.910111)
			(xy 415.73618 -114.924217) (xy 415.787509 -114.946029) (xy 415.835115 -114.975083) (xy 415.877983 -115.010758)
			(xy 415.9152 -115.052295) (xy 415.945973 -115.098808) (xy 415.969645 -115.149305) (xy 415.985713 -115.202712)
			(xy 415.993833 -115.257888) (xy 415.994342 -115.285774) (xy 415.993833 -115.31366) (xy 415.986872 -115.360958)
			(xy 422.41851 -115.360958) (xy 422.419008 -115.333589) (xy 422.426817 -115.279411) (xy 422.442299 -115.226908)
			(xy 422.465134 -115.177161) (xy 422.494852 -115.131193) (xy 422.51249 -115.11026) (xy 422.512744 -115.110006)
			(xy 422.51834 -115.102926) (xy 422.52458 -115.086004) (xy 422.524936 -115.076986) (xy 422.524936 -115.00993)
			(xy 422.524557 -115.000916) (xy 422.518324 -114.983999) (xy 422.512744 -114.97691) (xy 422.51249 -114.97691)
			(xy 422.51249 -114.976656) (xy 422.494862 -114.955715) (xy 422.465149 -114.909744) (xy 422.442311 -114.859999)
			(xy 422.426817 -114.807501) (xy 422.418986 -114.753327) (xy 422.41851 -114.725958) (xy 422.418939 -114.698705)
			(xy 422.426701 -114.644754) (xy 422.442063 -114.592457) (xy 422.46471 -114.542879) (xy 422.494183 -114.497028)
			(xy 422.52988 -114.455837) (xy 422.571076 -114.420147) (xy 422.616931 -114.390681) (xy 422.666514 -114.368042)
			(xy 422.718813 -114.352689) (xy 422.772765 -114.344935) (xy 422.800018 -114.34445) (xy 422.827389 -114.344893)
			(xy 422.88157 -114.352715) (xy 422.934074 -114.368208) (xy 422.98382 -114.391056) (xy 423.029786 -114.420786)
			(xy 423.050716 -114.43843) (xy 423.05097 -114.438684) (xy 423.058062 -114.444262) (xy 423.074975 -114.450514)
			(xy 423.08399 -114.450876) (xy 423.151046 -114.450876) (xy 423.160061 -114.450498) (xy 423.176978 -114.444266)
			(xy 423.184066 -114.438684) (xy 423.184066 -114.43843) (xy 423.18432 -114.43843) (xy 423.205275 -114.42082)
			(xy 423.251241 -114.391102) (xy 423.300983 -114.36826) (xy 423.353478 -114.352763) (xy 423.40765 -114.344928)
			(xy 423.435018 -114.34445) (xy 423.462268 -114.344961) (xy 423.516212 -114.352719) (xy 423.568504 -114.368074)
			(xy 423.618079 -114.390714) (xy 423.663927 -114.420179) (xy 423.705116 -114.455867) (xy 423.740807 -114.497054)
			(xy 423.770274 -114.5429) (xy 423.792918 -114.592473) (xy 423.808276 -114.644764) (xy 423.816037 -114.698708)
			(xy 423.816526 -114.725958) (xy 423.816053 -114.753328) (xy 423.80824 -114.807508) (xy 423.792753 -114.860011)
			(xy 423.769913 -114.909759) (xy 423.740188 -114.955725) (xy 423.722546 -114.976656) (xy 423.722292 -114.97691)
			(xy 423.716694 -114.983989) (xy 423.710455 -115.000912) (xy 423.7101 -115.00993) (xy 423.7101 -115.076986)
			(xy 423.710464 -115.086002) (xy 423.716707 -115.102919) (xy 423.722292 -115.110006) (xy 423.722546 -115.110006)
			(xy 423.722546 -115.11026) (xy 423.740171 -115.131203) (xy 423.769887 -115.177172) (xy 423.792727 -115.226917)
			(xy 423.808221 -115.279415) (xy 423.816051 -115.333589) (xy 423.816526 -115.360958) (xy 423.816006 -115.388209)
			(xy 423.808255 -115.442157) (xy 423.792905 -115.494453) (xy 423.770269 -115.544031) (xy 423.740807 -115.589884)
			(xy 423.705119 -115.631077) (xy 423.663932 -115.666771) (xy 423.618084 -115.69624) (xy 423.568509 -115.718884)
			(xy 423.516216 -115.734242) (xy 423.462269 -115.742001) (xy 423.435018 -115.742466) (xy 423.407648 -115.741998)
			(xy 423.353468 -115.734182) (xy 423.300965 -115.718694) (xy 423.251218 -115.695852) (xy 423.205251 -115.666127)
			(xy 423.18432 -115.648486) (xy 423.184066 -115.648232) (xy 423.176971 -115.642659) (xy 423.16006 -115.636406)
			(xy 423.151046 -115.63604) (xy 423.08399 -115.63604) (xy 423.074972 -115.636383) (xy 423.058054 -115.642639)
			(xy 423.05097 -115.648232) (xy 423.05097 -115.648486) (xy 423.050716 -115.648486) (xy 423.029787 -115.666129)
			(xy 422.983814 -115.695841) (xy 422.934065 -115.718676) (xy 422.881564 -115.734166) (xy 422.827387 -115.741993)
			(xy 422.800018 -115.742466) (xy 422.772764 -115.742028) (xy 422.71881 -115.734272) (xy 422.666509 -115.718916)
			(xy 422.616926 -115.696273) (xy 422.571071 -115.666803) (xy 422.529877 -115.631106) (xy 422.494183 -115.58991)
			(xy 422.464716 -115.544053) (xy 422.442075 -115.494469) (xy 422.426723 -115.442167) (xy 422.41897 -115.388212)
			(xy 422.41851 -115.360958) (xy 415.986872 -115.360958) (xy 415.985713 -115.368836) (xy 415.969645 -115.422243)
			(xy 415.945973 -115.47274) (xy 415.9152 -115.519253) (xy 415.877983 -115.56079) (xy 415.835115 -115.596465)
			(xy 415.787509 -115.625519) (xy 415.73618 -115.647331) (xy 415.682223 -115.661437) (xy 415.626786 -115.667537)
			(xy 415.571052 -115.6655) (xy 415.516209 -115.65537) (xy 415.463425 -115.637363) (xy 415.413825 -115.611862)
			(xy 415.368467 -115.579411) (xy 415.328318 -115.540702) (xy 415.294232 -115.496559) (xy 415.266936 -115.447924)
			(xy 415.247013 -115.395833) (xy 415.234887 -115.341396) (xy 415.230816 -115.285774) (xy 411.979476 -115.285774)
			(xy 411.97911 -115.292632) (xy 411.975808 -115.355624) (xy 411.967934 -115.50777) (xy 411.967934 -115.510818)
			(xy 411.968444 -115.521012) (xy 411.976456 -115.539765) (xy 411.991104 -115.553954) (xy 412.000446 -115.558062)
			(xy 412.00324 -115.558824) (xy 412.005018 -115.559586) (xy 412.00832 -115.560602) (xy 412.009844 -115.56111)
			(xy 412.012892 -115.562126) (xy 412.040379 -115.57247) (xy 412.09205 -115.60038) (xy 412.138841 -115.635868)
			(xy 412.179651 -115.678099) (xy 412.213518 -115.726077) (xy 412.239644 -115.778672) (xy 412.257414 -115.834646)
			(xy 412.266409 -115.892681) (xy 412.266892 -115.922044) (xy 412.26636 -115.950888) (xy 412.25767 -116.007919)
			(xy 412.240494 -116.062991) (xy 412.215224 -116.114851) (xy 412.182435 -116.162316) (xy 412.142876 -116.204305)
			(xy 412.097447 -116.23986) (xy 412.047183 -116.268172) (xy 411.993231 -116.288596) (xy 411.96514 -116.29517)
			(xy 411.964632 -116.29517) (xy 411.964378 -116.295424) (xy 411.956337 -116.297433) (xy 411.942083 -116.305865)
			(xy 411.936438 -116.311934) (xy 411.931104 -116.318284) (xy 411.928056 -116.32565) (xy 411.926707 -116.329207)
			(xy 411.924927 -116.336602) (xy 411.9245 -116.340382) (xy 411.918945 -116.44757) (xy 414.457132 -116.44757)
			(xy 414.461203 -116.391948) (xy 414.473329 -116.337511) (xy 414.493252 -116.28542) (xy 414.520548 -116.236785)
			(xy 414.554634 -116.192642) (xy 414.594783 -116.153933) (xy 414.640141 -116.121482) (xy 414.689741 -116.095981)
			(xy 414.742525 -116.077974) (xy 414.797368 -116.067844) (xy 414.853102 -116.065807) (xy 414.908539 -116.071907)
			(xy 414.962496 -116.086013) (xy 415.013825 -116.107825) (xy 415.061431 -116.136879) (xy 415.104299 -116.172554)
			(xy 415.141516 -116.214091) (xy 415.172289 -116.260604) (xy 415.195961 -116.311101) (xy 415.212029 -116.364508)
			(xy 415.220149 -116.419684) (xy 415.220658 -116.44757) (xy 415.220149 -116.475456) (xy 415.219879 -116.477288)
			(xy 419.604442 -116.477288) (xy 419.608513 -116.421666) (xy 419.620639 -116.367229) (xy 419.640562 -116.315138)
			(xy 419.667858 -116.266503) (xy 419.701944 -116.22236) (xy 419.742093 -116.183651) (xy 419.787451 -116.1512)
			(xy 419.837051 -116.125699) (xy 419.889835 -116.107692) (xy 419.944678 -116.097562) (xy 420.000412 -116.095525)
			(xy 420.055849 -116.101625) (xy 420.109806 -116.115731) (xy 420.161135 -116.137543) (xy 420.208741 -116.166597)
			(xy 420.251609 -116.202272) (xy 420.288826 -116.243809) (xy 420.319599 -116.290322) (xy 420.343271 -116.340819)
			(xy 420.359339 -116.394226) (xy 420.367459 -116.449402) (xy 420.367968 -116.477288) (xy 420.367459 -116.505174)
			(xy 420.359339 -116.56035) (xy 420.343271 -116.613757) (xy 420.319599 -116.664254) (xy 420.288826 -116.710767)
			(xy 420.251609 -116.752304) (xy 420.208741 -116.787979) (xy 420.161135 -116.817033) (xy 420.109806 -116.838845)
			(xy 420.055849 -116.852951) (xy 420.000412 -116.859051) (xy 419.944678 -116.857014) (xy 419.889835 -116.846884)
			(xy 419.837051 -116.828877) (xy 419.787451 -116.803376) (xy 419.742093 -116.770925) (xy 419.701944 -116.732216)
			(xy 419.667858 -116.688073) (xy 419.640562 -116.639438) (xy 419.620639 -116.587347) (xy 419.608513 -116.53291)
			(xy 419.604442 -116.477288) (xy 415.219879 -116.477288) (xy 415.212029 -116.530632) (xy 415.195961 -116.584039)
			(xy 415.172289 -116.634536) (xy 415.141516 -116.681049) (xy 415.104299 -116.722586) (xy 415.061431 -116.758261)
			(xy 415.013825 -116.787315) (xy 414.962496 -116.809127) (xy 414.908539 -116.823233) (xy 414.853102 -116.829333)
			(xy 414.797368 -116.827296) (xy 414.742525 -116.817166) (xy 414.689741 -116.799159) (xy 414.640141 -116.773658)
			(xy 414.594783 -116.741207) (xy 414.554634 -116.702498) (xy 414.520548 -116.658355) (xy 414.493252 -116.60972)
			(xy 414.473329 -116.557629) (xy 414.461203 -116.503192) (xy 414.457132 -116.44757) (xy 411.918945 -116.44757)
			(xy 411.896052 -116.889276) (xy 411.861254 -117.561614) (xy 411.852796 -117.723666) (xy 417.989764 -117.723666)
			(xy 417.993835 -117.668044) (xy 418.005961 -117.613607) (xy 418.025884 -117.561516) (xy 418.05318 -117.512881)
			(xy 418.087266 -117.468738) (xy 418.127415 -117.430029) (xy 418.172773 -117.397578) (xy 418.222373 -117.372077)
			(xy 418.275157 -117.35407) (xy 418.33 -117.34394) (xy 418.385734 -117.341903) (xy 418.441171 -117.348003)
			(xy 418.495128 -117.362109) (xy 418.546457 -117.383921) (xy 418.594063 -117.412975) (xy 418.636931 -117.44865)
			(xy 418.674148 -117.490187) (xy 418.704921 -117.5367) (xy 418.728593 -117.587197) (xy 418.744661 -117.640604)
			(xy 418.752781 -117.69578) (xy 418.75329 -117.723666) (xy 418.752781 -117.751552) (xy 418.751652 -117.759226)
			(xy 422.774872 -117.759226) (xy 422.774872 -116.895626) (xy 422.775362 -116.865642) (xy 422.78319 -116.806186)
			(xy 422.798711 -116.748261) (xy 422.82166 -116.692857) (xy 422.851644 -116.640923) (xy 422.88815 -116.593347)
			(xy 422.930555 -116.550942) (xy 422.978131 -116.514436) (xy 423.030065 -116.484452) (xy 423.085469 -116.461503)
			(xy 423.143394 -116.445982) (xy 423.20285 -116.438154) (xy 423.262818 -116.438154) (xy 423.322274 -116.445982)
			(xy 423.380199 -116.461503) (xy 423.435603 -116.484452) (xy 423.487537 -116.514436) (xy 423.535113 -116.550942)
			(xy 423.577518 -116.593347) (xy 423.614024 -116.640923) (xy 423.644008 -116.692857) (xy 423.666957 -116.748261)
			(xy 423.682478 -116.806186) (xy 423.690306 -116.865642) (xy 423.690796 -116.895626) (xy 423.690796 -117.759226)
			(xy 423.690306 -117.78921) (xy 423.682478 -117.848666) (xy 423.666957 -117.906591) (xy 423.644008 -117.961995)
			(xy 423.614024 -118.013929) (xy 423.577518 -118.061505) (xy 423.535113 -118.10391) (xy 423.487537 -118.140416)
			(xy 423.435603 -118.1704) (xy 423.380199 -118.193349) (xy 423.322274 -118.20887) (xy 423.262818 -118.216698)
			(xy 423.20285 -118.216698) (xy 423.143394 -118.20887) (xy 423.085469 -118.193349) (xy 423.030065 -118.1704)
			(xy 422.978131 -118.140416) (xy 422.930555 -118.10391) (xy 422.88815 -118.061505) (xy 422.851644 -118.013929)
			(xy 422.82166 -117.961995) (xy 422.798711 -117.906591) (xy 422.78319 -117.848666) (xy 422.775362 -117.78921)
			(xy 422.774872 -117.759226) (xy 418.751652 -117.759226) (xy 418.744661 -117.806728) (xy 418.728593 -117.860135)
			(xy 418.704921 -117.910632) (xy 418.674148 -117.957145) (xy 418.636931 -117.998682) (xy 418.594063 -118.034357)
			(xy 418.546457 -118.063411) (xy 418.495128 -118.085223) (xy 418.441171 -118.099329) (xy 418.385734 -118.105429)
			(xy 418.33 -118.103392) (xy 418.275157 -118.093262) (xy 418.222373 -118.075255) (xy 418.172773 -118.049754)
			(xy 418.127415 -118.017303) (xy 418.087266 -117.978594) (xy 418.05318 -117.934451) (xy 418.025884 -117.885816)
			(xy 418.005961 -117.833725) (xy 417.993835 -117.779288) (xy 417.989764 -117.723666) (xy 411.852796 -117.723666)
			(xy 411.837378 -118.019068) (xy 411.837378 -118.01983) (xy 411.83687 -118.031006) (xy 411.839664 -118.037864)
			(xy 411.8483 -118.050818) (xy 411.854396 -118.058184) (xy 411.875335 -118.080173) (xy 411.910819 -118.129441)
			(xy 411.938217 -118.183624) (xy 411.956863 -118.241406) (xy 411.966306 -118.301384) (xy 411.966918 -118.331742)
			(xy 411.966918 -118.331996) (xy 411.966388 -118.360927) (xy 411.957818 -118.41815) (xy 411.940867 -118.473473)
			(xy 411.915908 -118.525675) (xy 411.883493 -118.573604) (xy 411.844336 -118.616203) (xy 411.822138 -118.634764)
			(xy 411.806898 -118.64721) (xy 411.804104 -118.65864) (xy 411.797246 -118.788942) (xy 411.790134 -118.925594)
			(xy 411.781752 -119.086376) (xy 411.756735 -119.567198) (xy 414.899348 -119.567198) (xy 414.899348 -118.703598)
			(xy 414.899838 -118.673614) (xy 414.907666 -118.614158) (xy 414.923187 -118.556233) (xy 414.946136 -118.500829)
			(xy 414.97612 -118.448895) (xy 415.012626 -118.401319) (xy 415.055031 -118.358914) (xy 415.102607 -118.322408)
			(xy 415.154541 -118.292424) (xy 415.209945 -118.269475) (xy 415.26787 -118.253954) (xy 415.327326 -118.246126)
			(xy 415.387294 -118.246126) (xy 415.44675 -118.253954) (xy 415.504675 -118.269475) (xy 415.560079 -118.292424)
			(xy 415.612013 -118.322408) (xy 415.659589 -118.358914) (xy 415.701994 -118.401319) (xy 415.7385 -118.448895)
			(xy 415.768484 -118.500829) (xy 415.791433 -118.556233) (xy 415.806954 -118.614158) (xy 415.814782 -118.673614)
			(xy 415.815272 -118.703598) (xy 415.815272 -118.711218) (xy 418.109398 -118.711218) (xy 418.113469 -118.655596)
			(xy 418.125595 -118.601159) (xy 418.145518 -118.549068) (xy 418.172814 -118.500433) (xy 418.2069 -118.45629)
			(xy 418.247049 -118.417581) (xy 418.292407 -118.38513) (xy 418.342007 -118.359629) (xy 418.394791 -118.341622)
			(xy 418.449634 -118.331492) (xy 418.505368 -118.329455) (xy 418.560805 -118.335555) (xy 418.614762 -118.349661)
			(xy 418.666091 -118.371473) (xy 418.713697 -118.400527) (xy 418.756565 -118.436202) (xy 418.793782 -118.477739)
			(xy 418.824555 -118.524252) (xy 418.848227 -118.574749) (xy 418.864295 -118.628156) (xy 418.872415 -118.683332)
			(xy 418.872924 -118.711218) (xy 418.872415 -118.739104) (xy 418.864295 -118.79428) (xy 418.848227 -118.847687)
			(xy 418.824555 -118.898184) (xy 418.793782 -118.944697) (xy 418.756565 -118.986234) (xy 418.713697 -119.021909)
			(xy 418.666091 -119.050963) (xy 418.614762 -119.072775) (xy 418.560805 -119.086881) (xy 418.505368 -119.092981)
			(xy 418.449634 -119.090944) (xy 418.394791 -119.080814) (xy 418.342007 -119.062807) (xy 418.292407 -119.037306)
			(xy 418.247049 -119.004855) (xy 418.2069 -118.966146) (xy 418.172814 -118.922003) (xy 418.145518 -118.873368)
			(xy 418.125595 -118.821277) (xy 418.113469 -118.76684) (xy 418.109398 -118.711218) (xy 415.815272 -118.711218)
			(xy 415.815272 -119.567198) (xy 415.814782 -119.597182) (xy 415.806954 -119.656638) (xy 415.791433 -119.714563)
			(xy 415.768484 -119.769967) (xy 415.7385 -119.821901) (xy 415.701994 -119.869477) (xy 415.659589 -119.911882)
			(xy 415.612013 -119.948388) (xy 415.560079 -119.978372) (xy 415.504675 -120.001321) (xy 415.44675 -120.016842)
			(xy 415.387294 -120.02467) (xy 415.327326 -120.02467) (xy 415.26787 -120.016842) (xy 415.209945 -120.001321)
			(xy 415.154541 -119.978372) (xy 415.102607 -119.948388) (xy 415.055031 -119.911882) (xy 415.012626 -119.869477)
			(xy 414.97612 -119.821901) (xy 414.946136 -119.769967) (xy 414.923187 -119.714563) (xy 414.907666 -119.656638)
			(xy 414.899838 -119.597182) (xy 414.899348 -119.567198) (xy 411.756735 -119.567198) (xy 411.663896 -121.351548)
			(xy 411.663076 -121.367296) (xy 413.045148 -121.367296) (xy 413.045148 -120.503696) (xy 413.045638 -120.473712)
			(xy 413.053466 -120.414256) (xy 413.068987 -120.356331) (xy 413.091936 -120.300927) (xy 413.12192 -120.248993)
			(xy 413.158426 -120.201417) (xy 413.200831 -120.159012) (xy 413.248407 -120.122506) (xy 413.300341 -120.092522)
			(xy 413.355745 -120.069573) (xy 413.41367 -120.054052) (xy 413.473126 -120.046224) (xy 413.533094 -120.046224)
			(xy 413.59255 -120.054052) (xy 413.650475 -120.069573) (xy 413.705879 -120.092522) (xy 413.757813 -120.122506)
			(xy 413.805389 -120.159012) (xy 413.847794 -120.201417) (xy 413.8843 -120.248993) (xy 413.914284 -120.300927)
			(xy 413.937233 -120.356331) (xy 413.952754 -120.414256) (xy 413.960582 -120.473712) (xy 413.961072 -120.503696)
			(xy 413.961072 -121.367296) (xy 413.960582 -121.39728) (xy 413.952754 -121.456736) (xy 413.937233 -121.514661)
			(xy 413.914284 -121.570065) (xy 413.8843 -121.621999) (xy 413.847794 -121.669575) (xy 413.805389 -121.71198)
			(xy 413.757813 -121.748486) (xy 413.705879 -121.77847) (xy 413.650475 -121.801419) (xy 413.59255 -121.81694)
			(xy 413.533094 -121.824768) (xy 413.473126 -121.824768) (xy 413.41367 -121.81694) (xy 413.355745 -121.801419)
			(xy 413.300341 -121.77847) (xy 413.248407 -121.748486) (xy 413.200831 -121.71198) (xy 413.158426 -121.669575)
			(xy 413.12192 -121.621999) (xy 413.091936 -121.570065) (xy 413.068987 -121.514661) (xy 413.053466 -121.456736)
			(xy 413.045638 -121.39728) (xy 413.045148 -121.367296) (xy 411.663076 -121.367296) (xy 411.597856 -122.61977)
			(xy 411.569269 -123.16714) (xy 414.899348 -123.16714) (xy 414.899348 -122.30354) (xy 414.899838 -122.273556)
			(xy 414.907666 -122.2141) (xy 414.923187 -122.156175) (xy 414.946136 -122.100771) (xy 414.97612 -122.048837)
			(xy 415.012626 -122.001261) (xy 415.055031 -121.958856) (xy 415.102607 -121.92235) (xy 415.154541 -121.892366)
			(xy 415.209945 -121.869417) (xy 415.26787 -121.853896) (xy 415.327326 -121.846068) (xy 415.387294 -121.846068)
			(xy 415.44675 -121.853896) (xy 415.504675 -121.869417) (xy 415.560079 -121.892366) (xy 415.612013 -121.92235)
			(xy 415.659589 -121.958856) (xy 415.701994 -122.001261) (xy 415.7385 -122.048837) (xy 415.768484 -122.100771)
			(xy 415.791433 -122.156175) (xy 415.806954 -122.2141) (xy 415.814782 -122.273556) (xy 415.815272 -122.30354)
			(xy 415.815272 -123.16714) (xy 415.814782 -123.197124) (xy 415.806954 -123.25658) (xy 415.791433 -123.314505)
			(xy 415.768484 -123.369909) (xy 415.7385 -123.421843) (xy 415.701994 -123.469419) (xy 415.659589 -123.511824)
			(xy 415.612013 -123.54833) (xy 415.560079 -123.578314) (xy 415.504675 -123.601263) (xy 415.44675 -123.616784)
			(xy 415.387294 -123.624612) (xy 415.327326 -123.624612) (xy 415.26787 -123.616784) (xy 415.209945 -123.601263)
			(xy 415.154541 -123.578314) (xy 415.102607 -123.54833) (xy 415.055031 -123.511824) (xy 415.012626 -123.469419)
			(xy 414.97612 -123.421843) (xy 414.946136 -123.369909) (xy 414.923187 -123.314505) (xy 414.907666 -123.25658)
			(xy 414.899838 -123.197124) (xy 414.899348 -123.16714) (xy 411.569269 -123.16714) (xy 411.558232 -123.378468)
			(xy 411.475538 -124.967238) (xy 413.045148 -124.967238) (xy 413.045148 -124.103638) (xy 413.045638 -124.073654)
			(xy 413.053466 -124.014198) (xy 413.068987 -123.956273) (xy 413.091936 -123.900869) (xy 413.12192 -123.848935)
			(xy 413.158426 -123.801359) (xy 413.200831 -123.758954) (xy 413.248407 -123.722448) (xy 413.300341 -123.692464)
			(xy 413.355745 -123.669515) (xy 413.41367 -123.653994) (xy 413.473126 -123.646166) (xy 413.533094 -123.646166)
			(xy 413.59255 -123.653994) (xy 413.650475 -123.669515) (xy 413.705879 -123.692464) (xy 413.757813 -123.722448)
			(xy 413.805389 -123.758954) (xy 413.847794 -123.801359) (xy 413.8843 -123.848935) (xy 413.914284 -123.900869)
			(xy 413.937233 -123.956273) (xy 413.952754 -124.014198) (xy 413.960582 -124.073654) (xy 413.961072 -124.103638)
			(xy 413.961072 -124.967238) (xy 413.960582 -124.997222) (xy 413.952754 -125.056678) (xy 413.937233 -125.114603)
			(xy 413.914284 -125.170007) (xy 413.8843 -125.221941) (xy 413.847794 -125.269517) (xy 413.805389 -125.311922)
			(xy 413.757813 -125.348428) (xy 413.705879 -125.378412) (xy 413.650475 -125.401361) (xy 413.59255 -125.416882)
			(xy 413.533094 -125.42471) (xy 413.473126 -125.42471) (xy 413.41367 -125.416882) (xy 413.355745 -125.401361)
			(xy 413.300341 -125.378412) (xy 413.248407 -125.348428) (xy 413.200831 -125.311922) (xy 413.158426 -125.269517)
			(xy 413.12192 -125.221941) (xy 413.091936 -125.170007) (xy 413.068987 -125.114603) (xy 413.053466 -125.056678)
			(xy 413.045638 -124.997222) (xy 413.045148 -124.967238) (xy 411.475538 -124.967238) (xy 411.173132 -130.777234)
			(xy 414.899348 -130.777234) (xy 414.899348 -129.913634) (xy 414.899838 -129.88365) (xy 414.907666 -129.824194)
			(xy 414.923187 -129.766269) (xy 414.946136 -129.710865) (xy 414.97612 -129.658931) (xy 415.012626 -129.611355)
			(xy 415.055031 -129.56895) (xy 415.102607 -129.532444) (xy 415.154541 -129.50246) (xy 415.209945 -129.479511)
			(xy 415.26787 -129.46399) (xy 415.327326 -129.456162) (xy 415.387294 -129.456162) (xy 415.44675 -129.46399)
			(xy 415.504675 -129.479511) (xy 415.560079 -129.50246) (xy 415.612013 -129.532444) (xy 415.659589 -129.56895)
			(xy 415.701994 -129.611355) (xy 415.7385 -129.658931) (xy 415.768484 -129.710865) (xy 415.791433 -129.766269)
			(xy 415.806954 -129.824194) (xy 415.814782 -129.88365) (xy 415.815272 -129.913634) (xy 415.815272 -130.777234)
			(xy 415.814782 -130.807218) (xy 415.806954 -130.866674) (xy 415.791433 -130.924599) (xy 415.768484 -130.980003)
			(xy 415.7385 -131.031937) (xy 415.701994 -131.079513) (xy 415.659589 -131.121918) (xy 415.612013 -131.158424)
			(xy 415.560079 -131.188408) (xy 415.504675 -131.211357) (xy 415.44675 -131.226878) (xy 415.387294 -131.234706)
			(xy 415.327326 -131.234706) (xy 415.26787 -131.226878) (xy 415.209945 -131.211357) (xy 415.154541 -131.188408)
			(xy 415.102607 -131.158424) (xy 415.055031 -131.121918) (xy 415.012626 -131.079513) (xy 414.97612 -131.031937)
			(xy 414.946136 -130.980003) (xy 414.923187 -130.924599) (xy 414.907666 -130.866674) (xy 414.899838 -130.807218)
			(xy 414.899348 -130.777234) (xy 411.173132 -130.777234) (xy 411.079438 -132.577332) (xy 413.045148 -132.577332)
			(xy 413.045148 -131.713732) (xy 413.045638 -131.683748) (xy 413.053466 -131.624292) (xy 413.068987 -131.566367)
			(xy 413.091936 -131.510963) (xy 413.12192 -131.459029) (xy 413.158426 -131.411453) (xy 413.200831 -131.369048)
			(xy 413.248407 -131.332542) (xy 413.300341 -131.302558) (xy 413.355745 -131.279609) (xy 413.41367 -131.264088)
			(xy 413.473126 -131.25626) (xy 413.533094 -131.25626) (xy 413.59255 -131.264088) (xy 413.650475 -131.279609)
			(xy 413.705879 -131.302558) (xy 413.757813 -131.332542) (xy 413.805389 -131.369048) (xy 413.847794 -131.411453)
			(xy 413.8843 -131.459029) (xy 413.914284 -131.510963) (xy 413.937233 -131.566367) (xy 413.952754 -131.624292)
			(xy 413.960582 -131.683748) (xy 413.961072 -131.713732) (xy 413.961072 -132.577332) (xy 413.960582 -132.607316)
			(xy 413.952754 -132.666772) (xy 413.937233 -132.724697) (xy 413.914284 -132.780101) (xy 413.8843 -132.832035)
			(xy 413.847794 -132.879611) (xy 413.805389 -132.922016) (xy 413.757813 -132.958522) (xy 413.705879 -132.988506)
			(xy 413.650475 -133.011455) (xy 413.59255 -133.026976) (xy 413.533094 -133.034804) (xy 413.473126 -133.034804)
			(xy 413.41367 -133.026976) (xy 413.355745 -133.011455) (xy 413.300341 -132.988506) (xy 413.248407 -132.958522)
			(xy 413.200831 -132.922016) (xy 413.158426 -132.879611) (xy 413.12192 -132.832035) (xy 413.091936 -132.780101)
			(xy 413.068987 -132.724697) (xy 413.053466 -132.666772) (xy 413.045638 -132.607316) (xy 413.045148 -132.577332)
			(xy 411.079438 -132.577332) (xy 410.985758 -134.377176) (xy 414.899348 -134.377176) (xy 414.899348 -133.513576)
			(xy 414.899838 -133.483592) (xy 414.907666 -133.424136) (xy 414.923187 -133.366211) (xy 414.946136 -133.310807)
			(xy 414.97612 -133.258873) (xy 415.012626 -133.211297) (xy 415.055031 -133.168892) (xy 415.102607 -133.132386)
			(xy 415.154541 -133.102402) (xy 415.209945 -133.079453) (xy 415.26787 -133.063932) (xy 415.327326 -133.056104)
			(xy 415.387294 -133.056104) (xy 415.44675 -133.063932) (xy 415.504675 -133.079453) (xy 415.560079 -133.102402)
			(xy 415.612013 -133.132386) (xy 415.659589 -133.168892) (xy 415.701994 -133.211297) (xy 415.7385 -133.258873)
			(xy 415.768484 -133.310807) (xy 415.791433 -133.366211) (xy 415.806954 -133.424136) (xy 415.814782 -133.483592)
			(xy 415.815272 -133.513576) (xy 415.815272 -134.377176) (xy 415.814782 -134.40716) (xy 415.806954 -134.466616)
			(xy 415.791433 -134.524541) (xy 415.768484 -134.579945) (xy 415.7385 -134.631879) (xy 415.701994 -134.679455)
			(xy 415.659589 -134.72186) (xy 415.612013 -134.758366) (xy 415.560079 -134.78835) (xy 415.504675 -134.811299)
			(xy 415.44675 -134.82682) (xy 415.387294 -134.834648) (xy 415.327326 -134.834648) (xy 415.26787 -134.82682)
			(xy 415.209945 -134.811299) (xy 415.154541 -134.78835) (xy 415.102607 -134.758366) (xy 415.055031 -134.72186)
			(xy 415.012626 -134.679455) (xy 414.97612 -134.631879) (xy 414.946136 -134.579945) (xy 414.923187 -134.524541)
			(xy 414.907666 -134.466616) (xy 414.899838 -134.40716) (xy 414.899348 -134.377176) (xy 410.985758 -134.377176)
			(xy 410.892064 -136.177274) (xy 413.045148 -136.177274) (xy 413.045148 -135.313674) (xy 413.045638 -135.28369)
			(xy 413.053466 -135.224234) (xy 413.068987 -135.166309) (xy 413.091936 -135.110905) (xy 413.12192 -135.058971)
			(xy 413.158426 -135.011395) (xy 413.200831 -134.96899) (xy 413.248407 -134.932484) (xy 413.300341 -134.9025)
			(xy 413.355745 -134.879551) (xy 413.41367 -134.86403) (xy 413.473126 -134.856202) (xy 413.533094 -134.856202)
			(xy 413.59255 -134.86403) (xy 413.650475 -134.879551) (xy 413.705879 -134.9025) (xy 413.757813 -134.932484)
			(xy 413.805389 -134.96899) (xy 413.847794 -135.011395) (xy 413.8843 -135.058971) (xy 413.914284 -135.110905)
			(xy 413.937233 -135.166309) (xy 413.952754 -135.224234) (xy 413.960582 -135.28369) (xy 413.961072 -135.313674)
			(xy 413.961072 -136.177274) (xy 413.960582 -136.207258) (xy 413.952754 -136.266714) (xy 413.937233 -136.324639)
			(xy 413.914284 -136.380043) (xy 413.8843 -136.431977) (xy 413.847794 -136.479553) (xy 413.805389 -136.521958)
			(xy 413.757813 -136.558464) (xy 413.705879 -136.588448) (xy 413.650475 -136.611397) (xy 413.59255 -136.626918)
			(xy 413.533094 -136.634746) (xy 413.473126 -136.634746) (xy 413.41367 -136.626918) (xy 413.355745 -136.611397)
			(xy 413.300341 -136.588448) (xy 413.248407 -136.558464) (xy 413.200831 -136.521958) (xy 413.158426 -136.479553)
			(xy 413.12192 -136.431977) (xy 413.091936 -136.380043) (xy 413.068987 -136.324639) (xy 413.053466 -136.266714)
			(xy 413.045638 -136.207258) (xy 413.045148 -136.177274) (xy 410.892064 -136.177274) (xy 410.891482 -136.18845)
			(xy 410.861002 -136.776968) (xy 410.837634 -137.225786) (xy 410.825188 -137.465562) (xy 410.824426 -137.48004)
			(xy 410.824172 -137.483088) (xy 410.824172 -137.489946) (xy 410.824629 -137.495034) (xy 410.827321 -137.504886)
			(xy 410.829506 -137.509504) (xy 410.838142 -137.526268) (xy 410.840012 -137.529665) (xy 410.844599 -137.535918)
			(xy 410.847286 -137.538714) (xy 410.85262 -137.544048) (xy 410.875092 -137.561758) (xy 410.914983 -137.602774)
			(xy 410.948312 -137.649279) (xy 410.974334 -137.700234) (xy 410.992468 -137.7545) (xy 411.002307 -137.810862)
			(xy 411.003496 -137.83945) (xy 411.003496 -137.84834) (xy 411.003042 -137.87706) (xy 410.994561 -137.933868)
			(xy 410.977663 -137.988764) (xy 410.952727 -138.040507) (xy 410.920319 -138.087928) (xy 410.881169 -138.129957)
			(xy 410.836163 -138.165643) (xy 410.811472 -138.180318) (xy 410.804868 -138.184128) (xy 410.800804 -138.188446)
			(xy 410.793692 -138.197336) (xy 410.788866 -138.20648) (xy 410.786072 -138.216386) (xy 410.78531 -138.231626)
			(xy 410.78531 -138.232134) (xy 410.782516 -138.284458) (xy 410.781246 -138.30935) (xy 410.779214 -138.34745)
			(xy 410.77515 -138.425936) (xy 410.77515 -138.42746) (xy 410.774134 -138.44651) (xy 410.77388 -138.449812)
			(xy 410.77388 -138.451844) (xy 410.773626 -138.4554) (xy 410.773118 -138.467084) (xy 410.773104 -138.474724)
			(xy 410.777105 -138.489463) (xy 410.780992 -138.49604) (xy 410.782008 -138.498072) (xy 410.793438 -138.517122)
			(xy 410.796604 -138.521485) (xy 410.804412 -138.528916) (xy 410.808932 -138.531854) (xy 410.815536 -138.535664)
			(xy 410.816298 -138.536172) (xy 410.818838 -138.53795) (xy 410.820362 -138.538966) (xy 410.842231 -138.552785)
			(xy 410.882377 -138.58541) (xy 410.917746 -138.623161) (xy 410.947689 -138.665346) (xy 410.960062 -138.688064)
			(xy 410.972822 -138.713624) (xy 410.991447 -138.767628) (xy 411.001816 -138.823806) (xy 411.003696 -138.880901)
			(xy 410.997047 -138.937638) (xy 410.982015 -138.992751) (xy 410.958938 -139.045009) (xy 410.92833 -139.093243)
			(xy 410.890875 -139.136377) (xy 410.84741 -139.173447) (xy 410.798906 -139.203625) (xy 410.772864 -139.215368)
			(xy 410.763212 -139.219432) (xy 410.743146 -139.240514) (xy 410.737558 -139.248642) (xy 410.735466 -139.252772)
			(xy 410.732647 -139.261589) (xy 410.73197 -139.266168) (xy 410.64053 -141.012672) (xy 410.511721 -143.48714)
			(xy 414.899348 -143.48714) (xy 414.899348 -142.62354) (xy 414.899838 -142.593556) (xy 414.907666 -142.5341)
			(xy 414.923187 -142.476175) (xy 414.946136 -142.420771) (xy 414.97612 -142.368837) (xy 415.012626 -142.321261)
			(xy 415.055031 -142.278856) (xy 415.102607 -142.24235) (xy 415.154541 -142.212366) (xy 415.209945 -142.189417)
			(xy 415.26787 -142.173896) (xy 415.327326 -142.166068) (xy 415.387294 -142.166068) (xy 415.44675 -142.173896)
			(xy 415.504675 -142.189417) (xy 415.560079 -142.212366) (xy 415.612013 -142.24235) (xy 415.659589 -142.278856)
			(xy 415.701994 -142.321261) (xy 415.7385 -142.368837) (xy 415.768484 -142.420771) (xy 415.791433 -142.476175)
			(xy 415.806954 -142.5341) (xy 415.814782 -142.593556) (xy 415.815272 -142.62354) (xy 415.815272 -143.48714)
			(xy 415.814782 -143.517124) (xy 415.806954 -143.57658) (xy 415.791433 -143.634505) (xy 415.768484 -143.689909)
			(xy 415.7385 -143.741843) (xy 415.701994 -143.789419) (xy 415.659589 -143.831824) (xy 415.612013 -143.86833)
			(xy 415.560079 -143.898314) (xy 415.504675 -143.921263) (xy 415.44675 -143.936784) (xy 415.387294 -143.944612)
			(xy 415.327326 -143.944612) (xy 415.26787 -143.936784) (xy 415.209945 -143.921263) (xy 415.154541 -143.898314)
			(xy 415.102607 -143.86833) (xy 415.055031 -143.831824) (xy 415.012626 -143.789419) (xy 414.97612 -143.741843)
			(xy 414.946136 -143.689909) (xy 414.923187 -143.634505) (xy 414.907666 -143.57658) (xy 414.899838 -143.517124)
			(xy 414.899348 -143.48714) (xy 410.511721 -143.48714) (xy 410.418017 -145.287238) (xy 413.045148 -145.287238)
			(xy 413.045148 -144.423638) (xy 413.045638 -144.393654) (xy 413.053466 -144.334198) (xy 413.068987 -144.276273)
			(xy 413.091936 -144.220869) (xy 413.12192 -144.168935) (xy 413.158426 -144.121359) (xy 413.200831 -144.078954)
			(xy 413.248407 -144.042448) (xy 413.300341 -144.012464) (xy 413.355745 -143.989515) (xy 413.41367 -143.973994)
			(xy 413.473126 -143.966166) (xy 413.533094 -143.966166) (xy 413.59255 -143.973994) (xy 413.650475 -143.989515)
			(xy 413.705879 -144.012464) (xy 413.757813 -144.042448) (xy 413.805389 -144.078954) (xy 413.847794 -144.121359)
			(xy 413.8843 -144.168935) (xy 413.914284 -144.220869) (xy 413.937233 -144.276273) (xy 413.952754 -144.334198)
			(xy 413.960582 -144.393654) (xy 413.961072 -144.423638) (xy 413.961072 -145.287238) (xy 413.960582 -145.317222)
			(xy 413.952754 -145.376678) (xy 413.937233 -145.434603) (xy 413.914284 -145.490007) (xy 413.8843 -145.541941)
			(xy 413.847794 -145.589517) (xy 413.805389 -145.631922) (xy 413.757813 -145.668428) (xy 413.705879 -145.698412)
			(xy 413.650475 -145.721361) (xy 413.59255 -145.736882) (xy 413.533094 -145.74471) (xy 413.473126 -145.74471)
			(xy 413.41367 -145.736882) (xy 413.355745 -145.721361) (xy 413.300341 -145.698412) (xy 413.248407 -145.668428)
			(xy 413.200831 -145.631922) (xy 413.158426 -145.589517) (xy 413.12192 -145.541941) (xy 413.091936 -145.490007)
			(xy 413.068987 -145.434603) (xy 413.053466 -145.376678) (xy 413.045638 -145.317222) (xy 413.045148 -145.287238)
			(xy 410.418017 -145.287238) (xy 410.324313 -147.087336) (xy 414.899348 -147.087336) (xy 414.899348 -146.223736)
			(xy 414.899838 -146.193752) (xy 414.907666 -146.134296) (xy 414.923187 -146.076371) (xy 414.946136 -146.020967)
			(xy 414.97612 -145.969033) (xy 415.012626 -145.921457) (xy 415.055031 -145.879052) (xy 415.102607 -145.842546)
			(xy 415.154541 -145.812562) (xy 415.209945 -145.789613) (xy 415.26787 -145.774092) (xy 415.327326 -145.766264)
			(xy 415.387294 -145.766264) (xy 415.44675 -145.774092) (xy 415.504675 -145.789613) (xy 415.560079 -145.812562)
			(xy 415.612013 -145.842546) (xy 415.659589 -145.879052) (xy 415.701994 -145.921457) (xy 415.7385 -145.969033)
			(xy 415.768484 -146.020967) (xy 415.791433 -146.076371) (xy 415.806954 -146.134296) (xy 415.814782 -146.193752)
			(xy 415.815272 -146.223736) (xy 415.815272 -147.087336) (xy 415.814782 -147.11732) (xy 415.806954 -147.176776)
			(xy 415.791433 -147.234701) (xy 415.768484 -147.290105) (xy 415.7385 -147.342039) (xy 415.701994 -147.389615)
			(xy 415.659589 -147.43202) (xy 415.612013 -147.468526) (xy 415.560079 -147.49851) (xy 415.504675 -147.521459)
			(xy 415.44675 -147.53698) (xy 415.387294 -147.544808) (xy 415.327326 -147.544808) (xy 415.26787 -147.53698)
			(xy 415.209945 -147.521459) (xy 415.154541 -147.49851) (xy 415.102607 -147.468526) (xy 415.055031 -147.43202)
			(xy 415.012626 -147.389615) (xy 414.97612 -147.342039) (xy 414.946136 -147.290105) (xy 414.923187 -147.234701)
			(xy 414.907666 -147.176776) (xy 414.899838 -147.11732) (xy 414.899348 -147.087336) (xy 410.324313 -147.087336)
			(xy 410.303726 -147.482814) (xy 410.293058 -147.688554) (xy 410.230681 -148.887434) (xy 413.045148 -148.887434)
			(xy 413.045148 -148.023834) (xy 413.045638 -147.99385) (xy 413.053466 -147.934394) (xy 413.068987 -147.876469)
			(xy 413.091936 -147.821065) (xy 413.12192 -147.769131) (xy 413.158426 -147.721555) (xy 413.200831 -147.67915)
			(xy 413.248407 -147.642644) (xy 413.300341 -147.61266) (xy 413.355745 -147.589711) (xy 413.41367 -147.57419)
			(xy 413.473126 -147.566362) (xy 413.533094 -147.566362) (xy 413.59255 -147.57419) (xy 413.650475 -147.589711)
			(xy 413.705879 -147.61266) (xy 413.757813 -147.642644) (xy 413.805389 -147.67915) (xy 413.847794 -147.721555)
			(xy 413.8843 -147.769131) (xy 413.914284 -147.821065) (xy 413.937233 -147.876469) (xy 413.952754 -147.934394)
			(xy 413.960582 -147.99385) (xy 413.961072 -148.023834) (xy 413.961072 -148.887434) (xy 413.960582 -148.917418)
			(xy 413.952754 -148.976874) (xy 413.937233 -149.034799) (xy 413.914284 -149.090203) (xy 413.8843 -149.142137)
			(xy 413.847794 -149.189713) (xy 413.805389 -149.232118) (xy 413.757813 -149.268624) (xy 413.705879 -149.298608)
			(xy 413.650475 -149.321557) (xy 413.59255 -149.337078) (xy 413.533094 -149.344906) (xy 413.473126 -149.344906)
			(xy 413.41367 -149.337078) (xy 413.355745 -149.321557) (xy 413.300341 -149.298608) (xy 413.248407 -149.268624)
			(xy 413.200831 -149.232118) (xy 413.158426 -149.189713) (xy 413.12192 -149.142137) (xy 413.091936 -149.090203)
			(xy 413.068987 -149.034799) (xy 413.053466 -148.976874) (xy 413.045638 -148.917418) (xy 413.045148 -148.887434)
			(xy 410.230681 -148.887434) (xy 410.137036 -150.687278) (xy 414.899348 -150.687278) (xy 414.899348 -149.823678)
			(xy 414.899838 -149.793694) (xy 414.907666 -149.734238) (xy 414.923187 -149.676313) (xy 414.946136 -149.620909)
			(xy 414.97612 -149.568975) (xy 415.012626 -149.521399) (xy 415.055031 -149.478994) (xy 415.102607 -149.442488)
			(xy 415.154541 -149.412504) (xy 415.209945 -149.389555) (xy 415.26787 -149.374034) (xy 415.327326 -149.366206)
			(xy 415.387294 -149.366206) (xy 415.44675 -149.374034) (xy 415.504675 -149.389555) (xy 415.560079 -149.412504)
			(xy 415.612013 -149.442488) (xy 415.659589 -149.478994) (xy 415.701994 -149.521399) (xy 415.7385 -149.568975)
			(xy 415.768484 -149.620909) (xy 415.791433 -149.676313) (xy 415.806954 -149.734238) (xy 415.814782 -149.793694)
			(xy 415.815272 -149.823678) (xy 415.815272 -150.687278) (xy 415.814782 -150.717262) (xy 415.806954 -150.776718)
			(xy 415.791433 -150.834643) (xy 415.768484 -150.890047) (xy 415.7385 -150.941981) (xy 415.701994 -150.989557)
			(xy 415.659589 -151.031962) (xy 415.612013 -151.068468) (xy 415.560079 -151.098452) (xy 415.504675 -151.121401)
			(xy 415.44675 -151.136922) (xy 415.387294 -151.14475) (xy 415.327326 -151.14475) (xy 415.26787 -151.136922)
			(xy 415.209945 -151.121401) (xy 415.154541 -151.098452) (xy 415.102607 -151.068468) (xy 415.055031 -151.031962)
			(xy 415.012626 -150.989557) (xy 414.97612 -150.941981) (xy 414.946136 -150.890047) (xy 414.923187 -150.834643)
			(xy 414.907666 -150.776718) (xy 414.899838 -150.717262) (xy 414.899348 -150.687278) (xy 410.137036 -150.687278)
			(xy 410.086302 -151.662384) (xy 410.043429 -152.487376) (xy 413.045148 -152.487376) (xy 413.045148 -151.623776)
			(xy 413.045638 -151.593792) (xy 413.053466 -151.534336) (xy 413.068987 -151.476411) (xy 413.091936 -151.421007)
			(xy 413.12192 -151.369073) (xy 413.158426 -151.321497) (xy 413.200831 -151.279092) (xy 413.248407 -151.242586)
			(xy 413.300341 -151.212602) (xy 413.355745 -151.189653) (xy 413.41367 -151.174132) (xy 413.473126 -151.166304)
			(xy 413.533094 -151.166304) (xy 413.59255 -151.174132) (xy 413.650475 -151.189653) (xy 413.705879 -151.212602)
			(xy 413.757813 -151.242586) (xy 413.805389 -151.279092) (xy 413.847794 -151.321497) (xy 413.8843 -151.369073)
			(xy 413.914284 -151.421007) (xy 413.937233 -151.476411) (xy 413.952754 -151.534336) (xy 413.960582 -151.593792)
			(xy 413.961072 -151.623776) (xy 413.961072 -152.487376) (xy 413.960582 -152.51736) (xy 413.952754 -152.576816)
			(xy 413.937233 -152.634741) (xy 413.914284 -152.690145) (xy 413.8843 -152.742079) (xy 413.847794 -152.789655)
			(xy 413.805389 -152.83206) (xy 413.757813 -152.868566) (xy 413.705879 -152.89855) (xy 413.650475 -152.921499)
			(xy 413.59255 -152.93702) (xy 413.533094 -152.944848) (xy 413.473126 -152.944848) (xy 413.41367 -152.93702)
			(xy 413.355745 -152.921499) (xy 413.300341 -152.89855) (xy 413.248407 -152.868566) (xy 413.200831 -152.83206)
			(xy 413.158426 -152.789655) (xy 413.12192 -152.742079) (xy 413.091936 -152.690145) (xy 413.068987 -152.634741)
			(xy 413.053466 -152.576816) (xy 413.045638 -152.51736) (xy 413.045148 -152.487376) (xy 410.043429 -152.487376)
			(xy 409.98902 -153.534364) (xy 409.949805 -154.28722) (xy 414.899348 -154.28722) (xy 414.899348 -153.42362)
			(xy 414.899838 -153.393636) (xy 414.907666 -153.33418) (xy 414.923187 -153.276255) (xy 414.946136 -153.220851)
			(xy 414.97612 -153.168917) (xy 415.012626 -153.121341) (xy 415.055031 -153.078936) (xy 415.102607 -153.04243)
			(xy 415.154541 -153.012446) (xy 415.209945 -152.989497) (xy 415.26787 -152.973976) (xy 415.327326 -152.966148)
			(xy 415.387294 -152.966148) (xy 415.44675 -152.973976) (xy 415.504675 -152.989497) (xy 415.560079 -153.012446)
			(xy 415.612013 -153.04243) (xy 415.659589 -153.078936) (xy 415.701994 -153.121341) (xy 415.7385 -153.168917)
			(xy 415.768484 -153.220851) (xy 415.791433 -153.276255) (xy 415.806954 -153.33418) (xy 415.814782 -153.393636)
			(xy 415.815272 -153.42362) (xy 415.815272 -154.28722) (xy 415.814782 -154.317204) (xy 415.806954 -154.37666)
			(xy 415.791433 -154.434585) (xy 415.768484 -154.489989) (xy 415.7385 -154.541923) (xy 415.701994 -154.589499)
			(xy 415.659589 -154.631904) (xy 415.612013 -154.66841) (xy 415.560079 -154.698394) (xy 415.504675 -154.721343)
			(xy 415.44675 -154.736864) (xy 415.387294 -154.744692) (xy 415.327326 -154.744692) (xy 415.26787 -154.736864)
			(xy 415.209945 -154.721343) (xy 415.154541 -154.698394) (xy 415.102607 -154.66841) (xy 415.055031 -154.631904)
			(xy 415.012626 -154.589499) (xy 414.97612 -154.541923) (xy 414.946136 -154.489989) (xy 414.923187 -154.434585)
			(xy 414.907666 -154.37666) (xy 414.899838 -154.317204) (xy 414.899348 -154.28722) (xy 409.949805 -154.28722)
			(xy 409.933902 -154.592528) (xy 409.919424 -154.869896) (xy 409.873196 -155.759404) (xy 409.856138 -156.087318)
			(xy 413.045148 -156.087318) (xy 413.045148 -155.223718) (xy 413.045638 -155.193734) (xy 413.053466 -155.134278)
			(xy 413.068987 -155.076353) (xy 413.091936 -155.020949) (xy 413.12192 -154.969015) (xy 413.158426 -154.921439)
			(xy 413.200831 -154.879034) (xy 413.248407 -154.842528) (xy 413.300341 -154.812544) (xy 413.355745 -154.789595)
			(xy 413.41367 -154.774074) (xy 413.473126 -154.766246) (xy 413.533094 -154.766246) (xy 413.59255 -154.774074)
			(xy 413.650475 -154.789595) (xy 413.705879 -154.812544) (xy 413.757813 -154.842528) (xy 413.805389 -154.879034)
			(xy 413.847794 -154.921439) (xy 413.8843 -154.969015) (xy 413.914284 -155.020949) (xy 413.937233 -155.076353)
			(xy 413.952754 -155.134278) (xy 413.960582 -155.193734) (xy 413.961072 -155.223718) (xy 413.961072 -156.087318)
			(xy 413.960582 -156.117302) (xy 413.952754 -156.176758) (xy 413.937233 -156.234683) (xy 413.914284 -156.290087)
			(xy 413.8843 -156.342021) (xy 413.847794 -156.389597) (xy 413.805389 -156.432002) (xy 413.757813 -156.468508)
			(xy 413.705879 -156.498492) (xy 413.650475 -156.521441) (xy 413.59255 -156.536962) (xy 413.533094 -156.54479)
			(xy 413.473126 -156.54479) (xy 413.41367 -156.536962) (xy 413.355745 -156.521441) (xy 413.300341 -156.498492)
			(xy 413.248407 -156.468508) (xy 413.200831 -156.432002) (xy 413.158426 -156.389597) (xy 413.12192 -156.342021)
			(xy 413.091936 -156.290087) (xy 413.068987 -156.234683) (xy 413.053466 -156.176758) (xy 413.045638 -156.117302)
			(xy 413.045148 -156.087318) (xy 409.856138 -156.087318) (xy 409.847034 -156.262324) (xy 409.83154 -156.558234)
			(xy 409.831286 -156.564076) (xy 409.83027 -156.582364) (xy 409.83027 -156.587444) (xy 409.830957 -156.598892)
			(xy 409.84097 -156.619489) (xy 409.849574 -156.627068) (xy 409.852876 -156.629608) (xy 409.916884 -156.67736)
			(xy 409.921202 -156.679392) (xy 409.922726 -156.680154) (xy 409.928051 -156.682618) (xy 409.939467 -156.685317)
			(xy 409.945332 -156.685488) (xy 409.965144 -156.685488) (xy 409.973018 -156.682948) (xy 410.002104 -156.673945)
			(xy 410.06221 -156.664246) (xy 410.092652 -156.663644) (xy 410.119907 -156.664126) (xy 410.173862 -156.671877)
			(xy 410.226165 -156.687228) (xy 410.275752 -156.709865) (xy 410.321612 -156.73933) (xy 410.362812 -156.77502)
			(xy 410.398513 -156.816211) (xy 410.427989 -156.862064) (xy 410.450639 -156.911644) (xy 410.466002 -156.963944)
			(xy 410.473767 -157.017897) (xy 410.47416 -157.045152) (xy 410.726634 -157.045152) (xy 410.730705 -156.98953)
			(xy 410.742831 -156.935093) (xy 410.762754 -156.883002) (xy 410.79005 -156.834367) (xy 410.824136 -156.790224)
			(xy 410.864285 -156.751515) (xy 410.909643 -156.719064) (xy 410.959243 -156.693563) (xy 411.012027 -156.675556)
			(xy 411.06687 -156.665426) (xy 411.122604 -156.663389) (xy 411.178041 -156.669489) (xy 411.231998 -156.683595)
			(xy 411.283327 -156.705407) (xy 411.330933 -156.734461) (xy 411.373801 -156.770136) (xy 411.411018 -156.811673)
			(xy 411.441791 -156.858186) (xy 411.465463 -156.908683) (xy 411.481531 -156.96209) (xy 411.489651 -157.017266)
			(xy 411.49016 -157.045152) (xy 411.489651 -157.073038) (xy 411.481531 -157.128214) (xy 411.465463 -157.181621)
			(xy 411.441791 -157.232118) (xy 411.411018 -157.278631) (xy 411.373801 -157.320168) (xy 411.330933 -157.355843)
			(xy 411.283327 -157.384897) (xy 411.231998 -157.406709) (xy 411.178041 -157.420815) (xy 411.122604 -157.426915)
			(xy 411.06687 -157.424878) (xy 411.012027 -157.414748) (xy 410.959243 -157.396741) (xy 410.909643 -157.37124)
			(xy 410.864285 -157.338789) (xy 410.824136 -157.30008) (xy 410.79005 -157.255937) (xy 410.762754 -157.207302)
			(xy 410.742831 -157.155211) (xy 410.730705 -157.100774) (xy 410.726634 -157.045152) (xy 410.47416 -157.045152)
			(xy 410.473701 -157.071981) (xy 410.46618 -157.125108) (xy 410.451295 -157.176659) (xy 410.429337 -157.225618)
			(xy 410.40074 -157.27102) (xy 410.366067 -157.31197) (xy 410.326002 -157.347661) (xy 410.281334 -157.377391)
			(xy 410.232943 -157.400573) (xy 410.181782 -157.41675) (xy 410.128861 -157.425605) (xy 410.10205 -157.42666)
			(xy 410.093414 -157.42666) (xy 410.065988 -157.426233) (xy 410.011688 -157.418486) (xy 409.959051 -157.403064)
			(xy 409.933902 -157.392116) (xy 409.929076 -157.38983) (xy 409.91536 -157.386782) (xy 409.906989 -157.385529)
			(xy 409.890255 -157.388007) (xy 409.882594 -157.391608) (xy 409.83535 -157.419294) (xy 409.834842 -157.419294)
			(xy 409.805632 -157.43682) (xy 409.79791 -157.442715) (xy 409.787197 -157.458902) (xy 409.784804 -157.468316)
			(xy 409.784042 -157.473142) (xy 409.67025 -159.65678) (xy 409.642755 -160.1851) (xy 418.188915 -160.1851)
			(xy 418.192871 -160.093241) (xy 418.204708 -160.002062) (xy 418.22434 -159.912238) (xy 418.251621 -159.824435)
			(xy 418.286349 -159.739302) (xy 418.328267 -159.657469) (xy 418.377065 -159.579542) (xy 418.43238 -159.506099)
			(xy 418.493805 -159.437683) (xy 418.560884 -159.374801) (xy 418.633119 -159.317918) (xy 418.709978 -159.267455)
			(xy 418.79089 -159.223786) (xy 418.875256 -159.187234) (xy 418.962452 -159.15807) (xy 419.051833 -159.13651)
			(xy 419.142736 -159.122714) (xy 419.234489 -159.116782) (xy 419.326411 -159.118761) (xy 419.417824 -159.128634)
			(xy 419.508049 -159.146329) (xy 419.59642 -159.171714) (xy 419.68228 -159.204602) (xy 419.764996 -159.24475)
			(xy 419.843954 -159.291859) (xy 419.918571 -159.345582) (xy 419.988292 -159.40552) (xy 420.052603 -159.47123)
			(xy 420.111028 -159.542226) (xy 420.163133 -159.61798) (xy 420.208532 -159.697934) (xy 420.246891 -159.781494)
			(xy 420.277924 -159.868043) (xy 420.301402 -159.956939) (xy 420.317152 -160.047524) (xy 420.325056 -160.139128)
			(xy 420.32555 -160.1851) (xy 420.325056 -160.231072) (xy 420.317152 -160.322676) (xy 420.301402 -160.413261)
			(xy 420.277924 -160.502157) (xy 420.246891 -160.588706) (xy 420.208532 -160.672266) (xy 420.163133 -160.75222)
			(xy 420.111028 -160.827974) (xy 420.052603 -160.89897) (xy 419.988292 -160.96468) (xy 419.918571 -161.024618)
			(xy 419.843954 -161.078341) (xy 419.764996 -161.12545) (xy 419.68228 -161.165598) (xy 419.59642 -161.198486)
			(xy 419.508049 -161.223871) (xy 419.417824 -161.241566) (xy 419.326411 -161.251439) (xy 419.234489 -161.253418)
			(xy 419.142736 -161.247486) (xy 419.051833 -161.23369) (xy 418.962452 -161.21213) (xy 418.875256 -161.182966)
			(xy 418.79089 -161.146414) (xy 418.709978 -161.102745) (xy 418.633119 -161.052282) (xy 418.560884 -160.995399)
			(xy 418.493805 -160.932517) (xy 418.43238 -160.864101) (xy 418.377065 -160.790658) (xy 418.328267 -160.712731)
			(xy 418.286349 -160.630898) (xy 418.251621 -160.545765) (xy 418.22434 -160.457962) (xy 418.204708 -160.368138)
			(xy 418.192871 -160.276959) (xy 418.188915 -160.1851) (xy 409.642755 -160.1851) (xy 409.555696 -161.857944)
			(xy 409.476207 -163.386008) (xy 412.932878 -163.386008) (xy 412.936949 -163.330386) (xy 412.949075 -163.275949)
			(xy 412.968998 -163.223858) (xy 412.996294 -163.175223) (xy 413.03038 -163.13108) (xy 413.070529 -163.092371)
			(xy 413.115887 -163.05992) (xy 413.165487 -163.034419) (xy 413.218271 -163.016412) (xy 413.273114 -163.006282)
			(xy 413.328848 -163.004245) (xy 413.384285 -163.010345) (xy 413.438242 -163.024451) (xy 413.489571 -163.046263)
			(xy 413.537177 -163.075317) (xy 413.580045 -163.110992) (xy 413.617262 -163.152529) (xy 413.648035 -163.199042)
			(xy 413.671707 -163.249539) (xy 413.687775 -163.302946) (xy 413.695895 -163.358122) (xy 413.696404 -163.386008)
			(xy 413.695895 -163.413894) (xy 413.687775 -163.46907) (xy 413.671707 -163.522477) (xy 413.648035 -163.572974)
			(xy 413.617262 -163.619487) (xy 413.580045 -163.661024) (xy 413.537177 -163.696699) (xy 413.489571 -163.725753)
			(xy 413.438242 -163.747565) (xy 413.384285 -163.761671) (xy 413.328848 -163.767771) (xy 413.273114 -163.765734)
			(xy 413.218271 -163.755604) (xy 413.165487 -163.737597) (xy 413.115887 -163.712096) (xy 413.070529 -163.679645)
			(xy 413.03038 -163.640936) (xy 412.996294 -163.596793) (xy 412.968998 -163.548158) (xy 412.949075 -163.496067)
			(xy 412.936949 -163.44163) (xy 412.932878 -163.386008) (xy 409.476207 -163.386008) (xy 409.40355 -164.782754)
			(xy 409.30449 -166.684452) (xy 409.303393 -166.705534) (xy 409.41193 -166.705534) (xy 409.416001 -166.649912)
			(xy 409.428127 -166.595475) (xy 409.44805 -166.543384) (xy 409.475346 -166.494749) (xy 409.509432 -166.450606)
			(xy 409.549581 -166.411897) (xy 409.594939 -166.379446) (xy 409.644539 -166.353945) (xy 409.697323 -166.335938)
			(xy 409.752166 -166.325808) (xy 409.8079 -166.323771) (xy 409.863337 -166.329871) (xy 409.917294 -166.343977)
			(xy 409.968623 -166.365789) (xy 410.016229 -166.394843) (xy 410.059097 -166.430518) (xy 410.096314 -166.472055)
			(xy 410.127087 -166.518568) (xy 410.150759 -166.569065) (xy 410.166827 -166.622472) (xy 410.174947 -166.677648)
			(xy 410.175456 -166.705534) (xy 410.42793 -166.705534) (xy 410.432001 -166.649912) (xy 410.444127 -166.595475)
			(xy 410.46405 -166.543384) (xy 410.491346 -166.494749) (xy 410.525432 -166.450606) (xy 410.565581 -166.411897)
			(xy 410.610939 -166.379446) (xy 410.660539 -166.353945) (xy 410.713323 -166.335938) (xy 410.768166 -166.325808)
			(xy 410.8239 -166.323771) (xy 410.879337 -166.329871) (xy 410.933294 -166.343977) (xy 410.984623 -166.365789)
			(xy 411.032229 -166.394843) (xy 411.075097 -166.430518) (xy 411.112314 -166.472055) (xy 411.143087 -166.518568)
			(xy 411.166759 -166.569065) (xy 411.182827 -166.622472) (xy 411.190947 -166.677648) (xy 411.191456 -166.705534)
			(xy 411.44393 -166.705534) (xy 411.448001 -166.649912) (xy 411.460127 -166.595475) (xy 411.48005 -166.543384)
			(xy 411.507346 -166.494749) (xy 411.541432 -166.450606) (xy 411.581581 -166.411897) (xy 411.626939 -166.379446)
			(xy 411.676539 -166.353945) (xy 411.729323 -166.335938) (xy 411.784166 -166.325808) (xy 411.8399 -166.323771)
			(xy 411.895337 -166.329871) (xy 411.949294 -166.343977) (xy 412.000623 -166.365789) (xy 412.048229 -166.394843)
			(xy 412.091097 -166.430518) (xy 412.128314 -166.472055) (xy 412.159087 -166.518568) (xy 412.182759 -166.569065)
			(xy 412.198827 -166.622472) (xy 412.206947 -166.677648) (xy 412.207456 -166.705534) (xy 412.206947 -166.73342)
			(xy 412.198827 -166.788596) (xy 412.182759 -166.842003) (xy 412.159087 -166.8925) (xy 412.128314 -166.939013)
			(xy 412.091097 -166.98055) (xy 412.048229 -167.016225) (xy 412.000623 -167.045279) (xy 411.949294 -167.067091)
			(xy 411.895337 -167.081197) (xy 411.8399 -167.087297) (xy 411.784166 -167.08526) (xy 411.729323 -167.07513)
			(xy 411.676539 -167.057123) (xy 411.626939 -167.031622) (xy 411.581581 -166.999171) (xy 411.541432 -166.960462)
			(xy 411.507346 -166.916319) (xy 411.48005 -166.867684) (xy 411.460127 -166.815593) (xy 411.448001 -166.761156)
			(xy 411.44393 -166.705534) (xy 411.191456 -166.705534) (xy 411.190947 -166.73342) (xy 411.182827 -166.788596)
			(xy 411.166759 -166.842003) (xy 411.143087 -166.8925) (xy 411.112314 -166.939013) (xy 411.075097 -166.98055)
			(xy 411.032229 -167.016225) (xy 410.984623 -167.045279) (xy 410.933294 -167.067091) (xy 410.879337 -167.081197)
			(xy 410.8239 -167.087297) (xy 410.768166 -167.08526) (xy 410.713323 -167.07513) (xy 410.660539 -167.057123)
			(xy 410.610939 -167.031622) (xy 410.565581 -166.999171) (xy 410.525432 -166.960462) (xy 410.491346 -166.916319)
			(xy 410.46405 -166.867684) (xy 410.444127 -166.815593) (xy 410.432001 -166.761156) (xy 410.42793 -166.705534)
			(xy 410.175456 -166.705534) (xy 410.174947 -166.73342) (xy 410.166827 -166.788596) (xy 410.150759 -166.842003)
			(xy 410.127087 -166.8925) (xy 410.096314 -166.939013) (xy 410.059097 -166.98055) (xy 410.016229 -167.016225)
			(xy 409.968623 -167.045279) (xy 409.917294 -167.067091) (xy 409.863337 -167.081197) (xy 409.8079 -167.087297)
			(xy 409.752166 -167.08526) (xy 409.697323 -167.07513) (xy 409.644539 -167.057123) (xy 409.594939 -167.031622)
			(xy 409.549581 -166.999171) (xy 409.509432 -166.960462) (xy 409.475346 -166.916319) (xy 409.44805 -166.867684)
			(xy 409.428127 -166.815593) (xy 409.416001 -166.761156) (xy 409.41193 -166.705534) (xy 409.303393 -166.705534)
			(xy 409.01082 -172.329348) (xy 410.148022 -172.329348) (xy 410.152093 -172.273726) (xy 410.164219 -172.219289)
			(xy 410.184142 -172.167198) (xy 410.211438 -172.118563) (xy 410.245524 -172.07442) (xy 410.285673 -172.035711)
			(xy 410.331031 -172.00326) (xy 410.380631 -171.977759) (xy 410.433415 -171.959752) (xy 410.488258 -171.949622)
			(xy 410.543992 -171.947585) (xy 410.599429 -171.953685) (xy 410.653386 -171.967791) (xy 410.704715 -171.989603)
			(xy 410.752321 -172.018657) (xy 410.795189 -172.054332) (xy 410.832406 -172.095869) (xy 410.863179 -172.142382)
			(xy 410.886851 -172.192879) (xy 410.902919 -172.246286) (xy 410.911039 -172.301462) (xy 410.911548 -172.329348)
			(xy 410.911284 -172.343826) (xy 411.085282 -172.343826) (xy 411.089353 -172.288204) (xy 411.101479 -172.233767)
			(xy 411.121402 -172.181676) (xy 411.148698 -172.133041) (xy 411.182784 -172.088898) (xy 411.222933 -172.050189)
			(xy 411.268291 -172.017738) (xy 411.317891 -171.992237) (xy 411.370675 -171.97423) (xy 411.425518 -171.9641)
			(xy 411.481252 -171.962063) (xy 411.536689 -171.968163) (xy 411.590646 -171.982269) (xy 411.641975 -172.004081)
			(xy 411.689581 -172.033135) (xy 411.732449 -172.06881) (xy 411.769666 -172.110347) (xy 411.800439 -172.15686)
			(xy 411.824111 -172.207357) (xy 411.840179 -172.260764) (xy 411.848299 -172.31594) (xy 411.848808 -172.343826)
			(xy 411.848299 -172.371712) (xy 411.840179 -172.426888) (xy 411.824111 -172.480295) (xy 411.800439 -172.530792)
			(xy 411.769666 -172.577305) (xy 411.732449 -172.618842) (xy 411.689581 -172.654517) (xy 411.641975 -172.683571)
			(xy 411.590646 -172.705383) (xy 411.536689 -172.719489) (xy 411.481252 -172.725589) (xy 411.425518 -172.723552)
			(xy 411.370675 -172.713422) (xy 411.317891 -172.695415) (xy 411.268291 -172.669914) (xy 411.222933 -172.637463)
			(xy 411.182784 -172.598754) (xy 411.148698 -172.554611) (xy 411.121402 -172.505976) (xy 411.101479 -172.453885)
			(xy 411.089353 -172.399448) (xy 411.085282 -172.343826) (xy 410.911284 -172.343826) (xy 410.911039 -172.357234)
			(xy 410.902919 -172.41241) (xy 410.886851 -172.465817) (xy 410.863179 -172.516314) (xy 410.832406 -172.562827)
			(xy 410.795189 -172.604364) (xy 410.752321 -172.640039) (xy 410.704715 -172.669093) (xy 410.653386 -172.690905)
			(xy 410.599429 -172.705011) (xy 410.543992 -172.711111) (xy 410.488258 -172.709074) (xy 410.433415 -172.698944)
			(xy 410.380631 -172.680937) (xy 410.331031 -172.655436) (xy 410.285673 -172.622985) (xy 410.245524 -172.584276)
			(xy 410.211438 -172.540133) (xy 410.184142 -172.491498) (xy 410.164219 -172.439407) (xy 410.152093 -172.38497)
			(xy 410.148022 -172.329348) (xy 409.01082 -172.329348) (xy 408.935936 -173.768766) (xy 408.936178 -173.777501)
			(xy 408.941802 -173.794033) (xy 408.952622 -173.80774) (xy 408.959812 -173.812708) (xy 409.024582 -173.853094)
			(xy 409.030698 -173.856572) (xy 409.044222 -173.860431) (xy 409.051252 -173.860714) (xy 409.077922 -173.860714)
			(xy 409.086304 -173.858682) (xy 409.09367 -173.854872) (xy 409.121089 -173.841276) (xy 409.179182 -173.822027)
			(xy 409.2396 -173.812286) (xy 409.2702 -173.811692) (xy 409.270708 -173.811692) (xy 409.271216 -173.811692)
			(xy 409.271724 -173.811692) (xy 409.278328 -173.811692) (xy 409.305391 -173.812451) (xy 409.358904 -173.820669)
			(xy 409.410717 -173.836371) (xy 409.45979 -173.859238) (xy 409.505138 -173.888814) (xy 409.545849 -173.924503)
			(xy 409.581106 -173.965589) (xy 409.610201 -174.011246) (xy 409.63255 -174.060558) (xy 409.647703 -174.112534)
			(xy 409.655356 -174.16613) (xy 409.655772 -174.1932) (xy 409.655309 -174.220452) (xy 409.647551 -174.274401)
			(xy 409.632195 -174.326697) (xy 409.609552 -174.376275) (xy 409.580084 -174.422125) (xy 409.544389 -174.463315)
			(xy 409.503196 -174.499005) (xy 409.457343 -174.528469) (xy 409.407763 -174.551108) (xy 409.355466 -174.566459)
			(xy 409.301516 -174.574211) (xy 409.274264 -174.574708) (xy 409.27401 -174.574708) (xy 409.244806 -174.574126)
			(xy 409.187085 -174.565184) (xy 409.131395 -174.547569) (xy 409.079031 -174.52169) (xy 409.054808 -174.505366)
			(xy 409.052014 -174.503334) (xy 409.045918 -174.500032) (xy 409.03597 -174.495824) (xy 409.014395 -174.495279)
			(xy 409.004262 -174.499016) (xy 408.97683 -174.512224) (xy 408.93619 -174.532036) (xy 408.932126 -174.534068)
			(xy 408.923744 -174.538132) (xy 408.921204 -174.539656) (xy 408.9146 -174.543212) (xy 408.90825 -174.549562)
			(xy 408.901973 -174.556477) (xy 408.894421 -174.57354) (xy 408.893518 -174.582836) (xy 408.828579 -175.83023)
			(xy 410.059884 -175.83023) (xy 410.063955 -175.774608) (xy 410.076081 -175.720171) (xy 410.096004 -175.66808)
			(xy 410.1233 -175.619445) (xy 410.157386 -175.575302) (xy 410.197535 -175.536593) (xy 410.242893 -175.504142)
			(xy 410.292493 -175.478641) (xy 410.345277 -175.460634) (xy 410.40012 -175.450504) (xy 410.455854 -175.448467)
			(xy 410.511291 -175.454567) (xy 410.565248 -175.468673) (xy 410.616577 -175.490485) (xy 410.664183 -175.519539)
			(xy 410.707051 -175.555214) (xy 410.744268 -175.596751) (xy 410.775041 -175.643264) (xy 410.798713 -175.693761)
			(xy 410.814781 -175.747168) (xy 410.822901 -175.802344) (xy 410.82341 -175.83023) (xy 410.822901 -175.858116)
			(xy 410.814781 -175.913292) (xy 410.798713 -175.966699) (xy 410.775041 -176.017196) (xy 410.744268 -176.063709)
			(xy 410.707051 -176.105246) (xy 410.664183 -176.140921) (xy 410.616577 -176.169975) (xy 410.565248 -176.191787)
			(xy 410.511291 -176.205893) (xy 410.455854 -176.211993) (xy 410.40012 -176.209956) (xy 410.345277 -176.199826)
			(xy 410.292493 -176.181819) (xy 410.242893 -176.156318) (xy 410.197535 -176.123867) (xy 410.157386 -176.085158)
			(xy 410.1233 -176.041015) (xy 410.096004 -175.99238) (xy 410.076081 -175.940289) (xy 410.063955 -175.885852)
			(xy 410.059884 -175.83023) (xy 408.828579 -175.83023) (xy 408.648018 -179.2986) (xy 409.269182 -179.2986)
			(xy 409.273253 -179.242978) (xy 409.285379 -179.188541) (xy 409.305302 -179.13645) (xy 409.332598 -179.087815)
			(xy 409.366684 -179.043672) (xy 409.406833 -179.004963) (xy 409.452191 -178.972512) (xy 409.501791 -178.947011)
			(xy 409.554575 -178.929004) (xy 409.609418 -178.918874) (xy 409.665152 -178.916837) (xy 409.720589 -178.922937)
			(xy 409.774546 -178.937043) (xy 409.825875 -178.958855) (xy 409.873481 -178.987909) (xy 409.916349 -179.023584)
			(xy 409.953566 -179.065121) (xy 409.984339 -179.111634) (xy 410.008011 -179.162131) (xy 410.024079 -179.215538)
			(xy 410.032199 -179.270714) (xy 410.032708 -179.2986) (xy 411.250382 -179.2986) (xy 411.254453 -179.242978)
			(xy 411.266579 -179.188541) (xy 411.286502 -179.13645) (xy 411.313798 -179.087815) (xy 411.347884 -179.043672)
			(xy 411.388033 -179.004963) (xy 411.433391 -178.972512) (xy 411.482991 -178.947011) (xy 411.535775 -178.929004)
			(xy 411.590618 -178.918874) (xy 411.646352 -178.916837) (xy 411.701789 -178.922937) (xy 411.755746 -178.937043)
			(xy 411.807075 -178.958855) (xy 411.854681 -178.987909) (xy 411.897549 -179.023584) (xy 411.934766 -179.065121)
			(xy 411.965539 -179.111634) (xy 411.989211 -179.162131) (xy 412.005279 -179.215538) (xy 412.013399 -179.270714)
			(xy 412.013908 -179.2986) (xy 412.013399 -179.326486) (xy 412.005279 -179.381662) (xy 411.989211 -179.435069)
			(xy 411.965539 -179.485566) (xy 411.934766 -179.532079) (xy 411.897549 -179.573616) (xy 411.854681 -179.609291)
			(xy 411.807075 -179.638345) (xy 411.755746 -179.660157) (xy 411.701789 -179.674263) (xy 411.646352 -179.680363)
			(xy 411.590618 -179.678326) (xy 411.535775 -179.668196) (xy 411.482991 -179.650189) (xy 411.433391 -179.624688)
			(xy 411.388033 -179.592237) (xy 411.347884 -179.553528) (xy 411.313798 -179.509385) (xy 411.286502 -179.46075)
			(xy 411.266579 -179.408659) (xy 411.254453 -179.354222) (xy 411.250382 -179.2986) (xy 410.032708 -179.2986)
			(xy 410.032199 -179.326486) (xy 410.024079 -179.381662) (xy 410.008011 -179.435069) (xy 409.984339 -179.485566)
			(xy 409.953566 -179.532079) (xy 409.916349 -179.573616) (xy 409.873481 -179.609291) (xy 409.825875 -179.638345)
			(xy 409.774546 -179.660157) (xy 409.720589 -179.674263) (xy 409.665152 -179.680363) (xy 409.609418 -179.678326)
			(xy 409.554575 -179.668196) (xy 409.501791 -179.650189) (xy 409.452191 -179.624688) (xy 409.406833 -179.592237)
			(xy 409.366684 -179.553528) (xy 409.332598 -179.509385) (xy 409.305302 -179.46075) (xy 409.285379 -179.408659)
			(xy 409.273253 -179.354222) (xy 409.269182 -179.2986) (xy 408.648018 -179.2986) (xy 408.64536 -179.349654)
			(xy 408.575064 -180.699918) (xy 413.180782 -180.699918) (xy 413.184853 -180.644296) (xy 413.196979 -180.589859)
			(xy 413.216902 -180.537768) (xy 413.244198 -180.489133) (xy 413.278284 -180.44499) (xy 413.318433 -180.406281)
			(xy 413.363791 -180.37383) (xy 413.413391 -180.348329) (xy 413.466175 -180.330322) (xy 413.521018 -180.320192)
			(xy 413.576752 -180.318155) (xy 413.632189 -180.324255) (xy 413.686146 -180.338361) (xy 413.737475 -180.360173)
			(xy 413.785081 -180.389227) (xy 413.827949 -180.424902) (xy 413.865166 -180.466439) (xy 413.895939 -180.512952)
			(xy 413.919611 -180.563449) (xy 413.935679 -180.616856) (xy 413.943799 -180.672032) (xy 413.944308 -180.699918)
			(xy 413.943799 -180.727804) (xy 413.935679 -180.78298) (xy 413.919611 -180.836387) (xy 413.895939 -180.886884)
			(xy 413.865166 -180.933397) (xy 413.827949 -180.974934) (xy 413.785081 -181.010609) (xy 413.737475 -181.039663)
			(xy 413.686146 -181.061475) (xy 413.632189 -181.075581) (xy 413.576752 -181.081681) (xy 413.521018 -181.079644)
			(xy 413.466175 -181.069514) (xy 413.413391 -181.051507) (xy 413.363791 -181.026006) (xy 413.318433 -180.993555)
			(xy 413.278284 -180.954846) (xy 413.244198 -180.910703) (xy 413.216902 -180.862068) (xy 413.196979 -180.809977)
			(xy 413.184853 -180.75554) (xy 413.180782 -180.699918) (xy 408.575064 -180.699918) (xy 408.429475 -183.496458)
			(xy 408.81884 -183.496458) (xy 408.822911 -183.440836) (xy 408.835037 -183.386399) (xy 408.85496 -183.334308)
			(xy 408.882256 -183.285673) (xy 408.916342 -183.24153) (xy 408.956491 -183.202821) (xy 409.001849 -183.17037)
			(xy 409.051449 -183.144869) (xy 409.104233 -183.126862) (xy 409.159076 -183.116732) (xy 409.21481 -183.114695)
			(xy 409.270247 -183.120795) (xy 409.324204 -183.134901) (xy 409.375533 -183.156713) (xy 409.423139 -183.185767)
			(xy 409.466007 -183.221442) (xy 409.503224 -183.262979) (xy 409.533997 -183.309492) (xy 409.557669 -183.359989)
			(xy 409.573737 -183.413396) (xy 409.581857 -183.468572) (xy 409.582366 -183.496458) (xy 409.581857 -183.524344)
			(xy 409.573737 -183.57952) (xy 409.557669 -183.632927) (xy 409.533997 -183.683424) (xy 409.527794 -183.6928)
			(xy 411.224982 -183.6928) (xy 411.229053 -183.637178) (xy 411.241179 -183.582741) (xy 411.261102 -183.53065)
			(xy 411.288398 -183.482015) (xy 411.322484 -183.437872) (xy 411.362633 -183.399163) (xy 411.407991 -183.366712)
			(xy 411.457591 -183.341211) (xy 411.510375 -183.323204) (xy 411.565218 -183.313074) (xy 411.620952 -183.311037)
			(xy 411.676389 -183.317137) (xy 411.730346 -183.331243) (xy 411.781675 -183.353055) (xy 411.829281 -183.382109)
			(xy 411.872149 -183.417784) (xy 411.909366 -183.459321) (xy 411.940139 -183.505834) (xy 411.963811 -183.556331)
			(xy 411.979879 -183.609738) (xy 411.987999 -183.664914) (xy 411.988508 -183.6928) (xy 411.987999 -183.720686)
			(xy 411.979879 -183.775862) (xy 411.963811 -183.829269) (xy 411.940139 -183.879766) (xy 411.909366 -183.926279)
			(xy 411.872149 -183.967816) (xy 411.829281 -184.003491) (xy 411.781675 -184.032545) (xy 411.730346 -184.054357)
			(xy 411.676389 -184.068463) (xy 411.620952 -184.074563) (xy 411.565218 -184.072526) (xy 411.510375 -184.062396)
			(xy 411.457591 -184.044389) (xy 411.407991 -184.018888) (xy 411.362633 -183.986437) (xy 411.322484 -183.947728)
			(xy 411.288398 -183.903585) (xy 411.261102 -183.85495) (xy 411.241179 -183.802859) (xy 411.229053 -183.748422)
			(xy 411.224982 -183.6928) (xy 409.527794 -183.6928) (xy 409.503224 -183.729937) (xy 409.466007 -183.771474)
			(xy 409.423139 -183.807149) (xy 409.375533 -183.836203) (xy 409.324204 -183.858015) (xy 409.270247 -183.872121)
			(xy 409.21481 -183.878221) (xy 409.159076 -183.876184) (xy 409.104233 -183.866054) (xy 409.051449 -183.848047)
			(xy 409.001849 -183.822546) (xy 408.956491 -183.790095) (xy 408.916342 -183.751386) (xy 408.882256 -183.707243)
			(xy 408.85496 -183.658608) (xy 408.835037 -183.606517) (xy 408.822911 -183.55208) (xy 408.81884 -183.496458)
			(xy 408.429475 -183.496458) (xy 408.354234 -184.941718) (xy 414.979864 -184.941718) (xy 414.983935 -184.886096)
			(xy 414.996061 -184.831659) (xy 415.015984 -184.779568) (xy 415.04328 -184.730933) (xy 415.077366 -184.68679)
			(xy 415.117515 -184.648081) (xy 415.162873 -184.61563) (xy 415.212473 -184.590129) (xy 415.265257 -184.572122)
			(xy 415.3201 -184.561992) (xy 415.375834 -184.559955) (xy 415.431271 -184.566055) (xy 415.485228 -184.580161)
			(xy 415.536557 -184.601973) (xy 415.584163 -184.631027) (xy 415.627031 -184.666702) (xy 415.664248 -184.708239)
			(xy 415.695021 -184.754752) (xy 415.718693 -184.805249) (xy 415.734761 -184.858656) (xy 415.742881 -184.913832)
			(xy 415.74339 -184.941718) (xy 415.742881 -184.969604) (xy 415.734761 -185.02478) (xy 415.718693 -185.078187)
			(xy 415.695021 -185.128684) (xy 415.664248 -185.175197) (xy 415.627031 -185.216734) (xy 415.584163 -185.252409)
			(xy 415.536557 -185.281463) (xy 415.485228 -185.303275) (xy 415.431271 -185.317381) (xy 415.375834 -185.323481)
			(xy 415.3201 -185.321444) (xy 415.265257 -185.311314) (xy 415.212473 -185.293307) (xy 415.162873 -185.267806)
			(xy 415.117515 -185.235355) (xy 415.077366 -185.196646) (xy 415.04328 -185.152503) (xy 415.015984 -185.103868)
			(xy 414.996061 -185.051777) (xy 414.983935 -184.99734) (xy 414.979864 -184.941718) (xy 408.354234 -184.941718)
			(xy 408.25035 -186.937142) (xy 408.89504 -186.937142) (xy 408.899111 -186.88152) (xy 408.911237 -186.827083)
			(xy 408.93116 -186.774992) (xy 408.958456 -186.726357) (xy 408.992542 -186.682214) (xy 409.032691 -186.643505)
			(xy 409.078049 -186.611054) (xy 409.127649 -186.585553) (xy 409.180433 -186.567546) (xy 409.235276 -186.557416)
			(xy 409.29101 -186.555379) (xy 409.346447 -186.561479) (xy 409.400404 -186.575585) (xy 409.451733 -186.597397)
			(xy 409.499339 -186.626451) (xy 409.542207 -186.662126) (xy 409.579424 -186.703663) (xy 409.610197 -186.750176)
			(xy 409.633869 -186.800673) (xy 409.649937 -186.85408) (xy 409.658057 -186.909256) (xy 409.658566 -186.937142)
			(xy 409.658057 -186.965028) (xy 409.649937 -187.020204) (xy 409.633869 -187.073611) (xy 409.610197 -187.124108)
			(xy 409.579424 -187.170621) (xy 409.542207 -187.212158) (xy 409.499339 -187.247833) (xy 409.451733 -187.276887)
			(xy 409.400404 -187.298699) (xy 409.346447 -187.312805) (xy 409.29101 -187.318905) (xy 409.235276 -187.316868)
			(xy 409.180433 -187.306738) (xy 409.127649 -187.288731) (xy 409.078049 -187.26323) (xy 409.032691 -187.230779)
			(xy 408.992542 -187.19207) (xy 408.958456 -187.147927) (xy 408.93116 -187.099292) (xy 408.911237 -187.047201)
			(xy 408.899111 -186.992764) (xy 408.89504 -186.937142) (xy 408.25035 -186.937142) (xy 408.219579 -187.5282)
			(xy 411.123382 -187.5282) (xy 411.127453 -187.472578) (xy 411.139579 -187.418141) (xy 411.159502 -187.36605)
			(xy 411.186798 -187.317415) (xy 411.220884 -187.273272) (xy 411.261033 -187.234563) (xy 411.306391 -187.202112)
			(xy 411.355991 -187.176611) (xy 411.408775 -187.158604) (xy 411.463618 -187.148474) (xy 411.519352 -187.146437)
			(xy 411.574789 -187.152537) (xy 411.628746 -187.166643) (xy 411.680075 -187.188455) (xy 411.727681 -187.217509)
			(xy 411.770549 -187.253184) (xy 411.807766 -187.294721) (xy 411.838539 -187.341234) (xy 411.862211 -187.391731)
			(xy 411.878279 -187.445138) (xy 411.886399 -187.500314) (xy 411.886908 -187.5282) (xy 411.886399 -187.556086)
			(xy 411.878279 -187.611262) (xy 411.862211 -187.664669) (xy 411.838539 -187.715166) (xy 411.807766 -187.761679)
			(xy 411.770549 -187.803216) (xy 411.727681 -187.838891) (xy 411.680075 -187.867945) (xy 411.628746 -187.889757)
			(xy 411.574789 -187.903863) (xy 411.519352 -187.909963) (xy 411.463618 -187.907926) (xy 411.408775 -187.897796)
			(xy 411.355991 -187.879789) (xy 411.306391 -187.854288) (xy 411.261033 -187.821837) (xy 411.220884 -187.783128)
			(xy 411.186798 -187.738985) (xy 411.159502 -187.69035) (xy 411.139579 -187.638259) (xy 411.127453 -187.583822)
			(xy 411.123382 -187.5282) (xy 408.219579 -187.5282) (xy 408.137369 -189.107318) (xy 410.255464 -189.107318)
			(xy 410.259535 -189.051696) (xy 410.271661 -188.997259) (xy 410.291584 -188.945168) (xy 410.31888 -188.896533)
			(xy 410.352966 -188.85239) (xy 410.393115 -188.813681) (xy 410.438473 -188.78123) (xy 410.488073 -188.755729)
			(xy 410.540857 -188.737722) (xy 410.5957 -188.727592) (xy 410.651434 -188.725555) (xy 410.706871 -188.731655)
			(xy 410.760828 -188.745761) (xy 410.812157 -188.767573) (xy 410.859763 -188.796627) (xy 410.902631 -188.832302)
			(xy 410.939848 -188.873839) (xy 410.970621 -188.920352) (xy 410.994293 -188.970849) (xy 411.010361 -189.024256)
			(xy 411.018481 -189.079432) (xy 411.01899 -189.107318) (xy 411.018481 -189.135204) (xy 411.010361 -189.19038)
			(xy 410.994293 -189.243787) (xy 410.970621 -189.294284) (xy 410.939848 -189.340797) (xy 410.902631 -189.382334)
			(xy 410.859763 -189.418009) (xy 410.812157 -189.447063) (xy 410.760828 -189.468875) (xy 410.706871 -189.482981)
			(xy 410.651434 -189.489081) (xy 410.5957 -189.487044) (xy 410.540857 -189.476914) (xy 410.488073 -189.458907)
			(xy 410.438473 -189.433406) (xy 410.393115 -189.400955) (xy 410.352966 -189.362246) (xy 410.31888 -189.318103)
			(xy 410.291584 -189.269468) (xy 410.271661 -189.217377) (xy 410.259535 -189.16294) (xy 410.255464 -189.107318)
			(xy 408.137369 -189.107318) (xy 408.100727 -189.811152) (xy 413.217104 -189.811152) (xy 413.221175 -189.75553)
			(xy 413.233301 -189.701093) (xy 413.253224 -189.649002) (xy 413.28052 -189.600367) (xy 413.314606 -189.556224)
			(xy 413.354755 -189.517515) (xy 413.400113 -189.485064) (xy 413.449713 -189.459563) (xy 413.502497 -189.441556)
			(xy 413.55734 -189.431426) (xy 413.613074 -189.429389) (xy 413.668511 -189.435489) (xy 413.722468 -189.449595)
			(xy 413.773797 -189.471407) (xy 413.821403 -189.500461) (xy 413.864271 -189.536136) (xy 413.901488 -189.577673)
			(xy 413.932261 -189.624186) (xy 413.955933 -189.674683) (xy 413.972001 -189.72809) (xy 413.980121 -189.783266)
			(xy 413.98063 -189.811152) (xy 413.980121 -189.839038) (xy 413.972001 -189.894214) (xy 413.955933 -189.947621)
			(xy 413.932261 -189.998118) (xy 413.901488 -190.044631) (xy 413.864271 -190.086168) (xy 413.821403 -190.121843)
			(xy 413.773797 -190.150897) (xy 413.722468 -190.172709) (xy 413.668511 -190.186815) (xy 413.613074 -190.192915)
			(xy 413.55734 -190.190878) (xy 413.502497 -190.180748) (xy 413.449713 -190.162741) (xy 413.400113 -190.13724)
			(xy 413.354755 -190.104789) (xy 413.314606 -190.06608) (xy 413.28052 -190.021937) (xy 413.253224 -189.973302)
			(xy 413.233301 -189.921211) (xy 413.221175 -189.866774) (xy 413.217104 -189.811152) (xy 408.100727 -189.811152)
			(xy 408.000454 -191.737234) (xy 407.913852 -193.402458) (xy 409.211524 -193.402458) (xy 409.215595 -193.346836)
			(xy 409.227721 -193.292399) (xy 409.247644 -193.240308) (xy 409.27494 -193.191673) (xy 409.309026 -193.14753)
			(xy 409.349175 -193.108821) (xy 409.394533 -193.07637) (xy 409.444133 -193.050869) (xy 409.496917 -193.032862)
			(xy 409.55176 -193.022732) (xy 409.607494 -193.020695) (xy 409.662931 -193.026795) (xy 409.716888 -193.040901)
			(xy 409.768217 -193.062713) (xy 409.815823 -193.091767) (xy 409.858691 -193.127442) (xy 409.895908 -193.168979)
			(xy 409.926681 -193.215492) (xy 409.950353 -193.265989) (xy 409.951139 -193.2686) (xy 412.113982 -193.2686)
			(xy 412.118053 -193.212978) (xy 412.130179 -193.158541) (xy 412.150102 -193.10645) (xy 412.177398 -193.057815)
			(xy 412.211484 -193.013672) (xy 412.251633 -192.974963) (xy 412.296991 -192.942512) (xy 412.346591 -192.917011)
			(xy 412.399375 -192.899004) (xy 412.454218 -192.888874) (xy 412.509952 -192.886837) (xy 412.565389 -192.892937)
			(xy 412.619346 -192.907043) (xy 412.670675 -192.928855) (xy 412.718281 -192.957909) (xy 412.761149 -192.993584)
			(xy 412.798366 -193.035121) (xy 412.829139 -193.081634) (xy 412.852811 -193.132131) (xy 412.868879 -193.185538)
			(xy 412.876999 -193.240714) (xy 412.877508 -193.2686) (xy 412.876999 -193.296486) (xy 412.868879 -193.351662)
			(xy 412.852811 -193.405069) (xy 412.829139 -193.455566) (xy 412.798366 -193.502079) (xy 412.761149 -193.543616)
			(xy 412.718281 -193.579291) (xy 412.670675 -193.608345) (xy 412.619346 -193.630157) (xy 412.565389 -193.644263)
			(xy 412.509952 -193.650363) (xy 412.454218 -193.648326) (xy 412.399375 -193.638196) (xy 412.346591 -193.620189)
			(xy 412.296991 -193.594688) (xy 412.251633 -193.562237) (xy 412.211484 -193.523528) (xy 412.177398 -193.479385)
			(xy 412.150102 -193.43075) (xy 412.130179 -193.378659) (xy 412.118053 -193.324222) (xy 412.113982 -193.2686)
			(xy 409.951139 -193.2686) (xy 409.966421 -193.319396) (xy 409.974541 -193.374572) (xy 409.97505 -193.402458)
			(xy 409.974541 -193.430344) (xy 409.966421 -193.48552) (xy 409.950353 -193.538927) (xy 409.926681 -193.589424)
			(xy 409.895908 -193.635937) (xy 409.858691 -193.677474) (xy 409.815823 -193.713149) (xy 409.768217 -193.742203)
			(xy 409.716888 -193.764015) (xy 409.662931 -193.778121) (xy 409.607494 -193.784221) (xy 409.55176 -193.782184)
			(xy 409.496917 -193.772054) (xy 409.444133 -193.754047) (xy 409.394533 -193.728546) (xy 409.349175 -193.696095)
			(xy 409.309026 -193.657386) (xy 409.27494 -193.613243) (xy 409.247644 -193.564608) (xy 409.227721 -193.512517)
			(xy 409.215595 -193.45808) (xy 409.211524 -193.402458) (xy 407.913852 -193.402458) (xy 407.882598 -194.003422)
			(xy 407.71984 -197.1294) (xy 408.430982 -197.1294) (xy 408.435053 -197.073778) (xy 408.447179 -197.019341)
			(xy 408.467102 -196.96725) (xy 408.494398 -196.918615) (xy 408.528484 -196.874472) (xy 408.568633 -196.835763)
			(xy 408.613991 -196.803312) (xy 408.663591 -196.777811) (xy 408.716375 -196.759804) (xy 408.771218 -196.749674)
			(xy 408.826952 -196.747637) (xy 408.882389 -196.753737) (xy 408.888207 -196.755258) (xy 413.72104 -196.755258)
			(xy 413.725111 -196.699636) (xy 413.737237 -196.645199) (xy 413.75716 -196.593108) (xy 413.784456 -196.544473)
			(xy 413.818542 -196.50033) (xy 413.858691 -196.461621) (xy 413.904049 -196.42917) (xy 413.953649 -196.403669)
			(xy 414.006433 -196.385662) (xy 414.061276 -196.375532) (xy 414.11701 -196.373495) (xy 414.172447 -196.379595)
			(xy 414.226404 -196.393701) (xy 414.277733 -196.415513) (xy 414.325339 -196.444567) (xy 414.368207 -196.480242)
			(xy 414.405424 -196.521779) (xy 414.436197 -196.568292) (xy 414.459869 -196.618789) (xy 414.475937 -196.672196)
			(xy 414.484057 -196.727372) (xy 414.484566 -196.755258) (xy 414.484057 -196.783144) (xy 414.475937 -196.83832)
			(xy 414.459869 -196.891727) (xy 414.436197 -196.942224) (xy 414.405424 -196.988737) (xy 414.368207 -197.030274)
			(xy 414.325339 -197.065949) (xy 414.277733 -197.095003) (xy 414.226404 -197.116815) (xy 414.172447 -197.130921)
			(xy 414.11701 -197.137021) (xy 414.061276 -197.134984) (xy 414.006433 -197.124854) (xy 413.953649 -197.106847)
			(xy 413.904049 -197.081346) (xy 413.858691 -197.048895) (xy 413.818542 -197.010186) (xy 413.784456 -196.966043)
			(xy 413.75716 -196.917408) (xy 413.737237 -196.865317) (xy 413.725111 -196.81088) (xy 413.72104 -196.755258)
			(xy 408.888207 -196.755258) (xy 408.936346 -196.767843) (xy 408.987675 -196.789655) (xy 409.035281 -196.818709)
			(xy 409.078149 -196.854384) (xy 409.115366 -196.895921) (xy 409.146139 -196.942434) (xy 409.169811 -196.992931)
			(xy 409.185879 -197.046338) (xy 409.193999 -197.101514) (xy 409.194508 -197.1294) (xy 409.193999 -197.157286)
			(xy 409.185879 -197.212462) (xy 409.169811 -197.265869) (xy 409.146139 -197.316366) (xy 409.115366 -197.362879)
			(xy 409.078149 -197.404416) (xy 409.035281 -197.440091) (xy 408.987675 -197.469145) (xy 408.936346 -197.490957)
			(xy 408.882389 -197.505063) (xy 408.826952 -197.511163) (xy 408.771218 -197.509126) (xy 408.716375 -197.498996)
			(xy 408.663591 -197.480989) (xy 408.613991 -197.455488) (xy 408.568633 -197.423037) (xy 408.528484 -197.384328)
			(xy 408.494398 -197.340185) (xy 408.467102 -197.29155) (xy 408.447179 -197.239459) (xy 408.435053 -197.185022)
			(xy 408.430982 -197.1294) (xy 407.71984 -197.1294) (xy 407.663939 -198.203058) (xy 408.97124 -198.203058)
			(xy 408.975311 -198.147436) (xy 408.987437 -198.092999) (xy 409.00736 -198.040908) (xy 409.034656 -197.992273)
			(xy 409.068742 -197.94813) (xy 409.108891 -197.909421) (xy 409.154249 -197.87697) (xy 409.203849 -197.851469)
			(xy 409.256633 -197.833462) (xy 409.311476 -197.823332) (xy 409.36721 -197.821295) (xy 409.422647 -197.827395)
			(xy 409.476604 -197.841501) (xy 409.527933 -197.863313) (xy 409.575539 -197.892367) (xy 409.618407 -197.928042)
			(xy 409.655624 -197.969579) (xy 409.686397 -198.016092) (xy 409.710069 -198.066589) (xy 409.726137 -198.119996)
			(xy 409.734257 -198.175172) (xy 409.734766 -198.203058) (xy 409.734257 -198.230944) (xy 409.726137 -198.28612)
			(xy 409.710069 -198.339527) (xy 409.686397 -198.390024) (xy 409.655624 -198.436537) (xy 409.618407 -198.478074)
			(xy 409.575539 -198.513749) (xy 409.527933 -198.542803) (xy 409.476604 -198.564615) (xy 409.422647 -198.578721)
			(xy 409.36721 -198.584821) (xy 409.311476 -198.582784) (xy 409.256633 -198.572654) (xy 409.203849 -198.554647)
			(xy 409.154249 -198.529146) (xy 409.108891 -198.496695) (xy 409.068742 -198.457986) (xy 409.034656 -198.413843)
			(xy 409.00736 -198.365208) (xy 408.987437 -198.313117) (xy 408.975311 -198.25868) (xy 408.97124 -198.203058)
			(xy 407.663939 -198.203058) (xy 407.468211 -201.962258) (xy 409.033724 -201.962258) (xy 409.037795 -201.906636)
			(xy 409.049921 -201.852199) (xy 409.069844 -201.800108) (xy 409.09714 -201.751473) (xy 409.131226 -201.70733)
			(xy 409.171375 -201.668621) (xy 409.216733 -201.63617) (xy 409.266333 -201.610669) (xy 409.319117 -201.592662)
			(xy 409.37396 -201.582532) (xy 409.429694 -201.580495) (xy 409.485131 -201.586595) (xy 409.539088 -201.600701)
			(xy 409.590417 -201.622513) (xy 409.638023 -201.651567) (xy 409.680891 -201.687242) (xy 409.718108 -201.728779)
			(xy 409.748881 -201.775292) (xy 409.772553 -201.825789) (xy 409.788621 -201.879196) (xy 409.796741 -201.934372)
			(xy 409.79725 -201.962258) (xy 409.796741 -201.990144) (xy 409.788621 -202.04532) (xy 409.772553 -202.098727)
			(xy 409.748881 -202.149224) (xy 409.718108 -202.195737) (xy 409.680891 -202.237274) (xy 409.638023 -202.272949)
			(xy 409.590417 -202.302003) (xy 409.539088 -202.323815) (xy 409.485131 -202.337921) (xy 409.429694 -202.344021)
			(xy 409.37396 -202.341984) (xy 409.319117 -202.331854) (xy 409.266333 -202.313847) (xy 409.216733 -202.288346)
			(xy 409.171375 -202.255895) (xy 409.131226 -202.217186) (xy 409.09714 -202.173043) (xy 409.069844 -202.124408)
			(xy 409.049921 -202.072317) (xy 409.037795 -202.01788) (xy 409.033724 -201.962258) (xy 407.468211 -201.962258)
			(xy 407.438098 -202.540616) (xy 407.353896 -204.158596) (xy 407.590242 -204.158596) (xy 407.594313 -204.102974)
			(xy 407.606439 -204.048537) (xy 407.626362 -203.996446) (xy 407.653658 -203.947811) (xy 407.687744 -203.903668)
			(xy 407.727893 -203.864959) (xy 407.773251 -203.832508) (xy 407.822851 -203.807007) (xy 407.875635 -203.789)
			(xy 407.930478 -203.77887) (xy 407.986212 -203.776833) (xy 408.041649 -203.782933) (xy 408.095606 -203.797039)
			(xy 408.146935 -203.818851) (xy 408.194541 -203.847905) (xy 408.237409 -203.88358) (xy 408.274626 -203.925117)
			(xy 408.305399 -203.97163) (xy 408.329071 -204.022127) (xy 408.345139 -204.075534) (xy 408.353259 -204.13071)
			(xy 408.353768 -204.158596) (xy 408.353259 -204.186482) (xy 408.345139 -204.241658) (xy 408.329071 -204.295065)
			(xy 408.305399 -204.345562) (xy 408.274626 -204.392075) (xy 408.237409 -204.433612) (xy 408.194541 -204.469287)
			(xy 408.146935 -204.498341) (xy 408.095606 -204.520153) (xy 408.041649 -204.534259) (xy 407.986212 -204.540359)
			(xy 407.930478 -204.538322) (xy 407.875635 -204.528192) (xy 407.822851 -204.510185) (xy 407.773251 -204.484684)
			(xy 407.727893 -204.452233) (xy 407.687744 -204.413524) (xy 407.653658 -204.369381) (xy 407.626362 -204.320746)
			(xy 407.606439 -204.268655) (xy 407.594313 -204.214218) (xy 407.590242 -204.158596) (xy 407.353896 -204.158596)
			(xy 407.15045 -208.06791) (xy 407.722068 -208.06791) (xy 407.726139 -208.012288) (xy 407.738265 -207.957851)
			(xy 407.758188 -207.90576) (xy 407.785484 -207.857125) (xy 407.81957 -207.812982) (xy 407.859719 -207.774273)
			(xy 407.905077 -207.741822) (xy 407.954677 -207.716321) (xy 408.007461 -207.698314) (xy 408.062304 -207.688184)
			(xy 408.118038 -207.686147) (xy 408.173475 -207.692247) (xy 408.227432 -207.706353) (xy 408.278761 -207.728165)
			(xy 408.326367 -207.757219) (xy 408.369235 -207.792894) (xy 408.406452 -207.834431) (xy 408.437225 -207.880944)
			(xy 408.460897 -207.931441) (xy 408.476965 -207.984848) (xy 408.485085 -208.040024) (xy 408.485594 -208.06791)
			(xy 408.485085 -208.095796) (xy 408.476965 -208.150972) (xy 408.460897 -208.204379) (xy 408.437225 -208.254876)
			(xy 408.406452 -208.301389) (xy 408.369235 -208.342926) (xy 408.326367 -208.378601) (xy 408.278761 -208.407655)
			(xy 408.227432 -208.429467) (xy 408.173475 -208.443573) (xy 408.118038 -208.449673) (xy 408.062304 -208.447636)
			(xy 408.007461 -208.437506) (xy 407.954677 -208.419499) (xy 407.905077 -208.393998) (xy 407.859719 -208.361547)
			(xy 407.81957 -208.322838) (xy 407.785484 -208.278695) (xy 407.758188 -208.23006) (xy 407.738265 -208.177969)
			(xy 407.726139 -208.123532) (xy 407.722068 -208.06791) (xy 407.15045 -208.06791) (xy 407.032118 -210.341718)
			(xy 409.3497 -210.341718) (xy 409.353771 -210.286096) (xy 409.365897 -210.231659) (xy 409.38582 -210.179568)
			(xy 409.413116 -210.130933) (xy 409.447202 -210.08679) (xy 409.487351 -210.048081) (xy 409.532709 -210.01563)
			(xy 409.582309 -209.990129) (xy 409.635093 -209.972122) (xy 409.689936 -209.961992) (xy 409.74567 -209.959955)
			(xy 409.801107 -209.966055) (xy 409.855064 -209.980161) (xy 409.906393 -210.001973) (xy 409.953999 -210.031027)
			(xy 409.996867 -210.066702) (xy 410.034084 -210.108239) (xy 410.064857 -210.154752) (xy 410.088529 -210.205249)
			(xy 410.104597 -210.258656) (xy 410.112717 -210.313832) (xy 410.113226 -210.341718) (xy 410.112717 -210.369604)
			(xy 410.104597 -210.42478) (xy 410.088529 -210.478187) (xy 410.064857 -210.528684) (xy 410.034084 -210.575197)
			(xy 409.996867 -210.616734) (xy 409.953999 -210.652409) (xy 409.906393 -210.681463) (xy 409.855064 -210.703275)
			(xy 409.801107 -210.717381) (xy 409.74567 -210.723481) (xy 409.689936 -210.721444) (xy 409.635093 -210.711314)
			(xy 409.582309 -210.693307) (xy 409.532709 -210.667806) (xy 409.487351 -210.635355) (xy 409.447202 -210.596646)
			(xy 409.413116 -210.552503) (xy 409.38582 -210.503868) (xy 409.365897 -210.451777) (xy 409.353771 -210.39734)
			(xy 409.3497 -210.341718) (xy 407.032118 -210.341718) (xy 406.449276 -221.54134) (xy 406.449276 -221.543118)
			(xy 406.449416 -221.556598) (xy 406.455937 -221.582747) (xy 406.469078 -221.606275) (xy 406.487921 -221.625542)
			(xy 406.511151 -221.639203) (xy 406.537148 -221.646305) (xy 406.550622 -221.64675) (xy 410.65577 -221.64675)
			(xy 410.658056 -221.64675) (xy 410.669569 -221.645682) (xy 410.68987 -221.634664) (xy 410.703307 -221.615876)
			(xy 410.705808 -221.604586) (xy 413.778446 -203.962762) (xy 413.779684 -203.953414) (xy 413.775954 -203.934944)
			(xy 413.76577 -203.91909) (xy 413.75838 -203.913232) (xy 413.748982 -203.90612) (xy 413.747966 -203.905358)
			(xy 413.744135 -203.902655) (xy 413.735695 -203.898571) (xy 413.731202 -203.89723) (xy 413.722566 -203.894944)
			(xy 413.703008 -203.896976) (xy 413.694372 -203.901294) (xy 413.685422 -203.905838) (xy 413.667124 -203.914097)
			(xy 413.657796 -203.917804) (xy 413.625457 -203.929661) (xy 413.557855 -203.942828) (xy 413.52343 -203.943966)
			(xy 413.516572 -203.943966) (xy 413.48943 -203.943322) (xy 413.435737 -203.935297) (xy 413.383724 -203.919741)
			(xy 413.334441 -203.896967) (xy 413.288885 -203.867437) (xy 413.247976 -203.831746) (xy 413.21254 -203.790616)
			(xy 413.183293 -203.744878) (xy 413.160826 -203.695454) (xy 413.145594 -203.643345) (xy 413.137903 -203.589603)
			(xy 413.13735 -203.562458) (xy 413.137839 -203.535208) (xy 413.1456 -203.481262) (xy 413.160958 -203.42897)
			(xy 413.183601 -203.379395) (xy 413.213068 -203.333547) (xy 413.248759 -203.292359) (xy 413.289947 -203.256668)
			(xy 413.335795 -203.227201) (xy 413.38537 -203.204558) (xy 413.437662 -203.1892) (xy 413.491608 -203.181439)
			(xy 413.518858 -203.18095) (xy 413.544961 -203.181381) (xy 413.59668 -203.188505) (xy 413.646944 -203.202612)
			(xy 413.694817 -203.223438) (xy 413.739404 -203.250596) (xy 413.779873 -203.283578) (xy 413.798004 -203.302362)
			(xy 413.80138 -203.30584) (xy 413.809177 -203.311596) (xy 413.813498 -203.313792) (xy 413.81426 -203.314046)
			(xy 413.814768 -203.3143) (xy 413.817308 -203.31557) (xy 413.822134 -203.317094) (xy 413.828586 -203.31863)
			(xy 413.841844 -203.31863) (xy 413.848296 -203.317094) (xy 413.87649 -203.308458) (xy 413.877252 -203.308204)
			(xy 413.88665 -203.297536) (xy 413.891113 -203.292134) (xy 413.897177 -203.279507) (xy 413.898588 -203.272644)
			(xy 414.022794 -202.559158) (xy 414.178242 -201.666094) (xy 414.30575 -200.934828) (xy 414.403032 -200.376028)
			(xy 414.404313 -200.365841) (xy 414.399616 -200.345874) (xy 414.387489 -200.32933) (xy 414.378902 -200.323704)
			(xy 414.33623 -200.298558) (xy 414.29686 -200.27519) (xy 414.290025 -200.271503) (xy 414.274901 -200.268011)
			(xy 414.267142 -200.268332) (xy 414.259776 -200.26884) (xy 414.245806 -200.274174) (xy 414.239456 -200.279254)
			(xy 414.219101 -200.294966) (xy 414.174969 -200.321359) (xy 414.127691 -200.341582) (xy 414.078125 -200.355269)
			(xy 414.027169 -200.362173) (xy 414.001458 -200.362566) (xy 413.974212 -200.362077) (xy 413.920275 -200.354316)
			(xy 413.867991 -200.338959) (xy 413.818424 -200.316318) (xy 413.772584 -200.286854) (xy 413.731404 -200.251167)
			(xy 413.695721 -200.209982) (xy 413.666261 -200.164139) (xy 413.643626 -200.11457) (xy 413.628275 -200.062284)
			(xy 413.62052 -200.008346) (xy 413.62052 -199.953854) (xy 413.628275 -199.899916) (xy 413.643626 -199.84763)
			(xy 413.666261 -199.798061) (xy 413.695721 -199.752218) (xy 413.731404 -199.711033) (xy 413.772584 -199.675346)
			(xy 413.818424 -199.645882) (xy 413.867991 -199.623241) (xy 413.920275 -199.607884) (xy 413.974212 -199.600123)
			(xy 414.001458 -199.59955) (xy 414.029231 -199.600047) (xy 414.084189 -199.608095) (xy 414.1374 -199.624027)
			(xy 414.187739 -199.647506) (xy 414.234142 -199.678035) (xy 414.275627 -199.714971) (xy 414.311318 -199.757531)
			(xy 414.326324 -199.780906) (xy 414.328356 -199.784208) (xy 414.334149 -199.791573) (xy 414.349779 -199.801877)
			(xy 414.358836 -199.804274) (xy 414.379156 -199.804274) (xy 414.425892 -199.795384) (xy 414.472628 -199.78624)
			(xy 414.48216 -199.783963) (xy 414.498609 -199.773341) (xy 414.509872 -199.757325) (xy 414.512506 -199.747886)
			(xy 422.297606 -155.044648) (xy 422.296336 -155.04287) (xy 422.279064 -155.025598) (xy 422.259424 -155.005311)
			(xy 422.225732 -154.960001) (xy 422.19908 -154.910225) (xy 422.180047 -154.857066) (xy 422.16905 -154.801684)
			(xy 422.166328 -154.745286) (xy 422.17194 -154.689102) (xy 422.185765 -154.634358) (xy 422.2075 -154.582245)
			(xy 422.236672 -154.533902) (xy 422.272644 -154.490381) (xy 422.293288 -154.471116) (xy 422.314476 -154.452597)
			(xy 422.361275 -154.421347) (xy 422.386506 -154.408886) (xy 422.402254 -154.40152) (xy 422.410128 -154.396694)
			(xy 422.410636 -154.396186) (xy 422.41343 -154.380184) (xy 422.441116 -154.220926) (xy 422.44137 -154.220672)
			(xy 422.441624 -154.21864) (xy 422.441878 -154.21737) (xy 423.08145 -149.24532) (xy 423.642282 -144.885664)
			(xy 423.721022 -144.274032) (xy 423.72153 -144.267936) (xy 423.733468 -143.00962) (xy 423.737786 -142.56004)
			(xy 423.742104 -142.099792) (xy 423.798492 -136.127744) (xy 423.919396 -123.317762) (xy 423.979848 -116.901976)
			(xy 423.980254 -116.874731) (xy 423.983685 -116.820344) (xy 423.986706 -116.793264) (xy 423.989106 -116.774179)
			(xy 423.995202 -116.736195) (xy 423.998898 -116.717318) (xy 425.994322 -106.744008) (xy 425.995027 -106.735526)
			(xy 425.99139 -106.71891) (xy 425.98721 -106.711496) (xy 425.981368 -106.703368) (xy 425.974764 -106.696764)
			(xy 425.971462 -106.694224) (xy 425.950843 -106.678765) (xy 425.91355 -106.643197) (xy 425.881374 -106.60294)
			(xy 425.8549 -106.558725) (xy 425.834607 -106.511353) (xy 425.820863 -106.461684) (xy 425.813918 -106.410619)
			(xy 425.813474 -106.384852) (xy 425.813977 -106.356633) (xy 425.822277 -106.300809) (xy 425.838704 -106.246815)
			(xy 425.8629 -106.195828) (xy 425.894338 -106.148957) (xy 425.932332 -106.107224) (xy 425.976056 -106.071539)
			(xy 426.024556 -106.042679) (xy 426.076776 -106.021272) (xy 426.10405 -106.014012) (xy 426.111162 -106.012234)
			(xy 426.124878 -106.00436) (xy 426.130173 -106.001173) (xy 426.139159 -105.992691) (xy 426.142658 -105.987596)
			(xy 426.144786 -105.984102) (xy 426.147977 -105.976569) (xy 426.149008 -105.97261) (xy 426.149516 -105.97007)
			(xy 426.28566 -105.290874) (xy 426.316902 -105.13441) (xy 426.379894 -104.819958) (xy 426.396404 -104.737154)
			(xy 426.492924 -104.254808) (xy 426.489876 -104.243378) (xy 426.489114 -104.240076) (xy 426.486828 -104.232964)
			(xy 426.486066 -104.230424) (xy 426.485812 -104.229408) (xy 426.484796 -104.22636) (xy 426.477803 -104.200505)
			(xy 426.470288 -104.147476) (xy 426.46981 -104.120696) (xy 426.46981 -104.120188) (xy 426.47031 -104.092951)
			(xy 426.478087 -104.039034) (xy 426.493452 -103.986772) (xy 426.516094 -103.937225) (xy 426.545551 -103.891403)
			(xy 426.563028 -103.870506) (xy 426.568362 -103.86441) (xy 426.573188 -103.85425) (xy 426.57395 -103.85044)
			(xy 426.574204 -103.849932) (xy 426.574712 -103.846376) (xy 426.57649 -103.836978) (xy 426.65015 -103.466138)
			(xy 426.651273 -103.457049) (xy 426.647744 -103.439091) (xy 426.643292 -103.431086) (xy 426.636688 -103.422196)
			(xy 426.62983 -103.415338) (xy 426.626528 -103.413052) (xy 426.602724 -103.39492) (xy 426.560529 -103.352496)
			(xy 426.525467 -103.30401) (xy 426.498395 -103.250649) (xy 426.479976 -103.193719) (xy 426.470661 -103.134614)
			(xy 426.470064 -103.104696) (xy 426.470559 -103.076554) (xy 426.478812 -103.020879) (xy 426.495152 -102.96702)
			(xy 426.519225 -102.916145) (xy 426.55051 -102.869357) (xy 426.588327 -102.827672) (xy 426.631856 -102.791993)
			(xy 426.680153 -102.763094) (xy 426.732172 -102.741602) (xy 426.75937 -102.734364) (xy 426.764958 -102.733094)
			(xy 426.766736 -102.732586) (xy 426.77334 -102.731316) (xy 426.78604 -102.724458) (xy 426.791882 -102.718616)
			(xy 426.796918 -102.713197) (xy 426.803898 -102.700161) (xy 426.805598 -102.692962) (xy 426.80763 -102.682548)
			(xy 426.80763 -102.682294) (xy 426.853604 -102.452678) (xy 426.878242 -102.329234) (xy 427.031404 -101.562408)
			(xy 427.032022 -101.557049) (xy 427.031252 -101.54629) (xy 427.02988 -101.541072) (xy 427.026324 -101.529896)
			(xy 427.017688 -101.520752) (xy 427.01718 -101.520244) (xy 426.976794 -101.478588) (xy 426.958506 -101.459792)
			(xy 426.950326 -101.452405) (xy 426.929639 -101.444875) (xy 426.918628 -101.445314) (xy 426.917612 -101.445314)
			(xy 426.914564 -101.445822) (xy 426.89994 -101.448158) (xy 426.870442 -101.450829) (xy 426.855636 -101.451156)
			(xy 426.852842 -101.451156) (xy 426.852334 -101.451156) (xy 426.851572 -101.451156) (xy 426.824321 -101.450668)
			(xy 426.770374 -101.442909) (xy 426.718079 -101.427552) (xy 426.668503 -101.40491) (xy 426.622652 -101.375443)
			(xy 426.581462 -101.339753) (xy 426.545769 -101.298564) (xy 426.5163 -101.252715) (xy 426.493655 -101.203139)
			(xy 426.478295 -101.150846) (xy 426.470533 -101.096899) (xy 426.470064 -101.069648) (xy 426.470565 -101.041911)
			(xy 426.478604 -100.987022) (xy 426.494506 -100.933876) (xy 426.517934 -100.883592) (xy 426.548396 -100.83723)
			(xy 426.585249 -100.795766) (xy 426.627717 -100.760075) (xy 426.674905 -100.730909) (xy 426.725818 -100.708882)
			(xy 426.779384 -100.694458) (xy 426.806868 -100.69068) (xy 426.828204 -100.68814) (xy 426.833284 -100.687886)
			(xy 426.851572 -100.687886) (xy 426.879068 -100.688402) (xy 426.93348 -100.696374) (xy 426.986181 -100.712083)
			(xy 427.011338 -100.723192) (xy 427.021642 -100.728) (xy 427.041721 -100.738676) (xy 427.05147 -100.744528)
			(xy 427.053248 -100.745544) (xy 427.062392 -100.750116) (xy 427.072044 -100.753164) (xy 427.079066 -100.754319)
			(xy 427.093244 -100.753163) (xy 427.099984 -100.750878) (xy 427.155864 -100.726748) (xy 427.156372 -100.726748)
			(xy 427.175168 -100.718366) (xy 427.182534 -100.714302) (xy 427.192186 -100.707952) (xy 427.197455 -100.702855)
			(xy 427.20507 -100.690337) (xy 427.207172 -100.683314) (xy 427.300136 -100.221288) (xy 428.499524 -94.228158)
			(xy 428.932594 -92.064332) (xy 429.001428 -91.720162) (xy 429.187356 -90.791538) (xy 429.190404 -90.776298)
			(xy 429.188118 -90.765884) (xy 429.18507 -90.75166) (xy 429.182276 -90.735658) (xy 429.182276 -90.734642)
			(xy 429.181768 -90.73134) (xy 429.18126 -90.727276) (xy 429.18126 -90.726768) (xy 429.179736 -90.713814)
			(xy 429.178492 -90.696559) (xy 429.17875 -90.661962) (xy 429.180244 -90.644726) (xy 429.180752 -90.6399)
			(xy 429.180752 -90.639646) (xy 429.181514 -90.63355) (xy 429.2473 -90.130884) (xy 429.24803 -90.12228)
			(xy 429.244381 -90.105414) (xy 429.240188 -90.097864) (xy 429.227488 -90.085164) (xy 429.218852 -90.078306)
			(xy 429.20412 -90.069162) (xy 429.194816 -90.064628) (xy 429.174233 -90.062652) (xy 429.164242 -90.065352)
			(xy 429.1584 -90.067638) (xy 429.154749 -90.069317) (xy 429.147986 -90.073655) (xy 429.144938 -90.076274)
			(xy 429.14316 -90.077798) (xy 429.122686 -90.093832) (xy 429.078216 -90.120788) (xy 429.030492 -90.141445)
			(xy 428.980403 -90.155418) (xy 428.928878 -90.162447) (xy 428.902876 -90.162888) (xy 428.901606 -90.162888)
			(xy 428.879762 -90.16238) (xy 428.87519 -90.162126) (xy 428.846692 -90.15954) (xy 428.79088 -90.146914)
			(xy 428.737579 -90.1261) (xy 428.687981 -90.097563) (xy 428.643198 -90.061942) (xy 428.604234 -90.020037)
			(xy 428.57196 -89.972785) (xy 428.547102 -89.921245) (xy 428.530214 -89.866572) (xy 428.521676 -89.809991)
			(xy 428.521114 -89.78138) (xy 428.521579 -89.754129) (xy 428.529338 -89.700181) (xy 428.544696 -89.647887)
			(xy 428.56734 -89.598311) (xy 428.596809 -89.552462) (xy 428.632503 -89.511273) (xy 428.673695 -89.475584)
			(xy 428.719548 -89.44612) (xy 428.769126 -89.423481) (xy 428.821422 -89.408129) (xy 428.875371 -89.400376)
			(xy 428.902622 -89.399872) (xy 428.931805 -89.40042) (xy 428.989493 -89.409296) (xy 429.045157 -89.426853)
			(xy 429.097498 -89.45268) (xy 429.145296 -89.486177) (xy 429.187436 -89.526561) (xy 429.222936 -89.572891)
			(xy 429.237394 -89.598246) (xy 429.241458 -89.605612) (xy 429.24677 -89.614292) (xy 429.262757 -89.626854)
			(xy 429.282377 -89.632187) (xy 429.292512 -89.631266) (xy 429.305466 -89.629488) (xy 429.30572 -89.629488)
			(xy 429.318928 -89.62771) (xy 429.341026 -89.6239) (xy 429.350678 -89.620344) (xy 429.35906 -89.614756)
			(xy 429.366172 -89.608406) (xy 429.36922 -89.605104) (xy 429.372268 -89.59977) (xy 429.38954 -89.572338)
			(xy 429.397874 -89.560575) (xy 429.416053 -89.538198) (xy 429.425862 -89.527634) (xy 429.426116 -89.52738)
			(xy 429.428656 -89.524586) (xy 429.435768 -89.51468) (xy 429.437546 -89.511632) (xy 429.443896 -89.499948)
			(xy 429.447706 -89.489534) (xy 429.498252 -89.237566) (xy 429.514 -89.159334) (xy 429.59909 -88.73363)
			(xy 429.59909 -88.733122) (xy 429.61306 -88.66124) (xy 429.613568 -88.654382) (xy 429.613568 -88.636602)
			(xy 429.613323 -88.62942) (xy 429.609328 -88.615623) (xy 429.605694 -88.609424) (xy 429.590913 -88.585389)
			(xy 429.567557 -88.534027) (xy 429.551714 -88.479873) (xy 429.543704 -88.424022) (xy 429.54321 -88.39581)
			(xy 429.54367 -88.36812) (xy 429.551377 -88.31328) (xy 429.566642 -88.260046) (xy 429.589169 -88.209454)
			(xy 429.618518 -88.162491) (xy 429.654118 -88.120071) (xy 429.695276 -88.083018) (xy 429.717962 -88.067134)
			(xy 429.72609 -88.061546) (xy 429.731424 -88.053672) (xy 429.734094 -88.049457) (xy 429.737934 -88.040248)
			(xy 429.739044 -88.035384) (xy 430.045876 -86.501986) (xy 430.351438 -84.974684) (xy 430.520094 -84.131658)
			(xy 430.572164 -83.8708) (xy 432.65217 -73.387966) (xy 432.649122 -73.383394) (xy 432.642264 -73.37298)
			(xy 432.637184 -73.367138) (xy 432.635914 -73.365868) (xy 432.635406 -73.36536) (xy 432.634644 -73.364598)
			(xy 432.632104 -73.362312) (xy 432.620166 -73.353422) (xy 432.618388 -73.352152) (xy 432.61788 -73.351898)
			(xy 432.617372 -73.35139) (xy 432.613562 -73.349104) (xy 432.60264 -73.34377) (xy 432.59883 -73.3425)
			(xy 432.598576 -73.3425) (xy 432.573385 -73.333787) (xy 432.525508 -73.310356) (xy 432.481355 -73.280494)
			(xy 432.441785 -73.244782) (xy 432.407566 -73.203914) (xy 432.379363 -73.158683) (xy 432.357725 -73.10997)
			(xy 432.343072 -73.058721) (xy 432.335689 -73.005932) (xy 432.335178 -72.97928) (xy 432.335658 -72.952133)
			(xy 432.343358 -72.898388) (xy 432.358599 -72.846277) (xy 432.381074 -72.796854) (xy 432.410329 -72.751116)
			(xy 432.445773 -72.709987) (xy 432.486689 -72.674298) (xy 432.532251 -72.644771) (xy 432.58154 -72.622)
			(xy 432.633558 -72.606448) (xy 432.687257 -72.598427) (xy 432.7144 -72.597772) (xy 432.717194 -72.597772)
			(xy 432.729229 -72.597863) (xy 432.75325 -72.599389) (xy 432.7652 -72.60082) (xy 432.765708 -72.60082)
			(xy 432.783488 -72.602852) (xy 432.787741 -72.602891) (xy 432.796167 -72.601749) (xy 432.800252 -72.600566)
			(xy 432.808888 -72.59701) (xy 433.493926 -69.144642) (xy 434.69306 -63.100204) (xy 434.6946 -63.090178)
			(xy 434.690573 -63.070315) (xy 434.679206 -63.053534) (xy 434.670962 -63.047626) (xy 434.66385 -63.043054)
			(xy 434.625242 -63.017908) (xy 434.619146 -63.01486) (xy 434.614315 -63.012802) (xy 434.604073 -63.010499)
			(xy 434.598826 -63.010288) (xy 434.598572 -63.010288) (xy 434.585618 -63.012066) (xy 434.58384 -63.012574)
			(xy 434.567076 -63.017908) (xy 434.56098 -63.021972) (xy 434.537171 -63.037445) (xy 434.485945 -63.061936)
			(xy 434.431656 -63.07857) (xy 434.375502 -63.086981) (xy 434.347112 -63.087504) (xy 434.319859 -63.087041)
			(xy 434.265907 -63.079286) (xy 434.213608 -63.063931) (xy 434.164027 -63.04129) (xy 434.118173 -63.011822)
			(xy 434.07698 -62.976129) (xy 434.041285 -62.934936) (xy 434.011816 -62.889083) (xy 433.989173 -62.839503)
			(xy 433.973817 -62.787205) (xy 433.966059 -62.733253) (xy 433.966059 -62.678747) (xy 433.973817 -62.624795)
			(xy 433.989173 -62.572497) (xy 434.011816 -62.522917) (xy 434.041285 -62.477064) (xy 434.07698 -62.435871)
			(xy 434.118173 -62.400178) (xy 434.164027 -62.37071) (xy 434.213608 -62.348069) (xy 434.265907 -62.332714)
			(xy 434.319859 -62.324959) (xy 434.347112 -62.324488) (xy 434.348128 -62.324488) (xy 434.370175 -62.324801)
			(xy 434.413973 -62.329895) (xy 434.435504 -62.334648) (xy 434.442108 -62.336172) (xy 434.452014 -62.337188)
			(xy 434.459961 -62.337122) (xy 434.475223 -62.332726) (xy 434.481986 -62.328552) (xy 434.48859 -62.323218)
			(xy 434.529484 -62.27572) (xy 434.549804 -62.252098) (xy 434.557036 -62.242877) (xy 434.56301 -62.220245)
			(xy 434.561234 -62.208664) (xy 434.55971 -62.203584) (xy 434.549757 -62.179511) (xy 434.535729 -62.129345)
			(xy 434.528649 -62.077737) (xy 434.528214 -62.051692) (xy 434.528214 -62.051438) (xy 434.528676 -62.024092)
			(xy 434.536454 -61.969957) (xy 434.551858 -61.91748) (xy 434.574574 -61.86773) (xy 434.604139 -61.821719)
			(xy 434.639951 -61.780384) (xy 434.681282 -61.744566) (xy 434.727289 -61.714996) (xy 434.777037 -61.692274)
			(xy 434.829512 -61.676864) (xy 434.883646 -61.669079) (xy 434.910992 -61.66866) (xy 434.942488 -61.66993)
			(xy 434.952426 -61.667971) (xy 434.969709 -61.657439) (xy 434.981597 -61.641059) (xy 434.984398 -61.631322)
			(xy 435.013354 -61.486034) (xy 435.110636 -60.99429) (xy 435.111652 -60.985146) (xy 435.116478 -60.68187)
			(xy 435.11597 -60.678568) (xy 435.11475 -60.667305) (xy 435.113482 -60.644684) (xy 435.11343 -60.633356)
			(xy 435.11343 -60.626752) (xy 435.1147 -60.601352) (xy 435.114954 -60.59932) (xy 435.114954 -60.597796)
			(xy 435.115208 -60.595256) (xy 435.117494 -60.577222) (xy 435.117494 -60.576968) (xy 435.118002 -60.573412)
			(xy 435.148482 -58.624978) (xy 435.145942 -58.613802) (xy 435.143656 -58.608722) (xy 435.132709 -58.583662)
			(xy 435.117298 -58.531193) (xy 435.10954 -58.477061) (xy 435.109112 -58.449718) (xy 435.109366 -58.436002)
			(xy 435.110382 -58.421016) (xy 435.112605 -58.396676) (xy 435.122507 -58.348811) (xy 435.138455 -58.302608)
			(xy 435.14899 -58.280554) (xy 435.15153 -58.27522) (xy 435.15407 -58.264552) (xy 435.238398 -52.860448)
			(xy 435.289706 -49.568862) (xy 435.289452 -49.565052) (xy 435.289198 -49.563274) (xy 434.129434 -40.978074)
			(xy 433.962048 -39.7383) (xy 433.958273 -39.708718) (xy 433.953823 -39.649242) (xy 433.953158 -39.619428)
			(xy 433.952904 -39.60622) (xy 433.952396 -39.567866) (xy 433.951634 -39.523162) (xy 433.951126 -39.516558)
			(xy 433.865782 -38.931342) (xy 433.860917 -38.895855) (xy 433.855704 -38.824411) (xy 433.855368 -38.788594)
			(xy 433.855368 -37.5539) (xy 433.854098 -37.548312) (xy 433.84479 -37.503374) (xy 433.833466 -37.412297)
			(xy 433.831492 -37.366448) (xy 433.830476 -37.357812) (xy 433.827936 -37.345874) (xy 433.813157 -37.304592)
			(xy 433.790117 -37.219981) (xy 433.774669 -37.133661) (xy 433.766933 -37.046312) (xy 433.766468 -37.002466)
			(xy 433.766468 -37.000688) (xy 433.76596 -36.991544) (xy 433.764701 -36.984436) (xy 433.758772 -36.971283)
			(xy 433.754276 -36.965636) (xy 433.70627 -36.913058) (xy 433.696618 -36.908486) (xy 433.672234 -36.896548)
			(xy 433.663598 -36.895532) (xy 433.662582 -36.895532) (xy 433.634445 -36.892527) (xy 433.579435 -36.87927)
			(xy 433.526986 -36.858034) (xy 433.478249 -36.829284) (xy 433.434293 -36.793651) (xy 433.396083 -36.751916)
			(xy 433.364455 -36.704995) (xy 433.340105 -36.653918) (xy 433.323566 -36.599804) (xy 433.315202 -36.54384)
			(xy 433.314602 -36.515548) (xy 433.315139 -36.486647) (xy 433.323862 -36.429507) (xy 433.341101 -36.374335)
			(xy 433.366461 -36.322393) (xy 433.399364 -36.274869) (xy 433.439056 -36.23285) (xy 433.48463 -36.197295)
			(xy 433.535043 -36.169019) (xy 433.589144 -36.148667) (xy 433.645695 -36.136705) (xy 433.67452 -36.134548)
			(xy 433.685696 -36.133786) (xy 433.694332 -36.129468) (xy 433.698043 -36.127498) (xy 433.704808 -36.122517)
			(xy 433.707794 -36.119562) (xy 433.74437 -36.077652) (xy 433.745132 -36.07689) (xy 433.758086 -36.061396)
			(xy 433.763239 -36.054738) (xy 433.769322 -36.039052) (xy 433.770024 -36.030662) (xy 433.770024 -36.025328)
			(xy 433.76977 -36.023042) (xy 433.76977 -36.02228) (xy 433.769516 -36.020248) (xy 433.767484 -35.983418)
			(xy 433.767484 -35.98291) (xy 433.766468 -35.940492) (xy 433.766468 -35.601656) (xy 433.766214 -35.597084)
			(xy 433.76596 -35.594798) (xy 433.764462 -35.586335) (xy 433.756676 -35.571022) (xy 433.75072 -35.564826)
			(xy 433.743862 -35.55873) (xy 433.68722 -35.509708) (xy 433.684172 -35.507168) (xy 433.680108 -35.505644)
			(xy 433.659026 -35.508692) (xy 433.658518 -35.508692) (xy 433.639607 -35.511424) (xy 433.601624 -35.515615)
			(xy 433.582572 -35.517074) (xy 433.565959 -35.518262) (xy 433.532678 -35.51966) (xy 433.516024 -35.519868)
			(xy 433.50307 -35.519868) (xy 433.456675 -35.518986) (xy 433.364343 -35.509662) (xy 433.273278 -35.491795)
			(xy 433.184269 -35.46554) (xy 433.098085 -35.431126) (xy 433.015473 -35.388848) (xy 432.97602 -35.36442)
			(xy 432.971702 -35.365182) (xy 432.96967 -35.36569) (xy 432.953426 -35.368459) (xy 432.920614 -35.371512)
			(xy 432.904138 -35.371786) (xy 432.900836 -35.371786) (xy 432.873754 -35.371315) (xy 432.820134 -35.363661)
			(xy 432.768135 -35.348502) (xy 432.718802 -35.326142) (xy 432.673126 -35.29703) (xy 432.632026 -35.261753)
			(xy 432.596328 -35.221018) (xy 432.566748 -35.175644) (xy 432.543882 -35.126544) (xy 432.528188 -35.074703)
			(xy 432.519983 -35.021165) (xy 432.519328 -34.994088) (xy 432.519328 -34.990024) (xy 432.519837 -34.96277)
			(xy 432.527627 -34.908821) (xy 432.542996 -34.856523) (xy 432.553872 -34.831528) (xy 432.556158 -34.826448)
			(xy 432.557936 -34.81832) (xy 432.552612 -34.800887) (xy 432.543087 -34.765699) (xy 432.538886 -34.747962)
			(xy 432.530758 -34.709608) (xy 432.522505 -34.663251) (xy 432.513732 -34.569494) (xy 432.513232 -34.52241)
			(xy 432.513666 -34.479823) (xy 432.520905 -34.394958) (xy 432.535356 -34.31102) (xy 432.556914 -34.22862)
			(xy 432.585422 -34.148359) (xy 432.60264 -34.109406) (xy 432.605824 -34.100273) (xy 432.605828 -34.080946)
			(xy 432.60264 -34.071814) (xy 432.585431 -34.032858) (xy 432.556936 -33.952594) (xy 432.535384 -33.870195)
			(xy 432.52093 -33.786258) (xy 432.513681 -33.701396) (xy 432.513232 -33.65881) (xy 432.513232 -33.657794)
			(xy 432.51386 -33.607927) (xy 432.523867 -33.508696) (xy 432.54374 -33.410962) (xy 432.557936 -33.363154)
			(xy 432.55692 -33.358582) (xy 432.553364 -33.348168) (xy 432.549554 -33.339532) (xy 432.549554 -33.339278)
			(xy 432.547522 -33.333944) (xy 432.5366 -33.304226) (xy 432.5366 -33.303972) (xy 432.535584 -33.301178)
			(xy 432.535076 -33.299146) (xy 432.534822 -33.298384) (xy 432.534822 -33.29813) (xy 432.529962 -33.280914)
			(xy 432.523092 -33.245804) (xy 432.521106 -33.228026) (xy 432.519328 -33.1978) (xy 432.519328 -33.188402)
			(xy 432.519937 -33.161236) (xy 432.5279 -33.107484) (xy 432.543411 -33.055407) (xy 432.566154 -33.006058)
			(xy 432.59567 -32.960435) (xy 432.631361 -32.919463) (xy 432.672505 -32.883969) (xy 432.718269 -32.854673)
			(xy 432.767727 -32.832167) (xy 432.819878 -32.816907) (xy 432.873667 -32.809202) (xy 432.900836 -32.808672)
			(xy 432.905408 -32.808672) (xy 432.921501 -32.809012) (xy 432.953548 -32.812065) (xy 432.969416 -32.814768)
			(xy 432.976782 -32.816038) (xy 433.016122 -32.791744) (xy 433.098487 -32.749716) (xy 433.184389 -32.715494)
			(xy 433.27309 -32.689372) (xy 433.363829 -32.671573) (xy 433.455826 -32.662252) (xy 433.502054 -32.661352)
			(xy 433.514246 -32.661352) (xy 433.560863 -32.662082) (xy 433.653659 -32.671163) (xy 433.745203 -32.688867)
			(xy 433.834694 -32.715039) (xy 433.921351 -32.749451) (xy 434.004417 -32.791802) (xy 434.04409 -32.816292)
			(xy 434.05044 -32.815022) (xy 434.053234 -32.814514) (xy 434.053742 -32.814514) (xy 434.059584 -32.813498)
			(xy 434.061616 -32.81299) (xy 434.06568 -32.812482) (xy 434.066696 -32.812482) (xy 434.080775 -32.810536)
			(xy 434.109126 -32.808502) (xy 434.123338 -32.808418) (xy 434.125116 -32.808418) (xy 434.1622 -32.810704)
			(xy 434.181115 -32.813008) (xy 434.218396 -32.820894) (xy 434.236622 -32.826452) (xy 434.23713 -32.826452)
			(xy 434.237638 -32.826706) (xy 434.239924 -32.827468) (xy 434.24475 -32.828992) (xy 434.254656 -32.830262)
			(xy 434.263083 -32.830591) (xy 434.279422 -32.826459) (xy 434.28666 -32.822134) (xy 434.32603 -32.79394)
			(xy 434.326538 -32.79394) (xy 434.355748 -32.772604) (xy 434.355748 -32.77235) (xy 434.359279 -32.769602)
			(xy 434.365408 -32.763085) (xy 434.36794 -32.759396) (xy 434.367432 -32.741108) (xy 434.367432 -32.722312)
			(xy 434.367866 -32.679725) (xy 434.375105 -32.59486) (xy 434.389556 -32.510922) (xy 434.411114 -32.428522)
			(xy 434.439622 -32.348261) (xy 434.45684 -32.309308) (xy 434.460025 -32.300175) (xy 434.460029 -32.280847)
			(xy 434.45684 -32.271716) (xy 434.439631 -32.23276) (xy 434.411136 -32.152496) (xy 434.389583 -32.070097)
			(xy 434.37513 -31.98616) (xy 434.367881 -31.901298) (xy 434.367432 -31.858712) (xy 434.367432 -31.841186)
			(xy 434.367432 -31.839662) (xy 434.36794 -31.82112) (xy 434.365378 -31.817339) (xy 434.35912 -31.810689)
			(xy 434.355494 -31.807912) (xy 434.348636 -31.802832) (xy 434.288946 -31.759398) (xy 434.280293 -31.753693)
			(xy 434.260101 -31.749111) (xy 434.24983 -31.750508) (xy 434.24221 -31.752032) (xy 434.238654 -31.753302)
			(xy 434.209858 -31.762102) (xy 434.150395 -31.771552) (xy 434.12029 -31.772098) (xy 434.11902 -31.772098)
			(xy 434.102618 -31.771939) (xy 434.069933 -31.769142) (xy 434.053742 -31.76651) (xy 434.049424 -31.766002)
			(xy 434.043074 -31.765748) (xy 434.003229 -31.790278) (xy 433.919773 -31.832601) (xy 433.832716 -31.866912)
			(xy 433.742826 -31.89291) (xy 433.650895 -31.910366) (xy 433.557731 -31.919125) (xy 433.510944 -31.919672)
			(xy 433.505864 -31.919672) (xy 433.505864 -31.919926) (xy 433.461525 -31.919229) (xy 433.37323 -31.910931)
			(xy 433.286019 -31.89483) (xy 433.200582 -31.871052) (xy 433.117591 -31.839787) (xy 433.037703 -31.80128)
			(xy 432.999388 -31.778956) (xy 432.995832 -31.77667) (xy 432.990657 -31.774411) (xy 432.979633 -31.771978)
			(xy 432.973988 -31.771844) (xy 432.900836 -31.771844) (xy 432.873686 -31.771368) (xy 432.819934 -31.763675)
			(xy 432.767815 -31.748438) (xy 432.718383 -31.725967) (xy 432.672636 -31.696714) (xy 432.631499 -31.661271)
			(xy 432.595802 -31.620353) (xy 432.566267 -31.574788) (xy 432.54349 -31.525496) (xy 432.527932 -31.473473)
			(xy 432.519907 -31.419769) (xy 432.519328 -31.392622) (xy 432.519328 -31.38932) (xy 432.519787 -31.361885)
			(xy 432.527609 -31.307575) (xy 432.543123 -31.254945) (xy 432.554126 -31.229808) (xy 432.557428 -31.220156)
			(xy 432.557936 -31.218124) (xy 432.543756 -31.170312) (xy 432.523888 -31.072578) (xy 432.513865 -30.97335)
			(xy 432.513232 -30.923484) (xy 432.513232 -30.922468) (xy 432.513668 -30.879882) (xy 432.52091 -30.795018)
			(xy 432.535364 -30.711081) (xy 432.556926 -30.628682) (xy 432.585437 -30.548424) (xy 432.60264 -30.509464)
			(xy 432.605816 -30.500331) (xy 432.605805 -30.48101) (xy 432.60264 -30.471872) (xy 432.585429 -30.432916)
			(xy 432.556929 -30.352653) (xy 432.535372 -30.270254) (xy 432.520914 -30.186317) (xy 432.51366 -30.101454)
			(xy 432.513232 -30.058868) (xy 432.513232 -30.05836) (xy 432.513876 -30.008319) (xy 432.52395 -29.908744)
			(xy 432.543932 -29.810675) (xy 432.55819 -29.762704) (xy 432.556412 -29.755084) (xy 432.554126 -29.750258)
			(xy 432.543118 -29.725168) (xy 432.527607 -29.672622) (xy 432.519785 -29.618394) (xy 432.519328 -29.591)
			(xy 432.519328 -29.590238) (xy 432.519789 -29.562984) (xy 432.527542 -29.509031) (xy 432.542895 -29.456731)
			(xy 432.565535 -29.407148) (xy 432.595003 -29.361293) (xy 432.630697 -29.320099) (xy 432.671891 -29.284404)
			(xy 432.717746 -29.254936) (xy 432.767329 -29.232295) (xy 432.819629 -29.216942) (xy 432.873582 -29.209189)
			(xy 432.900836 -29.20873) (xy 432.901852 -29.20873) (xy 432.918704 -29.208894) (xy 432.952281 -29.21182)
			(xy 432.968908 -29.214572) (xy 432.977036 -29.216096) (xy 433.016963 -29.191468) (xy 433.100602 -29.148964)
			(xy 433.187859 -29.114496) (xy 433.277965 -29.088366) (xy 433.370126 -29.070805) (xy 433.463527 -29.061969)
			(xy 433.510436 -29.06141) (xy 433.557348 -29.061941) (xy 433.650758 -29.070744) (xy 433.742928 -29.088288)
			(xy 433.83304 -29.114416) (xy 433.920298 -29.148899) (xy 434.003929 -29.191429) (xy 434.043836 -29.216096)
			(xy 434.050186 -29.214826) (xy 434.067496 -29.211884) (xy 434.102478 -29.208833) (xy 434.120036 -29.20873)
			(xy 434.120798 -29.20873) (xy 434.148442 -29.209235) (xy 434.203144 -29.217262) (xy 434.229764 -29.224732)
			(xy 434.23332 -29.225748) (xy 434.24602 -29.22778) (xy 434.250846 -29.228034) (xy 434.263292 -29.228034)
			(xy 434.270937 -29.227776) (xy 434.285541 -29.223251) (xy 434.291994 -29.219144) (xy 434.312822 -29.20365)
			(xy 434.313584 -29.203142) (xy 434.356002 -29.172408) (xy 434.357018 -29.171646) (xy 434.36018 -29.169014)
			(xy 434.365663 -29.162881) (xy 434.36794 -29.159454) (xy 434.367432 -29.137356) (xy 434.367432 -29.12237)
			(xy 434.367868 -29.079784) (xy 434.37511 -28.99492) (xy 434.389564 -28.910982) (xy 434.411125 -28.828584)
			(xy 434.439636 -28.748325) (xy 434.45684 -28.709366) (xy 434.460017 -28.700233) (xy 434.460006 -28.680912)
			(xy 434.45684 -28.671774) (xy 434.439629 -28.632818) (xy 434.411129 -28.552555) (xy 434.389572 -28.470156)
			(xy 434.375113 -28.386219) (xy 434.367859 -28.301356) (xy 434.367432 -28.25877) (xy 434.36792 -28.211623)
			(xy 434.376694 -28.117738) (xy 434.384958 -28.071318) (xy 434.388606 -28.052831) (xy 434.397116 -28.016118)
			(xy 434.401976 -27.997912) (xy 434.412136 -27.96286) (xy 434.412136 -27.962606) (xy 434.410358 -27.954224)
			(xy 434.408072 -27.949144) (xy 434.407818 -27.948636) (xy 434.397275 -27.924428) (xy 434.382219 -27.873818)
			(xy 434.374301 -27.821613) (xy 434.373528 -27.79522) (xy 434.373528 -27.789886) (xy 434.374029 -27.762646)
			(xy 434.38181 -27.708723) (xy 434.397184 -27.656456) (xy 434.419838 -27.606908) (xy 434.449311 -27.561087)
			(xy 434.485003 -27.519926) (xy 434.526188 -27.484261) (xy 434.572028 -27.454818) (xy 434.621591 -27.432197)
			(xy 434.673868 -27.416857) (xy 434.727795 -27.409111) (xy 434.755036 -27.408632) (xy 434.756306 -27.408632)
			(xy 434.77065 -27.408764) (xy 434.799256 -27.410924) (xy 434.813456 -27.41295) (xy 434.822231 -27.413855)
			(xy 434.839506 -27.410341) (xy 434.847238 -27.406092) (xy 434.883052 -27.385264) (xy 434.88356 -27.385264)
			(xy 434.896006 -27.378152) (xy 434.899816 -27.368754) (xy 434.919628 -27.295348) (xy 434.919374 -27.281632)
			(xy 434.917596 -27.275028) (xy 434.913278 -27.259534) (xy 434.91023 -27.2542) (xy 434.898536 -27.232663)
			(xy 434.88012 -27.187248) (xy 434.867661 -27.139852) (xy 434.861364 -27.091251) (xy 434.860954 -27.066748)
			(xy 434.860954 -27.057604) (xy 434.861208 -27.054048) (xy 434.861208 -27.053032) (xy 434.862732 -27.030172)
			(xy 434.865478 -27.005455) (xy 434.876571 -26.956976) (xy 434.893877 -26.910353) (xy 434.90515 -26.888186)
			(xy 434.907182 -26.884122) (xy 434.908198 -26.882344) (xy 434.909214 -26.880566) (xy 434.909214 -26.880312)
			(xy 434.91609 -26.868281) (xy 434.931343 -26.845142) (xy 434.939694 -26.834084) (xy 434.940202 -26.833576)
			(xy 434.950108 -26.821638) (xy 434.951124 -26.820114) (xy 434.952902 -26.817828) (xy 434.954426 -26.816304)
			(xy 434.96865 -26.80081) (xy 434.996844 -26.774394) (xy 434.997098 -26.77414) (xy 435.000654 -26.771346)
			(xy 435.003956 -26.768552) (xy 435.004972 -26.76779) (xy 435.007258 -26.766012) (xy 435.00929 -26.76398)
			(xy 435.01183 -26.761948) (xy 435.016656 -26.757122) (xy 435.021736 -26.751026) (xy 435.02199 -26.750772)
			(xy 435.022498 -26.75001) (xy 435.027395 -26.743402) (xy 435.033107 -26.727988) (xy 435.033674 -26.719784)
			(xy 435.033674 -26.71572) (xy 435.029102 -26.630884) (xy 435.028351 -26.62538) (xy 435.024762 -26.61487)
			(xy 435.02199 -26.610056) (xy 435.018942 -26.60523) (xy 435.011068 -26.596848) (xy 435.004718 -26.593038)
			(xy 434.981004 -26.578118) (xy 434.93782 -26.542426) (xy 434.900316 -26.500805) (xy 434.869299 -26.45415)
			(xy 434.845433 -26.403462) (xy 434.829233 -26.34983) (xy 434.821045 -26.294407) (xy 434.820568 -26.266394)
			(xy 434.821054 -26.239143) (xy 434.82881 -26.185195) (xy 434.844165 -26.1329) (xy 434.866807 -26.083323)
			(xy 434.896273 -26.037473) (xy 434.931964 -25.996282) (xy 434.973155 -25.960591) (xy 435.019005 -25.931125)
			(xy 435.068582 -25.908483) (xy 435.120877 -25.893128) (xy 435.174825 -25.885372) (xy 435.229327 -25.885372)
			(xy 435.283275 -25.893128) (xy 435.33557 -25.908483) (xy 435.385147 -25.931125) (xy 435.430997 -25.960591)
			(xy 435.472188 -25.996282) (xy 435.507879 -26.037473) (xy 435.537345 -26.083323) (xy 435.559987 -26.1329)
			(xy 435.575342 -26.185195) (xy 435.583098 -26.239143) (xy 435.583584 -26.266394) (xy 435.583054 -26.295249)
			(xy 435.57436 -26.352301) (xy 435.557169 -26.407392) (xy 435.531875 -26.459264) (xy 435.499053 -26.506733)
			(xy 435.459455 -26.548715) (xy 435.437026 -26.566876) (xy 435.436518 -26.567384) (xy 435.4322 -26.57094)
			(xy 435.424326 -26.580338) (xy 435.423818 -26.5811) (xy 435.417309 -26.589037) (xy 435.410632 -26.608429)
			(xy 435.410864 -26.618692) (xy 435.41188 -26.637742) (xy 435.41188 -26.63825) (xy 435.415436 -26.707592)
			(xy 435.420008 -26.717498) (xy 435.425088 -26.72715) (xy 435.43474 -26.736548) (xy 435.439312 -26.739596)
			(xy 435.441344 -26.740866) (xy 435.443122 -26.741882) (xy 435.445662 -26.743406) (xy 435.46861 -26.758415)
			(xy 435.510353 -26.793969) (xy 435.546579 -26.835131) (xy 435.576542 -26.881052) (xy 435.599625 -26.930789)
			(xy 435.615353 -26.983317) (xy 435.623403 -27.037556) (xy 435.62397 -27.06497) (xy 435.62397 -27.070558)
			(xy 435.623725 -27.084974) (xy 435.621313 -27.113708) (xy 435.619144 -27.127962) (xy 435.61762 -27.136344)
			(xy 435.614977 -27.14995) (xy 435.607985 -27.176773) (xy 435.60365 -27.189938) (xy 435.602126 -27.194256)
			(xy 435.600771 -27.201865) (xy 435.602197 -27.217248) (xy 435.60492 -27.224482) (xy 435.636162 -27.286458)
			(xy 435.63843 -27.290228) (xy 435.644049 -27.296997) (xy 435.647338 -27.29992) (xy 435.651148 -27.303222)
			(xy 435.663848 -27.307286) (xy 435.714027 -27.323837) (xy 435.757595 -27.342846) (xy 442.8236 -27.342846)
			(xy 442.8236 -26.479246) (xy 442.82409 -26.449278) (xy 442.831913 -26.389856) (xy 442.847426 -26.331963)
			(xy 442.870362 -26.27659) (xy 442.900329 -26.224684) (xy 442.936816 -26.177134) (xy 442.979196 -26.134754)
			(xy 443.026746 -26.098267) (xy 443.078652 -26.0683) (xy 443.134025 -26.045364) (xy 443.191918 -26.029851)
			(xy 443.25134 -26.022028) (xy 443.311276 -26.022028) (xy 443.370698 -26.029851) (xy 443.428591 -26.045364)
			(xy 443.483964 -26.0683) (xy 443.53587 -26.098267) (xy 443.58342 -26.134754) (xy 443.6258 -26.177134)
			(xy 443.662287 -26.224684) (xy 443.692254 -26.27659) (xy 443.71519 -26.331963) (xy 443.722939 -26.360882)
			(xy 445.389506 -26.360882) (xy 445.393577 -26.30526) (xy 445.405703 -26.250823) (xy 445.425626 -26.198732)
			(xy 445.452922 -26.150097) (xy 445.487008 -26.105954) (xy 445.527157 -26.067245) (xy 445.572515 -26.034794)
			(xy 445.622115 -26.009293) (xy 445.674899 -25.991286) (xy 445.729742 -25.981156) (xy 445.785476 -25.979119)
			(xy 445.840913 -25.985219) (xy 445.89487 -25.999325) (xy 445.946199 -26.021137) (xy 445.993805 -26.050191)
			(xy 446.036673 -26.085866) (xy 446.07389 -26.127403) (xy 446.104663 -26.173916) (xy 446.128335 -26.224413)
			(xy 446.144403 -26.27782) (xy 446.150571 -26.319734) (xy 451.141844 -26.319734) (xy 451.145915 -26.264112)
			(xy 451.158041 -26.209675) (xy 451.177964 -26.157584) (xy 451.20526 -26.108949) (xy 451.239346 -26.064806)
			(xy 451.279495 -26.026097) (xy 451.324853 -25.993646) (xy 451.374453 -25.968145) (xy 451.427237 -25.950138)
			(xy 451.48208 -25.940008) (xy 451.537814 -25.937971) (xy 451.593251 -25.944071) (xy 451.647208 -25.958177)
			(xy 451.698537 -25.979989) (xy 451.746143 -26.009043) (xy 451.789011 -26.044718) (xy 451.826228 -26.086255)
			(xy 451.857001 -26.132768) (xy 451.880673 -26.183265) (xy 451.896741 -26.236672) (xy 451.904861 -26.291848)
			(xy 451.90537 -26.319734) (xy 451.904861 -26.34762) (xy 451.896741 -26.402796) (xy 451.880673 -26.456203)
			(xy 451.857001 -26.5067) (xy 451.826228 -26.553213) (xy 451.789011 -26.59475) (xy 451.746143 -26.630425)
			(xy 451.698537 -26.659479) (xy 451.647208 -26.681291) (xy 451.593251 -26.695397) (xy 451.537814 -26.701497)
			(xy 451.48208 -26.69946) (xy 451.427237 -26.68933) (xy 451.374453 -26.671323) (xy 451.324853 -26.645822)
			(xy 451.279495 -26.613371) (xy 451.239346 -26.574662) (xy 451.20526 -26.530519) (xy 451.177964 -26.481884)
			(xy 451.158041 -26.429793) (xy 451.145915 -26.375356) (xy 451.141844 -26.319734) (xy 446.150571 -26.319734)
			(xy 446.152523 -26.332996) (xy 446.153032 -26.360882) (xy 446.152523 -26.388768) (xy 446.144403 -26.443944)
			(xy 446.128335 -26.497351) (xy 446.104663 -26.547848) (xy 446.07389 -26.594361) (xy 446.036673 -26.635898)
			(xy 445.993805 -26.671573) (xy 445.946199 -26.700627) (xy 445.89487 -26.722439) (xy 445.840913 -26.736545)
			(xy 445.785476 -26.742645) (xy 445.729742 -26.740608) (xy 445.674899 -26.730478) (xy 445.622115 -26.712471)
			(xy 445.572515 -26.68697) (xy 445.527157 -26.654519) (xy 445.487008 -26.61581) (xy 445.452922 -26.571667)
			(xy 445.425626 -26.523032) (xy 445.405703 -26.470941) (xy 445.393577 -26.416504) (xy 445.389506 -26.360882)
			(xy 443.722939 -26.360882) (xy 443.730703 -26.389856) (xy 443.738526 -26.449278) (xy 443.739016 -26.479246)
			(xy 443.739016 -26.971244) (xy 447.150996 -26.971244) (xy 447.155067 -26.915622) (xy 447.167193 -26.861185)
			(xy 447.187116 -26.809094) (xy 447.214412 -26.760459) (xy 447.248498 -26.716316) (xy 447.288647 -26.677607)
			(xy 447.334005 -26.645156) (xy 447.383605 -26.619655) (xy 447.436389 -26.601648) (xy 447.491232 -26.591518)
			(xy 447.546966 -26.589481) (xy 447.602403 -26.595581) (xy 447.65636 -26.609687) (xy 447.707689 -26.631499)
			(xy 447.755295 -26.660553) (xy 447.798163 -26.696228) (xy 447.83538 -26.737765) (xy 447.866153 -26.784278)
			(xy 447.889825 -26.834775) (xy 447.905893 -26.888182) (xy 447.914013 -26.943358) (xy 447.914522 -26.971244)
			(xy 447.914013 -26.99913) (xy 447.905893 -27.054306) (xy 447.889825 -27.107713) (xy 447.866153 -27.15821)
			(xy 447.83538 -27.204723) (xy 447.798163 -27.24626) (xy 447.755295 -27.281935) (xy 447.707689 -27.310989)
			(xy 447.65636 -27.332801) (xy 447.602403 -27.346907) (xy 447.546966 -27.353007) (xy 447.491232 -27.35097)
			(xy 447.436389 -27.34084) (xy 447.383605 -27.322833) (xy 447.334005 -27.297332) (xy 447.288647 -27.264881)
			(xy 447.248498 -27.226172) (xy 447.214412 -27.182029) (xy 447.187116 -27.133394) (xy 447.167193 -27.081303)
			(xy 447.155067 -27.026866) (xy 447.150996 -26.971244) (xy 443.739016 -26.971244) (xy 443.739016 -27.342846)
			(xy 443.738526 -27.372814) (xy 443.730703 -27.432236) (xy 443.71519 -27.490129) (xy 443.692254 -27.545502)
			(xy 443.662287 -27.597408) (xy 443.6258 -27.644958) (xy 443.58342 -27.687338) (xy 443.53587 -27.723825)
			(xy 443.483964 -27.753792) (xy 443.428591 -27.776728) (xy 443.370698 -27.792241) (xy 443.311276 -27.800064)
			(xy 443.25134 -27.800064) (xy 443.191918 -27.792241) (xy 443.134025 -27.776728) (xy 443.078652 -27.753792)
			(xy 443.026746 -27.723825) (xy 442.979196 -27.687338) (xy 442.936816 -27.644958) (xy 442.900329 -27.597408)
			(xy 442.870362 -27.545502) (xy 442.847426 -27.490129) (xy 442.831913 -27.432236) (xy 442.82409 -27.372814)
			(xy 442.8236 -27.342846) (xy 435.757595 -27.342846) (xy 435.810876 -27.366093) (xy 435.857142 -27.391614)
			(xy 435.85765 -27.391614) (xy 435.874668 -27.401774) (xy 435.876192 -27.40279) (xy 435.876954 -27.403044)
			(xy 435.878224 -27.403806) (xy 435.883966 -27.40697) (xy 435.896569 -27.410563) (xy 435.903116 -27.410918)
			(xy 435.90972 -27.410664) (xy 435.919405 -27.409656) (xy 435.938846 -27.408515) (xy 435.948582 -27.408378)
			(xy 435.94909 -27.408378) (xy 435.96814 -27.408886) (xy 435.977792 -27.409648) (xy 436.006844 -27.412391)
			(xy 436.063684 -27.425587) (xy 436.117849 -27.447293) (xy 436.168072 -27.477002) (xy 436.213179 -27.514019)
			(xy 436.233062 -27.535378) (xy 436.233316 -27.535632) (xy 436.24086 -27.543142) (xy 436.26028 -27.5518)
			(xy 436.270908 -27.552396) (xy 436.31104 -27.552396) (xy 436.354559 -27.552855) (xy 436.441266 -27.560437)
			(xy 436.526981 -27.575549) (xy 436.611054 -27.598075) (xy 436.692842 -27.627845) (xy 436.771724 -27.664631)
			(xy 436.847099 -27.708153) (xy 436.918393 -27.75808) (xy 436.985063 -27.814032) (xy 437.016144 -27.844496)
			(xy 438.28589 -29.114242) (xy 445.147192 -29.114242) (xy 445.147192 -28.250642) (xy 445.147682 -28.220658)
			(xy 445.15551 -28.161202) (xy 445.171031 -28.103277) (xy 445.19398 -28.047873) (xy 445.223964 -27.995939)
			(xy 445.26047 -27.948363) (xy 445.302875 -27.905958) (xy 445.350451 -27.869452) (xy 445.402385 -27.839468)
			(xy 445.457789 -27.816519) (xy 445.515714 -27.800998) (xy 445.57517 -27.79317) (xy 445.635138 -27.79317)
			(xy 445.694594 -27.800998) (xy 445.752519 -27.816519) (xy 445.807923 -27.839468) (xy 445.859857 -27.869452)
			(xy 445.907433 -27.905958) (xy 445.949838 -27.948363) (xy 445.986344 -27.995939) (xy 446.016328 -28.047873)
			(xy 446.039277 -28.103277) (xy 446.054798 -28.161202) (xy 446.062626 -28.220658) (xy 446.063116 -28.250642)
			(xy 446.063116 -28.469082) (xy 450.052438 -28.469082) (xy 450.056509 -28.41346) (xy 450.068635 -28.359023)
			(xy 450.088558 -28.306932) (xy 450.115854 -28.258297) (xy 450.14994 -28.214154) (xy 450.190089 -28.175445)
			(xy 450.235447 -28.142994) (xy 450.285047 -28.117493) (xy 450.337831 -28.099486) (xy 450.392674 -28.089356)
			(xy 450.448408 -28.087319) (xy 450.503845 -28.093419) (xy 450.557802 -28.107525) (xy 450.609131 -28.129337)
			(xy 450.656737 -28.158391) (xy 450.699605 -28.194066) (xy 450.736822 -28.235603) (xy 450.767595 -28.282116)
			(xy 450.791267 -28.332613) (xy 450.807335 -28.38602) (xy 450.815455 -28.441196) (xy 450.815964 -28.469082)
			(xy 450.815455 -28.496968) (xy 450.807335 -28.552144) (xy 450.791267 -28.605551) (xy 450.767595 -28.656048)
			(xy 450.736822 -28.702561) (xy 450.699605 -28.744098) (xy 450.656737 -28.779773) (xy 450.609131 -28.808827)
			(xy 450.557802 -28.830639) (xy 450.503845 -28.844745) (xy 450.448408 -28.850845) (xy 450.392674 -28.848808)
			(xy 450.337831 -28.838678) (xy 450.285047 -28.820671) (xy 450.235447 -28.79517) (xy 450.190089 -28.762719)
			(xy 450.14994 -28.72401) (xy 450.115854 -28.679867) (xy 450.088558 -28.631232) (xy 450.068635 -28.579141)
			(xy 450.056509 -28.524704) (xy 450.052438 -28.469082) (xy 446.063116 -28.469082) (xy 446.063116 -29.114242)
			(xy 446.062626 -29.144226) (xy 446.054798 -29.203682) (xy 446.039277 -29.261607) (xy 446.016328 -29.317011)
			(xy 445.986344 -29.368945) (xy 445.949838 -29.416521) (xy 445.907433 -29.458926) (xy 445.859857 -29.495432)
			(xy 445.807923 -29.525416) (xy 445.752519 -29.548365) (xy 445.694594 -29.563886) (xy 445.635138 -29.571714)
			(xy 445.57517 -29.571714) (xy 445.515714 -29.563886) (xy 445.457789 -29.548365) (xy 445.402385 -29.525416)
			(xy 445.350451 -29.495432) (xy 445.302875 -29.458926) (xy 445.26047 -29.416521) (xy 445.223964 -29.368945)
			(xy 445.19398 -29.317011) (xy 445.171031 -29.261607) (xy 445.15551 -29.203682) (xy 445.147682 -29.144226)
			(xy 445.147192 -29.114242) (xy 438.28589 -29.114242) (xy 439.556906 -30.385258) (xy 439.590598 -30.419751)
			(xy 439.65188 -30.494201) (xy 439.70569 -30.574219) (xy 439.751525 -30.659058) (xy 439.770774 -30.703266)
			(xy 439.862555 -30.92069) (xy 447.7893 -30.92069) (xy 447.7893 -30.05709) (xy 447.78979 -30.027106)
			(xy 447.797618 -29.96765) (xy 447.813139 -29.909725) (xy 447.836088 -29.854321) (xy 447.866072 -29.802387)
			(xy 447.902578 -29.754811) (xy 447.944983 -29.712406) (xy 447.992559 -29.6759) (xy 448.044493 -29.645916)
			(xy 448.099897 -29.622967) (xy 448.157822 -29.607446) (xy 448.217278 -29.599618) (xy 448.277246 -29.599618)
			(xy 448.336702 -29.607446) (xy 448.394627 -29.622967) (xy 448.450031 -29.645916) (xy 448.501965 -29.6759)
			(xy 448.549541 -29.712406) (xy 448.591946 -29.754811) (xy 448.628452 -29.802387) (xy 448.658436 -29.854321)
			(xy 448.681385 -29.909725) (xy 448.696906 -29.96765) (xy 448.704734 -30.027106) (xy 448.705224 -30.05709)
			(xy 448.705224 -30.745738) (xy 457.614517 -30.745738) (xy 457.614517 -30.616598) (xy 457.622467 -30.487703)
			(xy 457.638337 -30.359543) (xy 457.662066 -30.232602) (xy 457.693565 -30.107363) (xy 457.732714 -29.9843)
			(xy 457.779365 -29.863881) (xy 457.83334 -29.746562) (xy 457.894435 -29.632788) (xy 457.962418 -29.522991)
			(xy 458.037032 -29.417588) (xy 458.117993 -29.316978) (xy 458.204993 -29.221543) (xy 458.297704 -29.131644)
			(xy 458.395774 -29.047623) (xy 458.498829 -28.969799) (xy 458.60648 -28.898467) (xy 458.718319 -28.833897)
			(xy 458.83392 -28.776335) (xy 458.952845 -28.725998) (xy 459.074644 -28.683078) (xy 459.198854 -28.647737)
			(xy 459.325003 -28.62011) (xy 459.452615 -28.600301) (xy 459.581204 -28.588385) (xy 459.710282 -28.584409)
			(xy 459.83936 -28.588385) (xy 459.967949 -28.600301) (xy 460.095561 -28.62011) (xy 460.22171 -28.647737)
			(xy 460.34592 -28.683078) (xy 460.467719 -28.725998) (xy 460.586644 -28.776335) (xy 460.702245 -28.833897)
			(xy 460.814084 -28.898467) (xy 460.921735 -28.969799) (xy 461.02479 -29.047623) (xy 461.12286 -29.131644)
			(xy 461.215571 -29.221543) (xy 461.302571 -29.316978) (xy 461.383532 -29.417588) (xy 461.458146 -29.522991)
			(xy 461.526129 -29.632788) (xy 461.587224 -29.746562) (xy 461.641199 -29.863881) (xy 461.68785 -29.9843)
			(xy 461.726999 -30.107363) (xy 461.758498 -30.232602) (xy 461.782227 -30.359543) (xy 461.798097 -30.487703)
			(xy 461.806047 -30.616598) (xy 461.806544 -30.681168) (xy 461.806047 -30.745738) (xy 461.798097 -30.874633)
			(xy 461.782227 -31.002793) (xy 461.758498 -31.129734) (xy 461.726999 -31.254973) (xy 461.68785 -31.378036)
			(xy 461.641199 -31.498455) (xy 461.587224 -31.615774) (xy 461.526129 -31.729548) (xy 461.458146 -31.839345)
			(xy 461.383532 -31.944748) (xy 461.302571 -32.045358) (xy 461.215571 -32.140793) (xy 461.12286 -32.230692)
			(xy 461.02479 -32.314713) (xy 460.921735 -32.392537) (xy 460.814084 -32.463869) (xy 460.702245 -32.528439)
			(xy 460.586644 -32.586001) (xy 460.467719 -32.636338) (xy 460.34592 -32.679258) (xy 460.22171 -32.714599)
			(xy 460.095561 -32.742226) (xy 459.967949 -32.762035) (xy 459.83936 -32.773951) (xy 459.710282 -32.777928)
			(xy 459.581204 -32.773951) (xy 459.452615 -32.762035) (xy 459.325003 -32.742226) (xy 459.198854 -32.714599)
			(xy 459.074644 -32.679258) (xy 458.952845 -32.636338) (xy 458.83392 -32.586001) (xy 458.718319 -32.528439)
			(xy 458.60648 -32.463869) (xy 458.498829 -32.392537) (xy 458.395774 -32.314713) (xy 458.297704 -32.230692)
			(xy 458.204993 -32.140793) (xy 458.117993 -32.045358) (xy 458.037032 -31.944748) (xy 457.962418 -31.839345)
			(xy 457.894435 -31.729548) (xy 457.83334 -31.615774) (xy 457.779365 -31.498455) (xy 457.732714 -31.378036)
			(xy 457.693565 -31.254973) (xy 457.662066 -31.129734) (xy 457.638337 -31.002793) (xy 457.622467 -30.874633)
			(xy 457.614517 -30.745738) (xy 448.705224 -30.745738) (xy 448.705224 -30.92069) (xy 448.704734 -30.950674)
			(xy 448.696906 -31.01013) (xy 448.681385 -31.068055) (xy 448.658436 -31.123459) (xy 448.628452 -31.175393)
			(xy 448.591946 -31.222969) (xy 448.549541 -31.265374) (xy 448.501965 -31.30188) (xy 448.450031 -31.331864)
			(xy 448.394627 -31.354813) (xy 448.336702 -31.370334) (xy 448.277246 -31.378162) (xy 448.217278 -31.378162)
			(xy 448.157822 -31.370334) (xy 448.099897 -31.354813) (xy 448.044493 -31.331864) (xy 447.992559 -31.30188)
			(xy 447.944983 -31.265374) (xy 447.902578 -31.222969) (xy 447.866072 -31.175393) (xy 447.836088 -31.123459)
			(xy 447.813139 -31.068055) (xy 447.797618 -31.01013) (xy 447.78979 -30.950674) (xy 447.7893 -30.92069)
			(xy 439.862555 -30.92069) (xy 439.896758 -31.001716) (xy 439.899298 -31.005526) (xy 439.925009 -31.045428)
			(xy 439.969534 -31.129267) (xy 439.988198 -31.172912) (xy 440.626852 -32.714184) (xy 445.147192 -32.714184)
			(xy 445.147192 -31.850584) (xy 445.147682 -31.8206) (xy 445.15551 -31.761144) (xy 445.171031 -31.703219)
			(xy 445.19398 -31.647815) (xy 445.223964 -31.595881) (xy 445.26047 -31.548305) (xy 445.302875 -31.5059)
			(xy 445.350451 -31.469394) (xy 445.402385 -31.43941) (xy 445.457789 -31.416461) (xy 445.515714 -31.40094)
			(xy 445.57517 -31.393112) (xy 445.635138 -31.393112) (xy 445.694594 -31.40094) (xy 445.752519 -31.416461)
			(xy 445.807923 -31.43941) (xy 445.859857 -31.469394) (xy 445.907433 -31.5059) (xy 445.949838 -31.548305)
			(xy 445.986344 -31.595881) (xy 446.016328 -31.647815) (xy 446.039277 -31.703219) (xy 446.054798 -31.761144)
			(xy 446.062626 -31.8206) (xy 446.063116 -31.850584) (xy 446.063116 -32.714184) (xy 446.062626 -32.744168)
			(xy 446.054798 -32.803624) (xy 446.039277 -32.861549) (xy 446.016328 -32.916953) (xy 445.986344 -32.968887)
			(xy 445.949838 -33.016463) (xy 445.907433 -33.058868) (xy 445.859857 -33.095374) (xy 445.807923 -33.125358)
			(xy 445.752519 -33.148307) (xy 445.694594 -33.163828) (xy 445.635138 -33.171656) (xy 445.57517 -33.171656)
			(xy 445.515714 -33.163828) (xy 445.457789 -33.148307) (xy 445.402385 -33.125358) (xy 445.350451 -33.095374)
			(xy 445.302875 -33.058868) (xy 445.26047 -33.016463) (xy 445.223964 -32.968887) (xy 445.19398 -32.916953)
			(xy 445.171031 -32.861549) (xy 445.15551 -32.803624) (xy 445.147682 -32.744168) (xy 445.147192 -32.714184)
			(xy 440.626852 -32.714184) (xy 440.663584 -32.80283) (xy 440.666124 -32.807402) (xy 440.670188 -32.812228)
			(xy 440.671966 -32.81426) (xy 440.67349 -32.816546) (xy 440.674252 -32.817562) (xy 440.684666 -32.827976)
			(xy 440.691778 -32.833818) (xy 440.701684 -32.840422) (xy 440.706002 -32.842454) (xy 440.731118 -32.854347)
			(xy 440.77791 -32.884323) (xy 440.819861 -32.920767) (xy 440.856083 -32.96291) (xy 440.885811 -33.00986)
			(xy 440.908417 -33.060625) (xy 440.923421 -33.114131) (xy 440.930508 -33.169248) (xy 440.930538 -33.197038)
			(xy 440.930284 -33.202118) (xy 440.930284 -33.202372) (xy 440.93003 -33.208214) (xy 440.928562 -33.231495)
			(xy 440.920666 -33.277471) (xy 440.914282 -33.299908) (xy 440.914282 -33.300416) (xy 440.912758 -33.305242)
			(xy 440.912758 -33.30575) (xy 440.904376 -33.32861) (xy 440.90082 -33.3375) (xy 440.898534 -33.347406)
			(xy 440.897174 -33.355156) (xy 440.898737 -33.370803) (xy 440.901582 -33.37814) (xy 440.969654 -33.542478)
			(xy 441.1218 -33.909254) (xy 441.1218 -33.909762) (xy 441.379226 -34.520886) (xy 447.7893 -34.520886)
			(xy 447.7893 -33.657286) (xy 447.78979 -33.627302) (xy 447.797618 -33.567846) (xy 447.813139 -33.509921)
			(xy 447.836088 -33.454517) (xy 447.866072 -33.402583) (xy 447.902578 -33.355007) (xy 447.944983 -33.312602)
			(xy 447.992559 -33.276096) (xy 448.044493 -33.246112) (xy 448.099897 -33.223163) (xy 448.157822 -33.207642)
			(xy 448.217278 -33.199814) (xy 448.277246 -33.199814) (xy 448.336702 -33.207642) (xy 448.394627 -33.223163)
			(xy 448.450031 -33.246112) (xy 448.501965 -33.276096) (xy 448.549541 -33.312602) (xy 448.591946 -33.355007)
			(xy 448.628452 -33.402583) (xy 448.658436 -33.454517) (xy 448.681385 -33.509921) (xy 448.696906 -33.567846)
			(xy 448.704734 -33.627302) (xy 448.705224 -33.657286) (xy 448.705224 -34.520886) (xy 448.704734 -34.55087)
			(xy 448.696906 -34.610326) (xy 448.681385 -34.668251) (xy 448.658436 -34.723655) (xy 448.628452 -34.775589)
			(xy 448.591946 -34.823165) (xy 448.549541 -34.86557) (xy 448.501965 -34.902076) (xy 448.450031 -34.93206)
			(xy 448.394627 -34.955009) (xy 448.336702 -34.97053) (xy 448.277246 -34.978358) (xy 448.217278 -34.978358)
			(xy 448.157822 -34.97053) (xy 448.099897 -34.955009) (xy 448.044493 -34.93206) (xy 447.992559 -34.902076)
			(xy 447.944983 -34.86557) (xy 447.902578 -34.823165) (xy 447.866072 -34.775589) (xy 447.836088 -34.723655)
			(xy 447.813139 -34.668251) (xy 447.797618 -34.610326) (xy 447.78979 -34.55087) (xy 447.7893 -34.520886)
			(xy 441.379226 -34.520886) (xy 442.463174 -37.09416) (xy 442.482707 -37.142217) (xy 442.512866 -37.24148)
			(xy 442.523372 -37.29228) (xy 442.633608 -37.863272) (xy 442.637349 -37.882907) (xy 442.643445 -37.922417)
			(xy 442.6458 -37.942266) (xy 442.648646 -37.969673) (xy 442.651693 -38.024695) (xy 442.651896 -38.052248)
			(xy 442.651677 -38.080123) (xy 442.648498 -38.135781) (xy 442.645546 -38.1635) (xy 442.608716 -38.49116)
			(xy 442.551566 -38.999922) (xy 442.551312 -39.00551) (xy 442.551312 -39.270432) (xy 442.550679 -39.320247)
			(xy 442.540627 -39.41937) (xy 442.531246 -39.468298) (xy 442.460888 -39.812722) (xy 442.460126 -39.81704)
			(xy 442.455554 -39.85641) (xy 442.430916 -40.076882) (xy 442.428138 -40.100332) (xy 442.42064 -40.14696)
			(xy 442.41593 -40.1701) (xy 442.410596 -40.195754) (xy 442.359796 -40.438832) (xy 442.28766 -40.783764)
			(xy 442.286156 -40.792617) (xy 442.28877 -40.810371) (xy 442.297387 -40.826112) (xy 442.303916 -40.832278)
			(xy 442.341 -40.86479) (xy 442.345572 -40.868854) (xy 442.352731 -40.874625) (xy 442.369914 -40.881132)
			(xy 442.3791 -40.881554) (xy 442.39815 -40.881554) (xy 442.40577 -40.879014) (xy 442.43468 -40.870118)
			(xy 442.4944 -40.860544) (xy 442.524642 -40.859964) (xy 442.529722 -40.859964) (xy 442.557899 -40.860826)
			(xy 442.613547 -40.869826) (xy 442.667264 -40.886918) (xy 442.717881 -40.911728) (xy 442.764296 -40.943718)
			(xy 442.785246 -40.96258) (xy 442.792866 -40.969946) (xy 442.801756 -40.973502) (xy 442.8109 -40.976042)
			(xy 442.819536 -40.976804) (xy 442.880496 -40.976804) (xy 442.885245 -40.976663) (xy 442.894573 -40.974871)
			(xy 442.899038 -40.973248) (xy 442.912246 -40.968168) (xy 442.915802 -40.966898) (xy 442.927486 -40.96004)
			(xy 442.928756 -40.95877) (xy 442.930534 -40.957246) (xy 442.951597 -40.939047) (xy 442.998002 -40.908307)
			(xy 443.048376 -40.884623) (xy 443.101652 -40.868497) (xy 443.156704 -40.860269) (xy 443.184534 -40.85971)
			(xy 443.19444 -40.859964) (xy 443.22398 -40.861271) (xy 443.28215 -40.87187) (xy 443.337992 -40.891305)
			(xy 443.390172 -40.919114) (xy 443.41415 -40.936418) (xy 443.437414 -40.954544) (xy 443.478597 -40.996756)
			(xy 443.51279 -41.044805) (xy 443.539181 -41.097545) (xy 443.557138 -41.153718) (xy 443.566235 -41.211985)
			(xy 443.566804 -41.241472) (xy 443.566343 -41.268736) (xy 443.558585 -41.32271) (xy 443.543224 -41.375029)
			(xy 443.520573 -41.42463) (xy 443.491092 -41.470501) (xy 443.473586 -41.491408) (xy 443.454716 -41.512391)
			(xy 443.411872 -41.549115) (xy 443.36409 -41.579135) (xy 443.31241 -41.601796) (xy 443.257958 -41.616605)
			(xy 443.23 -41.62044) (xy 443.209426 -41.62298) (xy 443.20333 -41.623234) (xy 443.185042 -41.623234)
			(xy 443.157156 -41.622737) (xy 443.101981 -41.614588) (xy 443.048582 -41.598487) (xy 442.9981 -41.574777)
			(xy 442.95161 -41.543965) (xy 442.930534 -41.525698) (xy 442.928756 -41.524174) (xy 442.927486 -41.522904)
			(xy 442.915802 -41.516046) (xy 442.912246 -41.514776) (xy 442.899038 -41.509696) (xy 442.894586 -41.508028)
			(xy 442.885249 -41.506237) (xy 442.880496 -41.50614) (xy 442.829696 -41.50614) (xy 442.824947 -41.506281)
			(xy 442.815619 -41.508073) (xy 442.811154 -41.509696) (xy 442.797946 -41.514776) (xy 442.794136 -41.516046)
			(xy 442.790326 -41.518078) (xy 442.78169 -41.52392) (xy 442.781436 -41.524174) (xy 442.779658 -41.525698)
			(xy 442.758557 -41.543973) (xy 442.712017 -41.574795) (xy 442.661482 -41.598506) (xy 442.608032 -41.6146)
			(xy 442.552806 -41.622733) (xy 442.524896 -41.623234) (xy 442.506354 -41.623234) (xy 442.500258 -41.62298)
			(xy 442.479938 -41.62044) (xy 442.479684 -41.62044) (xy 442.451211 -41.616556) (xy 442.395799 -41.601341)
			(xy 442.343295 -41.577989) (xy 442.294887 -41.547028) (xy 442.272928 -41.528492) (xy 442.266324 -41.52265)
			(xy 442.247528 -41.51503) (xy 442.243259 -41.513388) (xy 442.234315 -41.511469) (xy 442.229748 -41.51122)
			(xy 442.221112 -41.510966) (xy 442.162692 -41.530016) (xy 442.14161 -41.536874) (xy 442.1378 -41.538144)
			(xy 442.12891 -41.540938) (xy 441.759586 -43.305222) (xy 444.607188 -43.305222) (xy 444.60767 -43.277852)
			(xy 444.615484 -43.223674) (xy 444.63097 -43.171171) (xy 444.653808 -43.121424) (xy 444.683529 -43.075456)
			(xy 444.701168 -43.054524) (xy 444.701422 -43.05427) (xy 444.706988 -43.047169) (xy 444.713246 -43.030263)
			(xy 444.713614 -43.02125) (xy 444.713614 -42.954194) (xy 444.713257 -42.945177) (xy 444.707009 -42.92826)
			(xy 444.701422 -42.921174) (xy 444.701168 -42.921174) (xy 444.701168 -42.92092) (xy 444.68352 -42.899995)
			(xy 444.65381 -42.85402) (xy 444.630977 -42.804271) (xy 444.615488 -42.751768) (xy 444.607661 -42.697592)
			(xy 444.607188 -42.670222) (xy 444.607728 -42.641484) (xy 444.616347 -42.584657) (xy 444.633394 -42.529767)
			(xy 444.658482 -42.478055) (xy 444.691043 -42.430691) (xy 444.710312 -42.409364) (xy 444.716916 -42.402506)
			(xy 444.724028 -42.384472) (xy 444.724028 -42.295572) (xy 444.716916 -42.277538) (xy 444.710312 -42.27068)
			(xy 444.691064 -42.249334) (xy 444.658499 -42.201975) (xy 444.633407 -42.150266) (xy 444.616356 -42.095378)
			(xy 444.607731 -42.038554) (xy 444.607729 -41.981078) (xy 444.616348 -41.924253) (xy 444.633395 -41.869364)
			(xy 444.658482 -41.817653) (xy 444.691043 -41.770291) (xy 444.710312 -41.748964) (xy 444.716916 -41.742106)
			(xy 444.724028 -41.724072) (xy 444.724028 -41.635172) (xy 444.716916 -41.617138) (xy 444.710312 -41.61028)
			(xy 444.691047 -41.588948) (xy 444.658481 -41.541587) (xy 444.633388 -41.489876) (xy 444.616336 -41.434987)
			(xy 444.607711 -41.378161) (xy 444.607188 -41.349422) (xy 444.607674 -41.322171) (xy 444.61543 -41.268223)
			(xy 444.630785 -41.215928) (xy 444.653427 -41.166351) (xy 444.682893 -41.120501) (xy 444.718584 -41.07931)
			(xy 444.759775 -41.043619) (xy 444.805625 -41.014153) (xy 444.855202 -40.991511) (xy 444.907497 -40.976156)
			(xy 444.961445 -40.9684) (xy 445.015947 -40.9684) (xy 445.069895 -40.976156) (xy 445.12219 -40.991511)
			(xy 445.171767 -41.014153) (xy 445.217617 -41.043619) (xy 445.258808 -41.07931) (xy 445.294499 -41.120501)
			(xy 445.323965 -41.166351) (xy 445.346607 -41.215928) (xy 445.361962 -41.268223) (xy 445.369718 -41.322171)
			(xy 445.370204 -41.349422) (xy 445.369693 -41.378161) (xy 445.361067 -41.434989) (xy 445.344014 -41.48988)
			(xy 445.31892 -41.541592) (xy 445.286352 -41.588954) (xy 445.26708 -41.61028) (xy 445.260476 -41.617138)
			(xy 445.253364 -41.635172) (xy 445.253364 -41.724072) (xy 445.260476 -41.742106) (xy 445.26708 -41.748964)
			(xy 445.286372 -41.770272) (xy 445.318937 -41.817638) (xy 445.344027 -41.869353) (xy 445.361075 -41.924246)
			(xy 445.369695 -41.981076) (xy 445.369693 -42.038556) (xy 445.361068 -42.095385) (xy 445.344015 -42.150277)
			(xy 445.31892 -42.20199) (xy 445.286352 -42.249353) (xy 445.26708 -42.27068) (xy 445.260476 -42.277538)
			(xy 445.253364 -42.295572) (xy 445.253364 -42.384472) (xy 445.260476 -42.402506) (xy 445.26708 -42.409364)
			(xy 445.286364 -42.430679) (xy 445.318928 -42.478045) (xy 445.344017 -42.52976) (xy 445.361065 -42.584653)
			(xy 445.369685 -42.641482) (xy 445.370204 -42.670222) (xy 445.36975 -42.697593) (xy 445.361929 -42.751772)
			(xy 445.346437 -42.804275) (xy 445.325882 -42.849038) (xy 447.19189 -42.849038) (xy 447.195961 -42.793416)
			(xy 447.208087 -42.738979) (xy 447.22801 -42.686888) (xy 447.255306 -42.638253) (xy 447.289392 -42.59411)
			(xy 447.329541 -42.555401) (xy 447.374899 -42.52295) (xy 447.424499 -42.497449) (xy 447.477283 -42.479442)
			(xy 447.532126 -42.469312) (xy 447.58786 -42.467275) (xy 447.643297 -42.473375) (xy 447.697254 -42.487481)
			(xy 447.748583 -42.509293) (xy 447.796189 -42.538347) (xy 447.839057 -42.574022) (xy 447.876274 -42.615559)
			(xy 447.907047 -42.662072) (xy 447.930719 -42.712569) (xy 447.946787 -42.765976) (xy 447.954907 -42.821152)
			(xy 447.955268 -42.84091) (xy 453.233026 -42.84091) (xy 453.237097 -42.785288) (xy 453.249223 -42.730851)
			(xy 453.269146 -42.67876) (xy 453.296442 -42.630125) (xy 453.330528 -42.585982) (xy 453.370677 -42.547273)
			(xy 453.416035 -42.514822) (xy 453.465635 -42.489321) (xy 453.518419 -42.471314) (xy 453.573262 -42.461184)
			(xy 453.628996 -42.459147) (xy 453.684433 -42.465247) (xy 453.73839 -42.479353) (xy 453.789719 -42.501165)
			(xy 453.837325 -42.530219) (xy 453.880193 -42.565894) (xy 453.91741 -42.607431) (xy 453.948183 -42.653944)
			(xy 453.971855 -42.704441) (xy 453.987923 -42.757848) (xy 453.996043 -42.813024) (xy 453.996552 -42.84091)
			(xy 453.996043 -42.868796) (xy 453.987923 -42.923972) (xy 453.971855 -42.977379) (xy 453.948183 -43.027876)
			(xy 453.91741 -43.074389) (xy 453.880193 -43.115926) (xy 453.837325 -43.151601) (xy 453.789719 -43.180655)
			(xy 453.73839 -43.202467) (xy 453.684433 -43.216573) (xy 453.628996 -43.222673) (xy 453.573262 -43.220636)
			(xy 453.518419 -43.210506) (xy 453.465635 -43.192499) (xy 453.416035 -43.166998) (xy 453.370677 -43.134547)
			(xy 453.330528 -43.095838) (xy 453.296442 -43.051695) (xy 453.269146 -43.00306) (xy 453.249223 -42.950969)
			(xy 453.237097 -42.896532) (xy 453.233026 -42.84091) (xy 447.955268 -42.84091) (xy 447.955416 -42.849038)
			(xy 447.954907 -42.876924) (xy 447.946787 -42.9321) (xy 447.930719 -42.985507) (xy 447.907047 -43.036004)
			(xy 447.876274 -43.082517) (xy 447.839057 -43.124054) (xy 447.796189 -43.159729) (xy 447.748583 -43.188783)
			(xy 447.697254 -43.210595) (xy 447.643297 -43.224701) (xy 447.58786 -43.230801) (xy 447.532126 -43.228764)
			(xy 447.477283 -43.218634) (xy 447.424499 -43.200627) (xy 447.374899 -43.175126) (xy 447.329541 -43.142675)
			(xy 447.289392 -43.103966) (xy 447.255306 -43.059823) (xy 447.22801 -43.011188) (xy 447.208087 -42.959097)
			(xy 447.195961 -42.90466) (xy 447.19189 -42.849038) (xy 445.325882 -42.849038) (xy 445.323593 -42.854022)
			(xy 445.293866 -42.899989) (xy 445.276224 -42.92092) (xy 445.27597 -42.921174) (xy 445.270385 -42.928261)
			(xy 445.264138 -42.945178) (xy 445.263778 -42.954194) (xy 445.263778 -43.02125) (xy 445.264164 -43.030264)
			(xy 445.270392 -43.047181) (xy 445.27597 -43.05427) (xy 445.276224 -43.05427) (xy 445.276224 -43.054524)
			(xy 445.293845 -43.075471) (xy 445.323558 -43.12144) (xy 445.346398 -43.171184) (xy 445.361893 -43.223681)
			(xy 445.369727 -43.277854) (xy 445.370204 -43.305222) (xy 445.369718 -43.332473) (xy 445.361962 -43.386421)
			(xy 445.346607 -43.438716) (xy 445.323965 -43.488293) (xy 445.294499 -43.534143) (xy 445.258808 -43.575334)
			(xy 445.217617 -43.611025) (xy 445.171767 -43.640491) (xy 445.12219 -43.663133) (xy 445.069895 -43.678488)
			(xy 445.015947 -43.686244) (xy 444.961445 -43.686244) (xy 444.907497 -43.678488) (xy 444.855202 -43.663133)
			(xy 444.805625 -43.640491) (xy 444.759775 -43.611025) (xy 444.718584 -43.575334) (xy 444.682893 -43.534143)
			(xy 444.653427 -43.488293) (xy 444.630785 -43.438716) (xy 444.61543 -43.386421) (xy 444.607674 -43.332473)
			(xy 444.607188 -43.305222) (xy 441.759586 -43.305222) (xy 441.669355 -43.73626) (xy 446.512948 -43.73626)
			(xy 446.517019 -43.680638) (xy 446.529145 -43.626201) (xy 446.549068 -43.57411) (xy 446.576364 -43.525475)
			(xy 446.61045 -43.481332) (xy 446.650599 -43.442623) (xy 446.695957 -43.410172) (xy 446.745557 -43.384671)
			(xy 446.798341 -43.366664) (xy 446.853184 -43.356534) (xy 446.908918 -43.354497) (xy 446.964355 -43.360597)
			(xy 447.018312 -43.374703) (xy 447.069641 -43.396515) (xy 447.117247 -43.425569) (xy 447.160115 -43.461244)
			(xy 447.197332 -43.502781) (xy 447.228105 -43.549294) (xy 447.236331 -43.566842) (xy 449.633338 -43.566842)
			(xy 449.637409 -43.51122) (xy 449.649535 -43.456783) (xy 449.669458 -43.404692) (xy 449.696754 -43.356057)
			(xy 449.73084 -43.311914) (xy 449.770989 -43.273205) (xy 449.816347 -43.240754) (xy 449.865947 -43.215253)
			(xy 449.918731 -43.197246) (xy 449.973574 -43.187116) (xy 450.029308 -43.185079) (xy 450.084745 -43.191179)
			(xy 450.138702 -43.205285) (xy 450.190031 -43.227097) (xy 450.237637 -43.256151) (xy 450.280505 -43.291826)
			(xy 450.317722 -43.333363) (xy 450.348495 -43.379876) (xy 450.372167 -43.430373) (xy 450.388235 -43.48378)
			(xy 450.396355 -43.538956) (xy 450.396864 -43.566842) (xy 450.396355 -43.594728) (xy 450.388235 -43.649904)
			(xy 450.372167 -43.703311) (xy 450.348495 -43.753808) (xy 450.317722 -43.800321) (xy 450.280505 -43.841858)
			(xy 450.262418 -43.85691) (xy 451.01967 -43.85691) (xy 451.023741 -43.801288) (xy 451.035867 -43.746851)
			(xy 451.05579 -43.69476) (xy 451.083086 -43.646125) (xy 451.117172 -43.601982) (xy 451.157321 -43.563273)
			(xy 451.202679 -43.530822) (xy 451.252279 -43.505321) (xy 451.305063 -43.487314) (xy 451.359906 -43.477184)
			(xy 451.41564 -43.475147) (xy 451.471077 -43.481247) (xy 451.525034 -43.495353) (xy 451.576363 -43.517165)
			(xy 451.623969 -43.546219) (xy 451.666837 -43.581894) (xy 451.704054 -43.623431) (xy 451.734827 -43.669944)
			(xy 451.758499 -43.720441) (xy 451.774567 -43.773848) (xy 451.782687 -43.829024) (xy 451.783196 -43.85691)
			(xy 451.782687 -43.884796) (xy 451.774567 -43.939972) (xy 451.758499 -43.993379) (xy 451.734827 -44.043876)
			(xy 451.704054 -44.090389) (xy 451.666837 -44.131926) (xy 451.623969 -44.167601) (xy 451.576363 -44.196655)
			(xy 451.525034 -44.218467) (xy 451.471077 -44.232573) (xy 451.41564 -44.238673) (xy 451.359906 -44.236636)
			(xy 451.305063 -44.226506) (xy 451.252279 -44.208499) (xy 451.202679 -44.182998) (xy 451.157321 -44.150547)
			(xy 451.117172 -44.111838) (xy 451.083086 -44.067695) (xy 451.05579 -44.01906) (xy 451.035867 -43.966969)
			(xy 451.023741 -43.912532) (xy 451.01967 -43.85691) (xy 450.262418 -43.85691) (xy 450.237637 -43.877533)
			(xy 450.190031 -43.906587) (xy 450.138702 -43.928399) (xy 450.084745 -43.942505) (xy 450.029308 -43.948605)
			(xy 449.973574 -43.946568) (xy 449.918731 -43.936438) (xy 449.865947 -43.918431) (xy 449.816347 -43.89293)
			(xy 449.770989 -43.860479) (xy 449.73084 -43.82177) (xy 449.696754 -43.777627) (xy 449.669458 -43.728992)
			(xy 449.649535 -43.676901) (xy 449.637409 -43.622464) (xy 449.633338 -43.566842) (xy 447.236331 -43.566842)
			(xy 447.251777 -43.599791) (xy 447.267845 -43.653198) (xy 447.275965 -43.708374) (xy 447.276474 -43.73626)
			(xy 447.275965 -43.764146) (xy 447.267845 -43.819322) (xy 447.251777 -43.872729) (xy 447.228105 -43.923226)
			(xy 447.197332 -43.969739) (xy 447.160115 -44.011276) (xy 447.117247 -44.046951) (xy 447.069641 -44.076005)
			(xy 447.018312 -44.097817) (xy 446.964355 -44.111923) (xy 446.908918 -44.118023) (xy 446.853184 -44.115986)
			(xy 446.798341 -44.105856) (xy 446.745557 -44.087849) (xy 446.695957 -44.062348) (xy 446.650599 -44.029897)
			(xy 446.61045 -43.991188) (xy 446.576364 -43.947045) (xy 446.549068 -43.89841) (xy 446.529145 -43.846319)
			(xy 446.517019 -43.791882) (xy 446.512948 -43.73626) (xy 441.669355 -43.73626) (xy 441.380851 -45.114464)
			(xy 446.365374 -45.114464) (xy 446.369445 -45.058842) (xy 446.381571 -45.004405) (xy 446.401494 -44.952314)
			(xy 446.42879 -44.903679) (xy 446.462876 -44.859536) (xy 446.503025 -44.820827) (xy 446.548383 -44.788376)
			(xy 446.597983 -44.762875) (xy 446.650767 -44.744868) (xy 446.70561 -44.734738) (xy 446.761344 -44.732701)
			(xy 446.816781 -44.738801) (xy 446.870738 -44.752907) (xy 446.922067 -44.774719) (xy 446.969673 -44.803773)
			(xy 447.012541 -44.839448) (xy 447.042523 -44.87291) (xy 453.233026 -44.87291) (xy 453.237097 -44.817288)
			(xy 453.249223 -44.762851) (xy 453.269146 -44.71076) (xy 453.296442 -44.662125) (xy 453.330528 -44.617982)
			(xy 453.370677 -44.579273) (xy 453.416035 -44.546822) (xy 453.465635 -44.521321) (xy 453.518419 -44.503314)
			(xy 453.573262 -44.493184) (xy 453.628996 -44.491147) (xy 453.684433 -44.497247) (xy 453.73839 -44.511353)
			(xy 453.789719 -44.533165) (xy 453.837325 -44.562219) (xy 453.880193 -44.597894) (xy 453.91741 -44.639431)
			(xy 453.948183 -44.685944) (xy 453.971855 -44.736441) (xy 453.987923 -44.789848) (xy 453.996043 -44.845024)
			(xy 453.996552 -44.87291) (xy 453.996043 -44.900796) (xy 453.987923 -44.955972) (xy 453.971855 -45.009379)
			(xy 453.948183 -45.059876) (xy 453.91741 -45.106389) (xy 453.880193 -45.147926) (xy 453.837325 -45.183601)
			(xy 453.789719 -45.212655) (xy 453.73839 -45.234467) (xy 453.684433 -45.248573) (xy 453.628996 -45.254673)
			(xy 453.573262 -45.252636) (xy 453.518419 -45.242506) (xy 453.465635 -45.224499) (xy 453.416035 -45.198998)
			(xy 453.370677 -45.166547) (xy 453.330528 -45.127838) (xy 453.296442 -45.083695) (xy 453.269146 -45.03506)
			(xy 453.249223 -44.982969) (xy 453.237097 -44.928532) (xy 453.233026 -44.87291) (xy 447.042523 -44.87291)
			(xy 447.049758 -44.880985) (xy 447.080531 -44.927498) (xy 447.104203 -44.977995) (xy 447.120271 -45.031402)
			(xy 447.128391 -45.086578) (xy 447.1289 -45.114464) (xy 447.128391 -45.14235) (xy 447.120271 -45.197526)
			(xy 447.104203 -45.250933) (xy 447.080531 -45.30143) (xy 447.049758 -45.347943) (xy 447.044116 -45.35424)
			(xy 451.003668 -45.35424) (xy 451.007739 -45.298618) (xy 451.019865 -45.244181) (xy 451.039788 -45.19209)
			(xy 451.067084 -45.143455) (xy 451.10117 -45.099312) (xy 451.141319 -45.060603) (xy 451.186677 -45.028152)
			(xy 451.236277 -45.002651) (xy 451.289061 -44.984644) (xy 451.343904 -44.974514) (xy 451.399638 -44.972477)
			(xy 451.455075 -44.978577) (xy 451.509032 -44.992683) (xy 451.560361 -45.014495) (xy 451.607967 -45.043549)
			(xy 451.650835 -45.079224) (xy 451.688052 -45.120761) (xy 451.718825 -45.167274) (xy 451.742497 -45.217771)
			(xy 451.758565 -45.271178) (xy 451.766685 -45.326354) (xy 451.767194 -45.35424) (xy 451.766685 -45.382126)
			(xy 451.758565 -45.437302) (xy 451.742497 -45.490709) (xy 451.718825 -45.541206) (xy 451.688052 -45.587719)
			(xy 451.650835 -45.629256) (xy 451.607967 -45.664931) (xy 451.560361 -45.693985) (xy 451.509032 -45.715797)
			(xy 451.455075 -45.729903) (xy 451.399638 -45.736003) (xy 451.343904 -45.733966) (xy 451.289061 -45.723836)
			(xy 451.236277 -45.705829) (xy 451.186677 -45.680328) (xy 451.141319 -45.647877) (xy 451.10117 -45.609168)
			(xy 451.067084 -45.565025) (xy 451.039788 -45.51639) (xy 451.019865 -45.464299) (xy 451.007739 -45.409862)
			(xy 451.003668 -45.35424) (xy 447.044116 -45.35424) (xy 447.012541 -45.38948) (xy 446.969673 -45.425155)
			(xy 446.922067 -45.454209) (xy 446.870738 -45.476021) (xy 446.816781 -45.490127) (xy 446.761344 -45.496227)
			(xy 446.70561 -45.49419) (xy 446.650767 -45.48406) (xy 446.597983 -45.466053) (xy 446.548383 -45.440552)
			(xy 446.503025 -45.408101) (xy 446.462876 -45.369392) (xy 446.42879 -45.325249) (xy 446.401494 -45.276614)
			(xy 446.381571 -45.224523) (xy 446.369445 -45.170086) (xy 446.365374 -45.114464) (xy 441.380851 -45.114464)
			(xy 441.17827 -46.082204) (xy 444.352426 -46.082204) (xy 444.352859 -46.05495) (xy 444.360616 -46.000996)
			(xy 444.375974 -45.948695) (xy 444.398618 -45.899113) (xy 444.428089 -45.853258) (xy 444.463786 -45.812065)
			(xy 444.504982 -45.776371) (xy 444.550839 -45.746904) (xy 444.600424 -45.724263) (xy 444.652725 -45.70891)
			(xy 444.70668 -45.701157) (xy 444.733934 -45.700696) (xy 444.760837 -45.701132) (xy 444.814109 -45.708709)
			(xy 444.865787 -45.723693) (xy 444.914849 -45.745787) (xy 444.960321 -45.774553) (xy 445.001302 -45.809422)
			(xy 445.036979 -45.849701) (xy 445.052196 -45.871892) (xy 445.059308 -45.882814) (xy 445.082168 -45.894752)
			(xy 445.194436 -45.89272) (xy 445.216788 -45.879766) (xy 445.223646 -45.86859) (xy 445.23855 -45.844977)
			(xy 445.274232 -45.802025) (xy 445.315793 -45.764733) (xy 445.362346 -45.733897) (xy 445.412896 -45.710175)
			(xy 445.466364 -45.694075) (xy 445.521608 -45.68594) (xy 445.549528 -45.685456) (xy 445.576522 -45.685901)
			(xy 445.629971 -45.693511) (xy 445.681814 -45.708575) (xy 445.731019 -45.730792) (xy 445.776602 -45.75972)
			(xy 445.797432 -45.776896) (xy 445.80556 -45.784008) (xy 445.826134 -45.790104) (xy 445.911478 -45.779182)
			(xy 445.922022 -45.777407) (xy 445.940305 -45.766353) (xy 445.946784 -45.757846) (xy 445.962154 -45.736628)
			(xy 445.997738 -45.698175) (xy 446.038252 -45.664955) (xy 446.082933 -45.637595) (xy 446.130938 -45.616609)
			(xy 446.181364 -45.602394) (xy 446.233262 -45.595215) (xy 446.259458 -45.594778) (xy 446.286712 -45.595266)
			(xy 446.340665 -45.603018) (xy 446.392966 -45.61837) (xy 446.44255 -45.641009) (xy 446.488407 -45.670475)
			(xy 446.529603 -45.706168) (xy 446.5653 -45.74736) (xy 446.59477 -45.793213) (xy 446.617415 -45.842794)
			(xy 446.632773 -45.895094) (xy 446.640531 -45.949046) (xy 446.640531 -46.003554) (xy 446.632773 -46.057506)
			(xy 446.617415 -46.109806) (xy 446.59477 -46.159387) (xy 446.5653 -46.20524) (xy 446.529603 -46.246432)
			(xy 446.488407 -46.282125) (xy 446.44255 -46.311591) (xy 446.392966 -46.33423) (xy 446.340665 -46.349582)
			(xy 446.286712 -46.357334) (xy 446.259458 -46.357794) (xy 446.232464 -46.357345) (xy 446.179016 -46.349735)
			(xy 446.127173 -46.334671) (xy 446.077969 -46.312454) (xy 446.032385 -46.283528) (xy 446.011554 -46.266354)
			(xy 446.003426 -46.259242) (xy 445.982852 -46.253146) (xy 445.897508 -46.264068) (xy 445.886967 -46.265854)
			(xy 445.868684 -46.276901) (xy 445.862202 -46.285404) (xy 445.844586 -46.309702) (xy 445.802992 -46.352963)
			(xy 445.779398 -46.37151) (xy 445.771524 -46.377352) (xy 445.76111 -46.394878) (xy 445.747902 -46.485302)
			(xy 445.752728 -46.504606) (xy 445.75857 -46.51248) (xy 445.75857 -46.512734) (xy 445.776072 -46.537479)
			(xy 445.803875 -46.591331) (xy 445.822812 -46.648903) (xy 445.830015 -46.693836) (xy 450.976238 -46.693836)
			(xy 450.976724 -46.666585) (xy 450.98448 -46.612637) (xy 450.999835 -46.560342) (xy 451.022477 -46.510765)
			(xy 451.051943 -46.464915) (xy 451.087634 -46.423724) (xy 451.128825 -46.388033) (xy 451.174675 -46.358567)
			(xy 451.224252 -46.335925) (xy 451.276547 -46.32057) (xy 451.330495 -46.312814) (xy 451.384997 -46.312814)
			(xy 451.438945 -46.32057) (xy 451.49124 -46.335925) (xy 451.540817 -46.358567) (xy 451.586667 -46.388033)
			(xy 451.627858 -46.423724) (xy 451.663549 -46.464915) (xy 451.693015 -46.510765) (xy 451.715657 -46.560342)
			(xy 451.731012 -46.612637) (xy 451.738768 -46.666585) (xy 451.739254 -46.693836) (xy 451.738788 -46.720264)
			(xy 451.731477 -46.772612) (xy 451.717002 -46.823447) (xy 451.69564 -46.871793) (xy 451.682104 -46.894496)
			(xy 451.68185 -46.89475) (xy 451.676513 -46.904768) (xy 451.674256 -46.927318) (xy 451.677532 -46.938184)
			(xy 451.703694 -47.01286) (xy 451.708059 -47.023385) (xy 451.724161 -47.03947) (xy 451.734682 -47.043848)
			(xy 451.734936 -47.043848) (xy 451.759443 -47.052923) (xy 451.805895 -47.076865) (xy 451.848648 -47.106919)
			(xy 451.8869 -47.142526) (xy 451.919937 -47.183018) (xy 451.947141 -47.227638) (xy 451.968003 -47.275553)
			(xy 451.982133 -47.325866) (xy 451.989267 -47.377636) (xy 451.989698 -47.403766) (xy 451.989212 -47.431017)
			(xy 451.987689 -47.441612) (xy 453.261728 -47.441612) (xy 453.265799 -47.38599) (xy 453.277925 -47.331553)
			(xy 453.297848 -47.279462) (xy 453.325144 -47.230827) (xy 453.35923 -47.186684) (xy 453.399379 -47.147975)
			(xy 453.444737 -47.115524) (xy 453.494337 -47.090023) (xy 453.547121 -47.072016) (xy 453.601964 -47.061886)
			(xy 453.657698 -47.059849) (xy 453.713135 -47.065949) (xy 453.767092 -47.080055) (xy 453.818421 -47.101867)
			(xy 453.866027 -47.130921) (xy 453.908895 -47.166596) (xy 453.946112 -47.208133) (xy 453.976885 -47.254646)
			(xy 454.000557 -47.305143) (xy 454.016625 -47.35855) (xy 454.024745 -47.413726) (xy 454.025254 -47.441612)
			(xy 454.024745 -47.469498) (xy 454.016625 -47.524674) (xy 454.000557 -47.578081) (xy 453.976885 -47.628578)
			(xy 453.946112 -47.675091) (xy 453.908895 -47.716628) (xy 453.866027 -47.752303) (xy 453.818421 -47.781357)
			(xy 453.767092 -47.803169) (xy 453.713135 -47.817275) (xy 453.657698 -47.823375) (xy 453.601964 -47.821338)
			(xy 453.547121 -47.811208) (xy 453.494337 -47.793201) (xy 453.444737 -47.7677) (xy 453.399379 -47.735249)
			(xy 453.35923 -47.69654) (xy 453.325144 -47.652397) (xy 453.297848 -47.603762) (xy 453.277925 -47.551671)
			(xy 453.265799 -47.497234) (xy 453.261728 -47.441612) (xy 451.987689 -47.441612) (xy 451.981456 -47.484965)
			(xy 451.966101 -47.53726) (xy 451.943459 -47.586837) (xy 451.913993 -47.632687) (xy 451.878302 -47.673878)
			(xy 451.837111 -47.709569) (xy 451.791261 -47.739035) (xy 451.741684 -47.761677) (xy 451.689389 -47.777032)
			(xy 451.635441 -47.784788) (xy 451.580939 -47.784788) (xy 451.526991 -47.777032) (xy 451.474696 -47.761677)
			(xy 451.425119 -47.739035) (xy 451.379269 -47.709569) (xy 451.338078 -47.673878) (xy 451.302387 -47.632687)
			(xy 451.272921 -47.586837) (xy 451.250279 -47.53726) (xy 451.234924 -47.484965) (xy 451.227168 -47.431017)
			(xy 451.226682 -47.403766) (xy 451.227158 -47.377339) (xy 451.234467 -47.324991) (xy 451.248939 -47.274157)
			(xy 451.270298 -47.225809) (xy 451.283832 -47.203106) (xy 451.284086 -47.202852) (xy 451.289421 -47.192834)
			(xy 451.291678 -47.170284) (xy 451.288404 -47.159418) (xy 451.262242 -47.084742) (xy 451.25786 -47.074226)
			(xy 451.24177 -47.058137) (xy 451.231254 -47.053754) (xy 451.231 -47.053754) (xy 451.206502 -47.044657)
			(xy 451.160048 -47.02072) (xy 451.117295 -46.990669) (xy 451.079041 -46.955066) (xy 451.046003 -46.914576)
			(xy 451.018798 -46.869958) (xy 450.997935 -46.822045) (xy 450.983804 -46.771734) (xy 450.976669 -46.719965)
			(xy 450.976238 -46.693836) (xy 445.830015 -46.693836) (xy 445.832405 -46.708745) (xy 445.832992 -46.739048)
			(xy 445.832567 -46.766301) (xy 445.824803 -46.820252) (xy 445.809441 -46.872549) (xy 445.786793 -46.922127)
			(xy 445.757321 -46.967978) (xy 445.721623 -47.009168) (xy 445.680427 -47.044859) (xy 445.634571 -47.074324)
			(xy 445.584989 -47.096964) (xy 445.532689 -47.112317) (xy 445.478737 -47.120071) (xy 445.451484 -47.120556)
			(xy 445.42545 -47.120111) (xy 445.373868 -47.113022) (xy 445.323726 -47.098992) (xy 445.275955 -47.078281)
			(xy 445.23144 -47.051272) (xy 445.210946 -47.035212) (xy 445.203182 -47.029481) (xy 445.184777 -47.023734)
			(xy 445.175132 -47.024036) (xy 445.095376 -47.030386) (xy 445.077596 -47.039022) (xy 445.071246 -47.046388)
			(xy 445.053065 -47.066034) (xy 445.012157 -47.100556) (xy 444.966828 -47.129025) (xy 444.917967 -47.150882)
			(xy 444.866531 -47.1657) (xy 444.81353 -47.173187) (xy 444.786766 -47.173642) (xy 444.759515 -47.173154)
			(xy 444.70557 -47.165394) (xy 444.653277 -47.150036) (xy 444.603702 -47.127393) (xy 444.557853 -47.097927)
			(xy 444.516664 -47.062236) (xy 444.480973 -47.021047) (xy 444.451507 -46.975198) (xy 444.428864 -46.925623)
			(xy 444.413506 -46.87333) (xy 444.405746 -46.819385) (xy 444.405258 -46.792134) (xy 444.405794 -46.763361)
			(xy 444.414444 -46.706467) (xy 444.431538 -46.651517) (xy 444.456689 -46.599757) (xy 444.489326 -46.55236)
			(xy 444.508636 -46.531022) (xy 444.516002 -46.523148) (xy 444.523114 -46.503336) (xy 444.515748 -46.40707)
			(xy 444.505842 -46.388274) (xy 444.49746 -46.38167) (xy 444.475284 -46.363435) (xy 444.436071 -46.321503)
			(xy 444.403583 -46.27417) (xy 444.378553 -46.222504) (xy 444.361546 -46.167671) (xy 444.352944 -46.110909)
			(xy 444.352426 -46.082204) (xy 441.17827 -46.082204) (xy 441.061348 -46.64075) (xy 440.719804 -48.30699)
			(xy 450.853808 -48.30699) (xy 450.857879 -48.251368) (xy 450.870005 -48.196931) (xy 450.889928 -48.14484)
			(xy 450.917224 -48.096205) (xy 450.95131 -48.052062) (xy 450.991459 -48.013353) (xy 451.036817 -47.980902)
			(xy 451.086417 -47.955401) (xy 451.139201 -47.937394) (xy 451.194044 -47.927264) (xy 451.249778 -47.925227)
			(xy 451.305215 -47.931327) (xy 451.359172 -47.945433) (xy 451.410501 -47.967245) (xy 451.458107 -47.996299)
			(xy 451.500975 -48.031974) (xy 451.538192 -48.073511) (xy 451.568965 -48.120024) (xy 451.592637 -48.170521)
			(xy 451.608705 -48.223928) (xy 451.616825 -48.279104) (xy 451.617334 -48.30699) (xy 451.616825 -48.334876)
			(xy 451.608705 -48.390052) (xy 451.592637 -48.443459) (xy 451.568965 -48.493956) (xy 451.538192 -48.540469)
			(xy 451.500975 -48.582006) (xy 451.458107 -48.617681) (xy 451.410501 -48.646735) (xy 451.359172 -48.668547)
			(xy 451.305215 -48.682653) (xy 451.249778 -48.688753) (xy 451.194044 -48.686716) (xy 451.139201 -48.676586)
			(xy 451.086417 -48.658579) (xy 451.036817 -48.633078) (xy 450.991459 -48.600627) (xy 450.95131 -48.561918)
			(xy 450.917224 -48.517775) (xy 450.889928 -48.46914) (xy 450.870005 -48.417049) (xy 450.857879 -48.362612)
			(xy 450.853808 -48.30699) (xy 440.719804 -48.30699) (xy 440.628379 -48.753014) (xy 447.468242 -48.753014)
			(xy 447.472313 -48.697392) (xy 447.484439 -48.642955) (xy 447.504362 -48.590864) (xy 447.531658 -48.542229)
			(xy 447.565744 -48.498086) (xy 447.605893 -48.459377) (xy 447.651251 -48.426926) (xy 447.700851 -48.401425)
			(xy 447.753635 -48.383418) (xy 447.808478 -48.373288) (xy 447.864212 -48.371251) (xy 447.919649 -48.377351)
			(xy 447.973606 -48.391457) (xy 448.024935 -48.413269) (xy 448.072541 -48.442323) (xy 448.115409 -48.477998)
			(xy 448.152626 -48.519535) (xy 448.183399 -48.566048) (xy 448.207071 -48.616545) (xy 448.223139 -48.669952)
			(xy 448.231259 -48.725128) (xy 448.231768 -48.753014) (xy 448.231259 -48.7809) (xy 448.223139 -48.836076)
			(xy 448.220695 -48.8442) (xy 448.48729 -48.8442) (xy 448.491361 -48.788578) (xy 448.503487 -48.734141)
			(xy 448.52341 -48.68205) (xy 448.550706 -48.633415) (xy 448.584792 -48.589272) (xy 448.624941 -48.550563)
			(xy 448.670299 -48.518112) (xy 448.719899 -48.492611) (xy 448.772683 -48.474604) (xy 448.827526 -48.464474)
			(xy 448.88326 -48.462437) (xy 448.938697 -48.468537) (xy 448.992654 -48.482643) (xy 449.043983 -48.504455)
			(xy 449.091589 -48.533509) (xy 449.134457 -48.569184) (xy 449.171674 -48.610721) (xy 449.202447 -48.657234)
			(xy 449.226119 -48.707731) (xy 449.242187 -48.761138) (xy 449.250307 -48.816314) (xy 449.250816 -48.8442)
			(xy 449.250307 -48.872086) (xy 449.247309 -48.89246) (xy 449.513958 -48.89246) (xy 449.518029 -48.836838)
			(xy 449.530155 -48.782401) (xy 449.550078 -48.73031) (xy 449.577374 -48.681675) (xy 449.61146 -48.637532)
			(xy 449.651609 -48.598823) (xy 449.696967 -48.566372) (xy 449.746567 -48.540871) (xy 449.799351 -48.522864)
			(xy 449.854194 -48.512734) (xy 449.909928 -48.510697) (xy 449.965365 -48.516797) (xy 450.019322 -48.530903)
			(xy 450.070651 -48.552715) (xy 450.118257 -48.581769) (xy 450.161125 -48.617444) (xy 450.198342 -48.658981)
			(xy 450.229115 -48.705494) (xy 450.252787 -48.755991) (xy 450.268855 -48.809398) (xy 450.276975 -48.864574)
			(xy 450.277484 -48.89246) (xy 450.276975 -48.920346) (xy 450.274537 -48.93691) (xy 453.205848 -48.93691)
			(xy 453.209919 -48.881288) (xy 453.222045 -48.826851) (xy 453.241968 -48.77476) (xy 453.269264 -48.726125)
			(xy 453.30335 -48.681982) (xy 453.343499 -48.643273) (xy 453.388857 -48.610822) (xy 453.438457 -48.585321)
			(xy 453.491241 -48.567314) (xy 453.546084 -48.557184) (xy 453.601818 -48.555147) (xy 453.657255 -48.561247)
			(xy 453.711212 -48.575353) (xy 453.762541 -48.597165) (xy 453.810147 -48.626219) (xy 453.853015 -48.661894)
			(xy 453.890232 -48.703431) (xy 453.921005 -48.749944) (xy 453.944677 -48.800441) (xy 453.960745 -48.853848)
			(xy 453.968865 -48.909024) (xy 453.969374 -48.93691) (xy 453.968865 -48.964796) (xy 453.960745 -49.019972)
			(xy 453.944677 -49.073379) (xy 453.921005 -49.123876) (xy 453.890232 -49.170389) (xy 453.853015 -49.211926)
			(xy 453.810147 -49.247601) (xy 453.762541 -49.276655) (xy 453.711212 -49.298467) (xy 453.657255 -49.312573)
			(xy 453.601818 -49.318673) (xy 453.546084 -49.316636) (xy 453.491241 -49.306506) (xy 453.438457 -49.288499)
			(xy 453.388857 -49.262998) (xy 453.343499 -49.230547) (xy 453.30335 -49.191838) (xy 453.269264 -49.147695)
			(xy 453.241968 -49.09906) (xy 453.222045 -49.046969) (xy 453.209919 -48.992532) (xy 453.205848 -48.93691)
			(xy 450.274537 -48.93691) (xy 450.268855 -48.975522) (xy 450.252787 -49.028929) (xy 450.229115 -49.079426)
			(xy 450.198342 -49.125939) (xy 450.161125 -49.167476) (xy 450.118257 -49.203151) (xy 450.070651 -49.232205)
			(xy 450.019322 -49.254017) (xy 449.965365 -49.268123) (xy 449.909928 -49.274223) (xy 449.854194 -49.272186)
			(xy 449.799351 -49.262056) (xy 449.746567 -49.244049) (xy 449.696967 -49.218548) (xy 449.651609 -49.186097)
			(xy 449.61146 -49.147388) (xy 449.577374 -49.103245) (xy 449.550078 -49.05461) (xy 449.530155 -49.002519)
			(xy 449.518029 -48.948082) (xy 449.513958 -48.89246) (xy 449.247309 -48.89246) (xy 449.242187 -48.927262)
			(xy 449.226119 -48.980669) (xy 449.202447 -49.031166) (xy 449.171674 -49.077679) (xy 449.134457 -49.119216)
			(xy 449.091589 -49.154891) (xy 449.043983 -49.183945) (xy 448.992654 -49.205757) (xy 448.938697 -49.219863)
			(xy 448.88326 -49.225963) (xy 448.827526 -49.223926) (xy 448.772683 -49.213796) (xy 448.719899 -49.195789)
			(xy 448.670299 -49.170288) (xy 448.624941 -49.137837) (xy 448.584792 -49.099128) (xy 448.550706 -49.054985)
			(xy 448.52341 -49.00635) (xy 448.503487 -48.954259) (xy 448.491361 -48.899822) (xy 448.48729 -48.8442)
			(xy 448.220695 -48.8442) (xy 448.207071 -48.889483) (xy 448.183399 -48.93998) (xy 448.152626 -48.986493)
			(xy 448.115409 -49.02803) (xy 448.072541 -49.063705) (xy 448.024935 -49.092759) (xy 447.973606 -49.114571)
			(xy 447.919649 -49.128677) (xy 447.864212 -49.134777) (xy 447.808478 -49.13274) (xy 447.753635 -49.12261)
			(xy 447.700851 -49.104603) (xy 447.651251 -49.079102) (xy 447.605893 -49.046651) (xy 447.565744 -49.007942)
			(xy 447.531658 -48.963799) (xy 447.504362 -48.915164) (xy 447.484439 -48.863073) (xy 447.472313 -48.808636)
			(xy 447.468242 -48.753014) (xy 440.628379 -48.753014) (xy 440.569858 -49.03851) (xy 440.490102 -49.429162)
			(xy 440.48934 -49.436274) (xy 440.48934 -49.95291) (xy 453.233026 -49.95291) (xy 453.237097 -49.897288)
			(xy 453.249223 -49.842851) (xy 453.269146 -49.79076) (xy 453.296442 -49.742125) (xy 453.330528 -49.697982)
			(xy 453.370677 -49.659273) (xy 453.416035 -49.626822) (xy 453.465635 -49.601321) (xy 453.518419 -49.583314)
			(xy 453.573262 -49.573184) (xy 453.628996 -49.571147) (xy 453.684433 -49.577247) (xy 453.73839 -49.591353)
			(xy 453.789719 -49.613165) (xy 453.837325 -49.642219) (xy 453.880193 -49.677894) (xy 453.91741 -49.719431)
			(xy 453.948183 -49.765944) (xy 453.971855 -49.816441) (xy 453.987923 -49.869848) (xy 453.996043 -49.925024)
			(xy 453.996552 -49.95291) (xy 453.996043 -49.980796) (xy 453.987923 -50.035972) (xy 453.971855 -50.089379)
			(xy 453.948183 -50.139876) (xy 453.91741 -50.186389) (xy 453.880193 -50.227926) (xy 453.837325 -50.263601)
			(xy 453.789719 -50.292655) (xy 453.73839 -50.314467) (xy 453.684433 -50.328573) (xy 453.628996 -50.334673)
			(xy 453.573262 -50.332636) (xy 453.518419 -50.322506) (xy 453.465635 -50.304499) (xy 453.416035 -50.278998)
			(xy 453.370677 -50.246547) (xy 453.330528 -50.207838) (xy 453.296442 -50.163695) (xy 453.269146 -50.11506)
			(xy 453.249223 -50.062969) (xy 453.237097 -50.008532) (xy 453.233026 -49.95291) (xy 440.48934 -49.95291)
			(xy 440.48934 -51.019456) (xy 451.049388 -51.019456) (xy 451.053459 -50.963834) (xy 451.065585 -50.909397)
			(xy 451.085508 -50.857306) (xy 451.112804 -50.808671) (xy 451.14689 -50.764528) (xy 451.187039 -50.725819)
			(xy 451.232397 -50.693368) (xy 451.281997 -50.667867) (xy 451.334781 -50.64986) (xy 451.389624 -50.63973)
			(xy 451.445358 -50.637693) (xy 451.500795 -50.643793) (xy 451.554752 -50.657899) (xy 451.606081 -50.679711)
			(xy 451.653687 -50.708765) (xy 451.696555 -50.74444) (xy 451.733772 -50.785977) (xy 451.764545 -50.83249)
			(xy 451.788217 -50.882987) (xy 451.804285 -50.936394) (xy 451.812405 -50.99157) (xy 451.812914 -51.019456)
			(xy 451.812405 -51.047342) (xy 451.804285 -51.102518) (xy 451.788217 -51.155925) (xy 451.764545 -51.206422)
			(xy 451.733772 -51.252935) (xy 451.696555 -51.294472) (xy 451.653687 -51.330147) (xy 451.606081 -51.359201)
			(xy 451.554752 -51.381013) (xy 451.500795 -51.395119) (xy 451.445358 -51.401219) (xy 451.389624 -51.399182)
			(xy 451.334781 -51.389052) (xy 451.281997 -51.371045) (xy 451.232397 -51.345544) (xy 451.187039 -51.313093)
			(xy 451.14689 -51.274384) (xy 451.112804 -51.230241) (xy 451.085508 -51.181606) (xy 451.065585 -51.129515)
			(xy 451.053459 -51.075078) (xy 451.049388 -51.019456) (xy 440.48934 -51.019456) (xy 440.48934 -52.035456)
			(xy 453.241154 -52.035456) (xy 453.245225 -51.979834) (xy 453.257351 -51.925397) (xy 453.277274 -51.873306)
			(xy 453.30457 -51.824671) (xy 453.338656 -51.780528) (xy 453.378805 -51.741819) (xy 453.424163 -51.709368)
			(xy 453.473763 -51.683867) (xy 453.526547 -51.66586) (xy 453.58139 -51.65573) (xy 453.637124 -51.653693)
			(xy 453.692561 -51.659793) (xy 453.746518 -51.673899) (xy 453.797847 -51.695711) (xy 453.845453 -51.724765)
			(xy 453.888321 -51.76044) (xy 453.925538 -51.801977) (xy 453.956311 -51.84849) (xy 453.979983 -51.898987)
			(xy 453.996051 -51.952394) (xy 454.004171 -52.00757) (xy 454.00468 -52.035456) (xy 454.004171 -52.063342)
			(xy 453.996051 -52.118518) (xy 453.979983 -52.171925) (xy 453.956311 -52.222422) (xy 453.925538 -52.268935)
			(xy 453.888321 -52.310472) (xy 453.845453 -52.346147) (xy 453.797847 -52.375201) (xy 453.746518 -52.397013)
			(xy 453.692561 -52.411119) (xy 453.637124 -52.417219) (xy 453.58139 -52.415182) (xy 453.526547 -52.405052)
			(xy 453.473763 -52.387045) (xy 453.424163 -52.361544) (xy 453.378805 -52.329093) (xy 453.338656 -52.290384)
			(xy 453.30457 -52.246241) (xy 453.277274 -52.197606) (xy 453.257351 -52.145515) (xy 453.245225 -52.091078)
			(xy 453.241154 -52.035456) (xy 440.48934 -52.035456) (xy 440.48934 -52.548536) (xy 440.489445 -52.552883)
			(xy 440.49097 -52.561443) (xy 440.492388 -52.565554) (xy 440.500262 -52.587906) (xy 440.505342 -52.594256)
			(xy 440.520167 -52.614306) (xy 440.545043 -52.657522) (xy 440.564078 -52.70361) (xy 440.576949 -52.751785)
			(xy 440.583436 -52.801226) (xy 440.583828 -52.826158) (xy 440.583828 -52.826666) (xy 440.583242 -52.857755)
			(xy 440.573208 -52.919117) (xy 440.553352 -52.978038) (xy 440.524201 -53.032958) (xy 440.50585 -53.05806)
			(xy 440.504834 -53.05933) (xy 440.504326 -53.060092) (xy 440.497976 -53.06949) (xy 440.49442 -53.076602)
			(xy 440.49061 -53.087524) (xy 440.48934 -53.0987) (xy 440.48934 -53.184298) (xy 440.491118 -53.197506)
			(xy 440.491626 -53.198522) (xy 440.492134 -53.200808) (xy 440.499246 -53.221382) (xy 440.504326 -53.22824)
			(xy 440.50458 -53.228494) (xy 440.519657 -53.24882) (xy 440.544896 -53.292685) (xy 440.564129 -53.339496)
			(xy 440.577022 -53.388435) (xy 440.583347 -53.438646) (xy 440.583574 -53.463952) (xy 440.583016 -53.488906)
			(xy 440.576213 -53.538356) (xy 440.56303 -53.586498) (xy 440.543692 -53.632515) (xy 440.518528 -53.675623)
			(xy 440.503564 -53.6956) (xy 440.497976 -53.70449) (xy 440.493912 -53.712364) (xy 440.490356 -53.723286)
			(xy 440.490356 -53.723794) (xy 440.48934 -53.733446) (xy 440.48934 -53.819298) (xy 440.491118 -53.832506)
			(xy 440.491626 -53.833522) (xy 440.492134 -53.835808) (xy 440.499246 -53.856382) (xy 440.504326 -53.86324)
			(xy 440.50458 -53.863494) (xy 440.519657 -53.88382) (xy 440.544896 -53.927685) (xy 440.564129 -53.974496)
			(xy 440.577022 -54.023435) (xy 440.583347 -54.073646) (xy 440.583574 -54.098952) (xy 440.583016 -54.123906)
			(xy 440.576213 -54.173356) (xy 440.56303 -54.221498) (xy 440.543692 -54.267515) (xy 440.518528 -54.310623)
			(xy 440.503564 -54.3306) (xy 440.497976 -54.33949) (xy 440.493912 -54.347364) (xy 440.490356 -54.358286)
			(xy 440.490356 -54.358794) (xy 440.48934 -54.368446) (xy 440.48934 -54.464966) (xy 440.49188 -54.475888)
			(xy 440.494674 -54.481476) (xy 440.500262 -54.49316) (xy 440.503564 -54.497478) (xy 440.51869 -54.517603)
			(xy 440.544084 -54.561073) (xy 440.563544 -54.607503) (xy 440.576733 -54.656089) (xy 440.583421 -54.705987)
			(xy 440.583828 -54.731158) (xy 440.583828 -54.737508) (xy 440.583066 -54.751986) (xy 440.581064 -54.780026)
			(xy 440.578812 -54.791102) (xy 442.476382 -54.791102) (xy 442.476829 -54.763731) (xy 442.484649 -54.70955)
			(xy 442.500141 -54.657046) (xy 442.522987 -54.607299) (xy 442.552718 -54.561334) (xy 442.570362 -54.540404)
			(xy 442.570616 -54.54015) (xy 442.57619 -54.533055) (xy 442.582444 -54.516145) (xy 442.582808 -54.50713)
			(xy 442.582808 -54.440074) (xy 442.582461 -54.431056) (xy 442.576206 -54.414139) (xy 442.570616 -54.407054)
			(xy 442.570362 -54.407054) (xy 442.570362 -54.4068) (xy 442.552722 -54.385866) (xy 442.522994 -54.3399)
			(xy 442.500147 -54.290154) (xy 442.484649 -54.237651) (xy 442.476819 -54.183472) (xy 442.476819 -54.128731)
			(xy 442.484648 -54.074551) (xy 442.500146 -54.022049) (xy 442.522993 -53.972303) (xy 442.55272 -53.926336)
			(xy 442.570362 -53.905404) (xy 442.570616 -53.90515) (xy 442.57619 -53.898055) (xy 442.582444 -53.881145)
			(xy 442.582808 -53.87213) (xy 442.582808 -53.805074) (xy 442.582461 -53.796056) (xy 442.576206 -53.779139)
			(xy 442.570616 -53.772054) (xy 442.570362 -53.772054) (xy 442.570362 -53.7718) (xy 442.552722 -53.750866)
			(xy 442.522994 -53.7049) (xy 442.500147 -53.655154) (xy 442.484649 -53.602651) (xy 442.476819 -53.548472)
			(xy 442.476819 -53.493731) (xy 442.484648 -53.439551) (xy 442.500146 -53.387049) (xy 442.522993 -53.337303)
			(xy 442.55272 -53.291336) (xy 442.570362 -53.270404) (xy 442.570616 -53.27015) (xy 442.57619 -53.263055)
			(xy 442.582444 -53.246145) (xy 442.582808 -53.23713) (xy 442.582808 -53.170074) (xy 442.582461 -53.161056)
			(xy 442.576206 -53.144139) (xy 442.570616 -53.137054) (xy 442.570362 -53.137054) (xy 442.570362 -53.1368)
			(xy 442.552703 -53.115884) (xy 442.522995 -53.069906) (xy 442.500164 -53.020155) (xy 442.484677 -52.967651)
			(xy 442.476853 -52.913472) (xy 442.476382 -52.886102) (xy 442.476868 -52.858851) (xy 442.484624 -52.804903)
			(xy 442.499979 -52.752608) (xy 442.522621 -52.703031) (xy 442.552087 -52.657181) (xy 442.587778 -52.61599)
			(xy 442.628969 -52.580299) (xy 442.674819 -52.550833) (xy 442.724396 -52.528191) (xy 442.776691 -52.512836)
			(xy 442.830639 -52.50508) (xy 442.885141 -52.50508) (xy 442.939089 -52.512836) (xy 442.991384 -52.528191)
			(xy 443.030497 -52.546054) (xy 447.979473 -52.546054) (xy 447.979473 -52.491546) (xy 447.987231 -52.437594)
			(xy 448.002589 -52.385295) (xy 448.025234 -52.335714) (xy 448.054705 -52.289861) (xy 448.090401 -52.248669)
			(xy 448.131598 -52.212977) (xy 448.177454 -52.183512) (xy 448.227038 -52.160873) (xy 448.279339 -52.145521)
			(xy 448.333292 -52.13777) (xy 448.360546 -52.13731) (xy 448.387915 -52.137805) (xy 448.442093 -52.145616)
			(xy 448.494596 -52.161098) (xy 448.544343 -52.183933) (xy 448.590311 -52.213652) (xy 448.611244 -52.23129)
			(xy 448.611498 -52.231544) (xy 448.618577 -52.237141) (xy 448.6355 -52.24338) (xy 448.644518 -52.243736)
			(xy 448.711574 -52.243736) (xy 448.720589 -52.243359) (xy 448.737505 -52.237124) (xy 448.744594 -52.231544)
			(xy 448.744594 -52.23129) (xy 448.744848 -52.23129) (xy 448.765781 -52.213649) (xy 448.811749 -52.183925)
			(xy 448.861495 -52.161079) (xy 448.913997 -52.145583) (xy 448.968175 -52.137754) (xy 449.022917 -52.137754)
			(xy 449.077095 -52.145583) (xy 449.129597 -52.161079) (xy 449.179343 -52.183925) (xy 449.225311 -52.213649)
			(xy 449.246244 -52.23129) (xy 449.246498 -52.231544) (xy 449.253577 -52.237141) (xy 449.2705 -52.24338)
			(xy 449.279518 -52.243736) (xy 449.346574 -52.243736) (xy 449.355589 -52.243359) (xy 449.372505 -52.237124)
			(xy 449.379594 -52.231544) (xy 449.379594 -52.23129) (xy 449.379848 -52.23129) (xy 449.400788 -52.21366)
			(xy 449.446758 -52.183947) (xy 449.496504 -52.16111) (xy 449.549003 -52.145616) (xy 449.603177 -52.137786)
			(xy 449.630546 -52.13731) (xy 449.657796 -52.137763) (xy 449.711742 -52.145525) (xy 449.764033 -52.160885)
			(xy 449.813607 -52.18353) (xy 449.859454 -52.212999) (xy 449.900641 -52.248692) (xy 449.936329 -52.289883)
			(xy 449.965792 -52.335733) (xy 449.988431 -52.38531) (xy 450.003785 -52.437603) (xy 450.01154 -52.49155)
			(xy 450.01154 -52.54605) (xy 450.005596 -52.587398) (xy 451.05523 -52.587398) (xy 451.059301 -52.531776)
			(xy 451.071427 -52.477339) (xy 451.09135 -52.425248) (xy 451.118646 -52.376613) (xy 451.152732 -52.33247)
			(xy 451.192881 -52.293761) (xy 451.238239 -52.26131) (xy 451.287839 -52.235809) (xy 451.340623 -52.217802)
			(xy 451.395466 -52.207672) (xy 451.4512 -52.205635) (xy 451.506637 -52.211735) (xy 451.560594 -52.225841)
			(xy 451.611923 -52.247653) (xy 451.659529 -52.276707) (xy 451.702397 -52.312382) (xy 451.739614 -52.353919)
			(xy 451.770387 -52.400432) (xy 451.794059 -52.450929) (xy 451.810127 -52.504336) (xy 451.818247 -52.559512)
			(xy 451.818756 -52.587398) (xy 451.818247 -52.615284) (xy 451.810127 -52.67046) (xy 451.794059 -52.723867)
			(xy 451.770387 -52.774364) (xy 451.739614 -52.820877) (xy 451.702397 -52.862414) (xy 451.659529 -52.898089)
			(xy 451.611923 -52.927143) (xy 451.560594 -52.948955) (xy 451.506637 -52.963061) (xy 451.4512 -52.969161)
			(xy 451.395466 -52.967124) (xy 451.340623 -52.956994) (xy 451.287839 -52.938987) (xy 451.238239 -52.913486)
			(xy 451.192881 -52.881035) (xy 451.152732 -52.842326) (xy 451.118646 -52.798183) (xy 451.09135 -52.749548)
			(xy 451.071427 -52.697457) (xy 451.059301 -52.64302) (xy 451.05523 -52.587398) (xy 450.005596 -52.587398)
			(xy 450.003785 -52.599997) (xy 449.988431 -52.65229) (xy 449.965792 -52.701867) (xy 449.936329 -52.747717)
			(xy 449.900641 -52.788908) (xy 449.859454 -52.824601) (xy 449.813607 -52.85407) (xy 449.764033 -52.876715)
			(xy 449.711742 -52.892075) (xy 449.657796 -52.899837) (xy 449.630546 -52.900326) (xy 449.603176 -52.899851)
			(xy 449.548996 -52.892038) (xy 449.496493 -52.876552) (xy 449.446746 -52.853712) (xy 449.400779 -52.823988)
			(xy 449.379848 -52.806346) (xy 449.379594 -52.806092) (xy 449.372514 -52.800496) (xy 449.355592 -52.794255)
			(xy 449.346574 -52.7939) (xy 449.279518 -52.7939) (xy 449.270502 -52.794266) (xy 449.253585 -52.800507)
			(xy 449.246498 -52.806092) (xy 449.246244 -52.806346) (xy 449.225311 -52.823987) (xy 449.179343 -52.853711)
			(xy 449.129597 -52.876557) (xy 449.077095 -52.892053) (xy 449.022917 -52.899882) (xy 448.968175 -52.899882)
			(xy 448.913997 -52.892053) (xy 448.861495 -52.876557) (xy 448.811749 -52.853711) (xy 448.765781 -52.823987)
			(xy 448.744848 -52.806346) (xy 448.744594 -52.806092) (xy 448.737514 -52.800496) (xy 448.720592 -52.794255)
			(xy 448.711574 -52.7939) (xy 448.644518 -52.7939) (xy 448.635502 -52.794266) (xy 448.618585 -52.800507)
			(xy 448.611498 -52.806092) (xy 448.611498 -52.806346) (xy 448.611244 -52.806346) (xy 448.590299 -52.82397)
			(xy 448.544331 -52.853686) (xy 448.494587 -52.876525) (xy 448.442088 -52.89202) (xy 448.387914 -52.899851)
			(xy 448.360546 -52.900326) (xy 448.333292 -52.89983) (xy 448.279339 -52.892079) (xy 448.227038 -52.876727)
			(xy 448.177454 -52.854088) (xy 448.131598 -52.824623) (xy 448.090401 -52.788931) (xy 448.054705 -52.747739)
			(xy 448.025234 -52.701886) (xy 448.002589 -52.652305) (xy 447.987231 -52.600006) (xy 447.979473 -52.546054)
			(xy 443.030497 -52.546054) (xy 443.040961 -52.550833) (xy 443.086811 -52.580299) (xy 443.128002 -52.61599)
			(xy 443.163693 -52.657181) (xy 443.193159 -52.703031) (xy 443.215801 -52.752608) (xy 443.231156 -52.804903)
			(xy 443.238912 -52.858851) (xy 443.239398 -52.886102) (xy 443.238934 -52.913472) (xy 443.231115 -52.967651)
			(xy 443.215626 -53.020155) (xy 443.192784 -53.069901) (xy 443.163059 -53.115868) (xy 443.145418 -53.1368)
			(xy 443.145164 -53.137054) (xy 443.139587 -53.144147) (xy 443.133335 -53.161059) (xy 443.132972 -53.170074)
			(xy 443.132972 -53.23713) (xy 443.133321 -53.246148) (xy 443.139575 -53.263064) (xy 443.145164 -53.27015)
			(xy 443.145418 -53.27015) (xy 443.145418 -53.270404) (xy 443.163059 -53.291336) (xy 443.19278 -53.337305)
			(xy 443.215623 -53.387052) (xy 443.231117 -53.439553) (xy 443.238944 -53.493731) (xy 443.238944 -53.548472)
			(xy 443.231116 -53.602649) (xy 443.215621 -53.655151) (xy 443.192779 -53.704898) (xy 443.163057 -53.750866)
			(xy 443.146488 -53.77053) (xy 443.51067 -53.77053) (xy 443.511183 -53.741613) (xy 443.51991 -53.68444)
			(xy 443.537167 -53.62924) (xy 443.562559 -53.577278) (xy 443.595505 -53.529744) (xy 443.635249 -53.487729)
			(xy 443.657736 -53.46954) (xy 443.666521 -53.461912) (xy 443.676715 -53.441027) (xy 443.677294 -53.429408)
			(xy 443.677294 -53.349652) (xy 443.67677 -53.338018) (xy 443.666571 -53.317109) (xy 443.657736 -53.30952)
			(xy 443.63527 -53.291309) (xy 443.595532 -53.249294) (xy 443.56259 -53.201764) (xy 443.537198 -53.149806)
			(xy 443.519938 -53.094612) (xy 443.511206 -53.037445) (xy 443.51067 -53.00853) (xy 443.511183 -52.981279)
			(xy 443.518935 -52.927331) (xy 443.534287 -52.875035) (xy 443.556924 -52.825457) (xy 443.586387 -52.779605)
			(xy 443.622075 -52.738412) (xy 443.663263 -52.702718) (xy 443.709111 -52.673249) (xy 443.758687 -52.650605)
			(xy 443.81098 -52.635247) (xy 443.864927 -52.627487) (xy 443.892178 -52.627022) (xy 443.918492 -52.627497)
			(xy 443.97062 -52.634729) (xy 444.021263 -52.649046) (xy 444.069462 -52.670177) (xy 444.114306 -52.697723)
			(xy 444.154946 -52.731161) (xy 444.173102 -52.750212) (xy 444.180619 -52.757618) (xy 444.199903 -52.76614)
			(xy 444.21044 -52.766722) (xy 444.285116 -52.766722) (xy 444.295667 -52.766208) (xy 444.314962 -52.757662)
			(xy 444.322454 -52.750212) (xy 444.340593 -52.73114) (xy 444.381226 -52.697683) (xy 444.426069 -52.670126)
			(xy 444.474274 -52.648991) (xy 444.524924 -52.634677) (xy 444.577061 -52.627458) (xy 444.603378 -52.627022)
			(xy 444.630632 -52.627476) (xy 444.684585 -52.635231) (xy 444.736884 -52.650585) (xy 444.786466 -52.673228)
			(xy 444.832321 -52.702696) (xy 444.873515 -52.738391) (xy 444.909209 -52.779585) (xy 444.938676 -52.825441)
			(xy 444.961317 -52.875023) (xy 444.976671 -52.927323) (xy 444.984425 -52.981276) (xy 444.984886 -53.00853)
			(xy 444.984404 -53.036196) (xy 444.982173 -53.051456) (xy 453.241154 -53.051456) (xy 453.245225 -52.995834)
			(xy 453.257351 -52.941397) (xy 453.277274 -52.889306) (xy 453.30457 -52.840671) (xy 453.338656 -52.796528)
			(xy 453.378805 -52.757819) (xy 453.424163 -52.725368) (xy 453.473763 -52.699867) (xy 453.526547 -52.68186)
			(xy 453.58139 -52.67173) (xy 453.637124 -52.669693) (xy 453.692561 -52.675793) (xy 453.746518 -52.689899)
			(xy 453.797847 -52.711711) (xy 453.845453 -52.740765) (xy 453.888321 -52.77644) (xy 453.925538 -52.817977)
			(xy 453.956311 -52.86449) (xy 453.979983 -52.914987) (xy 453.996051 -52.968394) (xy 454.004171 -53.02357)
			(xy 454.00468 -53.051456) (xy 454.004171 -53.079342) (xy 453.996051 -53.134518) (xy 453.979983 -53.187925)
			(xy 453.956311 -53.238422) (xy 453.925538 -53.284935) (xy 453.888321 -53.326472) (xy 453.845453 -53.362147)
			(xy 453.797847 -53.391201) (xy 453.746518 -53.413013) (xy 453.692561 -53.427119) (xy 453.637124 -53.433219)
			(xy 453.58139 -53.431182) (xy 453.526547 -53.421052) (xy 453.473763 -53.403045) (xy 453.424163 -53.377544)
			(xy 453.378805 -53.345093) (xy 453.338656 -53.306384) (xy 453.30457 -53.262241) (xy 453.277274 -53.213606)
			(xy 453.257351 -53.161515) (xy 453.245225 -53.107078) (xy 453.241154 -53.051456) (xy 444.982173 -53.051456)
			(xy 444.9764 -53.090947) (xy 444.960578 -53.14397) (xy 444.937271 -53.194154) (xy 444.906965 -53.240449)
			(xy 444.870295 -53.281887) (xy 444.828029 -53.317598) (xy 444.8048 -53.332634) (xy 444.795119 -53.339266)
			(xy 444.782674 -53.35913) (xy 444.780924 -53.370734) (xy 444.77305 -53.450744) (xy 444.772399 -53.462383)
			(xy 444.780492 -53.484221) (xy 444.788544 -53.492654) (xy 444.788798 -53.492908) (xy 444.807365 -53.511003)
			(xy 444.839945 -53.551332) (xy 444.86676 -53.595703) (xy 444.887315 -53.643299) (xy 444.901231 -53.693241)
			(xy 444.908252 -53.744608) (xy 444.908686 -53.77053) (xy 444.90825 -53.797783) (xy 444.900489 -53.851734)
			(xy 444.885129 -53.904031) (xy 444.862483 -53.953609) (xy 444.833011 -53.999461) (xy 444.797314 -54.040651)
			(xy 444.756119 -54.076342) (xy 444.710264 -54.105808) (xy 444.660682 -54.128447) (xy 444.608383 -54.1438)
			(xy 444.554431 -54.151554) (xy 444.527178 -54.152038) (xy 444.499807 -54.1516) (xy 444.445626 -54.143778)
			(xy 444.393122 -54.128283) (xy 444.343375 -54.105435) (xy 444.29741 -54.075703) (xy 444.27648 -54.058058)
			(xy 444.276226 -54.057804) (xy 444.269136 -54.052223) (xy 444.252222 -54.045973) (xy 444.243206 -54.045612)
			(xy 444.17615 -54.045612) (xy 444.167135 -54.045991) (xy 444.150218 -54.052223) (xy 444.14313 -54.057804)
			(xy 444.14313 -54.058058) (xy 444.142876 -54.058058) (xy 444.121921 -54.075668) (xy 444.075955 -54.105386)
			(xy 444.026213 -54.128228) (xy 443.973718 -54.143726) (xy 443.919546 -54.151561) (xy 443.892178 -54.152038)
			(xy 443.864928 -54.151543) (xy 443.810982 -54.143784) (xy 443.758689 -54.128428) (xy 443.709114 -54.105786)
			(xy 443.663265 -54.07632) (xy 443.622076 -54.04063) (xy 443.586384 -53.999442) (xy 443.556918 -53.953593)
			(xy 443.534275 -53.904018) (xy 443.518918 -53.851726) (xy 443.511158 -53.79778) (xy 443.51067 -53.77053)
			(xy 443.146488 -53.77053) (xy 443.145418 -53.7718) (xy 443.145164 -53.772054) (xy 443.139587 -53.779147)
			(xy 443.133335 -53.796059) (xy 443.132972 -53.805074) (xy 443.132972 -53.87213) (xy 443.133321 -53.881148)
			(xy 443.139575 -53.898064) (xy 443.145164 -53.90515) (xy 443.145418 -53.90515) (xy 443.145418 -53.905404)
			(xy 443.163059 -53.926336) (xy 443.19278 -53.972305) (xy 443.215623 -54.022052) (xy 443.231117 -54.074553)
			(xy 443.238944 -54.128731) (xy 443.238944 -54.183472) (xy 443.231116 -54.237649) (xy 443.215621 -54.290151)
			(xy 443.20183 -54.320186) (xy 445.430402 -54.320186) (xy 445.430859 -54.292815) (xy 445.438679 -54.238636)
			(xy 445.45417 -54.186133) (xy 445.477014 -54.136386) (xy 445.50674 -54.09042) (xy 445.524382 -54.069488)
			(xy 445.524636 -54.069234) (xy 445.530218 -54.062145) (xy 445.536467 -54.04523) (xy 445.536828 -54.036214)
			(xy 445.536828 -53.969158) (xy 445.536437 -53.960145) (xy 445.530212 -53.943228) (xy 445.524636 -53.936138)
			(xy 445.524382 -53.936138) (xy 445.524382 -53.935884) (xy 445.506766 -53.914933) (xy 445.477051 -53.868965)
			(xy 445.454211 -53.819223) (xy 445.438715 -53.766726) (xy 445.43088 -53.712554) (xy 445.430402 -53.685186)
			(xy 445.430888 -53.657935) (xy 445.438644 -53.603987) (xy 445.453999 -53.551692) (xy 445.476641 -53.502115)
			(xy 445.506107 -53.456265) (xy 445.541798 -53.415074) (xy 445.582989 -53.379383) (xy 445.628839 -53.349917)
			(xy 445.678416 -53.327275) (xy 445.730711 -53.31192) (xy 445.784659 -53.304164) (xy 445.839161 -53.304164)
			(xy 445.893109 -53.31192) (xy 445.945404 -53.327275) (xy 445.994981 -53.349917) (xy 446.040831 -53.379383)
			(xy 446.082022 -53.415074) (xy 446.117713 -53.456265) (xy 446.147179 -53.502115) (xy 446.169821 -53.551692)
			(xy 446.185176 -53.603987) (xy 446.192932 -53.657935) (xy 446.193418 -53.685186) (xy 446.192964 -53.712557)
			(xy 446.185146 -53.766737) (xy 446.169655 -53.819241) (xy 446.14681 -53.868988) (xy 446.117082 -53.914954)
			(xy 446.099438 -53.935884) (xy 446.099184 -53.936138) (xy 446.093615 -53.943237) (xy 446.087358 -53.960144)
			(xy 446.086992 -53.969158) (xy 446.086992 -54.036214) (xy 446.087344 -54.045231) (xy 446.093595 -54.062148)
			(xy 446.099184 -54.069234) (xy 446.099438 -54.069234) (xy 446.099438 -54.069488) (xy 446.117091 -54.090409)
			(xy 446.1468 -54.136385) (xy 446.169632 -54.186136) (xy 446.18512 -54.238639) (xy 446.192946 -54.292816)
			(xy 446.193418 -54.320186) (xy 446.192932 -54.347437) (xy 446.185176 -54.401385) (xy 446.169821 -54.45368)
			(xy 446.147179 -54.503257) (xy 446.117713 -54.549107) (xy 446.082022 -54.590298) (xy 446.040831 -54.625989)
			(xy 445.994981 -54.655455) (xy 445.945404 -54.678097) (xy 445.893109 -54.693452) (xy 445.839161 -54.701208)
			(xy 445.784659 -54.701208) (xy 445.730711 -54.693452) (xy 445.678416 -54.678097) (xy 445.628839 -54.655455)
			(xy 445.582989 -54.625989) (xy 445.541798 -54.590298) (xy 445.506107 -54.549107) (xy 445.476641 -54.503257)
			(xy 445.453999 -54.45368) (xy 445.438644 -54.401385) (xy 445.430888 -54.347437) (xy 445.430402 -54.320186)
			(xy 443.20183 -54.320186) (xy 443.192779 -54.339898) (xy 443.163057 -54.385866) (xy 443.145418 -54.4068)
			(xy 443.145164 -54.407054) (xy 443.139587 -54.414147) (xy 443.133335 -54.431059) (xy 443.132972 -54.440074)
			(xy 443.132972 -54.50713) (xy 443.133321 -54.516148) (xy 443.139575 -54.533064) (xy 443.145164 -54.54015)
			(xy 443.145418 -54.54015) (xy 443.145418 -54.540404) (xy 443.163075 -54.561321) (xy 443.192784 -54.607299)
			(xy 443.215616 -54.65705) (xy 443.231103 -54.709554) (xy 443.238926 -54.763732) (xy 443.239043 -54.770528)
			(xy 446.370964 -54.770528) (xy 446.371431 -54.743158) (xy 446.379246 -54.688978) (xy 446.394734 -54.636474)
			(xy 446.417576 -54.586727) (xy 446.447302 -54.540761) (xy 446.464944 -54.51983) (xy 446.465198 -54.519576)
			(xy 446.470801 -54.5125) (xy 446.477038 -54.495575) (xy 446.47739 -54.486556) (xy 446.47739 -54.4195)
			(xy 446.477035 -54.410483) (xy 446.470786 -54.393566) (xy 446.465198 -54.38648) (xy 446.464944 -54.38648)
			(xy 446.464944 -54.386226) (xy 446.44731 -54.365289) (xy 446.417596 -54.319318) (xy 446.394759 -54.269572)
			(xy 446.379266 -54.217072) (xy 446.371438 -54.162897) (xy 446.370964 -54.135528) (xy 446.37145 -54.108277)
			(xy 446.379206 -54.054329) (xy 446.394561 -54.002034) (xy 446.417203 -53.952457) (xy 446.446669 -53.906607)
			(xy 446.48236 -53.865416) (xy 446.523551 -53.829725) (xy 446.569401 -53.800259) (xy 446.618978 -53.777617)
			(xy 446.671273 -53.762262) (xy 446.725221 -53.754506) (xy 446.779723 -53.754506) (xy 446.833671 -53.762262)
			(xy 446.885966 -53.777617) (xy 446.935543 -53.800259) (xy 446.981393 -53.829725) (xy 447.022584 -53.865416)
			(xy 447.058275 -53.906607) (xy 447.087741 -53.952457) (xy 447.092816 -53.96357) (xy 451.071994 -53.96357)
			(xy 451.076065 -53.907948) (xy 451.088191 -53.853511) (xy 451.108114 -53.80142) (xy 451.13541 -53.752785)
			(xy 451.169496 -53.708642) (xy 451.209645 -53.669933) (xy 451.255003 -53.637482) (xy 451.304603 -53.611981)
			(xy 451.357387 -53.593974) (xy 451.41223 -53.583844) (xy 451.467964 -53.581807) (xy 451.523401 -53.587907)
			(xy 451.577358 -53.602013) (xy 451.628687 -53.623825) (xy 451.676293 -53.652879) (xy 451.719161 -53.688554)
			(xy 451.756378 -53.730091) (xy 451.787151 -53.776604) (xy 451.810823 -53.827101) (xy 451.826891 -53.880508)
			(xy 451.835011 -53.935684) (xy 451.83552 -53.96357) (xy 451.835011 -53.991456) (xy 451.826891 -54.046632)
			(xy 451.810823 -54.100039) (xy 451.787151 -54.150536) (xy 451.756378 -54.197049) (xy 451.719161 -54.238586)
			(xy 451.676293 -54.274261) (xy 451.628687 -54.303315) (xy 451.577358 -54.325127) (xy 451.523401 -54.339233)
			(xy 451.467964 -54.345333) (xy 451.41223 -54.343296) (xy 451.357387 -54.333166) (xy 451.304603 -54.315159)
			(xy 451.255003 -54.289658) (xy 451.209645 -54.257207) (xy 451.169496 -54.218498) (xy 451.13541 -54.174355)
			(xy 451.108114 -54.12572) (xy 451.088191 -54.073629) (xy 451.076065 -54.019192) (xy 451.071994 -53.96357)
			(xy 447.092816 -53.96357) (xy 447.110383 -54.002034) (xy 447.125738 -54.054329) (xy 447.133494 -54.108277)
			(xy 447.13398 -54.135528) (xy 447.133535 -54.162899) (xy 447.125713 -54.217079) (xy 447.110219 -54.269583)
			(xy 447.087373 -54.319329) (xy 447.057643 -54.365295) (xy 447.04 -54.386226) (xy 447.039746 -54.38648)
			(xy 447.034155 -54.393563) (xy 447.027912 -54.410483) (xy 447.027554 -54.4195) (xy 447.027554 -54.486556)
			(xy 447.02792 -54.495572) (xy 447.03416 -54.51249) (xy 447.039746 -54.519576) (xy 447.04 -54.519576)
			(xy 447.04 -54.51983) (xy 447.05762 -54.540778) (xy 447.087334 -54.586746) (xy 447.110174 -54.63649)
			(xy 447.12567 -54.688987) (xy 447.133503 -54.74316) (xy 447.13398 -54.770528) (xy 447.133494 -54.797779)
			(xy 447.125738 -54.851727) (xy 447.110383 -54.904022) (xy 447.087741 -54.953599) (xy 447.058275 -54.999449)
			(xy 447.022584 -55.04064) (xy 446.981393 -55.076331) (xy 446.935543 -55.105797) (xy 446.885966 -55.128439)
			(xy 446.833671 -55.143794) (xy 446.779723 -55.15155) (xy 446.725221 -55.15155) (xy 446.671273 -55.143794)
			(xy 446.618978 -55.128439) (xy 446.569401 -55.105797) (xy 446.523551 -55.076331) (xy 446.48236 -55.04064)
			(xy 446.446669 -54.999449) (xy 446.417203 -54.953599) (xy 446.394561 -54.904022) (xy 446.379206 -54.851727)
			(xy 446.37145 -54.797779) (xy 446.370964 -54.770528) (xy 443.239043 -54.770528) (xy 443.239398 -54.791102)
			(xy 443.238912 -54.818353) (xy 443.231156 -54.872301) (xy 443.215801 -54.924596) (xy 443.193159 -54.974173)
			(xy 443.163693 -55.020023) (xy 443.128002 -55.061214) (xy 443.086811 -55.096905) (xy 443.040961 -55.126371)
			(xy 442.991384 -55.149013) (xy 442.939089 -55.164368) (xy 442.885141 -55.172124) (xy 442.830639 -55.172124)
			(xy 442.776691 -55.164368) (xy 442.724396 -55.149013) (xy 442.674819 -55.126371) (xy 442.628969 -55.096905)
			(xy 442.587778 -55.061214) (xy 442.552087 -55.020023) (xy 442.522621 -54.974173) (xy 442.499979 -54.924596)
			(xy 442.484624 -54.872301) (xy 442.476868 -54.818353) (xy 442.476382 -54.791102) (xy 440.578812 -54.791102)
			(xy 440.569864 -54.835112) (xy 440.550719 -54.887965) (xy 440.524041 -54.937444) (xy 440.507628 -54.960266)
			(xy 440.505088 -54.963568) (xy 440.499754 -54.973728) (xy 440.497214 -54.978808) (xy 440.49188 -54.995064)
			(xy 440.490716 -54.998898) (xy 440.489435 -55.006807) (xy 440.48934 -55.010812) (xy 440.48934 -55.722266)
			(xy 452.133968 -55.722266) (xy 452.138039 -55.666644) (xy 452.150165 -55.612207) (xy 452.170088 -55.560116)
			(xy 452.197384 -55.511481) (xy 452.23147 -55.467338) (xy 452.271619 -55.428629) (xy 452.316977 -55.396178)
			(xy 452.366577 -55.370677) (xy 452.419361 -55.35267) (xy 452.474204 -55.34254) (xy 452.529938 -55.340503)
			(xy 452.585375 -55.346603) (xy 452.639332 -55.360709) (xy 452.690661 -55.382521) (xy 452.738267 -55.411575)
			(xy 452.781135 -55.44725) (xy 452.818352 -55.488787) (xy 452.849125 -55.5353) (xy 452.872797 -55.585797)
			(xy 452.888865 -55.639204) (xy 452.896985 -55.69438) (xy 452.897494 -55.722266) (xy 452.896985 -55.750152)
			(xy 452.888865 -55.805328) (xy 452.872797 -55.858735) (xy 452.849125 -55.909232) (xy 452.818352 -55.955745)
			(xy 452.781135 -55.997282) (xy 452.738267 -56.032957) (xy 452.690661 -56.062011) (xy 452.639332 -56.083823)
			(xy 452.585375 -56.097929) (xy 452.529938 -56.104029) (xy 452.474204 -56.101992) (xy 452.419361 -56.091862)
			(xy 452.366577 -56.073855) (xy 452.316977 -56.048354) (xy 452.271619 -56.015903) (xy 452.23147 -55.977194)
			(xy 452.197384 -55.933051) (xy 452.170088 -55.884416) (xy 452.150165 -55.832325) (xy 452.138039 -55.777888)
			(xy 452.133968 -55.722266) (xy 440.48934 -55.722266) (xy 440.48934 -55.939436) (xy 440.489594 -55.94985)
			(xy 440.489594 -55.950866) (xy 440.48934 -55.968138) (xy 440.48934 -55.972964) (xy 440.489086 -55.973472)
			(xy 440.476386 -56.523382) (xy 440.476386 -56.52389) (xy 440.475878 -56.541924) (xy 440.479688 -56.55183)
			(xy 440.485276 -56.566054) (xy 440.486913 -56.569961) (xy 440.491251 -56.577237) (xy 440.493912 -56.580532)
			(xy 440.49696 -56.584088) (xy 440.497722 -56.585104) (xy 440.498738 -56.586374) (xy 440.498992 -56.586628)
			(xy 440.516897 -56.609677) (xy 440.546227 -56.660134) (xy 440.567528 -56.714471) (xy 440.580301 -56.771418)
			(xy 440.582812 -56.800496) (xy 440.583574 -56.82234) (xy 440.583574 -56.82742) (xy 440.582979 -56.855806)
			(xy 440.574423 -56.911932) (xy 440.557652 -56.966173) (xy 440.539963 -57.002934) (xy 447.863468 -57.002934)
			(xy 447.863996 -56.974844) (xy 447.872218 -56.919268) (xy 447.888504 -56.865501) (xy 447.912501 -56.814703)
			(xy 447.943691 -56.767976) (xy 447.981398 -56.72633) (xy 448.024806 -56.690666) (xy 448.048634 -56.675782)
			(xy 448.057524 -56.670448) (xy 448.069716 -56.65343) (xy 448.090036 -56.560212) (xy 448.085718 -56.539638)
			(xy 448.079876 -56.531002) (xy 448.063872 -56.506941) (xy 448.038531 -56.455008) (xy 448.021306 -56.399849)
			(xy 448.012592 -56.342725) (xy 448.012058 -56.313832) (xy 448.012608 -56.286583) (xy 448.020359 -56.232639)
			(xy 448.035709 -56.180348) (xy 448.058343 -56.130773) (xy 448.087803 -56.084924) (xy 448.123488 -56.043735)
			(xy 448.164672 -56.008043) (xy 448.210515 -55.978575) (xy 448.260086 -55.955932) (xy 448.312375 -55.940573)
			(xy 448.366317 -55.932813) (xy 448.393566 -55.932324) (xy 448.420936 -55.932804) (xy 448.475115 -55.940618)
			(xy 448.527618 -55.956103) (xy 448.577365 -55.978942) (xy 448.623332 -56.008664) (xy 448.644264 -56.026304)
			(xy 448.644518 -56.026558) (xy 448.65159 -56.032165) (xy 448.668518 -56.038398) (xy 448.677538 -56.03875)
			(xy 448.744594 -56.03875) (xy 448.753612 -56.038401) (xy 448.770529 -56.032149) (xy 448.777614 -56.026558)
			(xy 448.777614 -56.026304) (xy 448.777868 -56.026304) (xy 448.798801 -56.008663) (xy 448.844769 -55.978939)
			(xy 448.894515 -55.956093) (xy 448.947017 -55.940597) (xy 449.001195 -55.932768) (xy 449.055937 -55.932768)
			(xy 449.110115 -55.940597) (xy 449.162617 -55.956093) (xy 449.212363 -55.978939) (xy 449.258331 -56.008663)
			(xy 449.279264 -56.026304) (xy 449.279518 -56.026558) (xy 449.28659 -56.032165) (xy 449.303518 -56.038398)
			(xy 449.312538 -56.03875) (xy 449.379594 -56.03875) (xy 449.388612 -56.038401) (xy 449.405529 -56.032149)
			(xy 449.412614 -56.026558) (xy 449.412614 -56.026304) (xy 449.412868 -56.026304) (xy 449.433802 -56.008667)
			(xy 449.479774 -55.978955) (xy 449.529521 -55.956118) (xy 449.582021 -55.940627) (xy 449.636197 -55.932798)
			(xy 449.663566 -55.932324) (xy 449.690823 -55.932721) (xy 449.744782 -55.940474) (xy 449.797088 -55.955829)
			(xy 449.846677 -55.978471) (xy 449.892538 -56.007941) (xy 449.933738 -56.043637) (xy 449.969439 -56.084835)
			(xy 449.998913 -56.130693) (xy 450.021559 -56.18028) (xy 450.036918 -56.232585) (xy 450.044677 -56.286543)
			(xy 450.044677 -56.297068) (xy 450.386448 -56.297068) (xy 450.390519 -56.241446) (xy 450.402645 -56.187009)
			(xy 450.422568 -56.134918) (xy 450.449864 -56.086283) (xy 450.48395 -56.04214) (xy 450.524099 -56.003431)
			(xy 450.569457 -55.97098) (xy 450.619057 -55.945479) (xy 450.671841 -55.927472) (xy 450.726684 -55.917342)
			(xy 450.782418 -55.915305) (xy 450.837855 -55.921405) (xy 450.891812 -55.935511) (xy 450.943141 -55.957323)
			(xy 450.990747 -55.986377) (xy 451.033615 -56.022052) (xy 451.070832 -56.063589) (xy 451.101605 -56.110102)
			(xy 451.125277 -56.160599) (xy 451.141345 -56.214006) (xy 451.149465 -56.269182) (xy 451.149974 -56.297068)
			(xy 451.149465 -56.324954) (xy 451.141345 -56.38013) (xy 451.125277 -56.433537) (xy 451.101605 -56.484034)
			(xy 451.070832 -56.530547) (xy 451.033615 -56.572084) (xy 450.990747 -56.607759) (xy 450.943141 -56.636813)
			(xy 450.891812 -56.658625) (xy 450.837855 -56.672731) (xy 450.782418 -56.678831) (xy 450.726684 -56.676794)
			(xy 450.671841 -56.666664) (xy 450.619057 -56.648657) (xy 450.569457 -56.623156) (xy 450.524099 -56.590705)
			(xy 450.48395 -56.551996) (xy 450.449864 -56.507853) (xy 450.422568 -56.459218) (xy 450.402645 -56.407127)
			(xy 450.390519 -56.35269) (xy 450.386448 -56.297068) (xy 450.044677 -56.297068) (xy 450.044677 -56.341057)
			(xy 450.036918 -56.395015) (xy 450.021559 -56.44732) (xy 449.998913 -56.496907) (xy 449.969439 -56.542765)
			(xy 449.933738 -56.583963) (xy 449.892538 -56.619659) (xy 449.846677 -56.649129) (xy 449.797088 -56.671771)
			(xy 449.744782 -56.687126) (xy 449.690823 -56.694879) (xy 449.663566 -56.69534) (xy 449.636194 -56.694908)
			(xy 449.582013 -56.687085) (xy 449.529509 -56.671588) (xy 449.479763 -56.648738) (xy 449.433798 -56.619005)
			(xy 449.412868 -56.60136) (xy 449.412614 -56.601106) (xy 449.405527 -56.59552) (xy 449.388611 -56.589273)
			(xy 449.379594 -56.588914) (xy 449.312538 -56.588914) (xy 449.303523 -56.589286) (xy 449.286605 -56.595523)
			(xy 449.279518 -56.601106) (xy 449.279518 -56.60136) (xy 449.279264 -56.60136) (xy 449.258331 -56.619001)
			(xy 449.212363 -56.648725) (xy 449.162617 -56.671571) (xy 449.110115 -56.687067) (xy 449.055937 -56.694896)
			(xy 449.001195 -56.694896) (xy 448.947017 -56.687067) (xy 448.894515 -56.671571) (xy 448.844769 -56.648725)
			(xy 448.798801 -56.619001) (xy 448.777868 -56.60136) (xy 448.777614 -56.601106) (xy 448.770527 -56.59552)
			(xy 448.753611 -56.589273) (xy 448.744594 -56.588914) (xy 448.677538 -56.588914) (xy 448.668523 -56.589286)
			(xy 448.651605 -56.595523) (xy 448.644518 -56.601106) (xy 448.64401 -56.60136) (xy 448.631279 -56.612308)
			(xy 448.604185 -56.632147) (xy 448.589908 -56.640984) (xy 448.581018 -56.646318) (xy 448.568826 -56.663336)
			(xy 448.548506 -56.756554) (xy 448.552824 -56.777128) (xy 448.558666 -56.785764) (xy 448.574649 -56.809839)
			(xy 448.599997 -56.861766) (xy 448.617227 -56.916921) (xy 448.625947 -56.974042) (xy 448.626484 -57.002934)
			(xy 448.625998 -57.030185) (xy 448.618242 -57.084133) (xy 448.602887 -57.136428) (xy 448.580245 -57.186005)
			(xy 448.550779 -57.231855) (xy 448.515088 -57.273046) (xy 448.473897 -57.308737) (xy 448.428047 -57.338203)
			(xy 448.37847 -57.360845) (xy 448.326175 -57.3762) (xy 448.272227 -57.383956) (xy 448.217725 -57.383956)
			(xy 448.163777 -57.3762) (xy 448.111482 -57.360845) (xy 448.061905 -57.338203) (xy 448.016055 -57.308737)
			(xy 447.974864 -57.273046) (xy 447.939173 -57.231855) (xy 447.909707 -57.186005) (xy 447.887065 -57.136428)
			(xy 447.87171 -57.084133) (xy 447.863954 -57.030185) (xy 447.863468 -57.002934) (xy 440.539963 -57.002934)
			(xy 440.533035 -57.017333) (xy 440.501114 -57.064285) (xy 440.482228 -57.085484) (xy 440.476132 -57.092088)
			(xy 440.46394 -57.12079) (xy 440.462416 -57.129172) (xy 440.462162 -57.131712) (xy 440.461654 -57.148222)
			(xy 440.4614 -57.158636) (xy 440.4614 -57.159144) (xy 440.461146 -57.169304) (xy 440.468512 -57.1881)
			(xy 440.475878 -57.19572) (xy 440.495901 -57.217124) (xy 440.529801 -57.264933) (xy 440.555987 -57.317366)
			(xy 440.573843 -57.373188) (xy 440.582948 -57.431085) (xy 440.583574 -57.460388) (xy 440.583574 -57.465214)
			(xy 440.581796 -57.498996) (xy 440.581034 -57.505854) (xy 440.581034 -57.506362) (xy 440.577457 -57.532643)
			(xy 440.563974 -57.583938) (xy 440.543517 -57.632872) (xy 440.516481 -57.678502) (xy 440.483385 -57.719948)
			(xy 440.464448 -57.738518) (xy 440.458098 -57.74436) (xy 440.454796 -57.750964) (xy 440.453119 -57.754162)
			(xy 440.450568 -57.760917) (xy 440.449716 -57.764426) (xy 440.446668 -57.779158) (xy 440.446668 -57.781444)
			(xy 440.462162 -57.817004) (xy 440.469274 -57.824116) (xy 440.490514 -57.845786) (xy 440.526543 -57.894608)
			(xy 440.55439 -57.948517) (xy 440.573354 -58.006154) (xy 440.582956 -58.066066) (xy 440.583574 -58.096404)
			(xy 440.583496 -58.109142) (xy 440.581842 -58.134563) (xy 440.580272 -58.147204) (xy 440.580018 -58.149998)
			(xy 440.575503 -58.178128) (xy 440.559209 -58.232717) (xy 440.534962 -58.284269) (xy 440.519566 -58.30824)
			(xy 440.513978 -58.316368) (xy 440.51093 -58.320686) (xy 440.504834 -58.329068) (xy 440.500516 -58.334148)
			(xy 440.495944 -58.341514) (xy 440.494928 -58.343546) (xy 440.492466 -58.348872) (xy 440.489773 -58.360288)
			(xy 440.489594 -58.366152) (xy 440.489594 -58.387234) (xy 440.489451 -58.392673) (xy 440.487143 -58.403305)
			(xy 440.485022 -58.408316) (xy 440.478672 -58.420508) (xy 440.476507 -58.425446) (xy 440.474076 -58.435949)
			(xy 440.473846 -58.441336) (xy 440.473846 -58.444892) (xy 440.474354 -58.450734) (xy 440.475624 -58.457338)
			(xy 440.482482 -58.471816) (xy 440.487308 -58.47715) (xy 440.50538 -58.498237) (xy 440.535872 -58.544649)
			(xy 440.559328 -58.594985) (xy 440.575256 -58.648185) (xy 440.579827 -58.679334) (xy 448.295268 -58.679334)
			(xy 448.295702 -58.653019) (xy 448.302945 -58.600889) (xy 448.317271 -58.550246) (xy 448.33841 -58.502048)
			(xy 448.365962 -58.457205) (xy 448.399405 -58.416566) (xy 448.418458 -58.39841) (xy 448.425851 -58.390881)
			(xy 448.434382 -58.371607) (xy 448.434968 -58.361072) (xy 448.434968 -58.286396) (xy 448.434464 -58.275843)
			(xy 448.425912 -58.256548) (xy 448.418458 -58.249058) (xy 448.399381 -58.230924) (xy 448.365927 -58.190289)
			(xy 448.338372 -58.145444) (xy 448.317238 -58.097239) (xy 448.302925 -58.046588) (xy 448.295704 -57.994451)
			(xy 448.295268 -57.968134) (xy 448.295754 -57.940883) (xy 448.30351 -57.886935) (xy 448.318865 -57.83464)
			(xy 448.341507 -57.785063) (xy 448.370973 -57.739213) (xy 448.406664 -57.698022) (xy 448.447855 -57.662331)
			(xy 448.493705 -57.632865) (xy 448.543282 -57.610223) (xy 448.595577 -57.594868) (xy 448.649525 -57.587112)
			(xy 448.704027 -57.587112) (xy 448.757975 -57.594868) (xy 448.81027 -57.610223) (xy 448.859847 -57.632865)
			(xy 448.905697 -57.662331) (xy 448.946888 -57.698022) (xy 448.982579 -57.739213) (xy 449.012045 -57.785063)
			(xy 449.034687 -57.83464) (xy 449.050042 -57.886935) (xy 449.057798 -57.940883) (xy 449.058284 -57.968134)
			(xy 449.057844 -57.994449) (xy 449.050605 -58.046579) (xy 449.043337 -58.072274) (xy 452.29348 -58.072274)
			(xy 452.297551 -58.016652) (xy 452.309677 -57.962215) (xy 452.3296 -57.910124) (xy 452.356896 -57.861489)
			(xy 452.390982 -57.817346) (xy 452.431131 -57.778637) (xy 452.476489 -57.746186) (xy 452.526089 -57.720685)
			(xy 452.578873 -57.702678) (xy 452.633716 -57.692548) (xy 452.68945 -57.690511) (xy 452.744887 -57.696611)
			(xy 452.798844 -57.710717) (xy 452.850173 -57.732529) (xy 452.897779 -57.761583) (xy 452.940647 -57.797258)
			(xy 452.977864 -57.838795) (xy 453.008637 -57.885308) (xy 453.032309 -57.935805) (xy 453.048377 -57.989212)
			(xy 453.056497 -58.044388) (xy 453.057006 -58.072274) (xy 453.056497 -58.10016) (xy 453.048377 -58.155336)
			(xy 453.032309 -58.208743) (xy 453.008637 -58.25924) (xy 452.977864 -58.305753) (xy 452.940647 -58.34729)
			(xy 452.897779 -58.382965) (xy 452.850173 -58.412019) (xy 452.798844 -58.433831) (xy 452.744887 -58.447937)
			(xy 452.68945 -58.454037) (xy 452.633716 -58.452) (xy 452.578873 -58.44187) (xy 452.526089 -58.423863)
			(xy 452.476489 -58.398362) (xy 452.431131 -58.365911) (xy 452.390982 -58.327202) (xy 452.356896 -58.283059)
			(xy 452.3296 -58.234424) (xy 452.309677 -58.182333) (xy 452.297551 -58.127896) (xy 452.29348 -58.072274)
			(xy 449.043337 -58.072274) (xy 449.03628 -58.097222) (xy 449.015143 -58.145421) (xy 448.987592 -58.190264)
			(xy 448.954148 -58.230902) (xy 448.935094 -58.249058) (xy 448.927708 -58.256593) (xy 448.919175 -58.275863)
			(xy 448.918584 -58.286396) (xy 448.918584 -58.361072) (xy 448.91912 -58.371621) (xy 448.927651 -58.390916)
			(xy 448.935094 -58.39841) (xy 448.954146 -58.416569) (xy 448.987604 -58.457198) (xy 449.015164 -58.502037)
			(xy 449.036303 -58.550237) (xy 449.05062 -58.600884) (xy 449.057845 -58.653018) (xy 449.058284 -58.679334)
			(xy 449.057798 -58.706585) (xy 449.050042 -58.760533) (xy 449.034687 -58.812828) (xy 449.012045 -58.862405)
			(xy 448.982579 -58.908255) (xy 448.946888 -58.949446) (xy 448.905697 -58.985137) (xy 448.859847 -59.014603)
			(xy 448.81027 -59.037245) (xy 448.757975 -59.0526) (xy 448.704027 -59.060356) (xy 448.649525 -59.060356)
			(xy 448.595577 -59.0526) (xy 448.543282 -59.037245) (xy 448.493705 -59.014603) (xy 448.447855 -58.985137)
			(xy 448.406664 -58.949446) (xy 448.370973 -58.908255) (xy 448.341507 -58.862405) (xy 448.318865 -58.812828)
			(xy 448.30351 -58.760533) (xy 448.295754 -58.706585) (xy 448.295268 -58.679334) (xy 440.579827 -58.679334)
			(xy 440.583319 -58.70313) (xy 440.583828 -58.730896) (xy 440.583828 -58.731404) (xy 440.583828 -58.737754)
			(xy 440.583066 -58.75274) (xy 440.58161 -58.77386) (xy 440.574608 -58.815612) (xy 440.569096 -58.836052)
			(xy 440.560245 -58.864954) (xy 440.5347 -58.919735) (xy 440.500845 -58.969807) (xy 440.459525 -59.013921)
			(xy 440.436 -59.032902) (xy 440.435746 -59.032902) (xy 440.431438 -59.036493) (xy 440.424391 -59.045213)
			(xy 440.421776 -59.050174) (xy 440.419236 -59.055254) (xy 440.416442 -59.065922) (xy 440.394074 -60.019254)
			(xy 448.435661 -60.019254) (xy 448.435661 -59.964746) (xy 448.443419 -59.910794) (xy 448.458776 -59.858494)
			(xy 448.481421 -59.808913) (xy 448.510891 -59.763059) (xy 448.546587 -59.721866) (xy 448.587783 -59.686173)
			(xy 448.633639 -59.656706) (xy 448.683222 -59.634066) (xy 448.735523 -59.618713) (xy 448.789476 -59.610959)
			(xy 448.81673 -59.610498) (xy 448.844101 -59.610947) (xy 448.898281 -59.618769) (xy 448.950784 -59.634262)
			(xy 449.00053 -59.657108) (xy 449.046497 -59.686835) (xy 449.067428 -59.704478) (xy 449.067682 -59.704732)
			(xy 449.074767 -59.710321) (xy 449.091685 -59.716565) (xy 449.100702 -59.716924) (xy 449.167758 -59.716924)
			(xy 449.176772 -59.716542) (xy 449.193689 -59.710311) (xy 449.200778 -59.704732) (xy 449.200778 -59.704478)
			(xy 449.201032 -59.704478) (xy 449.221965 -59.686837) (xy 449.267933 -59.657113) (xy 449.317679 -59.634267)
			(xy 449.370181 -59.618771) (xy 449.424359 -59.610942) (xy 449.479101 -59.610942) (xy 449.533279 -59.618771)
			(xy 449.585781 -59.634267) (xy 449.635527 -59.657113) (xy 449.681495 -59.686837) (xy 449.702428 -59.704478)
			(xy 449.702682 -59.704732) (xy 449.709767 -59.710321) (xy 449.726685 -59.716565) (xy 449.735702 -59.716924)
			(xy 449.802758 -59.716924) (xy 449.811772 -59.716542) (xy 449.828689 -59.710311) (xy 449.835778 -59.704732)
			(xy 449.835778 -59.704478) (xy 449.836032 -59.704478) (xy 449.856976 -59.686854) (xy 449.902946 -59.657141)
			(xy 449.95269 -59.634302) (xy 450.005188 -59.618807) (xy 450.059362 -59.610975) (xy 450.08673 -59.610498)
			(xy 450.11398 -59.610974) (xy 450.167926 -59.618734) (xy 450.220218 -59.634092) (xy 450.269792 -59.656735)
			(xy 450.315639 -59.686203) (xy 450.356826 -59.721895) (xy 450.392515 -59.763085) (xy 450.421979 -59.808935)
			(xy 450.444619 -59.858511) (xy 450.459972 -59.910804) (xy 450.467728 -59.96475) (xy 450.467728 -60.01925)
			(xy 450.459972 -60.073196) (xy 450.444619 -60.125489) (xy 450.421979 -60.175065) (xy 450.392515 -60.220915)
			(xy 450.356826 -60.262105) (xy 450.315639 -60.297797) (xy 450.269792 -60.327265) (xy 450.220218 -60.349908)
			(xy 450.167926 -60.365266) (xy 450.11398 -60.373026) (xy 450.08673 -60.373514) (xy 450.059361 -60.373027)
			(xy 450.005183 -60.365214) (xy 449.95268 -60.349729) (xy 449.902933 -60.326892) (xy 449.856965 -60.297173)
			(xy 449.836032 -60.279534) (xy 449.835778 -60.27928) (xy 449.828704 -60.273676) (xy 449.811777 -60.26744)
			(xy 449.802758 -60.267088) (xy 449.735702 -60.267088) (xy 449.726686 -60.267449) (xy 449.709769 -60.273694)
			(xy 449.702682 -60.27928) (xy 449.702428 -60.279534) (xy 449.681495 -60.297175) (xy 449.635527 -60.326899)
			(xy 449.585781 -60.349745) (xy 449.533279 -60.365241) (xy 449.479101 -60.37307) (xy 449.424359 -60.37307)
			(xy 449.370181 -60.365241) (xy 449.317679 -60.349745) (xy 449.267933 -60.326899) (xy 449.221965 -60.297175)
			(xy 449.201032 -60.279534) (xy 449.200778 -60.27928) (xy 449.193704 -60.273676) (xy 449.176777 -60.26744)
			(xy 449.167758 -60.267088) (xy 449.100702 -60.267088) (xy 449.091686 -60.267449) (xy 449.074769 -60.273694)
			(xy 449.067682 -60.27928) (xy 449.067682 -60.279534) (xy 449.067428 -60.279534) (xy 449.046501 -60.297179)
			(xy 449.000526 -60.326889) (xy 448.950777 -60.349723) (xy 448.898276 -60.365213) (xy 448.844099 -60.37304)
			(xy 448.81673 -60.373514) (xy 448.789476 -60.373041) (xy 448.735523 -60.365287) (xy 448.683222 -60.349934)
			(xy 448.633639 -60.327294) (xy 448.587783 -60.297827) (xy 448.546587 -60.262134) (xy 448.510891 -60.220941)
			(xy 448.481421 -60.175087) (xy 448.458776 -60.125506) (xy 448.443419 -60.073206) (xy 448.435661 -60.019254)
			(xy 440.394074 -60.019254) (xy 440.375548 -60.80887) (xy 440.374947 -60.830953) (xy 440.372027 -60.875039)
			(xy 440.369706 -60.897008) (xy 440.367605 -60.914932) (xy 440.362268 -60.950627) (xy 440.359038 -60.968382)
			(xy 440.357768 -60.974986) (xy 440.356498 -60.981336) (xy 440.262518 -61.450728) (xy 440.262264 -61.452506)
			(xy 440.26201 -61.453522) (xy 440.260232 -61.463682) (xy 440.260232 -61.465206) (xy 440.25947 -61.46927)
			(xy 440.25947 -61.470286) (xy 440.25312 -61.504068) (xy 439.913944 -63.213554) (xy 448.420665 -63.213554)
			(xy 448.420665 -63.159046) (xy 448.428423 -63.105092) (xy 448.443781 -63.052793) (xy 448.466426 -63.003211)
			(xy 448.495898 -62.957357) (xy 448.531595 -62.916164) (xy 448.572792 -62.880471) (xy 448.618649 -62.851005)
			(xy 448.668234 -62.828366) (xy 448.720536 -62.813014) (xy 448.77449 -62.805262) (xy 448.801744 -62.804802)
			(xy 448.829113 -62.8053) (xy 448.883291 -62.81311) (xy 448.935794 -62.828592) (xy 448.985541 -62.851426)
			(xy 449.031509 -62.881144) (xy 449.052442 -62.898782) (xy 449.052696 -62.899036) (xy 449.059777 -62.904631)
			(xy 449.076698 -62.910872) (xy 449.085716 -62.911228) (xy 449.152772 -62.911228) (xy 449.161787 -62.910851)
			(xy 449.178704 -62.904617) (xy 449.185792 -62.899036) (xy 449.185792 -62.898782) (xy 449.186046 -62.898782)
			(xy 449.206979 -62.881141) (xy 449.252947 -62.851417) (xy 449.302693 -62.828571) (xy 449.355195 -62.813075)
			(xy 449.409373 -62.805246) (xy 449.464115 -62.805246) (xy 449.518293 -62.813075) (xy 449.570795 -62.828571)
			(xy 449.620541 -62.851417) (xy 449.666509 -62.881141) (xy 449.687442 -62.898782) (xy 449.687696 -62.899036)
			(xy 449.694777 -62.904631) (xy 449.711698 -62.910872) (xy 449.720716 -62.911228) (xy 449.787772 -62.911228)
			(xy 449.796787 -62.910851) (xy 449.813704 -62.904617) (xy 449.820792 -62.899036) (xy 449.820792 -62.898782)
			(xy 449.821046 -62.898782) (xy 449.841985 -62.881152) (xy 449.887956 -62.851439) (xy 449.937702 -62.828602)
			(xy 449.990201 -62.813109) (xy 450.044375 -62.805278) (xy 450.071744 -62.804802) (xy 450.098994 -62.805271)
			(xy 450.152938 -62.813033) (xy 450.205229 -62.828392) (xy 450.254802 -62.851036) (xy 450.300648 -62.880504)
			(xy 450.341834 -62.916197) (xy 450.377522 -62.957387) (xy 450.406985 -63.003237) (xy 450.429623 -63.052812)
			(xy 450.444977 -63.105105) (xy 450.452732 -63.15905) (xy 450.452732 -63.21355) (xy 450.444977 -63.267495)
			(xy 450.429623 -63.319788) (xy 450.406985 -63.369363) (xy 450.377522 -63.415213) (xy 450.341834 -63.456403)
			(xy 450.300648 -63.492096) (xy 450.254802 -63.521564) (xy 450.205229 -63.544208) (xy 450.152938 -63.559567)
			(xy 450.098994 -63.567329) (xy 450.071744 -63.567818) (xy 450.044374 -63.567346) (xy 449.990194 -63.559533)
			(xy 449.93769 -63.544046) (xy 449.887943 -63.521205) (xy 449.841977 -63.49148) (xy 449.821046 -63.473838)
			(xy 449.820792 -63.473584) (xy 449.813713 -63.467986) (xy 449.79679 -63.461747) (xy 449.787772 -63.461392)
			(xy 449.720716 -63.461392) (xy 449.7117 -63.461758) (xy 449.694783 -63.468) (xy 449.687696 -63.473584)
			(xy 449.687442 -63.473838) (xy 449.666509 -63.491479) (xy 449.620541 -63.521203) (xy 449.570795 -63.544049)
			(xy 449.518293 -63.559545) (xy 449.464115 -63.567374) (xy 449.409373 -63.567374) (xy 449.355195 -63.559545)
			(xy 449.302693 -63.544049) (xy 449.252947 -63.521203) (xy 449.206979 -63.491479) (xy 449.186046 -63.473838)
			(xy 449.185792 -63.473584) (xy 449.178713 -63.467986) (xy 449.16179 -63.461747) (xy 449.152772 -63.461392)
			(xy 449.085716 -63.461392) (xy 449.0767 -63.461758) (xy 449.059783 -63.468) (xy 449.052696 -63.473584)
			(xy 449.052696 -63.473838) (xy 449.052442 -63.473838) (xy 449.03151 -63.491477) (xy 448.985537 -63.521188)
			(xy 448.935789 -63.544023) (xy 448.883289 -63.559515) (xy 448.829113 -63.567344) (xy 448.801744 -63.567818)
			(xy 448.77449 -63.567338) (xy 448.720536 -63.559586) (xy 448.668234 -63.544234) (xy 448.618649 -63.521595)
			(xy 448.572792 -63.492129) (xy 448.531595 -63.456436) (xy 448.495898 -63.415243) (xy 448.466426 -63.369389)
			(xy 448.443781 -63.319807) (xy 448.428423 -63.267508) (xy 448.420665 -63.213554) (xy 439.913944 -63.213554)
			(xy 439.539466 -65.100962) (xy 446.43243 -65.100962) (xy 446.436501 -65.04534) (xy 446.448627 -64.990903)
			(xy 446.46855 -64.938812) (xy 446.495846 -64.890177) (xy 446.529932 -64.846034) (xy 446.570081 -64.807325)
			(xy 446.615439 -64.774874) (xy 446.665039 -64.749373) (xy 446.717823 -64.731366) (xy 446.772666 -64.721236)
			(xy 446.8284 -64.719199) (xy 446.883837 -64.725299) (xy 446.937794 -64.739405) (xy 446.989123 -64.761217)
			(xy 447.036729 -64.790271) (xy 447.079597 -64.825946) (xy 447.116814 -64.867483) (xy 447.147587 -64.913996)
			(xy 447.171259 -64.964493) (xy 447.187327 -65.0179) (xy 447.195447 -65.073076) (xy 447.195956 -65.100962)
			(xy 447.195447 -65.128848) (xy 447.187327 -65.184024) (xy 447.171259 -65.237431) (xy 447.147587 -65.287928)
			(xy 447.116814 -65.334441) (xy 447.079597 -65.375978) (xy 447.036729 -65.411653) (xy 446.989123 -65.440707)
			(xy 446.937794 -65.462519) (xy 446.883837 -65.476625) (xy 446.8284 -65.482725) (xy 446.772666 -65.480688)
			(xy 446.717823 -65.470558) (xy 446.665039 -65.452551) (xy 446.615439 -65.42705) (xy 446.570081 -65.394599)
			(xy 446.529932 -65.35589) (xy 446.495846 -65.311747) (xy 446.46855 -65.263112) (xy 446.448627 -65.211021)
			(xy 446.436501 -65.156584) (xy 446.43243 -65.100962) (xy 439.539466 -65.100962) (xy 439.409596 -65.75552)
			(xy 440.646564 -65.75552) (xy 440.650635 -65.699898) (xy 440.662761 -65.645461) (xy 440.682684 -65.59337)
			(xy 440.70998 -65.544735) (xy 440.744066 -65.500592) (xy 440.784215 -65.461883) (xy 440.829573 -65.429432)
			(xy 440.879173 -65.403931) (xy 440.931957 -65.385924) (xy 440.9868 -65.375794) (xy 441.042534 -65.373757)
			(xy 441.097971 -65.379857) (xy 441.151928 -65.393963) (xy 441.203257 -65.415775) (xy 441.250863 -65.444829)
			(xy 441.293731 -65.480504) (xy 441.330948 -65.522041) (xy 441.361721 -65.568554) (xy 441.385393 -65.619051)
			(xy 441.401461 -65.672458) (xy 441.409581 -65.727634) (xy 441.41009 -65.75552) (xy 441.409581 -65.783406)
			(xy 441.401461 -65.838582) (xy 441.385393 -65.891989) (xy 441.361721 -65.942486) (xy 441.330948 -65.988999)
			(xy 441.293731 -66.030536) (xy 441.250863 -66.066211) (xy 441.203257 -66.095265) (xy 441.151928 -66.117077)
			(xy 441.097971 -66.131183) (xy 441.042534 -66.137283) (xy 440.9868 -66.135246) (xy 440.931957 -66.125116)
			(xy 440.879173 -66.107109) (xy 440.829573 -66.081608) (xy 440.784215 -66.049157) (xy 440.744066 -66.010448)
			(xy 440.70998 -65.966305) (xy 440.682684 -65.91767) (xy 440.662761 -65.865579) (xy 440.650635 -65.811142)
			(xy 440.646564 -65.75552) (xy 439.409596 -65.75552) (xy 439.137095 -67.128953) (xy 440.666575 -67.128953)
			(xy 440.666575 -67.074447) (xy 440.674333 -67.020496) (xy 440.68969 -66.968199) (xy 440.712333 -66.918619)
			(xy 440.741803 -66.872767) (xy 440.777498 -66.831575) (xy 440.818692 -66.795883) (xy 440.864547 -66.766418)
			(xy 440.914129 -66.743778) (xy 440.966428 -66.728426) (xy 441.020379 -66.720673) (xy 441.047632 -66.720212)
			(xy 441.075003 -66.720656) (xy 441.129183 -66.728479) (xy 441.181687 -66.743973) (xy 441.231433 -66.76682)
			(xy 441.277399 -66.796549) (xy 441.29833 -66.814192) (xy 441.298584 -66.814446) (xy 441.305667 -66.820038)
			(xy 441.322587 -66.82628) (xy 441.331604 -66.826638) (xy 441.39866 -66.826638) (xy 441.407674 -66.826254)
			(xy 441.424591 -66.820024) (xy 441.43168 -66.814446) (xy 441.43168 -66.814192) (xy 441.431934 -66.814192)
			(xy 441.452879 -66.796569) (xy 441.498848 -66.766855) (xy 441.548593 -66.744016) (xy 441.60109 -66.728521)
			(xy 441.655264 -66.720689) (xy 441.682632 -66.720212) (xy 441.709883 -66.72066) (xy 441.76383 -66.728421)
			(xy 441.816124 -66.743779) (xy 441.8657 -66.766423) (xy 441.911549 -66.795892) (xy 441.952737 -66.831586)
			(xy 441.988427 -66.872777) (xy 442.017892 -66.918628) (xy 442.040532 -66.968206) (xy 442.055886 -67.020501)
			(xy 442.063642 -67.074449) (xy 442.063642 -67.128951) (xy 442.055886 -67.182899) (xy 442.040532 -67.235194)
			(xy 442.017892 -67.284772) (xy 441.988427 -67.330623) (xy 441.952737 -67.371814) (xy 441.911549 -67.407508)
			(xy 441.8657 -67.436977) (xy 441.816124 -67.459621) (xy 441.76383 -67.474979) (xy 441.709883 -67.48274)
			(xy 441.682632 -67.483228) (xy 441.655262 -67.482761) (xy 441.601082 -67.474946) (xy 441.548578 -67.459458)
			(xy 441.498831 -67.436616) (xy 441.452865 -67.40689) (xy 441.431934 -67.389248) (xy 441.43168 -67.388994)
			(xy 441.424604 -67.383392) (xy 441.407679 -67.377155) (xy 441.39866 -67.376802) (xy 441.331604 -67.376802)
			(xy 441.322587 -67.37716) (xy 441.30567 -67.383407) (xy 441.298584 -67.388994) (xy 441.298584 -67.389248)
			(xy 441.29833 -67.389248) (xy 441.277391 -67.406878) (xy 441.231421 -67.436593) (xy 441.181675 -67.459432)
			(xy 441.129176 -67.474925) (xy 441.075001 -67.482754) (xy 441.047632 -67.483228) (xy 441.020379 -67.482727)
			(xy 440.966428 -67.474974) (xy 440.914129 -67.459622) (xy 440.864547 -67.436982) (xy 440.818692 -67.407516)
			(xy 440.777498 -67.371825) (xy 440.741803 -67.330633) (xy 440.712333 -67.284781) (xy 440.68969 -67.235201)
			(xy 440.674333 -67.182904) (xy 440.666575 -67.128953) (xy 439.137095 -67.128953) (xy 439.065846 -67.488054)
			(xy 445.079118 -67.488054) (xy 445.083189 -67.432432) (xy 445.095315 -67.377995) (xy 445.115238 -67.325904)
			(xy 445.142534 -67.277269) (xy 445.17662 -67.233126) (xy 445.216769 -67.194417) (xy 445.262127 -67.161966)
			(xy 445.311727 -67.136465) (xy 445.364511 -67.118458) (xy 445.419354 -67.108328) (xy 445.475088 -67.106291)
			(xy 445.530525 -67.112391) (xy 445.584482 -67.126497) (xy 445.635811 -67.148309) (xy 445.683417 -67.177363)
			(xy 445.726285 -67.213038) (xy 445.763502 -67.254575) (xy 445.794275 -67.301088) (xy 445.817947 -67.351585)
			(xy 445.834015 -67.404992) (xy 445.842135 -67.460168) (xy 445.842644 -67.488054) (xy 445.842135 -67.51594)
			(xy 445.83895 -67.537584) (xy 446.371216 -67.537584) (xy 446.375287 -67.481962) (xy 446.387413 -67.427525)
			(xy 446.407336 -67.375434) (xy 446.434632 -67.326799) (xy 446.468718 -67.282656) (xy 446.508867 -67.243947)
			(xy 446.554225 -67.211496) (xy 446.603825 -67.185995) (xy 446.656609 -67.167988) (xy 446.711452 -67.157858)
			(xy 446.767186 -67.155821) (xy 446.822623 -67.161921) (xy 446.87658 -67.176027) (xy 446.927909 -67.197839)
			(xy 446.975515 -67.226893) (xy 447.018383 -67.262568) (xy 447.0556 -67.304105) (xy 447.086373 -67.350618)
			(xy 447.110045 -67.401115) (xy 447.126113 -67.454522) (xy 447.134233 -67.509698) (xy 447.134742 -67.537584)
			(xy 447.134233 -67.56547) (xy 447.130188 -67.592956) (xy 447.64528 -67.592956) (xy 447.649351 -67.537334)
			(xy 447.661477 -67.482897) (xy 447.6814 -67.430806) (xy 447.708696 -67.382171) (xy 447.742782 -67.338028)
			(xy 447.782931 -67.299319) (xy 447.828289 -67.266868) (xy 447.877889 -67.241367) (xy 447.930673 -67.22336)
			(xy 447.985516 -67.21323) (xy 448.04125 -67.211193) (xy 448.096687 -67.217293) (xy 448.150644 -67.231399)
			(xy 448.201973 -67.253211) (xy 448.249579 -67.282265) (xy 448.292447 -67.31794) (xy 448.329664 -67.359477)
			(xy 448.360437 -67.40599) (xy 448.384109 -67.456487) (xy 448.400177 -67.509894) (xy 448.408294 -67.565051)
			(xy 450.746593 -67.565051) (xy 450.746593 -67.510549) (xy 450.75435 -67.456601) (xy 450.769706 -67.404307)
			(xy 450.792348 -67.35473) (xy 450.821815 -67.308881) (xy 450.857507 -67.267692) (xy 450.898698 -67.232001)
			(xy 450.94455 -67.202537) (xy 450.994128 -67.179898) (xy 451.046423 -67.164545) (xy 451.100371 -67.156792)
			(xy 451.127622 -67.15633) (xy 451.154993 -67.156776) (xy 451.209173 -67.164597) (xy 451.261677 -67.180091)
			(xy 451.311423 -67.202937) (xy 451.357389 -67.232666) (xy 451.37832 -67.25031) (xy 451.378574 -67.250564)
			(xy 451.385658 -67.256153) (xy 451.402577 -67.262397) (xy 451.411594 -67.262756) (xy 451.47865 -67.262756)
			(xy 451.487666 -67.262385) (xy 451.504583 -67.256148) (xy 451.51167 -67.250564) (xy 451.51167 -67.25031)
			(xy 451.511924 -67.25031) (xy 451.532875 -67.232695) (xy 451.578843 -67.202979) (xy 451.628585 -67.180138)
			(xy 451.681082 -67.164642) (xy 451.735254 -67.156807) (xy 451.762622 -67.15633) (xy 451.789875 -67.156741)
			(xy 451.843826 -67.164501) (xy 451.896123 -67.17986) (xy 451.945702 -67.202504) (xy 451.991555 -67.231974)
			(xy 452.032746 -67.267669) (xy 452.068439 -67.308863) (xy 452.097906 -67.354717) (xy 452.120548 -67.404298)
			(xy 452.135903 -67.456596) (xy 452.14366 -67.510547) (xy 452.14366 -67.565053) (xy 452.135903 -67.619004)
			(xy 452.120548 -67.671302) (xy 452.097906 -67.720883) (xy 452.068439 -67.766737) (xy 452.032746 -67.807931)
			(xy 451.991555 -67.843626) (xy 451.945702 -67.873096) (xy 451.896123 -67.89574) (xy 451.843826 -67.911099)
			(xy 451.789875 -67.918859) (xy 451.762622 -67.919346) (xy 451.735252 -67.91888) (xy 451.681072 -67.911064)
			(xy 451.628568 -67.895576) (xy 451.578821 -67.872734) (xy 451.532855 -67.843008) (xy 451.511924 -67.825366)
			(xy 451.51167 -67.825112) (xy 451.504567 -67.81955) (xy 451.487663 -67.813288) (xy 451.47865 -67.81292)
			(xy 451.411594 -67.81292) (xy 451.402576 -67.81327) (xy 451.385659 -67.819522) (xy 451.378574 -67.825112)
			(xy 451.378574 -67.825366) (xy 451.37832 -67.825366) (xy 451.357387 -67.843004) (xy 451.311415 -67.872717)
			(xy 451.261668 -67.895554) (xy 451.209167 -67.911045) (xy 451.154991 -67.918873) (xy 451.127622 -67.919346)
			(xy 451.100371 -67.918808) (xy 451.046423 -67.911055) (xy 450.994128 -67.895702) (xy 450.94455 -67.873063)
			(xy 450.898698 -67.843599) (xy 450.857507 -67.807908) (xy 450.821815 -67.766719) (xy 450.792348 -67.72087)
			(xy 450.769706 -67.671293) (xy 450.75435 -67.618999) (xy 450.746593 -67.565051) (xy 448.408294 -67.565051)
			(xy 448.408297 -67.56507) (xy 448.408806 -67.592956) (xy 448.408297 -67.620842) (xy 448.400177 -67.676018)
			(xy 448.384109 -67.729425) (xy 448.360437 -67.779922) (xy 448.329664 -67.826435) (xy 448.292447 -67.867972)
			(xy 448.249579 -67.903647) (xy 448.201973 -67.932701) (xy 448.150644 -67.954513) (xy 448.096687 -67.968619)
			(xy 448.04125 -67.974719) (xy 447.985516 -67.972682) (xy 447.930673 -67.962552) (xy 447.877889 -67.944545)
			(xy 447.828289 -67.919044) (xy 447.782931 -67.886593) (xy 447.742782 -67.847884) (xy 447.708696 -67.803741)
			(xy 447.6814 -67.755106) (xy 447.661477 -67.703015) (xy 447.649351 -67.648578) (xy 447.64528 -67.592956)
			(xy 447.130188 -67.592956) (xy 447.126113 -67.620646) (xy 447.110045 -67.674053) (xy 447.086373 -67.72455)
			(xy 447.0556 -67.771063) (xy 447.018383 -67.8126) (xy 446.975515 -67.848275) (xy 446.927909 -67.877329)
			(xy 446.87658 -67.899141) (xy 446.822623 -67.913247) (xy 446.767186 -67.919347) (xy 446.711452 -67.91731)
			(xy 446.656609 -67.90718) (xy 446.603825 -67.889173) (xy 446.554225 -67.863672) (xy 446.508867 -67.831221)
			(xy 446.468718 -67.792512) (xy 446.434632 -67.748369) (xy 446.407336 -67.699734) (xy 446.387413 -67.647643)
			(xy 446.375287 -67.593206) (xy 446.371216 -67.537584) (xy 445.83895 -67.537584) (xy 445.834015 -67.571116)
			(xy 445.817947 -67.624523) (xy 445.794275 -67.67502) (xy 445.763502 -67.721533) (xy 445.726285 -67.76307)
			(xy 445.683417 -67.798745) (xy 445.635811 -67.827799) (xy 445.584482 -67.849611) (xy 445.530525 -67.863717)
			(xy 445.475088 -67.869817) (xy 445.419354 -67.86778) (xy 445.364511 -67.85765) (xy 445.311727 -67.839643)
			(xy 445.262127 -67.814142) (xy 445.216769 -67.781691) (xy 445.17662 -67.742982) (xy 445.142534 -67.698839)
			(xy 445.115238 -67.650204) (xy 445.095315 -67.598113) (xy 445.083189 -67.543676) (xy 445.079118 -67.488054)
			(xy 439.065846 -67.488054) (xy 438.847885 -68.586604) (xy 442.9252 -68.586604) (xy 442.925668 -68.559234)
			(xy 442.933486 -68.505055) (xy 442.948974 -68.452552) (xy 442.971815 -68.402805) (xy 443.001539 -68.356838)
			(xy 443.01918 -68.335906) (xy 443.019434 -68.335652) (xy 443.025009 -68.328557) (xy 443.031261 -68.311647)
			(xy 443.031626 -68.302632) (xy 443.031626 -68.235576) (xy 443.031275 -68.226559) (xy 443.025023 -68.209642)
			(xy 443.019434 -68.202556) (xy 443.01918 -68.202556) (xy 443.01918 -68.202302) (xy 443.001525 -68.181383)
			(xy 442.971816 -68.135406) (xy 442.948984 -68.085655) (xy 442.933496 -68.033152) (xy 442.925672 -67.978974)
			(xy 442.9252 -67.951604) (xy 442.925659 -67.924351) (xy 442.933416 -67.870399) (xy 442.948772 -67.818101)
			(xy 442.971414 -67.76852) (xy 443.000883 -67.722667) (xy 443.036577 -67.681474) (xy 443.07777 -67.64578)
			(xy 443.123624 -67.616312) (xy 443.173205 -67.59367) (xy 443.225503 -67.578315) (xy 443.279455 -67.570559)
			(xy 443.306708 -67.570096) (xy 443.333022 -67.570559) (xy 443.385151 -67.577795) (xy 443.435793 -67.592115)
			(xy 443.483992 -67.613248) (xy 443.528836 -67.640795) (xy 443.569475 -67.674234) (xy 443.587632 -67.693286)
			(xy 443.595142 -67.700702) (xy 443.614431 -67.709218) (xy 443.62497 -67.709796) (xy 443.699646 -67.709796)
			(xy 443.710194 -67.709253) (xy 443.72949 -67.700728) (xy 443.736984 -67.693286) (xy 443.755152 -67.674243)
			(xy 443.795779 -67.640785) (xy 443.840617 -67.613225) (xy 443.888815 -67.592084) (xy 443.93946 -67.577764)
			(xy 443.991593 -67.570536) (xy 444.017908 -67.570096) (xy 444.045278 -67.570558) (xy 444.099458 -67.578377)
			(xy 444.151961 -67.593867) (xy 444.201707 -67.61671) (xy 444.247674 -67.646435) (xy 444.268606 -67.664076)
			(xy 444.26886 -67.66433) (xy 444.275951 -67.669909) (xy 444.292865 -67.676159) (xy 444.30188 -67.676522)
			(xy 444.368936 -67.676522) (xy 444.377954 -67.676178) (xy 444.394871 -67.669921) (xy 444.401956 -67.66433)
			(xy 444.401956 -67.664076) (xy 444.40221 -67.664076) (xy 444.423124 -67.646415) (xy 444.469102 -67.616707)
			(xy 444.518854 -67.593876) (xy 444.571359 -67.57839) (xy 444.625538 -67.570567) (xy 444.652908 -67.570096)
			(xy 444.68016 -67.57057) (xy 444.734108 -67.578328) (xy 444.786403 -67.593684) (xy 444.835981 -67.616327)
			(xy 444.881831 -67.645794) (xy 444.923022 -67.681487) (xy 444.958713 -67.722678) (xy 444.988179 -67.76853)
			(xy 445.01082 -67.818108) (xy 445.026174 -67.870404) (xy 445.03393 -67.924352) (xy 445.034416 -67.951604)
			(xy 445.033973 -67.978975) (xy 445.026153 -68.033156) (xy 445.010659 -68.08566) (xy 444.987812 -68.135407)
			(xy 444.958081 -68.181372) (xy 444.940436 -68.202302) (xy 444.940182 -68.202556) (xy 444.934606 -68.20965)
			(xy 444.928353 -68.226561) (xy 444.92799 -68.235576) (xy 444.92799 -68.302632) (xy 444.928334 -68.31165)
			(xy 444.934591 -68.328567) (xy 444.940182 -68.335652) (xy 444.940436 -68.335652) (xy 444.940436 -68.335906)
			(xy 444.958097 -68.35682) (xy 444.987804 -68.402799) (xy 445.010635 -68.452551) (xy 445.026121 -68.505055)
			(xy 445.033945 -68.559234) (xy 445.034416 -68.586604) (xy 445.033926 -68.613855) (xy 445.026169 -68.667802)
			(xy 445.010814 -68.720096) (xy 444.994175 -68.75653) (xy 448.470274 -68.75653) (xy 448.47074 -68.72916)
			(xy 448.478555 -68.67498) (xy 448.494043 -68.622476) (xy 448.516885 -68.572729) (xy 448.546612 -68.526763)
			(xy 448.564254 -68.505832) (xy 448.564508 -68.505578) (xy 448.570111 -68.498503) (xy 448.576347 -68.481577)
			(xy 448.5767 -68.472558) (xy 448.5767 -68.405502) (xy 448.576342 -68.396485) (xy 448.570095 -68.379568)
			(xy 448.564508 -68.372482) (xy 448.564254 -68.372482) (xy 448.564254 -68.372228) (xy 448.546623 -68.351289)
			(xy 448.516908 -68.305319) (xy 448.49407 -68.255573) (xy 448.478577 -68.203074) (xy 448.470748 -68.148899)
			(xy 448.470274 -68.12153) (xy 448.470783 -68.094279) (xy 448.478536 -68.04033) (xy 448.493887 -67.988034)
			(xy 448.516525 -67.938456) (xy 448.545988 -67.892603) (xy 448.581677 -67.851411) (xy 448.622865 -67.815717)
			(xy 448.668713 -67.786248) (xy 448.718289 -67.763604) (xy 448.770583 -67.748246) (xy 448.824531 -67.740487)
			(xy 448.851782 -67.740022) (xy 448.879152 -67.740493) (xy 448.933331 -67.748309) (xy 448.985834 -67.763797)
			(xy 449.035581 -67.786637) (xy 449.081548 -67.816361) (xy 449.10248 -67.834002) (xy 449.102734 -67.834256)
			(xy 449.10983 -67.839828) (xy 449.12674 -67.846082) (xy 449.135754 -67.846448) (xy 449.20281 -67.846448)
			(xy 449.211829 -67.846107) (xy 449.228746 -67.839849) (xy 449.23583 -67.834256) (xy 449.23583 -67.834002)
			(xy 449.236084 -67.834002) (xy 449.257012 -67.816357) (xy 449.302986 -67.786646) (xy 449.352734 -67.763811)
			(xy 449.405236 -67.748322) (xy 449.459413 -67.740495) (xy 449.486782 -67.740022) (xy 449.513096 -67.740494)
			(xy 449.565224 -67.747727) (xy 449.615867 -67.762045) (xy 449.664067 -67.783176) (xy 449.70891 -67.810722)
			(xy 449.74955 -67.84416) (xy 449.767706 -67.863212) (xy 449.775222 -67.87062) (xy 449.794506 -67.879141)
			(xy 449.805044 -67.879722) (xy 449.87972 -67.879722) (xy 449.890265 -67.879157) (xy 449.909561 -67.870646)
			(xy 449.917058 -67.863212) (xy 449.935195 -67.844138) (xy 449.975828 -67.810682) (xy 450.020672 -67.783125)
			(xy 450.068877 -67.76199) (xy 450.119528 -67.747677) (xy 450.171665 -67.740457) (xy 450.197982 -67.740022)
			(xy 450.225236 -67.740472) (xy 450.279189 -67.748227) (xy 450.331489 -67.763583) (xy 450.381071 -67.786225)
			(xy 450.426925 -67.815694) (xy 450.468119 -67.851389) (xy 450.503813 -67.892584) (xy 450.53328 -67.93844)
			(xy 450.555921 -67.988023) (xy 450.571275 -68.040323) (xy 450.579029 -68.094276) (xy 450.57949 -68.12153)
			(xy 450.579044 -68.148901) (xy 450.571222 -68.203081) (xy 450.555728 -68.255584) (xy 450.532882 -68.305331)
			(xy 450.503153 -68.351297) (xy 450.48551 -68.372228) (xy 450.485256 -68.372482) (xy 450.479666 -68.379566)
			(xy 450.473422 -68.396485) (xy 450.473064 -68.405502) (xy 450.473064 -68.472558) (xy 450.473449 -68.481572)
			(xy 450.479678 -68.498489) (xy 450.485256 -68.505578) (xy 450.48551 -68.505578) (xy 450.48551 -68.505832)
			(xy 450.503132 -68.526778) (xy 450.532846 -68.572747) (xy 450.555685 -68.622491) (xy 450.57118 -68.674989)
			(xy 450.579013 -68.729162) (xy 450.57949 -68.75653) (xy 450.57905 -68.783783) (xy 450.571289 -68.837733)
			(xy 450.555929 -68.89003) (xy 450.533283 -68.939608) (xy 450.503812 -68.985459) (xy 450.468116 -69.02665)
			(xy 450.426921 -69.062341) (xy 450.381066 -69.091806) (xy 450.331485 -69.114446) (xy 450.279186 -69.129799)
			(xy 450.225235 -69.137553) (xy 450.197982 -69.138038) (xy 450.171667 -69.137602) (xy 450.119536 -69.130364)
			(xy 450.068892 -69.11604) (xy 450.020693 -69.094902) (xy 449.97585 -69.067349) (xy 449.935213 -69.033903)
			(xy 449.917058 -69.014848) (xy 449.909547 -69.007433) (xy 449.890259 -68.998915) (xy 449.87972 -68.998338)
			(xy 449.805044 -68.998338) (xy 449.794494 -68.998866) (xy 449.775198 -69.007401) (xy 449.767706 -69.014848)
			(xy 449.74955 -69.033903) (xy 449.708919 -69.067358) (xy 449.664079 -69.094916) (xy 449.615878 -69.116054)
			(xy 449.565231 -69.130372) (xy 449.513098 -69.137598) (xy 449.486782 -69.138038) (xy 449.459411 -69.137598)
			(xy 449.40523 -69.129776) (xy 449.352726 -69.114282) (xy 449.302979 -69.091434) (xy 449.257014 -69.061703)
			(xy 449.236084 -69.044058) (xy 449.23583 -69.043804) (xy 449.228739 -69.038224) (xy 449.211826 -69.031973)
			(xy 449.20281 -69.031612) (xy 449.135754 -69.031612) (xy 449.126739 -69.031992) (xy 449.109822 -69.038224)
			(xy 449.102734 -69.043804) (xy 449.102734 -69.044058) (xy 449.10248 -69.044058) (xy 449.081523 -69.061667)
			(xy 449.035558 -69.091384) (xy 448.985817 -69.114227) (xy 448.933321 -69.129725) (xy 448.87915 -69.13756)
			(xy 448.851782 -69.138038) (xy 448.824532 -69.137539) (xy 448.770586 -69.129781) (xy 448.718293 -69.114425)
			(xy 448.668718 -69.091784) (xy 448.622869 -69.062319) (xy 448.58168 -69.026629) (xy 448.545989 -68.98544)
			(xy 448.516522 -68.939593) (xy 448.493879 -68.890018) (xy 448.478522 -68.837726) (xy 448.470762 -68.78378)
			(xy 448.470274 -68.75653) (xy 444.994175 -68.75653) (xy 444.988173 -68.769673) (xy 444.958707 -68.815523)
			(xy 444.923016 -68.856713) (xy 444.881826 -68.892404) (xy 444.835977 -68.921871) (xy 444.7864 -68.944512)
			(xy 444.734106 -68.959868) (xy 444.680159 -68.967626) (xy 444.652908 -68.968112) (xy 444.625538 -68.967638)
			(xy 444.571359 -68.959822) (xy 444.518857 -68.944334) (xy 444.46911 -68.921494) (xy 444.423142 -68.891772)
			(xy 444.40221 -68.874132) (xy 444.401956 -68.873878) (xy 444.394859 -68.868306) (xy 444.37795 -68.862051)
			(xy 444.368936 -68.861686) (xy 444.30188 -68.861686) (xy 444.292863 -68.862037) (xy 444.275946 -68.868289)
			(xy 444.26886 -68.873878) (xy 444.26886 -68.874132) (xy 444.268606 -68.874132) (xy 444.247687 -68.891787)
			(xy 444.20171 -68.921495) (xy 444.151959 -68.944328) (xy 444.099456 -68.959815) (xy 444.045278 -68.96764)
			(xy 444.017908 -68.968112) (xy 443.991594 -68.967635) (xy 443.939466 -68.960402) (xy 443.888824 -68.946084)
			(xy 443.840625 -68.924954) (xy 443.795781 -68.897409) (xy 443.755141 -68.863973) (xy 443.736984 -68.844922)
			(xy 443.729467 -68.837515) (xy 443.710184 -68.828993) (xy 443.699646 -68.828412) (xy 443.62497 -68.828412)
			(xy 443.614423 -68.828962) (xy 443.595127 -68.837482) (xy 443.587632 -68.844922) (xy 443.569507 -68.864008)
			(xy 443.52887 -68.897461) (xy 443.484023 -68.925016) (xy 443.435817 -68.946149) (xy 443.385164 -68.96046)
			(xy 443.333026 -68.967677) (xy 443.306708 -68.968112) (xy 443.279456 -68.967637) (xy 443.225505 -68.959881)
			(xy 443.173208 -68.944527) (xy 443.123628 -68.921885) (xy 443.077775 -68.892419) (xy 443.036582 -68.856726)
			(xy 443.000889 -68.815535) (xy 442.97142 -68.769683) (xy 442.948778 -68.720103) (xy 442.933421 -68.667807)
			(xy 442.925664 -68.613856) (xy 442.9252 -68.586604) (xy 438.847885 -68.586604) (xy 438.258759 -71.555864)
			(xy 445.494408 -71.555864) (xy 445.498479 -71.500242) (xy 445.510605 -71.445805) (xy 445.530528 -71.393714)
			(xy 445.557824 -71.345079) (xy 445.59191 -71.300936) (xy 445.632059 -71.262227) (xy 445.677417 -71.229776)
			(xy 445.727017 -71.204275) (xy 445.779801 -71.186268) (xy 445.834644 -71.176138) (xy 445.890378 -71.174101)
			(xy 445.945815 -71.180201) (xy 445.999772 -71.194307) (xy 446.051101 -71.216119) (xy 446.098707 -71.245173)
			(xy 446.141575 -71.280848) (xy 446.178792 -71.322385) (xy 446.209565 -71.368898) (xy 446.233237 -71.419395)
			(xy 446.249305 -71.472802) (xy 446.257425 -71.527978) (xy 446.257934 -71.555864) (xy 446.257425 -71.58375)
			(xy 446.251586 -71.623428) (xy 447.003422 -71.623428) (xy 447.007493 -71.567806) (xy 447.019619 -71.513369)
			(xy 447.039542 -71.461278) (xy 447.066838 -71.412643) (xy 447.100924 -71.3685) (xy 447.141073 -71.329791)
			(xy 447.186431 -71.29734) (xy 447.236031 -71.271839) (xy 447.288815 -71.253832) (xy 447.343658 -71.243702)
			(xy 447.399392 -71.241665) (xy 447.454829 -71.247765) (xy 447.508786 -71.261871) (xy 447.560115 -71.283683)
			(xy 447.607721 -71.312737) (xy 447.650589 -71.348412) (xy 447.687806 -71.389949) (xy 447.718579 -71.436462)
			(xy 447.742251 -71.486959) (xy 447.758319 -71.540366) (xy 447.766439 -71.595542) (xy 447.766948 -71.623428)
			(xy 447.766439 -71.651314) (xy 447.758319 -71.70649) (xy 447.742251 -71.759897) (xy 447.718579 -71.810394)
			(xy 447.687806 -71.856907) (xy 447.650589 -71.898444) (xy 447.607721 -71.934119) (xy 447.560115 -71.963173)
			(xy 447.508786 -71.984985) (xy 447.454829 -71.999091) (xy 447.399392 -72.005191) (xy 447.343658 -72.003154)
			(xy 447.288815 -71.993024) (xy 447.236031 -71.975017) (xy 447.186431 -71.949516) (xy 447.141073 -71.917065)
			(xy 447.100924 -71.878356) (xy 447.066838 -71.834213) (xy 447.039542 -71.785578) (xy 447.019619 -71.733487)
			(xy 447.007493 -71.67905) (xy 447.003422 -71.623428) (xy 446.251586 -71.623428) (xy 446.249305 -71.638926)
			(xy 446.233237 -71.692333) (xy 446.209565 -71.74283) (xy 446.178792 -71.789343) (xy 446.141575 -71.83088)
			(xy 446.098707 -71.866555) (xy 446.051101 -71.895609) (xy 445.999772 -71.917421) (xy 445.945815 -71.931527)
			(xy 445.890378 -71.937627) (xy 445.834644 -71.93559) (xy 445.779801 -71.92546) (xy 445.727017 -71.907453)
			(xy 445.677417 -71.881952) (xy 445.632059 -71.849501) (xy 445.59191 -71.810792) (xy 445.557824 -71.766649)
			(xy 445.530528 -71.718014) (xy 445.510605 -71.665923) (xy 445.498479 -71.611486) (xy 445.494408 -71.555864)
			(xy 438.258759 -71.555864) (xy 437.618078 -74.784966) (xy 458.026514 -74.784966) (xy 458.030585 -74.729344)
			(xy 458.042711 -74.674907) (xy 458.062634 -74.622816) (xy 458.08993 -74.574181) (xy 458.124016 -74.530038)
			(xy 458.164165 -74.491329) (xy 458.209523 -74.458878) (xy 458.259123 -74.433377) (xy 458.311907 -74.41537)
			(xy 458.36675 -74.40524) (xy 458.422484 -74.403203) (xy 458.477921 -74.409303) (xy 458.531878 -74.423409)
			(xy 458.583207 -74.445221) (xy 458.630813 -74.474275) (xy 458.673681 -74.50995) (xy 458.710898 -74.551487)
			(xy 458.741671 -74.598) (xy 458.765343 -74.648497) (xy 458.781411 -74.701904) (xy 458.789531 -74.75708)
			(xy 458.79004 -74.784966) (xy 458.789531 -74.812852) (xy 458.781411 -74.868028) (xy 458.765343 -74.921435)
			(xy 458.741671 -74.971932) (xy 458.710898 -75.018445) (xy 458.673681 -75.059982) (xy 458.630813 -75.095657)
			(xy 458.583207 -75.124711) (xy 458.531878 -75.146523) (xy 458.477921 -75.160629) (xy 458.422484 -75.166729)
			(xy 458.36675 -75.164692) (xy 458.311907 -75.154562) (xy 458.259123 -75.136555) (xy 458.209523 -75.111054)
			(xy 458.164165 -75.078603) (xy 458.124016 -75.039894) (xy 458.08993 -74.995751) (xy 458.062634 -74.947116)
			(xy 458.042711 -74.895025) (xy 458.030585 -74.840588) (xy 458.026514 -74.784966) (xy 437.618078 -74.784966)
			(xy 437.289347 -76.441808) (xy 458.137766 -76.441808) (xy 458.141837 -76.386186) (xy 458.153963 -76.331749)
			(xy 458.173886 -76.279658) (xy 458.201182 -76.231023) (xy 458.235268 -76.18688) (xy 458.275417 -76.148171)
			(xy 458.320775 -76.11572) (xy 458.370375 -76.090219) (xy 458.423159 -76.072212) (xy 458.478002 -76.062082)
			(xy 458.533736 -76.060045) (xy 458.589173 -76.066145) (xy 458.64313 -76.080251) (xy 458.694459 -76.102063)
			(xy 458.742065 -76.131117) (xy 458.784933 -76.166792) (xy 458.82215 -76.208329) (xy 458.852923 -76.254842)
			(xy 458.876595 -76.305339) (xy 458.892663 -76.358746) (xy 458.900783 -76.413922) (xy 458.901292 -76.441808)
			(xy 458.900783 -76.469694) (xy 458.892663 -76.52487) (xy 458.876595 -76.578277) (xy 458.852923 -76.628774)
			(xy 458.82215 -76.675287) (xy 458.784933 -76.716824) (xy 458.742065 -76.752499) (xy 458.694459 -76.781553)
			(xy 458.64313 -76.803365) (xy 458.589173 -76.817471) (xy 458.533736 -76.823571) (xy 458.478002 -76.821534)
			(xy 458.423159 -76.811404) (xy 458.370375 -76.793397) (xy 458.320775 -76.767896) (xy 458.275417 -76.735445)
			(xy 458.235268 -76.696736) (xy 458.201182 -76.652593) (xy 458.173886 -76.603958) (xy 458.153963 -76.551867)
			(xy 458.141837 -76.49743) (xy 458.137766 -76.441808) (xy 437.289347 -76.441808) (xy 437.179585 -76.99502)
			(xy 453.687178 -76.99502) (xy 453.691249 -76.939398) (xy 453.703375 -76.884961) (xy 453.723298 -76.83287)
			(xy 453.750594 -76.784235) (xy 453.78468 -76.740092) (xy 453.824829 -76.701383) (xy 453.870187 -76.668932)
			(xy 453.919787 -76.643431) (xy 453.972571 -76.625424) (xy 454.027414 -76.615294) (xy 454.083148 -76.613257)
			(xy 454.138585 -76.619357) (xy 454.192542 -76.633463) (xy 454.243871 -76.655275) (xy 454.291477 -76.684329)
			(xy 454.334345 -76.720004) (xy 454.371562 -76.761541) (xy 454.402335 -76.808054) (xy 454.426007 -76.858551)
			(xy 454.442075 -76.911958) (xy 454.450195 -76.967134) (xy 454.450704 -76.99502) (xy 454.450195 -77.022906)
			(xy 454.446337 -77.049122) (xy 455.173078 -77.049122) (xy 455.177149 -76.9935) (xy 455.189275 -76.939063)
			(xy 455.209198 -76.886972) (xy 455.236494 -76.838337) (xy 455.27058 -76.794194) (xy 455.310729 -76.755485)
			(xy 455.356087 -76.723034) (xy 455.405687 -76.697533) (xy 455.458471 -76.679526) (xy 455.513314 -76.669396)
			(xy 455.569048 -76.667359) (xy 455.624485 -76.673459) (xy 455.678442 -76.687565) (xy 455.729771 -76.709377)
			(xy 455.777377 -76.738431) (xy 455.820245 -76.774106) (xy 455.857462 -76.815643) (xy 455.888235 -76.862156)
			(xy 455.911907 -76.912653) (xy 455.927975 -76.96606) (xy 455.936095 -77.021236) (xy 455.936604 -77.049122)
			(xy 455.936095 -77.077008) (xy 455.927975 -77.132184) (xy 455.911907 -77.185591) (xy 455.888235 -77.236088)
			(xy 455.857462 -77.282601) (xy 455.820245 -77.324138) (xy 455.777377 -77.359813) (xy 455.729771 -77.388867)
			(xy 455.678442 -77.410679) (xy 455.624485 -77.424785) (xy 455.569048 -77.430885) (xy 455.513314 -77.428848)
			(xy 455.458471 -77.418718) (xy 455.405687 -77.400711) (xy 455.356087 -77.37521) (xy 455.310729 -77.342759)
			(xy 455.27058 -77.30405) (xy 455.236494 -77.259907) (xy 455.209198 -77.211272) (xy 455.189275 -77.159181)
			(xy 455.177149 -77.104744) (xy 455.173078 -77.049122) (xy 454.446337 -77.049122) (xy 454.442075 -77.078082)
			(xy 454.426007 -77.131489) (xy 454.402335 -77.181986) (xy 454.371562 -77.228499) (xy 454.334345 -77.270036)
			(xy 454.291477 -77.305711) (xy 454.243871 -77.334765) (xy 454.192542 -77.356577) (xy 454.138585 -77.370683)
			(xy 454.083148 -77.376783) (xy 454.027414 -77.374746) (xy 453.972571 -77.364616) (xy 453.919787 -77.346609)
			(xy 453.870187 -77.321108) (xy 453.824829 -77.288657) (xy 453.78468 -77.249948) (xy 453.750594 -77.205805)
			(xy 453.723298 -77.15717) (xy 453.703375 -77.105079) (xy 453.691249 -77.050642) (xy 453.687178 -76.99502)
			(xy 437.179585 -76.99502) (xy 436.1053 -82.409538) (xy 436.104648 -82.415298) (xy 436.105681 -82.426841)
			(xy 436.107332 -82.432398) (xy 436.112158 -82.443066) (xy 436.121302 -82.457798) (xy 436.12943 -82.46364)
			(xy 436.129684 -82.463894) (xy 436.151782 -82.48015) (xy 436.160418 -82.48269) (xy 436.160672 -82.48269)
			(xy 436.186883 -82.490683) (xy 436.236866 -82.513141) (xy 436.283122 -82.542519) (xy 436.3247 -82.578212)
			(xy 436.360744 -82.619486) (xy 436.390512 -82.665491) (xy 436.413393 -82.715283) (xy 436.428915 -82.767835)
			(xy 436.436759 -82.822068) (xy 436.437278 -82.849466) (xy 436.436808 -82.87653) (xy 436.429164 -82.930116)
			(xy 436.414023 -82.982084) (xy 436.391691 -83.031391) (xy 436.362614 -83.077047) (xy 436.34533 -83.097878)
			(xy 436.329385 -83.115952) (xy 436.293696 -83.148345) (xy 436.254218 -83.175995) (xy 436.233062 -83.18754)
			(xy 436.2323 -83.188048) (xy 436.219092 -83.194652) (xy 436.209948 -83.198716) (xy 436.196994 -83.204304)
			(xy 436.195724 -83.204812) (xy 436.193692 -83.205574) (xy 436.192422 -83.206082) (xy 436.184481 -83.210483)
			(xy 436.172113 -83.223755) (xy 436.168292 -83.23199) (xy 436.146448 -83.28406) (xy 436.146448 -83.284568)
			(xy 436.141876 -83.294982) (xy 436.140005 -83.299721) (xy 436.137957 -83.309701) (xy 436.137812 -83.314794)
			(xy 436.137812 -83.324446) (xy 436.139844 -83.335876) (xy 436.141114 -83.340448) (xy 436.141876 -83.342734)
			(xy 436.142384 -83.344004) (xy 436.14975 -83.363054) (xy 436.15229 -83.370674) (xy 436.155626 -83.381257)
			(xy 436.161216 -83.402734) (xy 436.163466 -83.4136) (xy 436.165673 -83.425064) (xy 436.168853 -83.448194)
			(xy 436.169816 -83.459828) (xy 436.169816 -83.464654) (xy 436.17007 -83.469226) (xy 436.170324 -83.471258)
			(xy 436.170324 -83.472274) (xy 436.170578 -83.474814) (xy 436.170578 -83.483704) (xy 436.170832 -83.487768)
			(xy 436.170255 -83.517637) (xy 436.160946 -83.576646) (xy 436.142553 -83.633483) (xy 436.115524 -83.686757)
			(xy 436.08052 -83.735166) (xy 436.038397 -83.777526) (xy 436.014622 -83.795616) (xy 436.014368 -83.79587)
			(xy 436.006494 -83.801966) (xy 435.99789 -83.80929) (xy 435.987498 -83.829323) (xy 435.986428 -83.840574)
			(xy 435.984904 -83.88731) (xy 435.985087 -83.897676) (xy 435.992703 -83.916937) (xy 435.999636 -83.924648)
			(xy 436.005478 -83.93049) (xy 436.008526 -83.932776) (xy 436.029444 -83.949404) (xy 436.0672 -83.987217)
			(xy 436.099701 -84.029633) (xy 436.126391 -84.075926) (xy 436.146814 -84.125305) (xy 436.160621 -84.176926)
			(xy 436.167575 -84.229908) (xy 436.168038 -84.256626) (xy 436.167541 -84.285782) (xy 436.159238 -84.343499)
			(xy 436.142806 -84.399448) (xy 436.118579 -84.452488) (xy 436.087049 -84.501541) (xy 436.04886 -84.545607)
			(xy 436.004788 -84.583789) (xy 435.95573 -84.61531) (xy 435.902686 -84.639529) (xy 435.846735 -84.655952)
			(xy 435.789016 -84.664246) (xy 435.75986 -84.664804) (xy 435.759606 -84.664804) (xy 435.746362 -84.664731)
			(xy 435.719925 -84.663078) (xy 435.706774 -84.661502) (xy 435.679596 -84.657946) (xy 435.674053 -84.65823)
			(xy 435.66329 -84.660931) (xy 435.65826 -84.66328) (xy 435.61127 -84.900262) (xy 435.478936 -85.567774)
			(xy 435.344316 -86.246208) (xy 435.343456 -86.251124) (xy 435.343458 -86.261103) (xy 435.344316 -86.26602)
			(xy 435.346094 -86.275164) (xy 435.348888 -86.279482) (xy 435.357581 -86.292312) (xy 435.373093 -86.319142)
			(xy 435.379876 -86.333076) (xy 435.38013 -86.333838) (xy 435.382162 -86.338664) (xy 435.384431 -86.343369)
			(xy 435.390585 -86.351809) (xy 435.394354 -86.355428) (xy 435.399942 -86.360762) (xy 435.407054 -86.364064)
			(xy 435.419246 -86.367874) (xy 435.487826 -86.377272) (xy 435.488334 -86.377272) (xy 435.509416 -86.380066)
			(xy 435.520413 -86.380406) (xy 435.541074 -86.372902) (xy 435.549294 -86.365588) (xy 435.553104 -86.361778)
			(xy 435.554374 -86.360254) (xy 435.572565 -86.339415) (xy 435.613936 -86.302694) (xy 435.66018 -86.272341)
			(xy 435.710327 -86.248993) (xy 435.763323 -86.23314) (xy 435.818054 -86.225116) (xy 435.845712 -86.224618)
			(xy 435.860698 -86.224618) (xy 435.865778 -86.225126) (xy 435.866794 -86.225126) (xy 435.895676 -86.227219)
			(xy 435.952364 -86.239034) (xy 436.006614 -86.259283) (xy 436.05718 -86.287499) (xy 436.1029 -86.323034)
			(xy 436.142724 -86.365072) (xy 436.175735 -86.412646) (xy 436.201177 -86.464664) (xy 436.218463 -86.51993)
			(xy 436.227197 -86.577173) (xy 436.227728 -86.606126) (xy 436.227229 -86.633866) (xy 436.219193 -86.688762)
			(xy 436.203296 -86.741916) (xy 436.179871 -86.792209) (xy 436.149412 -86.838581) (xy 436.112561 -86.880055)
			(xy 436.070094 -86.915758) (xy 436.022906 -86.944937) (xy 435.971992 -86.966977) (xy 435.918422 -86.981415)
			(xy 435.890924 -86.985094) (xy 435.876446 -86.986618) (xy 435.84622 -86.987888) (xy 435.819222 -86.987422)
			(xy 435.765765 -86.979817) (xy 435.713912 -86.964757) (xy 435.664699 -86.94254) (xy 435.619107 -86.913612)
			(xy 435.578046 -86.878548) (xy 435.542334 -86.838048) (xy 435.512685 -86.792921) (xy 435.50078 -86.768686)
			(xy 435.497732 -86.762082) (xy 435.487064 -86.74989) (xy 435.486048 -86.748874) (xy 435.485032 -86.747858)
			(xy 435.480024 -86.743071) (xy 435.468053 -86.736107) (xy 435.46141 -86.734142) (xy 435.456076 -86.732872)
			(xy 435.416452 -86.727792) (xy 435.415944 -86.727792) (xy 435.374034 -86.72195) (xy 435.36331 -86.720981)
			(xy 435.342663 -86.727032) (xy 435.334156 -86.733634) (xy 435.331362 -86.736174) (xy 435.327552 -86.739984)
			(xy 435.326282 -86.741508) (xy 435.311846 -86.758142) (xy 435.27976 -86.788315) (xy 435.262274 -86.801706)
			(xy 435.261766 -86.802214) (xy 435.253384 -86.808564) (xy 435.252876 -86.808564) (xy 435.246018 -86.813644)
			(xy 435.23789 -86.819486) (xy 435.233064 -86.826598) (xy 435.230257 -86.830901) (xy 435.226284 -86.840374)
			(xy 435.22519 -86.845394) (xy 435.177184 -87.087964) (xy 435.17635 -87.098526) (xy 435.18227 -87.118846)
			(xy 435.188614 -87.127334) (xy 435.189884 -87.128604) (xy 435.208033 -87.149715) (xy 435.238665 -87.196199)
			(xy 435.262236 -87.246632) (xy 435.27825 -87.299949) (xy 435.286367 -87.355024) (xy 435.286912 -87.382858)
			(xy 435.286912 -87.383112) (xy 435.286833 -87.39585) (xy 435.285179 -87.421271) (xy 435.28361 -87.433912)
			(xy 435.279537 -87.461) (xy 435.264636 -87.513712) (xy 435.24235 -87.563751) (xy 435.213137 -87.610089)
			(xy 435.177597 -87.651772) (xy 435.136462 -87.687944) (xy 435.090576 -87.717861) (xy 435.065932 -87.729822)
			(xy 435.05882 -87.733124) (xy 435.053232 -87.74049) (xy 435.049783 -87.745224) (xy 435.044898 -87.755866)
			(xy 435.04358 -87.761572) (xy 433.756399 -94.24924) (xy 443.73622 -94.24924) (xy 443.740291 -94.193618)
			(xy 443.752417 -94.139181) (xy 443.77234 -94.08709) (xy 443.799636 -94.038455) (xy 443.833722 -93.994312)
			(xy 443.873871 -93.955603) (xy 443.919229 -93.923152) (xy 443.968829 -93.897651) (xy 444.021613 -93.879644)
			(xy 444.076456 -93.869514) (xy 444.13219 -93.867477) (xy 444.187627 -93.873577) (xy 444.241584 -93.887683)
			(xy 444.292913 -93.909495) (xy 444.340519 -93.938549) (xy 444.383387 -93.974224) (xy 444.420604 -94.015761)
			(xy 444.451377 -94.062274) (xy 444.475049 -94.112771) (xy 444.491117 -94.166178) (xy 444.499237 -94.221354)
			(xy 444.499746 -94.24924) (xy 444.499672 -94.253304) (xy 444.75222 -94.253304) (xy 444.756291 -94.197682)
			(xy 444.768417 -94.143245) (xy 444.78834 -94.091154) (xy 444.815636 -94.042519) (xy 444.849722 -93.998376)
			(xy 444.889871 -93.959667) (xy 444.935229 -93.927216) (xy 444.984829 -93.901715) (xy 445.037613 -93.883708)
			(xy 445.092456 -93.873578) (xy 445.14819 -93.871541) (xy 445.203627 -93.877641) (xy 445.257584 -93.891747)
			(xy 445.308913 -93.913559) (xy 445.356519 -93.942613) (xy 445.399387 -93.978288) (xy 445.436604 -94.019825)
			(xy 445.467377 -94.066338) (xy 445.491049 -94.116835) (xy 445.507117 -94.170242) (xy 445.515237 -94.225418)
			(xy 445.515746 -94.253304) (xy 445.515237 -94.28119) (xy 445.507117 -94.336366) (xy 445.491049 -94.389773)
			(xy 445.467377 -94.44027) (xy 445.436604 -94.486783) (xy 445.399387 -94.52832) (xy 445.356519 -94.563995)
			(xy 445.308913 -94.593049) (xy 445.257584 -94.614861) (xy 445.203627 -94.628967) (xy 445.14819 -94.635067)
			(xy 445.092456 -94.63303) (xy 445.037613 -94.6229) (xy 444.984829 -94.604893) (xy 444.935229 -94.579392)
			(xy 444.889871 -94.546941) (xy 444.849722 -94.508232) (xy 444.815636 -94.464089) (xy 444.78834 -94.415454)
			(xy 444.768417 -94.363363) (xy 444.756291 -94.308926) (xy 444.75222 -94.253304) (xy 444.499672 -94.253304)
			(xy 444.499237 -94.277126) (xy 444.491117 -94.332302) (xy 444.475049 -94.385709) (xy 444.451377 -94.436206)
			(xy 444.420604 -94.482719) (xy 444.383387 -94.524256) (xy 444.340519 -94.559931) (xy 444.292913 -94.588985)
			(xy 444.241584 -94.610797) (xy 444.187627 -94.624903) (xy 444.13219 -94.631003) (xy 444.076456 -94.628966)
			(xy 444.021613 -94.618836) (xy 443.968829 -94.600829) (xy 443.919229 -94.575328) (xy 443.873871 -94.542877)
			(xy 443.833722 -94.504168) (xy 443.799636 -94.460025) (xy 443.77234 -94.41139) (xy 443.752417 -94.359299)
			(xy 443.740291 -94.304862) (xy 443.73622 -94.24924) (xy 433.756399 -94.24924) (xy 433.448336 -95.801942)
			(xy 436.941466 -95.801942) (xy 436.945537 -95.74632) (xy 436.957663 -95.691883) (xy 436.977586 -95.639792)
			(xy 437.004882 -95.591157) (xy 437.038968 -95.547014) (xy 437.079117 -95.508305) (xy 437.124475 -95.475854)
			(xy 437.174075 -95.450353) (xy 437.226859 -95.432346) (xy 437.281702 -95.422216) (xy 437.337436 -95.420179)
			(xy 437.392873 -95.426279) (xy 437.44683 -95.440385) (xy 437.498159 -95.462197) (xy 437.545765 -95.491251)
			(xy 437.588633 -95.526926) (xy 437.62585 -95.568463) (xy 437.656623 -95.614976) (xy 437.680295 -95.665473)
			(xy 437.696363 -95.71888) (xy 437.704483 -95.774056) (xy 437.704992 -95.801942) (xy 438.974736 -95.801942)
			(xy 438.978807 -95.74632) (xy 438.990933 -95.691883) (xy 439.010856 -95.639792) (xy 439.038152 -95.591157)
			(xy 439.072238 -95.547014) (xy 439.112387 -95.508305) (xy 439.157745 -95.475854) (xy 439.207345 -95.450353)
			(xy 439.260129 -95.432346) (xy 439.314972 -95.422216) (xy 439.370706 -95.420179) (xy 439.426143 -95.426279)
			(xy 439.4801 -95.440385) (xy 439.531429 -95.462197) (xy 439.579035 -95.491251) (xy 439.621903 -95.526926)
			(xy 439.65912 -95.568463) (xy 439.689893 -95.614976) (xy 439.713565 -95.665473) (xy 439.729633 -95.71888)
			(xy 439.737753 -95.774056) (xy 439.738262 -95.801942) (xy 441.015626 -95.801942) (xy 441.019697 -95.74632)
			(xy 441.031823 -95.691883) (xy 441.051746 -95.639792) (xy 441.079042 -95.591157) (xy 441.113128 -95.547014)
			(xy 441.153277 -95.508305) (xy 441.198635 -95.475854) (xy 441.248235 -95.450353) (xy 441.301019 -95.432346)
			(xy 441.355862 -95.422216) (xy 441.411596 -95.420179) (xy 441.467033 -95.426279) (xy 441.52099 -95.440385)
			(xy 441.572319 -95.462197) (xy 441.619925 -95.491251) (xy 441.662793 -95.526926) (xy 441.70001 -95.568463)
			(xy 441.730783 -95.614976) (xy 441.754455 -95.665473) (xy 441.770523 -95.71888) (xy 441.778643 -95.774056)
			(xy 441.779152 -95.801942) (xy 442.021466 -95.801942) (xy 442.025537 -95.74632) (xy 442.037663 -95.691883)
			(xy 442.057586 -95.639792) (xy 442.084882 -95.591157) (xy 442.118968 -95.547014) (xy 442.159117 -95.508305)
			(xy 442.204475 -95.475854) (xy 442.254075 -95.450353) (xy 442.306859 -95.432346) (xy 442.361702 -95.422216)
			(xy 442.417436 -95.420179) (xy 442.472873 -95.426279) (xy 442.52683 -95.440385) (xy 442.578159 -95.462197)
			(xy 442.625765 -95.491251) (xy 442.668633 -95.526926) (xy 442.70585 -95.568463) (xy 442.736623 -95.614976)
			(xy 442.760295 -95.665473) (xy 442.776363 -95.71888) (xy 442.784483 -95.774056) (xy 442.784992 -95.801942)
			(xy 442.784483 -95.829828) (xy 442.777338 -95.878378) (xy 447.420115 -95.878378) (xy 447.427868 -95.824421)
			(xy 447.443221 -95.772116) (xy 447.465861 -95.722529) (xy 447.495329 -95.676668) (xy 447.531023 -95.635468)
			(xy 447.572217 -95.599767) (xy 447.618072 -95.570292) (xy 447.667656 -95.547643) (xy 447.719958 -95.532281)
			(xy 447.773914 -95.524519) (xy 447.828426 -95.524515) (xy 447.882383 -95.532268) (xy 447.934688 -95.547622)
			(xy 447.984275 -95.570263) (xy 448.030135 -95.599731) (xy 448.071335 -95.635425) (xy 448.107035 -95.67662)
			(xy 448.13651 -95.722476) (xy 448.159158 -95.77206) (xy 448.17452 -95.824362) (xy 448.182281 -95.878318)
			(xy 448.182746 -95.905574) (xy 448.182746 -95.906082) (xy 448.182663 -95.916454) (xy 448.181521 -95.937166)
			(xy 448.18046 -95.947484) (xy 448.179401 -95.96203) (xy 448.184605 -95.990714) (xy 448.197692 -96.016765)
			(xy 448.217597 -96.038064) (xy 448.242703 -96.052882) (xy 448.27097 -96.060014) (xy 448.3001 -96.05888)
			(xy 448.314064 -96.054672) (xy 448.343673 -96.045318) (xy 448.404939 -96.035236) (xy 448.435984 -96.034606)
			(xy 448.436238 -96.034606) (xy 448.463486 -96.035119) (xy 448.517426 -96.04288) (xy 448.569712 -96.058237)
			(xy 448.619281 -96.08088) (xy 448.665123 -96.110346) (xy 448.706305 -96.146036) (xy 448.741989 -96.187224)
			(xy 448.771448 -96.233071) (xy 448.794083 -96.282643) (xy 448.809433 -96.334932) (xy 448.817185 -96.388873)
			(xy 448.817182 -96.443368) (xy 448.809424 -96.497309) (xy 448.794069 -96.549596) (xy 448.771428 -96.599166)
			(xy 448.741964 -96.645009) (xy 448.706276 -96.686193) (xy 448.66509 -96.721879) (xy 448.619245 -96.75134)
			(xy 448.569673 -96.773977) (xy 448.517385 -96.789329) (xy 448.463444 -96.797084) (xy 448.408949 -96.797084)
			(xy 448.355008 -96.789328) (xy 448.30272 -96.773975) (xy 448.253149 -96.751337) (xy 448.207305 -96.721875)
			(xy 448.166119 -96.686188) (xy 448.130432 -96.645004) (xy 448.100968 -96.59916) (xy 448.078329 -96.54959)
			(xy 448.062974 -96.497302) (xy 448.055217 -96.443362) (xy 448.05473 -96.416114) (xy 448.05473 -96.415606)
			(xy 448.054812 -96.405234) (xy 448.055955 -96.384522) (xy 448.057016 -96.374204) (xy 448.058118 -96.359659)
			(xy 448.052909 -96.330969) (xy 448.039816 -96.304914) (xy 448.019904 -96.283612) (xy 447.99479 -96.268795)
			(xy 447.966515 -96.261666) (xy 447.937378 -96.262804) (xy 447.923412 -96.267016) (xy 447.893805 -96.276375)
			(xy 447.832537 -96.286454) (xy 447.801492 -96.287082) (xy 447.801238 -96.287082) (xy 447.773982 -96.286686)
			(xy 447.720025 -96.278933) (xy 447.66772 -96.263581) (xy 447.618132 -96.240941) (xy 447.572271 -96.211474)
			(xy 447.531071 -96.17578) (xy 447.495369 -96.134586) (xy 447.465894 -96.088731) (xy 447.443244 -96.039148)
			(xy 447.427882 -95.986846) (xy 447.420119 -95.93289) (xy 447.420115 -95.878378) (xy 442.777338 -95.878378)
			(xy 442.776363 -95.885004) (xy 442.760295 -95.938411) (xy 442.736623 -95.988908) (xy 442.70585 -96.035421)
			(xy 442.668633 -96.076958) (xy 442.625765 -96.112633) (xy 442.578159 -96.141687) (xy 442.52683 -96.163499)
			(xy 442.472873 -96.177605) (xy 442.417436 -96.183705) (xy 442.361702 -96.181668) (xy 442.306859 -96.171538)
			(xy 442.254075 -96.153531) (xy 442.204475 -96.12803) (xy 442.159117 -96.095579) (xy 442.118968 -96.05687)
			(xy 442.084882 -96.012727) (xy 442.057586 -95.964092) (xy 442.037663 -95.912001) (xy 442.025537 -95.857564)
			(xy 442.021466 -95.801942) (xy 441.779152 -95.801942) (xy 441.778643 -95.829828) (xy 441.770523 -95.885004)
			(xy 441.754455 -95.938411) (xy 441.730783 -95.988908) (xy 441.70001 -96.035421) (xy 441.662793 -96.076958)
			(xy 441.619925 -96.112633) (xy 441.572319 -96.141687) (xy 441.52099 -96.163499) (xy 441.467033 -96.177605)
			(xy 441.411596 -96.183705) (xy 441.355862 -96.181668) (xy 441.301019 -96.171538) (xy 441.248235 -96.153531)
			(xy 441.198635 -96.12803) (xy 441.153277 -96.095579) (xy 441.113128 -96.05687) (xy 441.079042 -96.012727)
			(xy 441.051746 -95.964092) (xy 441.031823 -95.912001) (xy 441.019697 -95.857564) (xy 441.015626 -95.801942)
			(xy 439.738262 -95.801942) (xy 439.737753 -95.829828) (xy 439.729633 -95.885004) (xy 439.713565 -95.938411)
			(xy 439.689893 -95.988908) (xy 439.65912 -96.035421) (xy 439.621903 -96.076958) (xy 439.579035 -96.112633)
			(xy 439.531429 -96.141687) (xy 439.4801 -96.163499) (xy 439.426143 -96.177605) (xy 439.370706 -96.183705)
			(xy 439.314972 -96.181668) (xy 439.260129 -96.171538) (xy 439.207345 -96.153531) (xy 439.157745 -96.12803)
			(xy 439.112387 -96.095579) (xy 439.072238 -96.05687) (xy 439.038152 -96.012727) (xy 439.010856 -95.964092)
			(xy 438.990933 -95.912001) (xy 438.978807 -95.857564) (xy 438.974736 -95.801942) (xy 437.704992 -95.801942)
			(xy 437.704483 -95.829828) (xy 437.696363 -95.885004) (xy 437.680295 -95.938411) (xy 437.656623 -95.988908)
			(xy 437.62585 -96.035421) (xy 437.588633 -96.076958) (xy 437.545765 -96.112633) (xy 437.498159 -96.141687)
			(xy 437.44683 -96.163499) (xy 437.392873 -96.177605) (xy 437.337436 -96.183705) (xy 437.281702 -96.181668)
			(xy 437.226859 -96.171538) (xy 437.174075 -96.153531) (xy 437.124475 -96.12803) (xy 437.079117 -96.095579)
			(xy 437.038968 -96.05687) (xy 437.004882 -96.012727) (xy 436.977586 -95.964092) (xy 436.957663 -95.912001)
			(xy 436.945537 -95.857564) (xy 436.941466 -95.801942) (xy 433.448336 -95.801942) (xy 433.334646 -96.374966)
			(xy 442.727078 -96.374966) (xy 442.731149 -96.319344) (xy 442.743275 -96.264907) (xy 442.763198 -96.212816)
			(xy 442.790494 -96.164181) (xy 442.82458 -96.120038) (xy 442.864729 -96.081329) (xy 442.910087 -96.048878)
			(xy 442.959687 -96.023377) (xy 443.012471 -96.00537) (xy 443.067314 -95.99524) (xy 443.123048 -95.993203)
			(xy 443.178485 -95.999303) (xy 443.232442 -96.013409) (xy 443.283771 -96.035221) (xy 443.331377 -96.064275)
			(xy 443.374245 -96.09995) (xy 443.411462 -96.141487) (xy 443.442235 -96.188) (xy 443.465907 -96.238497)
			(xy 443.480906 -96.288352) (xy 444.152272 -96.288352) (xy 444.156343 -96.23273) (xy 444.168469 -96.178293)
			(xy 444.188392 -96.126202) (xy 444.215688 -96.077567) (xy 444.249774 -96.033424) (xy 444.289923 -95.994715)
			(xy 444.335281 -95.962264) (xy 444.384881 -95.936763) (xy 444.437665 -95.918756) (xy 444.492508 -95.908626)
			(xy 444.548242 -95.906589) (xy 444.603679 -95.912689) (xy 444.657636 -95.926795) (xy 444.708965 -95.948607)
			(xy 444.756571 -95.977661) (xy 444.799439 -96.013336) (xy 444.836656 -96.054873) (xy 444.867429 -96.101386)
			(xy 444.891101 -96.151883) (xy 444.907169 -96.20529) (xy 444.915289 -96.260466) (xy 444.91552 -96.273112)
			(xy 445.497964 -96.273112) (xy 445.502035 -96.21749) (xy 445.514161 -96.163053) (xy 445.534084 -96.110962)
			(xy 445.56138 -96.062327) (xy 445.595466 -96.018184) (xy 445.635615 -95.979475) (xy 445.680973 -95.947024)
			(xy 445.730573 -95.921523) (xy 445.783357 -95.903516) (xy 445.8382 -95.893386) (xy 445.893934 -95.891349)
			(xy 445.949371 -95.897449) (xy 446.003328 -95.911555) (xy 446.054657 -95.933367) (xy 446.102263 -95.962421)
			(xy 446.145131 -95.998096) (xy 446.182348 -96.039633) (xy 446.213121 -96.086146) (xy 446.236793 -96.136643)
			(xy 446.252861 -96.19005) (xy 446.260981 -96.245226) (xy 446.26149 -96.273112) (xy 446.260981 -96.300998)
			(xy 446.252861 -96.356174) (xy 446.236793 -96.409581) (xy 446.213121 -96.460078) (xy 446.182348 -96.506591)
			(xy 446.145131 -96.548128) (xy 446.102263 -96.583803) (xy 446.054657 -96.612857) (xy 446.003328 -96.634669)
			(xy 445.949371 -96.648775) (xy 445.893934 -96.654875) (xy 445.8382 -96.652838) (xy 445.783357 -96.642708)
			(xy 445.730573 -96.624701) (xy 445.680973 -96.5992) (xy 445.635615 -96.566749) (xy 445.595466 -96.52804)
			(xy 445.56138 -96.483897) (xy 445.534084 -96.435262) (xy 445.514161 -96.383171) (xy 445.502035 -96.328734)
			(xy 445.497964 -96.273112) (xy 444.91552 -96.273112) (xy 444.915798 -96.288352) (xy 444.915289 -96.316238)
			(xy 444.907169 -96.371414) (xy 444.891101 -96.424821) (xy 444.867429 -96.475318) (xy 444.836656 -96.521831)
			(xy 444.799439 -96.563368) (xy 444.756571 -96.599043) (xy 444.708965 -96.628097) (xy 444.657636 -96.649909)
			(xy 444.603679 -96.664015) (xy 444.548242 -96.670115) (xy 444.492508 -96.668078) (xy 444.437665 -96.657948)
			(xy 444.384881 -96.639941) (xy 444.335281 -96.61444) (xy 444.289923 -96.581989) (xy 444.249774 -96.54328)
			(xy 444.215688 -96.499137) (xy 444.188392 -96.450502) (xy 444.168469 -96.398411) (xy 444.156343 -96.343974)
			(xy 444.152272 -96.288352) (xy 443.480906 -96.288352) (xy 443.481975 -96.291904) (xy 443.490095 -96.34708)
			(xy 443.490604 -96.374966) (xy 443.490095 -96.402852) (xy 443.481975 -96.458028) (xy 443.465907 -96.511435)
			(xy 443.442235 -96.561932) (xy 443.411462 -96.608445) (xy 443.374245 -96.649982) (xy 443.331377 -96.685657)
			(xy 443.283771 -96.714711) (xy 443.232442 -96.736523) (xy 443.178485 -96.750629) (xy 443.123048 -96.756729)
			(xy 443.067314 -96.754692) (xy 443.012471 -96.744562) (xy 442.959687 -96.726555) (xy 442.910087 -96.701054)
			(xy 442.864729 -96.668603) (xy 442.82458 -96.629894) (xy 442.790494 -96.585751) (xy 442.763198 -96.537116)
			(xy 442.743275 -96.485025) (xy 442.731149 -96.430588) (xy 442.727078 -96.374966) (xy 433.334646 -96.374966)
			(xy 433.021443 -97.953576) (xy 436.643016 -97.953576) (xy 436.647087 -97.897954) (xy 436.659213 -97.843517)
			(xy 436.679136 -97.791426) (xy 436.706432 -97.742791) (xy 436.740518 -97.698648) (xy 436.780667 -97.659939)
			(xy 436.826025 -97.627488) (xy 436.875625 -97.601987) (xy 436.928409 -97.58398) (xy 436.983252 -97.57385)
			(xy 437.038986 -97.571813) (xy 437.094423 -97.577913) (xy 437.14838 -97.592019) (xy 437.199709 -97.613831)
			(xy 437.247315 -97.642885) (xy 437.290183 -97.67856) (xy 437.3274 -97.720097) (xy 437.358173 -97.76661)
			(xy 437.381845 -97.817107) (xy 437.383089 -97.821242) (xy 437.957466 -97.821242) (xy 437.961537 -97.76562)
			(xy 437.973663 -97.711183) (xy 437.993586 -97.659092) (xy 438.020882 -97.610457) (xy 438.054968 -97.566314)
			(xy 438.095117 -97.527605) (xy 438.140475 -97.495154) (xy 438.190075 -97.469653) (xy 438.242859 -97.451646)
			(xy 438.297702 -97.441516) (xy 438.353436 -97.439479) (xy 438.408873 -97.445579) (xy 438.46283 -97.459685)
			(xy 438.514159 -97.481497) (xy 438.561765 -97.510551) (xy 438.604633 -97.546226) (xy 438.64185 -97.587763)
			(xy 438.672623 -97.634276) (xy 438.696295 -97.684773) (xy 438.712363 -97.73818) (xy 438.720483 -97.793356)
			(xy 438.720992 -97.821242) (xy 438.720495 -97.848447) (xy 439.22852 -97.848447) (xy 439.22852 -97.793953)
			(xy 439.236275 -97.740012) (xy 439.251628 -97.687725) (xy 439.274265 -97.638154) (xy 439.303727 -97.592309)
			(xy 439.339413 -97.551124) (xy 439.380597 -97.515437) (xy 439.42644 -97.485973) (xy 439.47601 -97.463334)
			(xy 439.528297 -97.447979) (xy 439.582237 -97.440221) (xy 439.609484 -97.439734) (xy 439.638401 -97.440251)
			(xy 439.695573 -97.448978) (xy 439.750772 -97.466236) (xy 439.802734 -97.491628) (xy 439.850268 -97.524572)
			(xy 439.892284 -97.564314) (xy 439.910474 -97.5868) (xy 439.918102 -97.595585) (xy 439.938987 -97.605781)
			(xy 439.950606 -97.606358) (xy 440.030362 -97.606358) (xy 440.041999 -97.605855) (xy 440.062909 -97.595642)
			(xy 440.070494 -97.5868) (xy 440.088688 -97.564319) (xy 440.130707 -97.524584) (xy 440.178242 -97.491645)
			(xy 440.230202 -97.466256) (xy 440.285399 -97.448999) (xy 440.342568 -97.440269) (xy 440.371484 -97.439734)
			(xy 440.398741 -97.440112) (xy 440.452699 -97.447868) (xy 440.505005 -97.463224) (xy 440.554593 -97.485868)
			(xy 440.600453 -97.515339) (xy 440.641652 -97.551037) (xy 440.677351 -97.592234) (xy 440.706824 -97.638093)
			(xy 440.72947 -97.68768) (xy 440.744829 -97.739985) (xy 440.752587 -97.793943) (xy 440.752587 -97.821242)
			(xy 441.005466 -97.821242) (xy 441.009537 -97.76562) (xy 441.021663 -97.711183) (xy 441.041586 -97.659092)
			(xy 441.068882 -97.610457) (xy 441.102968 -97.566314) (xy 441.143117 -97.527605) (xy 441.188475 -97.495154)
			(xy 441.238075 -97.469653) (xy 441.290859 -97.451646) (xy 441.345702 -97.441516) (xy 441.401436 -97.439479)
			(xy 441.456873 -97.445579) (xy 441.51083 -97.459685) (xy 441.562159 -97.481497) (xy 441.609765 -97.510551)
			(xy 441.629968 -97.527364) (xy 442.639702 -97.527364) (xy 442.643773 -97.471742) (xy 442.655899 -97.417305)
			(xy 442.675822 -97.365214) (xy 442.703118 -97.316579) (xy 442.737204 -97.272436) (xy 442.777353 -97.233727)
			(xy 442.822711 -97.201276) (xy 442.872311 -97.175775) (xy 442.925095 -97.157768) (xy 442.979938 -97.147638)
			(xy 443.035672 -97.145601) (xy 443.091109 -97.151701) (xy 443.145066 -97.165807) (xy 443.196395 -97.187619)
			(xy 443.244001 -97.216673) (xy 443.286869 -97.252348) (xy 443.324086 -97.293885) (xy 443.354859 -97.340398)
			(xy 443.378531 -97.390895) (xy 443.394599 -97.444302) (xy 443.402719 -97.499478) (xy 443.403228 -97.527364)
			(xy 443.402719 -97.55525) (xy 443.394599 -97.610426) (xy 443.378531 -97.663833) (xy 443.354859 -97.71433)
			(xy 443.324086 -97.760843) (xy 443.286869 -97.80238) (xy 443.244001 -97.838055) (xy 443.196395 -97.867109)
			(xy 443.145066 -97.888921) (xy 443.091109 -97.903027) (xy 443.035672 -97.909127) (xy 442.979938 -97.90709)
			(xy 442.925095 -97.89696) (xy 442.872311 -97.878953) (xy 442.822711 -97.853452) (xy 442.777353 -97.821001)
			(xy 442.737204 -97.782292) (xy 442.703118 -97.738149) (xy 442.675822 -97.689514) (xy 442.655899 -97.637423)
			(xy 442.643773 -97.582986) (xy 442.639702 -97.527364) (xy 441.629968 -97.527364) (xy 441.652633 -97.546226)
			(xy 441.68985 -97.587763) (xy 441.720623 -97.634276) (xy 441.744295 -97.684773) (xy 441.760363 -97.73818)
			(xy 441.768483 -97.793356) (xy 441.768992 -97.821242) (xy 441.768483 -97.849128) (xy 441.760363 -97.904304)
			(xy 441.744295 -97.957711) (xy 441.720623 -98.008208) (xy 441.68985 -98.054721) (xy 441.652633 -98.096258)
			(xy 441.609765 -98.131933) (xy 441.562159 -98.160987) (xy 441.51083 -98.182799) (xy 441.456873 -98.196905)
			(xy 441.401436 -98.203005) (xy 441.345702 -98.200968) (xy 441.290859 -98.190838) (xy 441.238075 -98.172831)
			(xy 441.188475 -98.14733) (xy 441.143117 -98.114879) (xy 441.102968 -98.07617) (xy 441.068882 -98.032027)
			(xy 441.041586 -97.983392) (xy 441.021663 -97.931301) (xy 441.009537 -97.876864) (xy 441.005466 -97.821242)
			(xy 440.752587 -97.821242) (xy 440.752587 -97.848457) (xy 440.744829 -97.902415) (xy 440.72947 -97.95472)
			(xy 440.706824 -98.004307) (xy 440.677351 -98.050166) (xy 440.641652 -98.091363) (xy 440.600453 -98.127061)
			(xy 440.554593 -98.156532) (xy 440.505005 -98.179176) (xy 440.452699 -98.194532) (xy 440.398741 -98.202288)
			(xy 440.371484 -98.20275) (xy 440.342568 -98.20219) (xy 440.285398 -98.193472) (xy 440.2302 -98.176224)
			(xy 440.178237 -98.15084) (xy 440.130702 -98.117903) (xy 440.088685 -98.078167) (xy 440.070494 -98.055684)
			(xy 440.062883 -98.046881) (xy 440.041985 -98.036696) (xy 440.030362 -98.036126) (xy 439.950606 -98.036126)
			(xy 439.938975 -98.036674) (xy 439.918065 -98.046856) (xy 439.910474 -98.055684) (xy 439.892294 -98.078177)
			(xy 439.850272 -98.117912) (xy 439.802735 -98.15085) (xy 439.750772 -98.176237) (xy 439.695572 -98.193491)
			(xy 439.638401 -98.202217) (xy 439.609484 -98.20275) (xy 439.582237 -98.202179) (xy 439.528297 -98.194421)
			(xy 439.47601 -98.179066) (xy 439.42644 -98.156427) (xy 439.380597 -98.126963) (xy 439.339413 -98.091276)
			(xy 439.303727 -98.050091) (xy 439.274265 -98.004246) (xy 439.251628 -97.954675) (xy 439.236275 -97.902388)
			(xy 439.22852 -97.848447) (xy 438.720495 -97.848447) (xy 438.720483 -97.849128) (xy 438.712363 -97.904304)
			(xy 438.696295 -97.957711) (xy 438.672623 -98.008208) (xy 438.64185 -98.054721) (xy 438.604633 -98.096258)
			(xy 438.561765 -98.131933) (xy 438.514159 -98.160987) (xy 438.46283 -98.182799) (xy 438.408873 -98.196905)
			(xy 438.353436 -98.203005) (xy 438.297702 -98.200968) (xy 438.242859 -98.190838) (xy 438.190075 -98.172831)
			(xy 438.140475 -98.14733) (xy 438.095117 -98.114879) (xy 438.054968 -98.07617) (xy 438.020882 -98.032027)
			(xy 437.993586 -97.983392) (xy 437.973663 -97.931301) (xy 437.961537 -97.876864) (xy 437.957466 -97.821242)
			(xy 437.383089 -97.821242) (xy 437.397913 -97.870514) (xy 437.406033 -97.92569) (xy 437.406542 -97.953576)
			(xy 437.406033 -97.981462) (xy 437.397913 -98.036638) (xy 437.381845 -98.090045) (xy 437.358173 -98.140542)
			(xy 437.3274 -98.187055) (xy 437.290183 -98.228592) (xy 437.247315 -98.264267) (xy 437.199709 -98.293321)
			(xy 437.14838 -98.315133) (xy 437.094423 -98.329239) (xy 437.038986 -98.335339) (xy 436.983252 -98.333302)
			(xy 436.928409 -98.323172) (xy 436.875625 -98.305165) (xy 436.826025 -98.279664) (xy 436.780667 -98.247213)
			(xy 436.740518 -98.208504) (xy 436.706432 -98.164361) (xy 436.679136 -98.115726) (xy 436.659213 -98.063635)
			(xy 436.647087 -98.009198) (xy 436.643016 -97.953576) (xy 433.021443 -97.953576) (xy 432.904427 -98.543364)
			(xy 435.285894 -98.543364) (xy 435.289965 -98.487742) (xy 435.302091 -98.433305) (xy 435.322014 -98.381214)
			(xy 435.34931 -98.332579) (xy 435.383396 -98.288436) (xy 435.423545 -98.249727) (xy 435.468903 -98.217276)
			(xy 435.518503 -98.191775) (xy 435.571287 -98.173768) (xy 435.62613 -98.163638) (xy 435.681864 -98.161601)
			(xy 435.737301 -98.167701) (xy 435.791258 -98.181807) (xy 435.842587 -98.203619) (xy 435.890193 -98.232673)
			(xy 435.933061 -98.268348) (xy 435.970278 -98.309885) (xy 436.001051 -98.356398) (xy 436.024723 -98.406895)
			(xy 436.040791 -98.460302) (xy 436.048911 -98.515478) (xy 436.04942 -98.543364) (xy 436.048911 -98.57125)
			(xy 436.040791 -98.626426) (xy 436.024723 -98.679833) (xy 436.001051 -98.73033) (xy 435.98174 -98.759518)
			(xy 447.471292 -98.759518) (xy 447.471771 -98.732148) (xy 447.479586 -98.67797) (xy 447.495072 -98.625467)
			(xy 447.517911 -98.57572) (xy 447.547632 -98.529752) (xy 447.565272 -98.50882) (xy 447.565526 -98.508566)
			(xy 447.571094 -98.501467) (xy 447.577351 -98.48456) (xy 447.577718 -98.475546) (xy 447.577718 -98.40849)
			(xy 447.577362 -98.399473) (xy 447.571113 -98.382556) (xy 447.565526 -98.37547) (xy 447.565272 -98.37547)
			(xy 447.565272 -98.375216) (xy 447.547647 -98.35427) (xy 447.517918 -98.308306) (xy 447.495069 -98.258562)
			(xy 447.479569 -98.206061) (xy 447.471738 -98.151884) (xy 447.471736 -98.097143) (xy 447.479564 -98.042965)
			(xy 447.495059 -97.990464) (xy 447.517905 -97.940718) (xy 447.547631 -97.894752) (xy 447.565272 -97.87382)
			(xy 447.565526 -97.873566) (xy 447.571094 -97.866467) (xy 447.577351 -97.84956) (xy 447.577718 -97.840546)
			(xy 447.577718 -97.77349) (xy 447.577362 -97.764473) (xy 447.571113 -97.747556) (xy 447.565526 -97.74047)
			(xy 447.565272 -97.74047) (xy 447.565272 -97.740216) (xy 447.547623 -97.719292) (xy 447.517913 -97.673317)
			(xy 447.49508 -97.623567) (xy 447.479591 -97.571065) (xy 447.471765 -97.516888) (xy 447.471292 -97.489518)
			(xy 447.471778 -97.462267) (xy 447.479534 -97.408319) (xy 447.494889 -97.356024) (xy 447.517531 -97.306447)
			(xy 447.546997 -97.260597) (xy 447.582688 -97.219406) (xy 447.623879 -97.183715) (xy 447.669729 -97.154249)
			(xy 447.719306 -97.131607) (xy 447.771601 -97.116252) (xy 447.825549 -97.108496) (xy 447.880051 -97.108496)
			(xy 447.933999 -97.116252) (xy 447.986294 -97.131607) (xy 448.035871 -97.154249) (xy 448.081721 -97.183715)
			(xy 448.122912 -97.219406) (xy 448.158603 -97.260597) (xy 448.188069 -97.306447) (xy 448.210711 -97.356024)
			(xy 448.226066 -97.408319) (xy 448.233822 -97.462267) (xy 448.234308 -97.489518) (xy 448.233851 -97.516889)
			(xy 448.22603 -97.571068) (xy 448.210539 -97.623571) (xy 448.187696 -97.673318) (xy 448.15797 -97.719284)
			(xy 448.140328 -97.740216) (xy 448.140074 -97.74047) (xy 448.134491 -97.747559) (xy 448.128243 -97.764474)
			(xy 448.127882 -97.77349) (xy 448.127882 -97.840546) (xy 448.128269 -97.84956) (xy 448.134496 -97.866477)
			(xy 448.140074 -97.873566) (xy 448.140328 -97.873566) (xy 448.140328 -97.87382) (xy 448.157988 -97.894738)
			(xy 448.187716 -97.940707) (xy 448.210563 -97.990455) (xy 448.22606 -98.04296) (xy 448.233887 -98.097142)
			(xy 448.233886 -98.151886) (xy 448.226054 -98.206066) (xy 448.210553 -98.25857) (xy 448.187703 -98.308317)
			(xy 448.157972 -98.354284) (xy 448.140328 -98.375216) (xy 448.140074 -98.37547) (xy 448.134491 -98.382559)
			(xy 448.128243 -98.399474) (xy 448.127882 -98.40849) (xy 448.127882 -98.475546) (xy 448.128269 -98.48456)
			(xy 448.134496 -98.501477) (xy 448.136129 -98.503552) (xy 449.126063 -98.503552) (xy 449.126063 -98.449048)
			(xy 449.13382 -98.395098) (xy 449.149176 -98.342801) (xy 449.171818 -98.293222) (xy 449.201286 -98.247369)
			(xy 449.236979 -98.206177) (xy 449.278171 -98.170485) (xy 449.324023 -98.141017) (xy 449.373603 -98.118375)
			(xy 449.4259 -98.10302) (xy 449.47985 -98.095263) (xy 449.507102 -98.0948) (xy 449.533416 -98.095266)
			(xy 449.585545 -98.102501) (xy 449.636187 -98.116821) (xy 449.684386 -98.137953) (xy 449.72923 -98.1655)
			(xy 449.769869 -98.198938) (xy 449.788026 -98.21799) (xy 449.795537 -98.225404) (xy 449.814825 -98.233921)
			(xy 449.825364 -98.2345) (xy 449.90004 -98.2345) (xy 449.910588 -98.233952) (xy 449.929883 -98.22543)
			(xy 449.937378 -98.21799) (xy 449.955549 -98.19895) (xy 449.996176 -98.165492) (xy 450.041013 -98.137931)
			(xy 450.089211 -98.11679) (xy 450.139855 -98.102469) (xy 450.191987 -98.095241) (xy 450.218302 -98.0948)
			(xy 450.245554 -98.09527) (xy 450.299502 -98.103027) (xy 450.351798 -98.118382) (xy 450.401376 -98.141024)
			(xy 450.447227 -98.170491) (xy 450.488418 -98.206183) (xy 450.52411 -98.247374) (xy 450.553577 -98.293226)
			(xy 450.573272 -98.336354) (xy 451.149466 -98.336354) (xy 451.149948 -98.308984) (xy 451.157759 -98.254805)
			(xy 451.173244 -98.202302) (xy 451.196082 -98.152554) (xy 451.225805 -98.106587) (xy 451.243446 -98.085656)
			(xy 451.2437 -98.085402) (xy 451.249292 -98.078319) (xy 451.255535 -98.0614) (xy 451.255892 -98.052382)
			(xy 451.255892 -97.985326) (xy 451.255524 -97.97631) (xy 451.249284 -97.959393) (xy 451.2437 -97.952306)
			(xy 451.243446 -97.952306) (xy 451.243446 -97.952052) (xy 451.225759 -97.931156) (xy 451.196035 -97.885182)
			(xy 451.173191 -97.83543) (xy 451.157698 -97.782922) (xy 451.149873 -97.728738) (xy 451.149878 -97.673992)
			(xy 451.157713 -97.61981) (xy 451.173216 -97.567305) (xy 451.196068 -97.517557) (xy 451.225801 -97.471588)
			(xy 451.243446 -97.450656) (xy 451.2437 -97.450402) (xy 451.249292 -97.443319) (xy 451.255535 -97.4264)
			(xy 451.255892 -97.417382) (xy 451.255892 -97.350326) (xy 451.255524 -97.34131) (xy 451.249284 -97.324393)
			(xy 451.2437 -97.317306) (xy 451.243446 -97.317306) (xy 451.243446 -97.317052) (xy 451.225825 -97.296105)
			(xy 451.196109 -97.250137) (xy 451.173269 -97.200394) (xy 451.157774 -97.147896) (xy 451.149942 -97.093722)
			(xy 451.149466 -97.066354) (xy 451.149952 -97.039103) (xy 451.157708 -96.985155) (xy 451.173063 -96.93286)
			(xy 451.195705 -96.883283) (xy 451.225171 -96.837433) (xy 451.260862 -96.796242) (xy 451.302053 -96.760551)
			(xy 451.347903 -96.731085) (xy 451.39748 -96.708443) (xy 451.449775 -96.693088) (xy 451.503723 -96.685332)
			(xy 451.558225 -96.685332) (xy 451.612173 -96.693088) (xy 451.664468 -96.708443) (xy 451.714045 -96.731085)
			(xy 451.759895 -96.760551) (xy 451.801086 -96.796242) (xy 451.836777 -96.837433) (xy 451.866243 -96.883283)
			(xy 451.888885 -96.93286) (xy 451.90424 -96.985155) (xy 451.911996 -97.039103) (xy 451.912482 -97.066354)
			(xy 451.911993 -97.093723) (xy 451.904182 -97.147902) (xy 451.888698 -97.200405) (xy 451.865861 -97.250152)
			(xy 451.836141 -97.29612) (xy 451.818502 -97.317052) (xy 451.818248 -97.317306) (xy 451.812647 -97.324382)
			(xy 451.80641 -97.341307) (xy 451.806056 -97.350326) (xy 451.806056 -97.417382) (xy 451.80641 -97.426399)
			(xy 451.812658 -97.443317) (xy 451.818248 -97.450402) (xy 451.818502 -97.450402) (xy 451.818502 -97.450656)
			(xy 451.836096 -97.471626) (xy 451.865821 -97.517588) (xy 451.888667 -97.567328) (xy 451.904166 -97.619824)
			(xy 451.911998 -97.673997) (xy 451.912003 -97.728733) (xy 451.904181 -97.782908) (xy 451.888692 -97.835407)
			(xy 451.865854 -97.885151) (xy 451.836138 -97.931119) (xy 451.818502 -97.952052) (xy 451.818248 -97.952306)
			(xy 451.812647 -97.959382) (xy 451.80641 -97.976307) (xy 451.806056 -97.985326) (xy 451.806056 -98.052382)
			(xy 451.80641 -98.061399) (xy 451.812658 -98.078317) (xy 451.818248 -98.085402) (xy 451.818502 -98.085402)
			(xy 451.818502 -98.085656) (xy 451.836134 -98.106594) (xy 451.865847 -98.152565) (xy 451.888684 -98.202311)
			(xy 451.904177 -98.25481) (xy 451.912007 -98.308985) (xy 451.912482 -98.336354) (xy 451.911996 -98.363605)
			(xy 451.90424 -98.417553) (xy 451.888885 -98.469848) (xy 451.866243 -98.519425) (xy 451.836777 -98.565275)
			(xy 451.801086 -98.606466) (xy 451.759895 -98.642157) (xy 451.714045 -98.671623) (xy 451.664468 -98.694265)
			(xy 451.612173 -98.70962) (xy 451.558225 -98.717376) (xy 451.503723 -98.717376) (xy 451.449775 -98.70962)
			(xy 451.39748 -98.694265) (xy 451.347903 -98.671623) (xy 451.302053 -98.642157) (xy 451.260862 -98.606466)
			(xy 451.225171 -98.565275) (xy 451.195705 -98.519425) (xy 451.173063 -98.469848) (xy 451.157708 -98.417553)
			(xy 451.149952 -98.363605) (xy 451.149466 -98.336354) (xy 450.573272 -98.336354) (xy 450.576218 -98.342804)
			(xy 450.591574 -98.3951) (xy 450.59933 -98.449048) (xy 450.59933 -98.503552) (xy 450.591574 -98.5575)
			(xy 450.576218 -98.609796) (xy 450.553577 -98.659374) (xy 450.52411 -98.705226) (xy 450.488418 -98.746417)
			(xy 450.447227 -98.782109) (xy 450.401376 -98.811576) (xy 450.351798 -98.834218) (xy 450.299502 -98.849573)
			(xy 450.245554 -98.85733) (xy 450.218302 -98.857816) (xy 450.191988 -98.857342) (xy 450.13986 -98.850108)
			(xy 450.089218 -98.83579) (xy 450.041019 -98.814658) (xy 449.996175 -98.787114) (xy 449.955535 -98.753677)
			(xy 449.937378 -98.734626) (xy 449.929863 -98.727216) (xy 449.910578 -98.718696) (xy 449.90004 -98.718116)
			(xy 449.825364 -98.718116) (xy 449.814816 -98.718662) (xy 449.79552 -98.727185) (xy 449.788026 -98.734626)
			(xy 449.769856 -98.753667) (xy 449.729229 -98.787124) (xy 449.684391 -98.814685) (xy 449.636194 -98.835826)
			(xy 449.585549 -98.850146) (xy 449.533417 -98.857375) (xy 449.507102 -98.857816) (xy 449.47985 -98.857337)
			(xy 449.4259 -98.84958) (xy 449.373603 -98.834225) (xy 449.324023 -98.811583) (xy 449.278171 -98.782115)
			(xy 449.236979 -98.746423) (xy 449.201286 -98.705231) (xy 449.171818 -98.659378) (xy 449.149176 -98.609799)
			(xy 449.13382 -98.557502) (xy 449.126063 -98.503552) (xy 448.136129 -98.503552) (xy 448.140074 -98.508566)
			(xy 448.140328 -98.509074) (xy 448.151273 -98.521808) (xy 448.171114 -98.548899) (xy 448.179952 -98.563176)
			(xy 448.185286 -98.572066) (xy 448.202304 -98.584258) (xy 448.295522 -98.604578) (xy 448.316096 -98.60026)
			(xy 448.324732 -98.594418) (xy 448.348787 -98.578404) (xy 448.400722 -98.553064) (xy 448.455882 -98.535842)
			(xy 448.513009 -98.527132) (xy 448.541902 -98.5266) (xy 448.569154 -98.52707) (xy 448.623102 -98.534827)
			(xy 448.675398 -98.550182) (xy 448.724976 -98.572824) (xy 448.770827 -98.602291) (xy 448.812018 -98.637983)
			(xy 448.84771 -98.679174) (xy 448.877177 -98.725026) (xy 448.899818 -98.774604) (xy 448.915174 -98.8269)
			(xy 448.92293 -98.880848) (xy 448.92293 -98.935352) (xy 448.915174 -98.9893) (xy 448.899818 -99.041596)
			(xy 448.877177 -99.091174) (xy 448.84771 -99.137026) (xy 448.812018 -99.178217) (xy 448.770827 -99.213909)
			(xy 448.724976 -99.243376) (xy 448.675398 -99.266018) (xy 448.623102 -99.281373) (xy 448.569154 -99.28913)
			(xy 448.541902 -99.289616) (xy 448.51381 -99.28912) (xy 448.458233 -99.280893) (xy 448.404464 -99.264602)
			(xy 448.353667 -99.2406) (xy 448.30694 -99.209405) (xy 448.265295 -99.171693) (xy 448.229633 -99.12828)
			(xy 448.21475 -99.10445) (xy 448.209416 -99.09556) (xy 448.192398 -99.083368) (xy 448.09918 -99.063048)
			(xy 448.078606 -99.067366) (xy 448.06997 -99.073208) (xy 448.045916 -99.089224) (xy 447.993981 -99.114563)
			(xy 447.93882 -99.131784) (xy 447.881693 -99.140494) (xy 447.8528 -99.141026) (xy 447.82555 -99.140522)
			(xy 447.771603 -99.132766) (xy 447.71931 -99.117412) (xy 447.669734 -99.094772) (xy 447.623885 -99.065308)
			(xy 447.582695 -99.029618) (xy 447.547003 -98.98843) (xy 447.517536 -98.942582) (xy 447.494894 -98.893007)
			(xy 447.479538 -98.840714) (xy 447.471779 -98.786768) (xy 447.471292 -98.759518) (xy 435.98174 -98.759518)
			(xy 435.970278 -98.776843) (xy 435.933061 -98.81838) (xy 435.890193 -98.854055) (xy 435.842587 -98.883109)
			(xy 435.791258 -98.904921) (xy 435.737301 -98.919027) (xy 435.681864 -98.925127) (xy 435.62613 -98.92309)
			(xy 435.571287 -98.91296) (xy 435.518503 -98.894953) (xy 435.468903 -98.869452) (xy 435.423545 -98.837001)
			(xy 435.383396 -98.798292) (xy 435.34931 -98.754149) (xy 435.322014 -98.705514) (xy 435.302091 -98.653423)
			(xy 435.289965 -98.598986) (xy 435.285894 -98.543364) (xy 432.904427 -98.543364) (xy 432.724669 -99.449382)
			(xy 436.206136 -99.449382) (xy 436.210207 -99.39376) (xy 436.222333 -99.339323) (xy 436.242256 -99.287232)
			(xy 436.269552 -99.238597) (xy 436.303638 -99.194454) (xy 436.343787 -99.155745) (xy 436.389145 -99.123294)
			(xy 436.438745 -99.097793) (xy 436.491529 -99.079786) (xy 436.546372 -99.069656) (xy 436.602106 -99.067619)
			(xy 436.657543 -99.073719) (xy 436.7115 -99.087825) (xy 436.762829 -99.109637) (xy 436.810435 -99.138691)
			(xy 436.853303 -99.174366) (xy 436.89052 -99.215903) (xy 436.921293 -99.262416) (xy 436.944965 -99.312913)
			(xy 436.961033 -99.36632) (xy 436.969153 -99.421496) (xy 436.969662 -99.449382) (xy 436.969495 -99.458526)
			(xy 441.938662 -99.458526) (xy 441.942733 -99.402904) (xy 441.954859 -99.348467) (xy 441.974782 -99.296376)
			(xy 442.002078 -99.247741) (xy 442.036164 -99.203598) (xy 442.076313 -99.164889) (xy 442.121671 -99.132438)
			(xy 442.171271 -99.106937) (xy 442.224055 -99.08893) (xy 442.278898 -99.0788) (xy 442.334632 -99.076763)
			(xy 442.390069 -99.082863) (xy 442.444026 -99.096969) (xy 442.495355 -99.118781) (xy 442.542961 -99.147835)
			(xy 442.585829 -99.18351) (xy 442.623046 -99.225047) (xy 442.653819 -99.27156) (xy 442.677491 -99.322057)
			(xy 442.693559 -99.375464) (xy 442.701679 -99.43064) (xy 442.702188 -99.458526) (xy 442.701679 -99.486412)
			(xy 442.693559 -99.541588) (xy 442.677491 -99.594995) (xy 442.653819 -99.645492) (xy 442.623046 -99.692005)
			(xy 442.585829 -99.733542) (xy 442.542961 -99.769217) (xy 442.495355 -99.798271) (xy 442.444026 -99.820083)
			(xy 442.390069 -99.834189) (xy 442.334632 -99.840289) (xy 442.278898 -99.838252) (xy 442.224055 -99.828122)
			(xy 442.171271 -99.810115) (xy 442.121671 -99.784614) (xy 442.076313 -99.752163) (xy 442.036164 -99.713454)
			(xy 442.002078 -99.669311) (xy 441.974782 -99.620676) (xy 441.954859 -99.568585) (xy 441.942733 -99.514148)
			(xy 441.938662 -99.458526) (xy 436.969495 -99.458526) (xy 436.969153 -99.477268) (xy 436.961033 -99.532444)
			(xy 436.944965 -99.585851) (xy 436.921293 -99.636348) (xy 436.89052 -99.682861) (xy 436.853303 -99.724398)
			(xy 436.810435 -99.760073) (xy 436.762829 -99.789127) (xy 436.7115 -99.810939) (xy 436.657543 -99.825045)
			(xy 436.602106 -99.831145) (xy 436.546372 -99.829108) (xy 436.491529 -99.818978) (xy 436.438745 -99.800971)
			(xy 436.389145 -99.77547) (xy 436.343787 -99.743019) (xy 436.303638 -99.70431) (xy 436.269552 -99.660167)
			(xy 436.242256 -99.611532) (xy 436.222333 -99.559441) (xy 436.210207 -99.505004) (xy 436.206136 -99.449382)
			(xy 432.724669 -99.449382) (xy 432.379353 -101.18985) (xy 445.29349 -101.18985) (xy 445.29349 -101.13535)
			(xy 445.301246 -101.081404) (xy 445.316601 -101.029111) (xy 445.339241 -100.979536) (xy 445.368706 -100.933687)
			(xy 445.404396 -100.892499) (xy 445.445584 -100.856808) (xy 445.491433 -100.827343) (xy 445.541008 -100.804702)
			(xy 445.5933 -100.789347) (xy 445.647246 -100.781591) (xy 445.674496 -100.781104) (xy 445.701866 -100.781571)
			(xy 445.756045 -100.789389) (xy 445.808548 -100.804877) (xy 445.858295 -100.827719) (xy 445.904262 -100.857443)
			(xy 445.925194 -100.875084) (xy 445.925448 -100.875338) (xy 445.932542 -100.880913) (xy 445.949453 -100.887166)
			(xy 445.958468 -100.88753) (xy 446.025524 -100.88753) (xy 446.034541 -100.887178) (xy 446.051458 -100.880926)
			(xy 446.058544 -100.875338) (xy 446.058544 -100.875084) (xy 446.058798 -100.875084) (xy 446.079718 -100.85743)
			(xy 446.125694 -100.827721) (xy 446.175445 -100.804888) (xy 446.227948 -100.7894) (xy 446.282126 -100.781576)
			(xy 446.309496 -100.781104) (xy 446.33675 -100.781543) (xy 446.390703 -100.789299) (xy 446.443003 -100.804656)
			(xy 446.492585 -100.827299) (xy 446.53844 -100.856767) (xy 446.579635 -100.892462) (xy 446.61533 -100.933656)
			(xy 446.6448 -100.979511) (xy 446.667443 -101.029093) (xy 446.6828 -101.081393) (xy 446.690557 -101.135346)
			(xy 446.690557 -101.189854) (xy 446.6828 -101.243807) (xy 446.667443 -101.296107) (xy 446.6448 -101.345689)
			(xy 446.61533 -101.391544) (xy 446.579635 -101.432738) (xy 446.53844 -101.468433) (xy 446.492585 -101.497901)
			(xy 446.443003 -101.520544) (xy 446.390703 -101.535901) (xy 446.33675 -101.543657) (xy 446.309496 -101.54412)
			(xy 446.282125 -101.543676) (xy 446.227944 -101.535856) (xy 446.17544 -101.520363) (xy 446.125693 -101.497515)
			(xy 446.079728 -101.467785) (xy 446.058798 -101.45014) (xy 446.058544 -101.449886) (xy 446.05145 -101.44431)
			(xy 446.034539 -101.438057) (xy 446.025524 -101.437694) (xy 445.958468 -101.437694) (xy 445.94945 -101.438037)
			(xy 445.932533 -101.444295) (xy 445.925448 -101.449886) (xy 445.925448 -101.45014) (xy 445.925194 -101.45014)
			(xy 445.90428 -101.467802) (xy 445.858302 -101.497509) (xy 445.80855 -101.52034) (xy 445.756045 -101.535826)
			(xy 445.701866 -101.543649) (xy 445.674496 -101.54412) (xy 445.647246 -101.543609) (xy 445.5933 -101.535853)
			(xy 445.541008 -101.520498) (xy 445.491433 -101.497857) (xy 445.445584 -101.468392) (xy 445.404396 -101.432701)
			(xy 445.368706 -101.391513) (xy 445.339241 -101.345664) (xy 445.316601 -101.296089) (xy 445.301246 -101.243796)
			(xy 445.29349 -101.18985) (xy 432.379353 -101.18985) (xy 432.30211 -101.579172) (xy 436.070754 -101.579172)
			(xy 436.074825 -101.52355) (xy 436.086951 -101.469113) (xy 436.106874 -101.417022) (xy 436.13417 -101.368387)
			(xy 436.168256 -101.324244) (xy 436.208405 -101.285535) (xy 436.253763 -101.253084) (xy 436.303363 -101.227583)
			(xy 436.356147 -101.209576) (xy 436.41099 -101.199446) (xy 436.466724 -101.197409) (xy 436.522161 -101.203509)
			(xy 436.576118 -101.217615) (xy 436.627447 -101.239427) (xy 436.675053 -101.268481) (xy 436.717921 -101.304156)
			(xy 436.755138 -101.345693) (xy 436.785911 -101.392206) (xy 436.809583 -101.442703) (xy 436.825651 -101.49611)
			(xy 436.833771 -101.551286) (xy 436.83428 -101.579172) (xy 436.833771 -101.607058) (xy 436.825651 -101.662234)
			(xy 436.809583 -101.715641) (xy 436.785911 -101.766138) (xy 436.755138 -101.812651) (xy 436.717921 -101.854188)
			(xy 436.698003 -101.870764) (xy 441.53912 -101.870764) (xy 441.543191 -101.815142) (xy 441.555317 -101.760705)
			(xy 441.57524 -101.708614) (xy 441.602536 -101.659979) (xy 441.636622 -101.615836) (xy 441.676771 -101.577127)
			(xy 441.722129 -101.544676) (xy 441.771729 -101.519175) (xy 441.824513 -101.501168) (xy 441.879356 -101.491038)
			(xy 441.93509 -101.489001) (xy 441.990527 -101.495101) (xy 442.044484 -101.509207) (xy 442.095813 -101.531019)
			(xy 442.143419 -101.560073) (xy 442.186287 -101.595748) (xy 442.223504 -101.637285) (xy 442.254277 -101.683798)
			(xy 442.277949 -101.734295) (xy 442.294017 -101.787702) (xy 442.302137 -101.842878) (xy 442.302646 -101.870764)
			(xy 442.302137 -101.89865) (xy 442.294017 -101.953826) (xy 442.277949 -102.007233) (xy 442.254277 -102.05773)
			(xy 442.223504 -102.104243) (xy 442.200022 -102.130451) (xy 444.843152 -102.130451) (xy 444.843152 -102.075949)
			(xy 444.850908 -102.022002) (xy 444.866261 -101.969707) (xy 444.888901 -101.920129) (xy 444.918365 -101.874278)
			(xy 444.954054 -101.833086) (xy 444.995241 -101.797392) (xy 445.041089 -101.767923) (xy 445.090664 -101.745277)
			(xy 445.142957 -101.729917) (xy 445.196903 -101.722155) (xy 445.224154 -101.721666) (xy 445.251524 -101.722143)
			(xy 445.305703 -101.729956) (xy 445.358207 -101.745441) (xy 445.407954 -101.768281) (xy 445.453921 -101.798005)
			(xy 445.474852 -101.815646) (xy 445.475106 -101.8159) (xy 445.482187 -101.821495) (xy 445.499108 -101.827737)
			(xy 445.508126 -101.828092) (xy 445.575182 -101.828092) (xy 445.584198 -101.827728) (xy 445.601115 -101.821486)
			(xy 445.608202 -101.8159) (xy 445.608202 -101.815646) (xy 445.608456 -101.815646) (xy 445.6294 -101.798021)
			(xy 445.675369 -101.768306) (xy 445.725113 -101.745466) (xy 445.777611 -101.729972) (xy 445.831786 -101.722141)
			(xy 445.859154 -101.721666) (xy 445.886407 -101.722178) (xy 445.940359 -101.729929) (xy 445.992659 -101.74528)
			(xy 446.042242 -101.767919) (xy 446.088097 -101.797383) (xy 446.129293 -101.833075) (xy 446.164989 -101.874266)
			(xy 446.194459 -101.920118) (xy 446.217104 -101.969698) (xy 446.232461 -102.021996) (xy 446.240219 -102.075947)
			(xy 446.240219 -102.130453) (xy 446.232461 -102.184404) (xy 446.217104 -102.236702) (xy 446.194459 -102.286282)
			(xy 446.164989 -102.332134) (xy 446.129293 -102.373325) (xy 446.088097 -102.409017) (xy 446.042242 -102.438481)
			(xy 445.992659 -102.46112) (xy 445.940359 -102.476471) (xy 445.886407 -102.484222) (xy 445.859154 -102.484682)
			(xy 445.831785 -102.484189) (xy 445.777607 -102.476378) (xy 445.725104 -102.460896) (xy 445.675356 -102.43806)
			(xy 445.629388 -102.408341) (xy 445.608456 -102.390702) (xy 445.608202 -102.390448) (xy 445.601124 -102.38485)
			(xy 445.5842 -102.378611) (xy 445.575182 -102.378256) (xy 445.508126 -102.378256) (xy 445.499109 -102.378613)
			(xy 445.482191 -102.384859) (xy 445.475106 -102.390448) (xy 445.475106 -102.390702) (xy 445.474852 -102.390702)
			(xy 445.453911 -102.40833) (xy 445.407941 -102.438044) (xy 445.358196 -102.460882) (xy 445.305697 -102.476375)
			(xy 445.251523 -102.484206) (xy 445.224154 -102.484682) (xy 445.196903 -102.484245) (xy 445.142957 -102.476483)
			(xy 445.090664 -102.461123) (xy 445.041089 -102.438477) (xy 444.995241 -102.409008) (xy 444.954054 -102.373314)
			(xy 444.918365 -102.332122) (xy 444.888901 -102.286271) (xy 444.866261 -102.236693) (xy 444.850908 -102.184398)
			(xy 444.843152 -102.130451) (xy 442.200022 -102.130451) (xy 442.186287 -102.14578) (xy 442.143419 -102.181455)
			(xy 442.095813 -102.210509) (xy 442.044484 -102.232321) (xy 441.990527 -102.246427) (xy 441.93509 -102.252527)
			(xy 441.879356 -102.25049) (xy 441.824513 -102.24036) (xy 441.771729 -102.222353) (xy 441.722129 -102.196852)
			(xy 441.676771 -102.164401) (xy 441.636622 -102.125692) (xy 441.602536 -102.081549) (xy 441.57524 -102.032914)
			(xy 441.555317 -101.980823) (xy 441.543191 -101.926386) (xy 441.53912 -101.870764) (xy 436.698003 -101.870764)
			(xy 436.675053 -101.889863) (xy 436.627447 -101.918917) (xy 436.576118 -101.940729) (xy 436.522161 -101.954835)
			(xy 436.466724 -101.960935) (xy 436.41099 -101.958898) (xy 436.356147 -101.948768) (xy 436.303363 -101.930761)
			(xy 436.253763 -101.90526) (xy 436.208405 -101.872809) (xy 436.168256 -101.8341) (xy 436.13417 -101.789957)
			(xy 436.106874 -101.741322) (xy 436.086951 -101.689231) (xy 436.074825 -101.634794) (xy 436.070754 -101.579172)
			(xy 432.30211 -101.579172) (xy 431.992586 -103.13924) (xy 437.807098 -103.13924) (xy 437.811169 -103.083618)
			(xy 437.823295 -103.029181) (xy 437.843218 -102.97709) (xy 437.870514 -102.928455) (xy 437.9046 -102.884312)
			(xy 437.944749 -102.845603) (xy 437.990107 -102.813152) (xy 438.039707 -102.787651) (xy 438.092491 -102.769644)
			(xy 438.147334 -102.759514) (xy 438.203068 -102.757477) (xy 438.258505 -102.763577) (xy 438.312462 -102.777683)
			(xy 438.363791 -102.799495) (xy 438.411397 -102.828549) (xy 438.454265 -102.864224) (xy 438.491482 -102.905761)
			(xy 438.522255 -102.952274) (xy 438.545927 -103.002771) (xy 438.561995 -103.056178) (xy 438.570115 -103.111354)
			(xy 438.570624 -103.13924) (xy 438.570115 -103.167126) (xy 438.561995 -103.222302) (xy 438.545927 -103.275709)
			(xy 438.522255 -103.326206) (xy 438.491482 -103.372719) (xy 438.454265 -103.414256) (xy 438.411397 -103.449931)
			(xy 438.363791 -103.478985) (xy 438.312462 -103.500797) (xy 438.258505 -103.514903) (xy 438.203068 -103.521003)
			(xy 438.147334 -103.518966) (xy 438.092491 -103.508836) (xy 438.039707 -103.490829) (xy 437.990107 -103.465328)
			(xy 437.944749 -103.432877) (xy 437.9046 -103.394168) (xy 437.870514 -103.350025) (xy 437.843218 -103.30139)
			(xy 437.823295 -103.249299) (xy 437.811169 -103.194862) (xy 437.807098 -103.13924) (xy 431.992586 -103.13924)
			(xy 431.6879 -104.674924) (xy 436.859424 -104.674924) (xy 436.863495 -104.619302) (xy 436.875621 -104.564865)
			(xy 436.895544 -104.512774) (xy 436.92284 -104.464139) (xy 436.956926 -104.419996) (xy 436.997075 -104.381287)
			(xy 437.042433 -104.348836) (xy 437.092033 -104.323335) (xy 437.144817 -104.305328) (xy 437.19966 -104.295198)
			(xy 437.255394 -104.293161) (xy 437.310831 -104.299261) (xy 437.364788 -104.313367) (xy 437.416117 -104.335179)
			(xy 437.463723 -104.364233) (xy 437.506591 -104.399908) (xy 437.543808 -104.441445) (xy 437.574581 -104.487958)
			(xy 437.598253 -104.538455) (xy 437.614321 -104.591862) (xy 437.622441 -104.647038) (xy 437.62295 -104.674924)
			(xy 437.622441 -104.70281) (xy 437.614321 -104.757986) (xy 437.598253 -104.811393) (xy 437.574581 -104.86189)
			(xy 437.543808 -104.908403) (xy 437.506591 -104.94994) (xy 437.463723 -104.985615) (xy 437.416117 -105.014669)
			(xy 437.364788 -105.036481) (xy 437.310831 -105.050587) (xy 437.255394 -105.056687) (xy 437.19966 -105.05465)
			(xy 437.144817 -105.04452) (xy 437.092033 -105.026513) (xy 437.042433 -105.001012) (xy 436.997075 -104.968561)
			(xy 436.956926 -104.929852) (xy 436.92284 -104.885709) (xy 436.895544 -104.837074) (xy 436.875621 -104.784983)
			(xy 436.863495 -104.730546) (xy 436.859424 -104.674924) (xy 431.6879 -104.674924) (xy 431.215047 -107.058206)
			(xy 437.873902 -107.058206) (xy 437.874429 -107.029467) (xy 437.883051 -106.97264) (xy 437.9001 -106.917749)
			(xy 437.925191 -106.866037) (xy 437.957755 -106.818675) (xy 437.977026 -106.797348) (xy 437.98363 -106.79049)
			(xy 437.990742 -106.772456) (xy 437.990742 -106.683556) (xy 437.98363 -106.665522) (xy 437.977026 -106.658664)
			(xy 437.957761 -106.637332) (xy 437.925195 -106.589971) (xy 437.900103 -106.53826) (xy 437.883053 -106.48337)
			(xy 437.87443 -106.426543) (xy 437.874429 -106.369066) (xy 437.883051 -106.312239) (xy 437.9001 -106.257349)
			(xy 437.925191 -106.205637) (xy 437.957756 -106.158275) (xy 437.977026 -106.136948) (xy 437.98363 -106.13009)
			(xy 437.990742 -106.112056) (xy 437.990742 -106.023156) (xy 437.98363 -106.005122) (xy 437.977026 -105.998264)
			(xy 437.957756 -105.976936) (xy 437.92519 -105.929574) (xy 437.900098 -105.877863) (xy 437.883047 -105.822972)
			(xy 437.874423 -105.766145) (xy 437.873902 -105.737406) (xy 437.874388 -105.710155) (xy 437.882144 -105.656207)
			(xy 437.897499 -105.603912) (xy 437.920141 -105.554335) (xy 437.949607 -105.508485) (xy 437.985298 -105.467294)
			(xy 438.026489 -105.431603) (xy 438.072339 -105.402137) (xy 438.121916 -105.379495) (xy 438.174211 -105.36414)
			(xy 438.228159 -105.356384) (xy 438.282661 -105.356384) (xy 438.336609 -105.36414) (xy 438.388904 -105.379495)
			(xy 438.438481 -105.402137) (xy 438.484331 -105.431603) (xy 438.525522 -105.467294) (xy 438.561213 -105.508485)
			(xy 438.590679 -105.554335) (xy 438.613321 -105.603912) (xy 438.628676 -105.656207) (xy 438.636432 -105.710155)
			(xy 438.636918 -105.737406) (xy 438.636393 -105.766145) (xy 438.62777 -105.822972) (xy 438.61072 -105.877862)
			(xy 438.585629 -105.929574) (xy 438.553064 -105.976937) (xy 438.533794 -105.998264) (xy 438.52719 -106.005122)
			(xy 438.520078 -106.023156) (xy 438.520078 -106.112056) (xy 438.52719 -106.13009) (xy 438.533794 -106.136948)
			(xy 438.55307 -106.15827) (xy 438.585633 -106.205634) (xy 438.610724 -106.257346) (xy 438.627772 -106.312238)
			(xy 438.636394 -106.369065) (xy 438.636393 -106.426543) (xy 438.62777 -106.483371) (xy 438.61072 -106.538262)
			(xy 438.585629 -106.589974) (xy 438.553064 -106.637337) (xy 438.533794 -106.658664) (xy 438.52719 -106.665522)
			(xy 438.520078 -106.683556) (xy 438.520078 -106.772456) (xy 438.52719 -106.79049) (xy 438.533794 -106.797348)
			(xy 438.553056 -106.818683) (xy 438.585626 -106.866042) (xy 438.610721 -106.917751) (xy 438.627773 -106.972641)
			(xy 438.636397 -107.029467) (xy 438.636918 -107.058206) (xy 438.636432 -107.085457) (xy 438.628676 -107.139405)
			(xy 438.613321 -107.1917) (xy 438.590679 -107.241277) (xy 438.561213 -107.287127) (xy 438.525522 -107.328318)
			(xy 438.484331 -107.364009) (xy 438.438481 -107.393475) (xy 438.388904 -107.416117) (xy 438.336609 -107.431472)
			(xy 438.282661 -107.439228) (xy 438.228159 -107.439228) (xy 438.174211 -107.431472) (xy 438.121916 -107.416117)
			(xy 438.072339 -107.393475) (xy 438.026489 -107.364009) (xy 437.985298 -107.328318) (xy 437.949607 -107.287127)
			(xy 437.920141 -107.241277) (xy 437.897499 -107.1917) (xy 437.882144 -107.139405) (xy 437.874388 -107.085457)
			(xy 437.873902 -107.058206) (xy 431.215047 -107.058206) (xy 430.952994 -108.379006) (xy 438.762902 -108.379006)
			(xy 438.763429 -108.350267) (xy 438.772051 -108.29344) (xy 438.7891 -108.238549) (xy 438.814191 -108.186837)
			(xy 438.846755 -108.139475) (xy 438.866026 -108.118148) (xy 438.87263 -108.11129) (xy 438.879742 -108.093256)
			(xy 438.879742 -108.004356) (xy 438.87263 -107.986322) (xy 438.866026 -107.979464) (xy 438.846761 -107.958132)
			(xy 438.814195 -107.910771) (xy 438.789103 -107.85906) (xy 438.772053 -107.80417) (xy 438.76343 -107.747343)
			(xy 438.763429 -107.689866) (xy 438.772051 -107.633039) (xy 438.7891 -107.578149) (xy 438.814191 -107.526437)
			(xy 438.846756 -107.479075) (xy 438.866026 -107.457748) (xy 438.87263 -107.45089) (xy 438.879742 -107.432856)
			(xy 438.879742 -107.343956) (xy 438.87263 -107.325922) (xy 438.866026 -107.319064) (xy 438.846761 -107.297732)
			(xy 438.814195 -107.250371) (xy 438.789103 -107.19866) (xy 438.772053 -107.14377) (xy 438.76343 -107.086943)
			(xy 438.763429 -107.029466) (xy 438.772051 -106.972639) (xy 438.7891 -106.917749) (xy 438.814191 -106.866037)
			(xy 438.846756 -106.818675) (xy 438.866026 -106.797348) (xy 438.87263 -106.79049) (xy 438.879742 -106.772456)
			(xy 438.879742 -106.683556) (xy 438.87263 -106.665522) (xy 438.866026 -106.658664) (xy 438.846761 -106.637332)
			(xy 438.814195 -106.589971) (xy 438.789103 -106.53826) (xy 438.772053 -106.48337) (xy 438.76343 -106.426543)
			(xy 438.763429 -106.369066) (xy 438.772051 -106.312239) (xy 438.7891 -106.257349) (xy 438.814191 -106.205637)
			(xy 438.846756 -106.158275) (xy 438.866026 -106.136948) (xy 438.87263 -106.13009) (xy 438.879742 -106.112056)
			(xy 438.879742 -106.023156) (xy 438.87263 -106.005122) (xy 438.866026 -105.998264) (xy 438.846761 -105.976932)
			(xy 438.814195 -105.929571) (xy 438.789103 -105.87786) (xy 438.772053 -105.82297) (xy 438.76343 -105.766143)
			(xy 438.763429 -105.708666) (xy 438.772051 -105.651839) (xy 438.7891 -105.596949) (xy 438.814191 -105.545237)
			(xy 438.846756 -105.497875) (xy 438.866026 -105.476548) (xy 438.87263 -105.46969) (xy 438.879742 -105.451656)
			(xy 438.879742 -105.362756) (xy 438.87263 -105.344722) (xy 438.866026 -105.337864) (xy 438.846761 -105.316532)
			(xy 438.814195 -105.269171) (xy 438.789103 -105.21746) (xy 438.772053 -105.16257) (xy 438.76343 -105.105743)
			(xy 438.763429 -105.048266) (xy 438.772051 -104.991439) (xy 438.7891 -104.936549) (xy 438.814191 -104.884837)
			(xy 438.846756 -104.837475) (xy 438.866026 -104.816148) (xy 438.87263 -104.80929) (xy 438.879742 -104.791256)
			(xy 438.879742 -104.702356) (xy 438.87263 -104.684322) (xy 438.866026 -104.677464) (xy 438.846761 -104.656132)
			(xy 438.814195 -104.608771) (xy 438.789103 -104.55706) (xy 438.772053 -104.50217) (xy 438.76343 -104.445343)
			(xy 438.763429 -104.387866) (xy 438.772051 -104.331039) (xy 438.7891 -104.276149) (xy 438.814191 -104.224437)
			(xy 438.846756 -104.177075) (xy 438.866026 -104.155748) (xy 438.87263 -104.14889) (xy 438.879742 -104.130856)
			(xy 438.879742 -104.041956) (xy 438.87263 -104.023922) (xy 438.866026 -104.017064) (xy 438.846761 -103.995732)
			(xy 438.814195 -103.948371) (xy 438.789103 -103.89666) (xy 438.772053 -103.84177) (xy 438.76343 -103.784943)
			(xy 438.763429 -103.727466) (xy 438.772051 -103.670639) (xy 438.7891 -103.615749) (xy 438.814191 -103.564037)
			(xy 438.846756 -103.516675) (xy 438.866026 -103.495348) (xy 438.87263 -103.48849) (xy 438.879742 -103.470456)
			(xy 438.879742 -103.381556) (xy 438.87263 -103.363522) (xy 438.866026 -103.356664) (xy 438.846756 -103.335336)
			(xy 438.81419 -103.287974) (xy 438.789098 -103.236263) (xy 438.772047 -103.181372) (xy 438.763423 -103.124545)
			(xy 438.762902 -103.095806) (xy 438.763344 -103.068599) (xy 438.771069 -103.014735) (xy 438.786375 -102.962517)
			(xy 438.808953 -102.913008) (xy 438.838342 -102.867212) (xy 438.873946 -102.826063) (xy 438.915041 -102.790395)
			(xy 438.937654 -102.775258) (xy 438.946036 -102.769924) (xy 438.957212 -102.753668) (xy 438.9755 -102.674674)
			(xy 438.977308 -102.665045) (xy 438.974311 -102.645703) (xy 438.969658 -102.637082) (xy 438.969404 -102.637082)
			(xy 438.969404 -102.636574) (xy 438.956199 -102.614063) (xy 438.935343 -102.566221) (xy 438.921193 -102.515987)
			(xy 438.914009 -102.464294) (xy 438.913524 -102.4382) (xy 438.91401 -102.410949) (xy 438.921766 -102.357001)
			(xy 438.937121 -102.304706) (xy 438.959763 -102.255129) (xy 438.989229 -102.209279) (xy 439.02492 -102.168088)
			(xy 439.066111 -102.132397) (xy 439.111961 -102.102931) (xy 439.161538 -102.080289) (xy 439.213833 -102.064934)
			(xy 439.267781 -102.057178) (xy 439.322283 -102.057178) (xy 439.376231 -102.064934) (xy 439.428526 -102.080289)
			(xy 439.478103 -102.102931) (xy 439.523953 -102.132397) (xy 439.565144 -102.168088) (xy 439.600835 -102.209279)
			(xy 439.630301 -102.255129) (xy 439.652943 -102.304706) (xy 439.668298 -102.357001) (xy 439.676054 -102.410949)
			(xy 439.67654 -102.4382) (xy 439.676083 -102.465407) (xy 439.668359 -102.519269) (xy 439.653054 -102.571485)
			(xy 439.630478 -102.620994) (xy 439.601091 -102.666789) (xy 439.56549 -102.70794) (xy 439.524399 -102.743609)
			(xy 439.501788 -102.758748) (xy 439.493406 -102.764082) (xy 439.48223 -102.780338) (xy 439.463942 -102.859332)
			(xy 439.462138 -102.868962) (xy 439.465134 -102.888302) (xy 439.469784 -102.896924) (xy 439.470038 -102.896924)
			(xy 439.470038 -102.897432) (xy 439.48325 -102.919939) (xy 439.504103 -102.967783) (xy 439.518251 -103.018018)
			(xy 439.525433 -103.069712) (xy 439.525918 -103.095806) (xy 439.525393 -103.124545) (xy 439.51677 -103.181372)
			(xy 439.49972 -103.236262) (xy 439.474629 -103.287974) (xy 439.442064 -103.335337) (xy 439.422794 -103.356664)
			(xy 439.41619 -103.363522) (xy 439.409078 -103.381556) (xy 439.409078 -103.470456) (xy 439.41619 -103.48849)
			(xy 439.422794 -103.495348) (xy 439.44207 -103.51667) (xy 439.474633 -103.564034) (xy 439.499724 -103.615746)
			(xy 439.516772 -103.670638) (xy 439.525394 -103.727465) (xy 439.525393 -103.784943) (xy 439.51677 -103.841771)
			(xy 439.49972 -103.896662) (xy 439.474629 -103.948374) (xy 439.442064 -103.995737) (xy 439.422794 -104.017064)
			(xy 439.417168 -104.022906) (xy 444.16599 -104.022906) (xy 444.166465 -103.996592) (xy 444.173698 -103.944464)
			(xy 444.188016 -103.893822) (xy 444.209147 -103.845623) (xy 444.236692 -103.800779) (xy 444.270129 -103.760139)
			(xy 444.28918 -103.741982) (xy 444.296589 -103.734466) (xy 444.30511 -103.715182) (xy 444.30569 -103.704644)
			(xy 444.30569 -103.629968) (xy 444.30514 -103.619421) (xy 444.29662 -103.600125) (xy 444.28918 -103.59263)
			(xy 444.270142 -103.574457) (xy 444.236684 -103.53383) (xy 444.209123 -103.488994) (xy 444.187982 -103.440796)
			(xy 444.173661 -103.390152) (xy 444.166431 -103.338021) (xy 444.16599 -103.311706) (xy 444.166461 -103.284453)
			(xy 444.174217 -103.230503) (xy 444.189572 -103.178205) (xy 444.212214 -103.128625) (xy 444.241681 -103.082772)
			(xy 444.277374 -103.04158) (xy 444.318566 -103.005886) (xy 444.364418 -102.976418) (xy 444.413998 -102.953775)
			(xy 444.466295 -102.938419) (xy 444.520245 -102.930661) (xy 444.547498 -102.930198) (xy 444.575163 -102.930713)
			(xy 444.629912 -102.938712) (xy 444.682933 -102.954528) (xy 444.733117 -102.977831) (xy 444.779413 -103.008132)
			(xy 444.820851 -103.044796) (xy 444.856564 -103.087057) (xy 444.871602 -103.110284) (xy 444.878229 -103.119969)
			(xy 444.898098 -103.132408) (xy 444.909702 -103.13416) (xy 444.989712 -103.142034) (xy 445.001351 -103.14267)
			(xy 445.023189 -103.134588) (xy 445.031622 -103.12654) (xy 445.031876 -103.126286) (xy 445.049936 -103.107683)
			(xy 445.090272 -103.075107) (xy 445.134651 -103.048297) (xy 445.182254 -103.027749) (xy 445.232202 -103.01384)
			(xy 445.283574 -103.006827) (xy 445.309498 -103.006398) (xy 445.336751 -103.006857) (xy 445.390702 -103.014614)
			(xy 445.443001 -103.02997) (xy 445.492581 -103.052613) (xy 445.538435 -103.082081) (xy 445.579628 -103.117775)
			(xy 445.615321 -103.158969) (xy 445.644789 -103.204822) (xy 445.667431 -103.254403) (xy 445.682787 -103.306701)
			(xy 445.690543 -103.360653) (xy 445.691006 -103.387906) (xy 445.690542 -103.415276) (xy 445.682723 -103.469455)
			(xy 445.667234 -103.521958) (xy 445.644392 -103.571705) (xy 445.614667 -103.617672) (xy 445.597026 -103.638604)
			(xy 445.596772 -103.638858) (xy 445.591194 -103.64595) (xy 445.584943 -103.662863) (xy 445.58458 -103.671878)
			(xy 445.58458 -103.685653) (xy 456.792771 -103.685653) (xy 456.792771 -103.631147) (xy 456.800529 -103.577195)
			(xy 456.815886 -103.524896) (xy 456.838531 -103.475315) (xy 456.868001 -103.429462) (xy 456.903697 -103.38827)
			(xy 456.944893 -103.352578) (xy 456.990749 -103.323112) (xy 457.040332 -103.300473) (xy 457.092632 -103.285121)
			(xy 457.146585 -103.277369) (xy 457.173838 -103.276908) (xy 457.200153 -103.277348) (xy 457.252283 -103.284588)
			(xy 457.302926 -103.298912) (xy 457.351125 -103.32005) (xy 457.395968 -103.347601) (xy 457.436606 -103.381044)
			(xy 457.454762 -103.400098) (xy 457.462296 -103.407484) (xy 457.481567 -103.416017) (xy 457.4921 -103.416608)
			(xy 457.566776 -103.416608) (xy 457.577325 -103.416077) (xy 457.596621 -103.407543) (xy 457.604114 -103.400098)
			(xy 457.623934 -103.37931) (xy 457.668706 -103.343335) (xy 457.718364 -103.314475) (xy 457.771786 -103.293382)
			(xy 457.827765 -103.280533) (xy 457.885038 -103.276218) (xy 457.942311 -103.280533) (xy 457.99829 -103.293382)
			(xy 458.051712 -103.314475) (xy 458.10137 -103.343335) (xy 458.146142 -103.37931) (xy 458.165962 -103.400098)
			(xy 458.173496 -103.407484) (xy 458.192767 -103.416017) (xy 458.2033 -103.416608) (xy 458.277976 -103.416608)
			(xy 458.288525 -103.416077) (xy 458.307821 -103.407543) (xy 458.315314 -103.400098) (xy 458.333469 -103.381042)
			(xy 458.374099 -103.347585) (xy 458.418939 -103.320026) (xy 458.46714 -103.298888) (xy 458.517788 -103.284571)
			(xy 458.569922 -103.277346) (xy 458.596238 -103.276908) (xy 458.623489 -103.277364) (xy 458.677434 -103.285126)
			(xy 458.729727 -103.300485) (xy 458.779301 -103.323129) (xy 458.825149 -103.352598) (xy 458.866336 -103.388291)
			(xy 458.902025 -103.429482) (xy 458.931489 -103.475332) (xy 458.954129 -103.524909) (xy 458.969482 -103.577203)
			(xy 458.977238 -103.631149) (xy 458.977238 -103.685651) (xy 458.969482 -103.739597) (xy 458.954129 -103.791891)
			(xy 458.931489 -103.841468) (xy 458.902025 -103.887319) (xy 458.866336 -103.928509) (xy 458.825149 -103.964202)
			(xy 458.779301 -103.993671) (xy 458.729727 -104.016315) (xy 458.677434 -104.031674) (xy 458.623489 -104.039436)
			(xy 458.596238 -104.039924) (xy 458.569923 -104.03949) (xy 458.517793 -104.032247) (xy 458.46715 -104.017921)
			(xy 458.418952 -103.996782) (xy 458.374109 -103.969231) (xy 458.33347 -103.935788) (xy 458.315314 -103.916734)
			(xy 458.307785 -103.909341) (xy 458.288511 -103.900811) (xy 458.277976 -103.900224) (xy 458.2033 -103.900224)
			(xy 458.192748 -103.900733) (xy 458.173452 -103.909281) (xy 458.165962 -103.916734) (xy 458.146142 -103.937522)
			(xy 458.10137 -103.973497) (xy 458.051712 -104.002357) (xy 457.99829 -104.02345) (xy 457.942311 -104.036299)
			(xy 457.885038 -104.040614) (xy 457.827765 -104.036299) (xy 457.771786 -104.02345) (xy 457.718364 -104.002357)
			(xy 457.668706 -103.973497) (xy 457.623934 -103.937522) (xy 457.604114 -103.916734) (xy 457.596585 -103.909341)
			(xy 457.577311 -103.900811) (xy 457.566776 -103.900224) (xy 457.4921 -103.900224) (xy 457.481548 -103.900733)
			(xy 457.462252 -103.909281) (xy 457.454762 -103.916734) (xy 457.436625 -103.935807) (xy 457.39599 -103.969262)
			(xy 457.351146 -103.996817) (xy 457.302942 -104.017953) (xy 457.252291 -104.032266) (xy 457.200155 -104.039487)
			(xy 457.173838 -104.039924) (xy 457.146585 -104.039431) (xy 457.092632 -104.031679) (xy 457.040332 -104.016327)
			(xy 456.990749 -103.993688) (xy 456.944893 -103.964222) (xy 456.903697 -103.92853) (xy 456.868001 -103.887338)
			(xy 456.838531 -103.841485) (xy 456.815886 -103.791904) (xy 456.800529 -103.739605) (xy 456.792771 -103.685653)
			(xy 445.58458 -103.685653) (xy 445.58458 -103.738934) (xy 445.584925 -103.747952) (xy 445.591181 -103.764869)
			(xy 445.596772 -103.771954) (xy 445.597026 -103.771954) (xy 445.597026 -103.772208) (xy 445.614686 -103.793123)
			(xy 445.644394 -103.839101) (xy 445.667226 -103.888853) (xy 445.682712 -103.941357) (xy 445.690535 -103.995536)
			(xy 445.691006 -104.022906) (xy 445.690528 -104.050157) (xy 445.68277 -104.104106) (xy 445.667414 -104.156401)
			(xy 445.644772 -104.205978) (xy 445.615305 -104.251828) (xy 445.579613 -104.293019) (xy 445.538422 -104.32871)
			(xy 445.492571 -104.358176) (xy 445.442993 -104.380817) (xy 445.390698 -104.396172) (xy 445.336749 -104.403928)
			(xy 445.309498 -104.404414) (xy 445.280579 -104.40393) (xy 445.223405 -104.395198) (xy 445.168204 -104.377936)
			(xy 445.116242 -104.352538) (xy 445.068709 -104.319587) (xy 445.026696 -104.279838) (xy 445.008508 -104.257348)
			(xy 445.000897 -104.248546) (xy 444.979999 -104.238361) (xy 444.968376 -104.23779) (xy 444.88862 -104.23779)
			(xy 444.876992 -104.238359) (xy 444.856082 -104.248527) (xy 444.848488 -104.257348) (xy 444.830316 -104.279847)
			(xy 444.788291 -104.319579) (xy 444.740751 -104.352515) (xy 444.688787 -104.3779) (xy 444.633587 -104.395154)
			(xy 444.576415 -104.40388) (xy 444.547498 -104.404414) (xy 444.520247 -104.403924) (xy 444.4663 -104.396167)
			(xy 444.414005 -104.380812) (xy 444.364429 -104.358171) (xy 444.318578 -104.328706) (xy 444.277388 -104.293014)
			(xy 444.241697 -104.251825) (xy 444.21223 -104.205975) (xy 444.189589 -104.156398) (xy 444.174233 -104.104104)
			(xy 444.166476 -104.050157) (xy 444.16599 -104.022906) (xy 439.417168 -104.022906) (xy 439.41619 -104.023922)
			(xy 439.409078 -104.041956) (xy 439.409078 -104.130856) (xy 439.41619 -104.14889) (xy 439.422794 -104.155748)
			(xy 439.44207 -104.17707) (xy 439.474633 -104.224434) (xy 439.499724 -104.276146) (xy 439.516772 -104.331038)
			(xy 439.525394 -104.387865) (xy 439.525393 -104.445343) (xy 439.51677 -104.502171) (xy 439.49972 -104.557062)
			(xy 439.474629 -104.608774) (xy 439.442064 -104.656137) (xy 439.422794 -104.677464) (xy 439.41619 -104.684322)
			(xy 439.409078 -104.702356) (xy 439.409078 -104.791256) (xy 439.41619 -104.80929) (xy 439.422794 -104.816148)
			(xy 439.44207 -104.83747) (xy 439.474633 -104.884834) (xy 439.499724 -104.936546) (xy 439.516772 -104.991438)
			(xy 439.525394 -105.048265) (xy 439.525393 -105.08445) (xy 444.044072 -105.08445) (xy 444.044072 -105.02995)
			(xy 444.051828 -104.976004) (xy 444.067181 -104.923711) (xy 444.089821 -104.874135) (xy 444.119285 -104.828285)
			(xy 444.154974 -104.787095) (xy 444.196161 -104.751403) (xy 444.242008 -104.721935) (xy 444.291582 -104.699292)
			(xy 444.343874 -104.683934) (xy 444.39782 -104.676174) (xy 444.42507 -104.675686) (xy 444.452439 -104.676173)
			(xy 444.506617 -104.683986) (xy 444.55912 -104.699471) (xy 444.608867 -104.722308) (xy 444.654835 -104.752027)
			(xy 444.675768 -104.769666) (xy 444.676022 -104.76992) (xy 444.683096 -104.775524) (xy 444.700023 -104.78176)
			(xy 444.709042 -104.782112) (xy 444.776098 -104.782112) (xy 444.785114 -104.781751) (xy 444.802031 -104.775506)
			(xy 444.809118 -104.76992) (xy 444.809118 -104.769666) (xy 444.809372 -104.769666) (xy 444.830305 -104.752025)
			(xy 444.876273 -104.722301) (xy 444.926019 -104.699455) (xy 444.978521 -104.683959) (xy 445.032699 -104.67613)
			(xy 445.087441 -104.67613) (xy 445.141619 -104.683959) (xy 445.194121 -104.699455) (xy 445.243867 -104.722301)
			(xy 445.289835 -104.752025) (xy 445.310768 -104.769666) (xy 445.311022 -104.76992) (xy 445.318096 -104.775524)
			(xy 445.335023 -104.78176) (xy 445.344042 -104.782112) (xy 445.411098 -104.782112) (xy 445.420114 -104.781751)
			(xy 445.437031 -104.775506) (xy 445.444118 -104.76992) (xy 445.444118 -104.769666) (xy 445.444372 -104.769666)
			(xy 445.465305 -104.752025) (xy 445.511273 -104.722301) (xy 445.561019 -104.699455) (xy 445.613521 -104.683959)
			(xy 445.667699 -104.67613) (xy 445.722441 -104.67613) (xy 445.776619 -104.683959) (xy 445.829121 -104.699455)
			(xy 445.878867 -104.722301) (xy 445.924835 -104.752025) (xy 445.945768 -104.769666) (xy 445.946022 -104.76992)
			(xy 445.953096 -104.775524) (xy 445.970023 -104.78176) (xy 445.979042 -104.782112) (xy 446.046098 -104.782112)
			(xy 446.055114 -104.781751) (xy 446.072031 -104.775506) (xy 446.079118 -104.76992) (xy 446.079118 -104.769666)
			(xy 446.079372 -104.769666) (xy 446.100299 -104.752021) (xy 446.146274 -104.722311) (xy 446.196023 -104.699477)
			(xy 446.248524 -104.683987) (xy 446.302701 -104.67616) (xy 446.33007 -104.675686) (xy 446.357324 -104.676159)
			(xy 446.411277 -104.683913) (xy 446.463578 -104.699266) (xy 446.513161 -104.721906) (xy 446.559017 -104.751373)
			(xy 446.600213 -104.787066) (xy 446.635909 -104.828259) (xy 446.665379 -104.874113) (xy 446.688024 -104.923694)
			(xy 446.703381 -104.975994) (xy 446.711139 -105.029946) (xy 446.711139 -105.084454) (xy 446.703381 -105.138406)
			(xy 446.688024 -105.190706) (xy 446.665379 -105.240287) (xy 446.635909 -105.286141) (xy 446.600213 -105.327334)
			(xy 446.559017 -105.363027) (xy 446.513161 -105.392494) (xy 446.463578 -105.415134) (xy 446.411277 -105.430487)
			(xy 446.357324 -105.438241) (xy 446.33007 -105.438702) (xy 446.302699 -105.438253) (xy 446.248519 -105.430431)
			(xy 446.196016 -105.414938) (xy 446.14627 -105.392092) (xy 446.100303 -105.362365) (xy 446.079372 -105.344722)
			(xy 446.079118 -105.344468) (xy 446.072033 -105.338879) (xy 446.055115 -105.332635) (xy 446.046098 -105.332276)
			(xy 445.979042 -105.332276) (xy 445.970028 -105.332658) (xy 445.953111 -105.338889) (xy 445.946022 -105.344468)
			(xy 445.945768 -105.344722) (xy 445.924835 -105.362363) (xy 445.878867 -105.392087) (xy 445.829121 -105.414933)
			(xy 445.776619 -105.430429) (xy 445.722441 -105.438258) (xy 445.667699 -105.438258) (xy 445.613521 -105.430429)
			(xy 445.561019 -105.414933) (xy 445.511273 -105.392087) (xy 445.465305 -105.362363) (xy 445.444372 -105.344722)
			(xy 445.444118 -105.344468) (xy 445.437033 -105.338879) (xy 445.420115 -105.332635) (xy 445.411098 -105.332276)
			(xy 445.344042 -105.332276) (xy 445.335028 -105.332658) (xy 445.318111 -105.338889) (xy 445.311022 -105.344468)
			(xy 445.311022 -105.344722) (xy 445.310768 -105.344722) (xy 445.289835 -105.362363) (xy 445.243867 -105.392087)
			(xy 445.194121 -105.414933) (xy 445.141619 -105.430429) (xy 445.087441 -105.438258) (xy 445.032699 -105.438258)
			(xy 444.978521 -105.430429) (xy 444.926019 -105.414933) (xy 444.876273 -105.392087) (xy 444.830305 -105.362363)
			(xy 444.809372 -105.344722) (xy 444.809118 -105.344468) (xy 444.802033 -105.338879) (xy 444.785115 -105.332635)
			(xy 444.776098 -105.332276) (xy 444.709042 -105.332276) (xy 444.700028 -105.332658) (xy 444.683111 -105.338889)
			(xy 444.676022 -105.344468) (xy 444.676022 -105.344722) (xy 444.675768 -105.344722) (xy 444.654824 -105.362346)
			(xy 444.608854 -105.392059) (xy 444.55911 -105.414898) (xy 444.506612 -105.430393) (xy 444.452438 -105.438225)
			(xy 444.42507 -105.438702) (xy 444.39782 -105.438226) (xy 444.343874 -105.430466) (xy 444.291582 -105.415108)
			(xy 444.242008 -105.392465) (xy 444.196161 -105.362997) (xy 444.154974 -105.327305) (xy 444.119285 -105.286115)
			(xy 444.089821 -105.240265) (xy 444.067181 -105.190689) (xy 444.051828 -105.138396) (xy 444.044072 -105.08445)
			(xy 439.525393 -105.08445) (xy 439.525393 -105.105743) (xy 439.51677 -105.162571) (xy 439.49972 -105.217462)
			(xy 439.474629 -105.269174) (xy 439.442064 -105.316537) (xy 439.422794 -105.337864) (xy 439.41619 -105.344722)
			(xy 439.409078 -105.362756) (xy 439.409078 -105.451656) (xy 439.41619 -105.46969) (xy 439.422794 -105.476548)
			(xy 439.44207 -105.49787) (xy 439.474633 -105.545234) (xy 439.499724 -105.596946) (xy 439.516772 -105.651838)
			(xy 439.525394 -105.708665) (xy 439.525393 -105.766143) (xy 439.51677 -105.822971) (xy 439.49972 -105.877862)
			(xy 439.474629 -105.929574) (xy 439.442064 -105.976937) (xy 439.422794 -105.998264) (xy 439.41619 -106.005122)
			(xy 439.409078 -106.023156) (xy 439.409078 -106.112056) (xy 439.41619 -106.13009) (xy 439.422794 -106.136948)
			(xy 439.44207 -106.15827) (xy 439.474633 -106.205634) (xy 439.499724 -106.257346) (xy 439.516772 -106.312238)
			(xy 439.525394 -106.369065) (xy 439.525393 -106.426543) (xy 439.51677 -106.483371) (xy 439.49972 -106.538262)
			(xy 439.474629 -106.589974) (xy 439.442064 -106.637337) (xy 439.422794 -106.658664) (xy 439.41619 -106.665522)
			(xy 439.409078 -106.683556) (xy 439.409078 -106.772456) (xy 439.41619 -106.79049) (xy 439.422794 -106.797348)
			(xy 439.427403 -106.802446) (xy 456.721028 -106.802446) (xy 456.721028 -106.747954) (xy 456.728782 -106.694018)
			(xy 456.744133 -106.641733) (xy 456.766768 -106.592166) (xy 456.796226 -106.546323) (xy 456.831909 -106.50514)
			(xy 456.873088 -106.469453) (xy 456.918927 -106.439989) (xy 456.968492 -106.417349) (xy 457.020775 -106.401992)
			(xy 457.07471 -106.394231) (xy 457.101956 -106.393742) (xy 457.128272 -106.394159) (xy 457.180403 -106.401402)
			(xy 457.231047 -106.41573) (xy 457.279246 -106.436872) (xy 457.324089 -106.464428) (xy 457.364725 -106.497876)
			(xy 457.38288 -106.516932) (xy 457.390416 -106.524317) (xy 457.409685 -106.532853) (xy 457.420218 -106.533442)
			(xy 457.494894 -106.533442) (xy 457.505443 -106.532911) (xy 457.524738 -106.524376) (xy 457.532232 -106.516932)
			(xy 457.552052 -106.496144) (xy 457.596824 -106.460169) (xy 457.646482 -106.431309) (xy 457.699904 -106.410216)
			(xy 457.755883 -106.397367) (xy 457.813156 -106.393052) (xy 457.870429 -106.397367) (xy 457.926408 -106.410216)
			(xy 457.97983 -106.431309) (xy 458.029488 -106.460169) (xy 458.07426 -106.496144) (xy 458.09408 -106.516932)
			(xy 458.101616 -106.524317) (xy 458.120885 -106.532853) (xy 458.131418 -106.533442) (xy 458.206094 -106.533442)
			(xy 458.216643 -106.532911) (xy 458.235938 -106.524376) (xy 458.243432 -106.516932) (xy 458.261585 -106.497874)
			(xy 458.302215 -106.464416) (xy 458.347055 -106.436856) (xy 458.395257 -106.415718) (xy 458.445905 -106.401402)
			(xy 458.49804 -106.394179) (xy 458.524356 -106.393742) (xy 458.551614 -106.394102) (xy 458.605577 -106.401855)
			(xy 458.657887 -106.417209) (xy 458.70748 -106.439852) (xy 458.753344 -106.469323) (xy 458.794548 -106.505021)
			(xy 458.830251 -106.54622) (xy 458.859727 -106.592082) (xy 458.882375 -106.641671) (xy 458.897736 -106.69398)
			(xy 458.905495 -106.747942) (xy 458.905495 -106.802458) (xy 458.897736 -106.85642) (xy 458.882375 -106.908729)
			(xy 458.859727 -106.958318) (xy 458.830251 -107.00418) (xy 458.794548 -107.045379) (xy 458.753344 -107.081077)
			(xy 458.70748 -107.110548) (xy 458.657887 -107.133191) (xy 458.605577 -107.148545) (xy 458.551615 -107.156298)
			(xy 458.524356 -107.156758) (xy 458.49804 -107.156333) (xy 458.44591 -107.149092) (xy 458.395265 -107.134765)
			(xy 458.347066 -107.113625) (xy 458.302224 -107.08607) (xy 458.261587 -107.052624) (xy 458.243432 -107.033568)
			(xy 458.235891 -107.026188) (xy 458.216626 -107.017649) (xy 458.206094 -107.017058) (xy 458.131418 -107.017058)
			(xy 458.12087 -107.017596) (xy 458.101575 -107.026126) (xy 458.09408 -107.033568) (xy 458.07426 -107.054356)
			(xy 458.029488 -107.090331) (xy 457.97983 -107.119191) (xy 457.926408 -107.140284) (xy 457.870429 -107.153133)
			(xy 457.813156 -107.157448) (xy 457.755883 -107.153133) (xy 457.699904 -107.140284) (xy 457.646482 -107.119191)
			(xy 457.596824 -107.090331) (xy 457.552052 -107.054356) (xy 457.532232 -107.033568) (xy 457.524691 -107.026188)
			(xy 457.505426 -107.017649) (xy 457.494894 -107.017058) (xy 457.420218 -107.017058) (xy 457.40967 -107.017596)
			(xy 457.390375 -107.026126) (xy 457.38288 -107.033568) (xy 457.364721 -107.05262) (xy 457.324093 -107.086079)
			(xy 457.279253 -107.113639) (xy 457.231053 -107.134778) (xy 457.180406 -107.149096) (xy 457.128272 -107.15632)
			(xy 457.101956 -107.156758) (xy 457.07471 -107.156169) (xy 457.020775 -107.148408) (xy 456.968492 -107.133051)
			(xy 456.918927 -107.110411) (xy 456.873088 -107.080947) (xy 456.831909 -107.04526) (xy 456.796226 -107.004077)
			(xy 456.766768 -106.958234) (xy 456.744133 -106.908667) (xy 456.728782 -106.856382) (xy 456.721028 -106.802446)
			(xy 439.427403 -106.802446) (xy 439.44207 -106.81867) (xy 439.474633 -106.866034) (xy 439.499724 -106.917746)
			(xy 439.516772 -106.972638) (xy 439.525394 -107.029465) (xy 439.525393 -107.086943) (xy 439.51677 -107.143771)
			(xy 439.49972 -107.198662) (xy 439.474629 -107.250374) (xy 439.442064 -107.297737) (xy 439.422794 -107.319064)
			(xy 439.41619 -107.325922) (xy 439.409078 -107.343956) (xy 439.409078 -107.432856) (xy 439.41619 -107.45089)
			(xy 439.422794 -107.457748) (xy 439.44207 -107.47907) (xy 439.474633 -107.526434) (xy 439.499724 -107.578146)
			(xy 439.516772 -107.633038) (xy 439.525394 -107.689865) (xy 439.525393 -107.740249) (xy 443.984396 -107.740249)
			(xy 443.984396 -107.685751) (xy 443.992152 -107.631808) (xy 444.007505 -107.579517) (xy 444.030144 -107.529944)
			(xy 444.059607 -107.484096) (xy 444.095294 -107.442909) (xy 444.13648 -107.407219) (xy 444.182326 -107.377753)
			(xy 444.231898 -107.355112) (xy 444.284188 -107.339756) (xy 444.338131 -107.331998) (xy 444.36538 -107.33151)
			(xy 444.39275 -107.331985) (xy 444.446929 -107.339801) (xy 444.499432 -107.355287) (xy 444.549179 -107.378127)
			(xy 444.595146 -107.40785) (xy 444.616078 -107.42549) (xy 444.616332 -107.425744) (xy 444.62343 -107.431314)
			(xy 444.640338 -107.437569) (xy 444.649352 -107.437936) (xy 444.716408 -107.437936) (xy 444.725424 -107.437575)
			(xy 444.742341 -107.43133) (xy 444.749428 -107.425744) (xy 444.749428 -107.42549) (xy 444.749682 -107.42549)
			(xy 444.770615 -107.407849) (xy 444.816583 -107.378125) (xy 444.866329 -107.355279) (xy 444.918831 -107.339783)
			(xy 444.973009 -107.331954) (xy 445.027751 -107.331954) (xy 445.081929 -107.339783) (xy 445.134431 -107.355279)
			(xy 445.184177 -107.378125) (xy 445.230145 -107.407849) (xy 445.251078 -107.42549) (xy 445.251332 -107.425744)
			(xy 445.25843 -107.431314) (xy 445.275338 -107.437569) (xy 445.284352 -107.437936) (xy 445.351408 -107.437936)
			(xy 445.360424 -107.437575) (xy 445.377341 -107.43133) (xy 445.384428 -107.425744) (xy 445.384428 -107.42549)
			(xy 445.384682 -107.42549) (xy 445.405615 -107.407849) (xy 445.451583 -107.378125) (xy 445.501329 -107.355279)
			(xy 445.553831 -107.339783) (xy 445.608009 -107.331954) (xy 445.662751 -107.331954) (xy 445.716929 -107.339783)
			(xy 445.769431 -107.355279) (xy 445.819177 -107.378125) (xy 445.865145 -107.407849) (xy 445.886078 -107.42549)
			(xy 445.886332 -107.425744) (xy 445.89343 -107.431314) (xy 445.910338 -107.437569) (xy 445.919352 -107.437936)
			(xy 445.986408 -107.437936) (xy 445.995424 -107.437575) (xy 446.012341 -107.43133) (xy 446.019428 -107.425744)
			(xy 446.019428 -107.42549) (xy 446.019682 -107.42549) (xy 446.040609 -107.407844) (xy 446.086583 -107.378134)
			(xy 446.136332 -107.355299) (xy 446.188834 -107.33981) (xy 446.24301 -107.331983) (xy 446.27038 -107.33151)
			(xy 446.297635 -107.331936) (xy 446.351591 -107.339691) (xy 446.403894 -107.355046) (xy 446.453479 -107.377688)
			(xy 446.499336 -107.407157) (xy 446.540534 -107.442852) (xy 446.576231 -107.484047) (xy 446.605702 -107.529904)
			(xy 446.628347 -107.579488) (xy 446.643705 -107.63179) (xy 446.651463 -107.685745) (xy 446.651463 -107.740255)
			(xy 446.643705 -107.79421) (xy 446.628347 -107.846512) (xy 446.605702 -107.896096) (xy 446.576231 -107.941953)
			(xy 446.540534 -107.983148) (xy 446.499336 -108.018843) (xy 446.453479 -108.048312) (xy 446.403894 -108.070954)
			(xy 446.351591 -108.086309) (xy 446.297635 -108.094064) (xy 446.27038 -108.094526) (xy 446.243008 -108.09409)
			(xy 446.188827 -108.086267) (xy 446.136323 -108.070772) (xy 446.086577 -108.047924) (xy 446.040612 -108.018191)
			(xy 446.019682 -108.000546) (xy 446.019428 -108.000292) (xy 446.012338 -107.99471) (xy 445.995424 -107.988461)
			(xy 445.986408 -107.9881) (xy 445.919352 -107.9881) (xy 445.910338 -107.988482) (xy 445.893421 -107.994712)
			(xy 445.886332 -108.000292) (xy 445.886078 -108.000546) (xy 445.865145 -108.018187) (xy 445.819177 -108.047911)
			(xy 445.769431 -108.070757) (xy 445.716929 -108.086253) (xy 445.662751 -108.094082) (xy 445.608009 -108.094082)
			(xy 445.553831 -108.086253) (xy 445.501329 -108.070757) (xy 445.451583 -108.047911) (xy 445.405615 -108.018187)
			(xy 445.384682 -108.000546) (xy 445.384428 -108.000292) (xy 445.377338 -107.99471) (xy 445.360424 -107.988461)
			(xy 445.351408 -107.9881) (xy 445.284352 -107.9881) (xy 445.275338 -107.988482) (xy 445.258421 -107.994712)
			(xy 445.251332 -108.000292) (xy 445.251332 -108.000546) (xy 445.251078 -108.000546) (xy 445.230145 -108.018187)
			(xy 445.184177 -108.047911) (xy 445.134431 -108.070757) (xy 445.081929 -108.086253) (xy 445.027751 -108.094082)
			(xy 444.973009 -108.094082) (xy 444.918831 -108.086253) (xy 444.866329 -108.070757) (xy 444.816583 -108.047911)
			(xy 444.770615 -108.018187) (xy 444.749682 -108.000546) (xy 444.749428 -108.000292) (xy 444.742338 -107.99471)
			(xy 444.725424 -107.988461) (xy 444.716408 -107.9881) (xy 444.649352 -107.9881) (xy 444.640338 -107.988482)
			(xy 444.623421 -107.994712) (xy 444.616332 -108.000292) (xy 444.616332 -108.000546) (xy 444.616078 -108.000546)
			(xy 444.59512 -108.018154) (xy 444.549155 -108.047872) (xy 444.499415 -108.070715) (xy 444.446919 -108.086213)
			(xy 444.392748 -108.094048) (xy 444.36538 -108.094526) (xy 444.338131 -108.094002) (xy 444.284188 -108.086244)
			(xy 444.231898 -108.070888) (xy 444.182326 -108.048247) (xy 444.13648 -108.018781) (xy 444.095294 -107.983091)
			(xy 444.059607 -107.941904) (xy 444.030144 -107.896056) (xy 444.007505 -107.846483) (xy 443.992152 -107.794192)
			(xy 443.984396 -107.740249) (xy 439.525393 -107.740249) (xy 439.525393 -107.747343) (xy 439.51677 -107.804171)
			(xy 439.49972 -107.859062) (xy 439.474629 -107.910774) (xy 439.442064 -107.958137) (xy 439.422794 -107.979464)
			(xy 439.41619 -107.986322) (xy 439.409078 -108.004356) (xy 439.409078 -108.093256) (xy 439.41619 -108.11129)
			(xy 439.422794 -108.118148) (xy 439.442056 -108.139483) (xy 439.474626 -108.186842) (xy 439.499721 -108.238551)
			(xy 439.516773 -108.293441) (xy 439.525397 -108.350267) (xy 439.525918 -108.379006) (xy 439.525432 -108.406257)
			(xy 439.517676 -108.460205) (xy 439.502321 -108.5125) (xy 439.479679 -108.562077) (xy 439.474905 -108.569506)
			(xy 455.161142 -108.569506) (xy 455.161601 -108.542135) (xy 455.169419 -108.487956) (xy 455.184909 -108.435452)
			(xy 455.207753 -108.385705) (xy 455.23748 -108.339739) (xy 455.255122 -108.318808) (xy 455.255376 -108.318554)
			(xy 455.260955 -108.311463) (xy 455.267204 -108.294549) (xy 455.267568 -108.285534) (xy 455.267568 -108.218478)
			(xy 455.267229 -108.209459) (xy 455.26097 -108.192542) (xy 455.255376 -108.185458) (xy 455.255122 -108.185458)
			(xy 455.255122 -108.185204) (xy 455.237475 -108.164278) (xy 455.207763 -108.118304) (xy 455.184929 -108.068555)
			(xy 455.16944 -108.016053) (xy 455.161614 -107.961876) (xy 455.161142 -107.934506) (xy 455.161628 -107.907255)
			(xy 455.169384 -107.853307) (xy 455.184739 -107.801012) (xy 455.207381 -107.751435) (xy 455.236847 -107.705585)
			(xy 455.272538 -107.664394) (xy 455.313729 -107.628703) (xy 455.359579 -107.599237) (xy 455.409156 -107.576595)
			(xy 455.461451 -107.56124) (xy 455.515399 -107.553484) (xy 455.569901 -107.553484) (xy 455.623849 -107.56124)
			(xy 455.676144 -107.576595) (xy 455.725721 -107.599237) (xy 455.771571 -107.628703) (xy 455.812762 -107.664394)
			(xy 455.848453 -107.705585) (xy 455.877919 -107.751435) (xy 455.900561 -107.801012) (xy 455.915916 -107.853307)
			(xy 455.923672 -107.907255) (xy 455.924158 -107.934506) (xy 455.923706 -107.961877) (xy 455.915886 -108.016057)
			(xy 455.900394 -108.068561) (xy 455.877549 -108.118307) (xy 455.847821 -108.164273) (xy 455.830178 -108.185204)
			(xy 455.829924 -108.185458) (xy 455.82434 -108.192546) (xy 455.818094 -108.209462) (xy 455.817732 -108.218478)
			(xy 455.817732 -108.285534) (xy 455.818066 -108.294553) (xy 455.824329 -108.311471) (xy 455.829924 -108.318554)
			(xy 455.830178 -108.318554) (xy 455.830178 -108.318808) (xy 455.847831 -108.339729) (xy 455.877541 -108.385705)
			(xy 455.900375 -108.435455) (xy 455.915863 -108.487958) (xy 455.923687 -108.542136) (xy 455.924158 -108.569506)
			(xy 455.923672 -108.596757) (xy 455.915916 -108.650705) (xy 455.900561 -108.703) (xy 455.877919 -108.752577)
			(xy 455.848453 -108.798427) (xy 455.812762 -108.839618) (xy 455.771571 -108.875309) (xy 455.725721 -108.904775)
			(xy 455.676144 -108.927417) (xy 455.623849 -108.942772) (xy 455.569901 -108.950528) (xy 455.515399 -108.950528)
			(xy 455.461451 -108.942772) (xy 455.409156 -108.927417) (xy 455.359579 -108.904775) (xy 455.313729 -108.875309)
			(xy 455.272538 -108.839618) (xy 455.236847 -108.798427) (xy 455.207381 -108.752577) (xy 455.184739 -108.703)
			(xy 455.169384 -108.650705) (xy 455.161628 -108.596757) (xy 455.161142 -108.569506) (xy 439.474905 -108.569506)
			(xy 439.450213 -108.607927) (xy 439.414522 -108.649118) (xy 439.373331 -108.684809) (xy 439.327481 -108.714275)
			(xy 439.277904 -108.736917) (xy 439.225609 -108.752272) (xy 439.171661 -108.760028) (xy 439.117159 -108.760028)
			(xy 439.063211 -108.752272) (xy 439.010916 -108.736917) (xy 438.961339 -108.714275) (xy 438.915489 -108.684809)
			(xy 438.874298 -108.649118) (xy 438.838607 -108.607927) (xy 438.809141 -108.562077) (xy 438.786499 -108.5125)
			(xy 438.771144 -108.460205) (xy 438.763388 -108.406257) (xy 438.762902 -108.379006) (xy 430.952994 -108.379006)
			(xy 430.730098 -109.502448) (xy 457.714602 -109.502448) (xy 457.718673 -109.446826) (xy 457.730799 -109.392389)
			(xy 457.750722 -109.340298) (xy 457.778018 -109.291663) (xy 457.812104 -109.24752) (xy 457.852253 -109.208811)
			(xy 457.897611 -109.17636) (xy 457.947211 -109.150859) (xy 457.999995 -109.132852) (xy 458.054838 -109.122722)
			(xy 458.110572 -109.120685) (xy 458.166009 -109.126785) (xy 458.219966 -109.140891) (xy 458.271295 -109.162703)
			(xy 458.318901 -109.191757) (xy 458.361769 -109.227432) (xy 458.398986 -109.268969) (xy 458.429759 -109.315482)
			(xy 458.453431 -109.365979) (xy 458.469499 -109.419386) (xy 458.477619 -109.474562) (xy 458.478128 -109.502448)
			(xy 458.477619 -109.530334) (xy 458.469499 -109.58551) (xy 458.453431 -109.638917) (xy 458.429759 -109.689414)
			(xy 458.398986 -109.735927) (xy 458.361769 -109.777464) (xy 458.318901 -109.813139) (xy 458.271295 -109.842193)
			(xy 458.219966 -109.864005) (xy 458.166009 -109.878111) (xy 458.110572 -109.884211) (xy 458.054838 -109.882174)
			(xy 457.999995 -109.872044) (xy 457.947211 -109.854037) (xy 457.897611 -109.828536) (xy 457.852253 -109.796085)
			(xy 457.812104 -109.757376) (xy 457.778018 -109.713233) (xy 457.750722 -109.664598) (xy 457.730799 -109.612507)
			(xy 457.718673 -109.55807) (xy 457.714602 -109.502448) (xy 430.730098 -109.502448) (xy 430.508059 -110.621572)
			(xy 438.8612 -110.621572) (xy 438.861649 -110.595257) (xy 438.868887 -110.543128) (xy 438.88321 -110.492485)
			(xy 438.904346 -110.444286) (xy 438.931895 -110.399443) (xy 438.965337 -110.358804) (xy 438.98439 -110.340648)
			(xy 438.991815 -110.333146) (xy 439.000326 -110.313851) (xy 439.0009 -110.30331) (xy 439.0009 -110.228634)
			(xy 439.000366 -110.218085) (xy 438.991834 -110.198789) (xy 438.98439 -110.191296) (xy 438.965338 -110.173137)
			(xy 438.931881 -110.132508) (xy 438.904321 -110.087668) (xy 438.883182 -110.039468) (xy 438.868864 -109.988821)
			(xy 438.861639 -109.936688) (xy 438.8612 -109.910372) (xy 438.861686 -109.883121) (xy 438.869442 -109.829173)
			(xy 438.884797 -109.776878) (xy 438.907439 -109.727301) (xy 438.936905 -109.681451) (xy 438.972596 -109.64026)
			(xy 439.013787 -109.604569) (xy 439.059637 -109.575103) (xy 439.109214 -109.552461) (xy 439.161509 -109.537106)
			(xy 439.215457 -109.52935) (xy 439.269959 -109.52935) (xy 439.323907 -109.537106) (xy 439.376202 -109.552461)
			(xy 439.425779 -109.575103) (xy 439.471629 -109.604569) (xy 439.51282 -109.64026) (xy 439.548511 -109.681451)
			(xy 439.577977 -109.727301) (xy 439.600619 -109.776878) (xy 439.615974 -109.829173) (xy 439.62373 -109.883121)
			(xy 439.624216 -109.910372) (xy 439.623791 -109.936687) (xy 439.616547 -109.988818) (xy 439.602219 -110.039461)
			(xy 439.581079 -110.08766) (xy 439.553525 -110.132502) (xy 439.52008 -110.17314) (xy 439.501026 -110.191296)
			(xy 439.493628 -110.198821) (xy 439.485101 -110.218098) (xy 439.484516 -110.228634) (xy 439.484516 -110.30331)
			(xy 439.485022 -110.313863) (xy 439.493573 -110.333158) (xy 439.501026 -110.340648) (xy 439.520103 -110.358782)
			(xy 439.553557 -110.399417) (xy 439.581113 -110.444262) (xy 439.602247 -110.492467) (xy 439.61656 -110.543118)
			(xy 439.62378 -110.595255) (xy 439.624216 -110.621572) (xy 439.62373 -110.648823) (xy 439.615974 -110.702771)
			(xy 439.600619 -110.755066) (xy 439.577977 -110.804643) (xy 439.548511 -110.850493) (xy 439.51282 -110.891684)
			(xy 439.471629 -110.927375) (xy 439.425779 -110.956841) (xy 439.376202 -110.979483) (xy 439.323907 -110.994838)
			(xy 439.269959 -111.002594) (xy 439.215457 -111.002594) (xy 439.161509 -110.994838) (xy 439.109214 -110.979483)
			(xy 439.059637 -110.956841) (xy 439.013787 -110.927375) (xy 438.972596 -110.891684) (xy 438.936905 -110.850493)
			(xy 438.907439 -110.804643) (xy 438.884797 -110.755066) (xy 438.869442 -110.702771) (xy 438.861686 -110.648823)
			(xy 438.8612 -110.621572) (xy 430.508059 -110.621572) (xy 430.175454 -112.297972) (xy 441.369958 -112.297972)
			(xy 441.370388 -112.271657) (xy 441.377628 -112.219526) (xy 441.391953 -112.168882) (xy 441.413093 -112.120682)
			(xy 441.440646 -112.07584) (xy 441.474093 -112.035203) (xy 441.493148 -112.017048) (xy 441.500567 -112.009541)
			(xy 441.509083 -111.99025) (xy 441.509658 -111.97971) (xy 441.509658 -111.905034) (xy 441.509136 -111.894483)
			(xy 441.500597 -111.875187) (xy 441.493148 -111.867696) (xy 441.474088 -111.849546) (xy 441.440633 -111.808914)
			(xy 441.413076 -111.764072) (xy 441.391939 -111.71587) (xy 441.377622 -111.665222) (xy 441.370397 -111.613088)
			(xy 441.369958 -111.586772) (xy 441.370444 -111.559521) (xy 441.3782 -111.505573) (xy 441.393555 -111.453278)
			(xy 441.416197 -111.403701) (xy 441.445663 -111.357851) (xy 441.481354 -111.31666) (xy 441.522545 -111.280969)
			(xy 441.568395 -111.251503) (xy 441.617972 -111.228861) (xy 441.670267 -111.213506) (xy 441.724215 -111.20575)
			(xy 441.778717 -111.20575) (xy 441.832665 -111.213506) (xy 441.88496 -111.228861) (xy 441.934537 -111.251503)
			(xy 441.980387 -111.280969) (xy 442.021578 -111.31666) (xy 442.057269 -111.357851) (xy 442.086735 -111.403701)
			(xy 442.109377 -111.453278) (xy 442.124732 -111.505573) (xy 442.132488 -111.559521) (xy 442.132974 -111.586772)
			(xy 442.132563 -111.613088) (xy 442.125318 -111.665219) (xy 442.110988 -111.715863) (xy 442.089845 -111.764062)
			(xy 442.062289 -111.808904) (xy 442.02884 -111.849541) (xy 442.009784 -111.867696) (xy 442.00238 -111.875215)
			(xy 441.993857 -111.894497) (xy 441.993274 -111.905034) (xy 441.993274 -111.97971) (xy 441.993792 -111.990261)
			(xy 442.002336 -112.009556) (xy 442.009784 -112.017048) (xy 442.028853 -112.03519) (xy 442.062309 -112.075823)
			(xy 442.089867 -112.120665) (xy 442.111003 -112.168869) (xy 442.125317 -112.219519) (xy 442.132538 -112.271655)
			(xy 442.132974 -112.297972) (xy 443.401958 -112.297972) (xy 443.402388 -112.271657) (xy 443.409628 -112.219526)
			(xy 443.423953 -112.168882) (xy 443.445093 -112.120682) (xy 443.472646 -112.07584) (xy 443.506093 -112.035203)
			(xy 443.525148 -112.017048) (xy 443.532567 -112.009541) (xy 443.541083 -111.99025) (xy 443.541658 -111.97971)
			(xy 443.541658 -111.905034) (xy 443.541136 -111.894483) (xy 443.532597 -111.875187) (xy 443.525148 -111.867696)
			(xy 443.506088 -111.849546) (xy 443.472633 -111.808914) (xy 443.445076 -111.764072) (xy 443.423939 -111.71587)
			(xy 443.409622 -111.665222) (xy 443.402397 -111.613088) (xy 443.401958 -111.586772) (xy 443.402444 -111.559521)
			(xy 443.4102 -111.505573) (xy 443.425555 -111.453278) (xy 443.448197 -111.403701) (xy 443.477663 -111.357851)
			(xy 443.513354 -111.31666) (xy 443.554545 -111.280969) (xy 443.600395 -111.251503) (xy 443.649972 -111.228861)
			(xy 443.702267 -111.213506) (xy 443.756215 -111.20575) (xy 443.810717 -111.20575) (xy 443.864665 -111.213506)
			(xy 443.91696 -111.228861) (xy 443.966537 -111.251503) (xy 444.012387 -111.280969) (xy 444.053578 -111.31666)
			(xy 444.089269 -111.357851) (xy 444.118735 -111.403701) (xy 444.141377 -111.453278) (xy 444.156732 -111.505573)
			(xy 444.164488 -111.559521) (xy 444.164974 -111.586772) (xy 444.164563 -111.613088) (xy 444.157318 -111.665219)
			(xy 444.142988 -111.715863) (xy 444.121845 -111.764062) (xy 444.094289 -111.808904) (xy 444.06084 -111.849541)
			(xy 444.041784 -111.867696) (xy 444.03438 -111.875215) (xy 444.025857 -111.894497) (xy 444.025274 -111.905034)
			(xy 444.025274 -111.97971) (xy 444.025792 -111.990261) (xy 444.034336 -112.009556) (xy 444.041784 -112.017048)
			(xy 444.060853 -112.03519) (xy 444.06285 -112.037615) (xy 445.856202 -112.037615) (xy 445.860515 -111.980345)
			(xy 445.87336 -111.924368) (xy 445.894448 -111.870948) (xy 445.923303 -111.821291) (xy 445.959273 -111.776519)
			(xy 445.980058 -111.756698) (xy 445.987456 -111.749173) (xy 445.995984 -111.729896) (xy 445.996568 -111.71936)
			(xy 445.996568 -111.644684) (xy 445.99607 -111.63413) (xy 445.987514 -111.614835) (xy 445.980058 -111.607346)
			(xy 445.960975 -111.589218) (xy 445.927522 -111.548581) (xy 445.899968 -111.503735) (xy 445.878834 -111.455529)
			(xy 445.864523 -111.404877) (xy 445.857304 -111.35274) (xy 445.856868 -111.326422) (xy 445.857354 -111.299171)
			(xy 445.86511 -111.245223) (xy 445.880465 -111.192928) (xy 445.903107 -111.143351) (xy 445.932573 -111.097501)
			(xy 445.968264 -111.05631) (xy 446.009455 -111.020619) (xy 446.055305 -110.991153) (xy 446.104882 -110.968511)
			(xy 446.157177 -110.953156) (xy 446.211125 -110.9454) (xy 446.265627 -110.9454) (xy 446.319575 -110.953156)
			(xy 446.37187 -110.968511) (xy 446.421447 -110.991153) (xy 446.467297 -111.020619) (xy 446.508488 -111.05631)
			(xy 446.544179 -111.097501) (xy 446.573645 -111.143351) (xy 446.596287 -111.192928) (xy 446.611642 -111.245223)
			(xy 446.619398 -111.299171) (xy 446.619884 -111.326422) (xy 446.619436 -111.352737) (xy 446.612198 -111.404866)
			(xy 446.597876 -111.45551) (xy 446.576739 -111.503709) (xy 446.54919 -111.548552) (xy 446.515747 -111.58919)
			(xy 446.496694 -111.607346) (xy 446.489269 -111.614848) (xy 446.480759 -111.634143) (xy 446.480184 -111.644684)
			(xy 446.480184 -111.71936) (xy 446.480726 -111.729908) (xy 446.489253 -111.749203) (xy 446.496694 -111.756698)
			(xy 446.517505 -111.776495) (xy 446.553482 -111.82127) (xy 446.582343 -111.870931) (xy 446.603436 -111.924356)
			(xy 446.616284 -111.980339) (xy 446.620598 -112.037615) (xy 448.394417 -112.037615) (xy 448.39873 -111.980345)
			(xy 448.411576 -111.924367) (xy 448.432666 -111.870947) (xy 448.461522 -111.82129) (xy 448.497494 -111.776518)
			(xy 448.51828 -111.756698) (xy 448.525682 -111.749176) (xy 448.534207 -111.729896) (xy 448.53479 -111.71936)
			(xy 448.53479 -111.644684) (xy 448.534286 -111.634131) (xy 448.525734 -111.614836) (xy 448.51828 -111.607346)
			(xy 448.499201 -111.589214) (xy 448.465747 -111.548578) (xy 448.438192 -111.503733) (xy 448.417057 -111.455528)
			(xy 448.402745 -111.404877) (xy 448.395526 -111.352739) (xy 448.39509 -111.326422) (xy 448.395576 -111.299171)
			(xy 448.403332 -111.245223) (xy 448.418687 -111.192928) (xy 448.441329 -111.143351) (xy 448.470795 -111.097501)
			(xy 448.506486 -111.05631) (xy 448.547677 -111.020619) (xy 448.593527 -110.991153) (xy 448.643104 -110.968511)
			(xy 448.695399 -110.953156) (xy 448.749347 -110.9454) (xy 448.803849 -110.9454) (xy 448.857797 -110.953156)
			(xy 448.910092 -110.968511) (xy 448.959669 -110.991153) (xy 449.005519 -111.020619) (xy 449.04671 -111.05631)
			(xy 449.082401 -111.097501) (xy 449.111867 -111.143351) (xy 449.134509 -111.192928) (xy 449.149864 -111.245223)
			(xy 449.15762 -111.299171) (xy 449.158106 -111.326422) (xy 449.157651 -111.352736) (xy 449.150414 -111.404865)
			(xy 449.136092 -111.455508) (xy 449.114957 -111.503707) (xy 449.087409 -111.54855) (xy 449.053968 -111.58919)
			(xy 449.034916 -111.607346) (xy 449.027494 -111.614851) (xy 449.018981 -111.634143) (xy 449.018406 -111.644684)
			(xy 449.018406 -111.71936) (xy 449.018941 -111.729909) (xy 449.027472 -111.749205) (xy 449.034916 -111.756698)
			(xy 449.055726 -111.776496) (xy 449.091701 -111.821271) (xy 449.12056 -111.870932) (xy 449.141652 -111.924357)
			(xy 449.154499 -111.98034) (xy 449.155522 -111.993923) (xy 452.597351 -111.993923) (xy 452.601664 -111.936653)
			(xy 452.61451 -111.880675) (xy 452.6356 -111.827255) (xy 452.664458 -111.777599) (xy 452.700431 -111.732829)
			(xy 452.721218 -111.71301) (xy 452.72862 -111.705489) (xy 452.737144 -111.686208) (xy 452.737728 -111.675672)
			(xy 452.737728 -111.600996) (xy 452.737206 -111.590446) (xy 452.728665 -111.571151) (xy 452.721218 -111.563658)
			(xy 452.700462 -111.543805) (xy 452.664484 -111.499039) (xy 452.63562 -111.449386) (xy 452.614523 -111.395969)
			(xy 452.60167 -111.339993) (xy 452.597351 -111.282723) (xy 452.601664 -111.225453) (xy 452.61451 -111.169475)
			(xy 452.6356 -111.116055) (xy 452.664458 -111.066399) (xy 452.700431 -111.021629) (xy 452.721218 -111.00181)
			(xy 452.72862 -110.994289) (xy 452.737144 -110.975008) (xy 452.737728 -110.964472) (xy 452.737728 -110.889796)
			(xy 452.737206 -110.879246) (xy 452.728665 -110.859951) (xy 452.721218 -110.852458) (xy 452.702153 -110.834312)
			(xy 452.668696 -110.793681) (xy 452.641137 -110.748839) (xy 452.620001 -110.700636) (xy 452.605686 -110.649986)
			(xy 452.598464 -110.597851) (xy 452.598028 -110.571534) (xy 452.598487 -110.54428) (xy 452.60624 -110.490327)
			(xy 452.621594 -110.438027) (xy 452.644235 -110.388445) (xy 452.673703 -110.34259) (xy 452.709397 -110.301396)
			(xy 452.750591 -110.265702) (xy 452.796447 -110.236234) (xy 452.846029 -110.213593) (xy 452.898329 -110.19824)
			(xy 452.952282 -110.190487) (xy 452.979536 -110.190026) (xy 453.005851 -110.190461) (xy 453.057981 -110.197701)
			(xy 453.108625 -110.212026) (xy 453.156824 -110.233165) (xy 453.201667 -110.260717) (xy 453.242305 -110.294162)
			(xy 453.26046 -110.313216) (xy 453.267992 -110.320604) (xy 453.287264 -110.329136) (xy 453.297798 -110.329726)
			(xy 453.372474 -110.329726) (xy 453.383022 -110.329188) (xy 453.402317 -110.320658) (xy 453.409812 -110.313216)
			(xy 453.427972 -110.294165) (xy 453.4686 -110.260707) (xy 453.51344 -110.233147) (xy 453.56164 -110.212007)
			(xy 453.612286 -110.197689) (xy 453.66442 -110.190464) (xy 453.690736 -110.190026) (xy 453.71799 -110.190444)
			(xy 453.771942 -110.198207) (xy 453.82424 -110.213568) (xy 453.873819 -110.236216) (xy 453.913439 -110.261683)
			(xy 455.214548 -110.261683) (xy 455.214548 -110.209717) (xy 455.222677 -110.158392) (xy 455.238734 -110.10897)
			(xy 455.262325 -110.062668) (xy 455.292869 -110.020627) (xy 455.329613 -109.983881) (xy 455.371653 -109.953335)
			(xy 455.417953 -109.929741) (xy 455.467374 -109.913681) (xy 455.518699 -109.905549) (xy 455.544682 -109.905038)
			(xy 455.571328 -109.905497) (xy 455.623931 -109.914033) (xy 455.674482 -109.930904) (xy 455.721668 -109.955672)
			(xy 455.764266 -109.987694) (xy 455.80117 -110.026139) (xy 455.816716 -110.047786) (xy 455.82508 -110.059072)
			(xy 455.846753 -110.076927) (xy 455.872467 -110.08821) (xy 455.900282 -110.092068) (xy 455.928097 -110.08821)
			(xy 455.953811 -110.076927) (xy 455.975484 -110.059072) (xy 455.983848 -110.047786) (xy 455.999412 -110.026159)
			(xy 456.036331 -109.987743) (xy 456.078931 -109.955744) (xy 456.126112 -109.930989) (xy 456.176652 -109.914121)
			(xy 456.229242 -109.905575) (xy 456.255882 -109.905038) (xy 456.281876 -109.905428) (xy 456.333224 -109.913558)
			(xy 456.382667 -109.929621) (xy 456.42899 -109.953221) (xy 456.471049 -109.983777) (xy 456.507811 -110.020537)
			(xy 456.53837 -110.062595) (xy 456.561972 -110.108916) (xy 456.578038 -110.158359) (xy 456.586171 -110.209706)
			(xy 456.586171 -110.261694) (xy 456.578038 -110.313041) (xy 456.561972 -110.362484) (xy 456.53837 -110.408805)
			(xy 456.507811 -110.450863) (xy 456.471049 -110.487623) (xy 456.432466 -110.515654) (xy 459.128112 -110.515654)
			(xy 459.132183 -110.460032) (xy 459.144309 -110.405595) (xy 459.164232 -110.353504) (xy 459.191528 -110.304869)
			(xy 459.225614 -110.260726) (xy 459.265763 -110.222017) (xy 459.311121 -110.189566) (xy 459.360721 -110.164065)
			(xy 459.413505 -110.146058) (xy 459.468348 -110.135928) (xy 459.524082 -110.133891) (xy 459.579519 -110.139991)
			(xy 459.633476 -110.154097) (xy 459.684805 -110.175909) (xy 459.732411 -110.204963) (xy 459.775279 -110.240638)
			(xy 459.812496 -110.282175) (xy 459.843269 -110.328688) (xy 459.866941 -110.379185) (xy 459.883009 -110.432592)
			(xy 459.891129 -110.487768) (xy 459.891638 -110.515654) (xy 459.891129 -110.54354) (xy 459.883009 -110.598716)
			(xy 459.866941 -110.652123) (xy 459.843269 -110.70262) (xy 459.812496 -110.749133) (xy 459.775279 -110.79067)
			(xy 459.732411 -110.826345) (xy 459.684805 -110.855399) (xy 459.633476 -110.877211) (xy 459.579519 -110.891317)
			(xy 459.524082 -110.897417) (xy 459.468348 -110.89538) (xy 459.413505 -110.88525) (xy 459.360721 -110.867243)
			(xy 459.311121 -110.841742) (xy 459.265763 -110.809291) (xy 459.225614 -110.770582) (xy 459.191528 -110.726439)
			(xy 459.164232 -110.677804) (xy 459.144309 -110.625713) (xy 459.132183 -110.571276) (xy 459.128112 -110.515654)
			(xy 456.432466 -110.515654) (xy 456.42899 -110.518179) (xy 456.382667 -110.541779) (xy 456.333224 -110.557842)
			(xy 456.281876 -110.565972) (xy 456.255882 -110.566454) (xy 456.229238 -110.565951) (xy 456.176636 -110.557424)
			(xy 456.126087 -110.540563) (xy 456.0789 -110.515803) (xy 456.036301 -110.483789) (xy 455.999395 -110.44535)
			(xy 455.983848 -110.423706) (xy 455.975484 -110.41242) (xy 455.953811 -110.394565) (xy 455.928097 -110.383282)
			(xy 455.900282 -110.379424) (xy 455.872467 -110.383282) (xy 455.846753 -110.394565) (xy 455.82508 -110.41242)
			(xy 455.816716 -110.423706) (xy 455.80111 -110.445301) (xy 455.7642 -110.483719) (xy 455.721608 -110.515722)
			(xy 455.674436 -110.540482) (xy 455.623904 -110.557357) (xy 455.57132 -110.565912) (xy 455.544682 -110.566454)
			(xy 455.518699 -110.565851) (xy 455.467374 -110.557719) (xy 455.417953 -110.541659) (xy 455.371653 -110.518065)
			(xy 455.329613 -110.487519) (xy 455.292869 -110.450773) (xy 455.262325 -110.408732) (xy 455.238734 -110.36243)
			(xy 455.222677 -110.313008) (xy 455.214548 -110.261683) (xy 453.913439 -110.261683) (xy 453.919671 -110.265689)
			(xy 453.960862 -110.301388) (xy 453.996553 -110.342585) (xy 454.026018 -110.388442) (xy 454.048656 -110.438026)
			(xy 454.064008 -110.490327) (xy 454.071761 -110.54428) (xy 454.072244 -110.571534) (xy 454.071817 -110.59785)
			(xy 454.064577 -110.649981) (xy 454.050251 -110.700625) (xy 454.029111 -110.748824) (xy 454.001557 -110.793666)
			(xy 453.96811 -110.834303) (xy 453.949054 -110.852458) (xy 453.941677 -110.860001) (xy 453.933137 -110.879264)
			(xy 453.932544 -110.889796) (xy 453.932544 -110.964472) (xy 453.933062 -110.975023) (xy 453.941604 -110.994319)
			(xy 453.949054 -111.00181) (xy 453.969874 -111.021597) (xy 454.005846 -111.066375) (xy 454.034702 -111.116038)
			(xy 454.052798 -111.161885) (xy 455.214523 -111.161885) (xy 455.214523 -111.109915) (xy 455.222653 -111.058586)
			(xy 455.238712 -111.00916) (xy 455.262304 -110.962855) (xy 455.29285 -110.920811) (xy 455.329597 -110.884062)
			(xy 455.37164 -110.853514) (xy 455.417944 -110.829919) (xy 455.467369 -110.813857) (xy 455.518697 -110.805725)
			(xy 455.544682 -110.805214) (xy 455.571327 -110.805683) (xy 455.62393 -110.814219) (xy 455.674479 -110.831089)
			(xy 455.721665 -110.855854) (xy 455.764264 -110.887874) (xy 455.801169 -110.926316) (xy 455.816716 -110.947962)
			(xy 455.82508 -110.959248) (xy 455.846753 -110.977103) (xy 455.872467 -110.988386) (xy 455.900282 -110.992244)
			(xy 455.928097 -110.988386) (xy 455.953811 -110.977103) (xy 455.975484 -110.959248) (xy 455.983848 -110.947962)
			(xy 455.999405 -110.92633) (xy 456.036326 -110.887915) (xy 456.078928 -110.855917) (xy 456.12611 -110.831164)
			(xy 456.176651 -110.814296) (xy 456.229242 -110.805751) (xy 456.255882 -110.805214) (xy 456.281874 -110.805652)
			(xy 456.333218 -110.813781) (xy 456.382658 -110.829843) (xy 456.428977 -110.853441) (xy 456.471034 -110.883995)
			(xy 456.507793 -110.920752) (xy 456.538349 -110.962808) (xy 456.56195 -111.009125) (xy 456.578014 -111.058564)
			(xy 456.586147 -111.109908) (xy 456.586147 -111.161892) (xy 456.578014 -111.213236) (xy 456.56195 -111.262675)
			(xy 456.538349 -111.308992) (xy 456.507793 -111.351048) (xy 456.471034 -111.387805) (xy 456.428977 -111.418359)
			(xy 456.382658 -111.441957) (xy 456.333218 -111.458019) (xy 456.281874 -111.466148) (xy 456.255882 -111.46663)
			(xy 456.229237 -111.466138) (xy 456.176635 -111.45761) (xy 456.126084 -111.440747) (xy 456.078897 -111.415985)
			(xy 456.036299 -111.383969) (xy 455.999394 -111.345527) (xy 455.983848 -111.323882) (xy 455.975484 -111.312596)
			(xy 455.953811 -111.294741) (xy 455.928097 -111.283458) (xy 455.900282 -111.2796) (xy 455.872467 -111.283458)
			(xy 455.846753 -111.294741) (xy 455.82508 -111.312596) (xy 455.816716 -111.323882) (xy 455.801133 -111.345494)
			(xy 455.764215 -111.383907) (xy 455.721618 -111.415906) (xy 455.674441 -111.440662) (xy 455.623907 -111.457535)
			(xy 455.571321 -111.466089) (xy 455.544682 -111.46663) (xy 455.518697 -111.466075) (xy 455.467369 -111.457943)
			(xy 455.417944 -111.441881) (xy 455.37164 -111.418286) (xy 455.329597 -111.387738) (xy 455.29285 -111.350989)
			(xy 455.262304 -111.308945) (xy 455.238712 -111.26264) (xy 455.222653 -111.213214) (xy 455.214523 -111.161885)
			(xy 454.052798 -111.161885) (xy 454.05579 -111.169465) (xy 454.068636 -111.225447) (xy 454.072947 -111.282723)
			(xy 454.068629 -111.339998) (xy 454.055777 -111.395979) (xy 454.034681 -111.449403) (xy 454.00582 -111.499063)
			(xy 453.969843 -111.543837) (xy 453.949054 -111.563658) (xy 453.941677 -111.571201) (xy 453.933137 -111.590464)
			(xy 453.932544 -111.600996) (xy 453.932544 -111.675672) (xy 453.933062 -111.686223) (xy 453.941604 -111.705519)
			(xy 453.949054 -111.71301) (xy 453.969874 -111.732797) (xy 454.005846 -111.777575) (xy 454.034702 -111.827238)
			(xy 454.05579 -111.880665) (xy 454.068636 -111.936647) (xy 454.072947 -111.993923) (xy 454.068629 -112.051198)
			(xy 454.066199 -112.061783) (xy 455.214546 -112.061783) (xy 455.214546 -112.009817) (xy 455.222675 -111.958491)
			(xy 455.238732 -111.909069) (xy 455.262324 -111.862767) (xy 455.292867 -111.820725) (xy 455.329612 -111.783979)
			(xy 455.371652 -111.753433) (xy 455.417952 -111.729839) (xy 455.467374 -111.713779) (xy 455.518699 -111.705647)
			(xy 455.544682 -111.705136) (xy 455.571328 -111.705595) (xy 455.623931 -111.714132) (xy 455.674481 -111.731003)
			(xy 455.721668 -111.755771) (xy 455.764266 -111.787792) (xy 455.80117 -111.826237) (xy 455.816716 -111.847884)
			(xy 455.82508 -111.85917) (xy 455.846753 -111.877025) (xy 455.872467 -111.888308) (xy 455.900282 -111.892166)
			(xy 455.928097 -111.888308) (xy 455.953811 -111.877025) (xy 455.975484 -111.85917) (xy 455.983848 -111.847884)
			(xy 455.999411 -111.826257) (xy 456.03633 -111.787841) (xy 456.078931 -111.755841) (xy 456.126112 -111.731087)
			(xy 456.176651 -111.714219) (xy 456.229242 -111.705673) (xy 456.255882 -111.705136) (xy 456.281876 -111.70553)
			(xy 456.333223 -111.71366) (xy 456.382667 -111.729723) (xy 456.428989 -111.753323) (xy 456.471048 -111.783879)
			(xy 456.472823 -111.785654) (xy 457.757782 -111.785654) (xy 457.761853 -111.730032) (xy 457.773979 -111.675595)
			(xy 457.793902 -111.623504) (xy 457.821198 -111.574869) (xy 457.855284 -111.530726) (xy 457.895433 -111.492017)
			(xy 457.940791 -111.459566) (xy 457.990391 -111.434065) (xy 458.043175 -111.416058) (xy 458.098018 -111.405928)
			(xy 458.153752 -111.403891) (xy 458.209189 -111.409991) (xy 458.263146 -111.424097) (xy 458.314475 -111.445909)
			(xy 458.362081 -111.474963) (xy 458.404949 -111.510638) (xy 458.442166 -111.552175) (xy 458.472939 -111.598688)
			(xy 458.496611 -111.649185) (xy 458.512679 -111.702592) (xy 458.520799 -111.757768) (xy 458.521308 -111.785654)
			(xy 458.520799 -111.81354) (xy 458.512679 -111.868716) (xy 458.496611 -111.922123) (xy 458.472939 -111.97262)
			(xy 458.442166 -112.019133) (xy 458.404949 -112.06067) (xy 458.362081 -112.096345) (xy 458.314475 -112.125399)
			(xy 458.263146 -112.147211) (xy 458.209189 -112.161317) (xy 458.153752 -112.167417) (xy 458.098018 -112.16538)
			(xy 458.043175 -112.15525) (xy 457.990391 -112.137243) (xy 457.940791 -112.111742) (xy 457.895433 -112.079291)
			(xy 457.855284 -112.040582) (xy 457.821198 -111.996439) (xy 457.793902 -111.947804) (xy 457.773979 -111.895713)
			(xy 457.761853 -111.841276) (xy 457.757782 -111.785654) (xy 456.472823 -111.785654) (xy 456.50781 -111.820638)
			(xy 456.538368 -111.862696) (xy 456.56197 -111.909017) (xy 456.578036 -111.958459) (xy 456.586169 -112.009806)
			(xy 456.586169 -112.061794) (xy 456.578036 -112.113141) (xy 456.56197 -112.162583) (xy 456.538368 -112.208904)
			(xy 456.50781 -112.250962) (xy 456.471048 -112.287721) (xy 456.458336 -112.296956) (xy 459.194914 -112.296956)
			(xy 459.198985 -112.241334) (xy 459.211111 -112.186897) (xy 459.231034 -112.134806) (xy 459.25833 -112.086171)
			(xy 459.292416 -112.042028) (xy 459.332565 -112.003319) (xy 459.377923 -111.970868) (xy 459.427523 -111.945367)
			(xy 459.480307 -111.92736) (xy 459.53515 -111.91723) (xy 459.590884 -111.915193) (xy 459.646321 -111.921293)
			(xy 459.700278 -111.935399) (xy 459.751607 -111.957211) (xy 459.799213 -111.986265) (xy 459.842081 -112.02194)
			(xy 459.879298 -112.063477) (xy 459.910071 -112.10999) (xy 459.933743 -112.160487) (xy 459.949811 -112.213894)
			(xy 459.957931 -112.26907) (xy 459.95844 -112.296956) (xy 459.957931 -112.324842) (xy 459.949811 -112.380018)
			(xy 459.933743 -112.433425) (xy 459.910071 -112.483922) (xy 459.879298 -112.530435) (xy 459.842081 -112.571972)
			(xy 459.799213 -112.607647) (xy 459.751607 -112.636701) (xy 459.700278 -112.658513) (xy 459.646321 -112.672619)
			(xy 459.590884 -112.678719) (xy 459.53515 -112.676682) (xy 459.480307 -112.666552) (xy 459.427523 -112.648545)
			(xy 459.377923 -112.623044) (xy 459.332565 -112.590593) (xy 459.292416 -112.551884) (xy 459.25833 -112.507741)
			(xy 459.231034 -112.459106) (xy 459.211111 -112.407015) (xy 459.198985 -112.352578) (xy 459.194914 -112.296956)
			(xy 456.458336 -112.296956) (xy 456.428989 -112.318277) (xy 456.382667 -112.341877) (xy 456.333223 -112.35794)
			(xy 456.281876 -112.36607) (xy 456.255882 -112.366552) (xy 456.229238 -112.36605) (xy 456.176636 -112.357523)
			(xy 456.126086 -112.340661) (xy 456.0789 -112.315902) (xy 456.036301 -112.283887) (xy 455.999395 -112.245448)
			(xy 455.983848 -112.223804) (xy 455.975484 -112.212518) (xy 455.953811 -112.194663) (xy 455.928097 -112.18338)
			(xy 455.900282 -112.179522) (xy 455.872467 -112.18338) (xy 455.846753 -112.194663) (xy 455.82508 -112.212518)
			(xy 455.816716 -112.223804) (xy 455.801109 -112.245399) (xy 455.7642 -112.283817) (xy 455.721608 -112.31582)
			(xy 455.674436 -112.340579) (xy 455.623904 -112.357455) (xy 455.57132 -112.36601) (xy 455.544682 -112.366552)
			(xy 455.518699 -112.365953) (xy 455.467374 -112.357821) (xy 455.417952 -112.341761) (xy 455.371652 -112.318167)
			(xy 455.329612 -112.287621) (xy 455.292867 -112.250875) (xy 455.262324 -112.208833) (xy 455.238732 -112.162531)
			(xy 455.222675 -112.113109) (xy 455.214546 -112.061783) (xy 454.066199 -112.061783) (xy 454.055777 -112.107179)
			(xy 454.034681 -112.160603) (xy 454.00582 -112.210263) (xy 453.969843 -112.255037) (xy 453.949054 -112.274858)
			(xy 453.941677 -112.282401) (xy 453.933137 -112.301664) (xy 453.932544 -112.312196) (xy 453.932544 -112.386872)
			(xy 453.933062 -112.397423) (xy 453.941604 -112.416719) (xy 453.949054 -112.42421) (xy 453.968118 -112.442357)
			(xy 454.001572 -112.48299) (xy 454.029129 -112.527832) (xy 454.050265 -112.576034) (xy 454.064581 -112.626683)
			(xy 454.071806 -112.678818) (xy 454.072244 -112.705134) (xy 454.071754 -112.732384) (xy 454.063994 -112.78633)
			(xy 454.048636 -112.838623) (xy 454.025994 -112.888198) (xy 453.996527 -112.934046) (xy 453.972487 -112.961789)
			(xy 455.214468 -112.961789) (xy 455.214468 -112.909811) (xy 455.222598 -112.858473) (xy 455.23866 -112.809039)
			(xy 455.262257 -112.762726) (xy 455.292808 -112.720674) (xy 455.329561 -112.683919) (xy 455.371611 -112.653366)
			(xy 455.417922 -112.629767) (xy 455.467356 -112.613703) (xy 455.518693 -112.605569) (xy 455.544682 -112.605058)
			(xy 455.571328 -112.605508) (xy 455.623932 -112.614045) (xy 455.674484 -112.630917) (xy 455.72167 -112.655687)
			(xy 455.764268 -112.687711) (xy 455.801171 -112.726158) (xy 455.816716 -112.747806) (xy 455.82508 -112.759092)
			(xy 455.846753 -112.776947) (xy 455.872467 -112.78823) (xy 455.900282 -112.792088) (xy 455.928097 -112.78823)
			(xy 455.953811 -112.776947) (xy 455.975484 -112.759092) (xy 455.983848 -112.747806) (xy 455.999388 -112.726162)
			(xy 456.036315 -112.68775) (xy 456.078921 -112.655755) (xy 456.126106 -112.631005) (xy 456.176648 -112.614139)
			(xy 456.229241 -112.605594) (xy 456.255882 -112.605058) (xy 456.28187 -112.605608) (xy 456.333205 -112.613736)
			(xy 456.382637 -112.629795) (xy 456.428948 -112.653389) (xy 456.470997 -112.683938) (xy 456.50775 -112.720689)
			(xy 456.538301 -112.762737) (xy 456.561898 -112.809046) (xy 456.57796 -112.858477) (xy 456.586091 -112.909813)
			(xy 456.586091 -112.961787) (xy 456.57796 -113.013123) (xy 456.561898 -113.062554) (xy 456.538301 -113.108863)
			(xy 456.50775 -113.150911) (xy 456.470997 -113.187662) (xy 456.428948 -113.218211) (xy 456.382637 -113.241805)
			(xy 456.333205 -113.257864) (xy 456.28187 -113.265992) (xy 456.255882 -113.266474) (xy 456.229238 -113.265963)
			(xy 456.176638 -113.257436) (xy 456.126088 -113.240576) (xy 456.078902 -113.215818) (xy 456.036303 -113.183805)
			(xy 455.999395 -113.145369) (xy 455.983848 -113.123726) (xy 455.975484 -113.11244) (xy 455.953811 -113.094585)
			(xy 455.928097 -113.083302) (xy 455.900282 -113.079444) (xy 455.872467 -113.083302) (xy 455.846753 -113.094585)
			(xy 455.82508 -113.11244) (xy 455.816716 -113.123726) (xy 455.801116 -113.145325) (xy 455.764204 -113.183742)
			(xy 455.721611 -113.215744) (xy 455.674437 -113.240503) (xy 455.623904 -113.257378) (xy 455.57132 -113.265932)
			(xy 455.544682 -113.266474) (xy 455.518693 -113.266031) (xy 455.467356 -113.257897) (xy 455.417922 -113.241833)
			(xy 455.371611 -113.218234) (xy 455.329561 -113.187681) (xy 455.292808 -113.150926) (xy 455.262257 -113.108874)
			(xy 455.23866 -113.062561) (xy 455.222598 -113.013127) (xy 455.214468 -112.961789) (xy 453.972487 -112.961789)
			(xy 453.960836 -112.975235) (xy 453.919648 -113.010926) (xy 453.873799 -113.040393) (xy 453.824224 -113.063035)
			(xy 453.771932 -113.078393) (xy 453.717986 -113.086154) (xy 453.690736 -113.086642) (xy 453.66442 -113.086236)
			(xy 453.612288 -113.078991) (xy 453.561643 -113.064661) (xy 453.513444 -113.043517) (xy 453.468602 -113.01596)
			(xy 453.427966 -112.982509) (xy 453.409812 -112.963452) (xy 453.402281 -112.956061) (xy 453.383008 -112.947529)
			(xy 453.372474 -112.946942) (xy 453.297798 -112.946942) (xy 453.287245 -112.947444) (xy 453.267949 -112.955997)
			(xy 453.26046 -112.963452) (xy 453.242327 -112.98253) (xy 453.201691 -113.015983) (xy 453.156846 -113.043538)
			(xy 453.108641 -113.064672) (xy 453.05799 -113.078985) (xy 453.005853 -113.086206) (xy 452.979536 -113.086642)
			(xy 452.952286 -113.086111) (xy 452.898339 -113.07836) (xy 452.846044 -113.06301) (xy 452.796467 -113.040375)
			(xy 452.750615 -113.010913) (xy 452.709423 -112.975227) (xy 452.673729 -112.934041) (xy 452.644259 -112.888195)
			(xy 452.621614 -112.838621) (xy 452.606255 -112.78633) (xy 452.598494 -112.732384) (xy 452.598028 -112.705134)
			(xy 452.598442 -112.678818) (xy 452.605687 -112.626687) (xy 452.620016 -112.576043) (xy 452.641158 -112.527844)
			(xy 452.668714 -112.483002) (xy 452.702162 -112.442365) (xy 452.721218 -112.42421) (xy 452.72862 -112.416689)
			(xy 452.737144 -112.397408) (xy 452.737728 -112.386872) (xy 452.737728 -112.312196) (xy 452.737206 -112.301646)
			(xy 452.728665 -112.282351) (xy 452.721218 -112.274858) (xy 452.700462 -112.255005) (xy 452.664484 -112.210239)
			(xy 452.63562 -112.160586) (xy 452.614523 -112.107169) (xy 452.60167 -112.051193) (xy 452.597351 -111.993923)
			(xy 449.155522 -111.993923) (xy 449.158813 -112.037615) (xy 449.154495 -112.09489) (xy 449.141643 -112.150871)
			(xy 449.120547 -112.204294) (xy 449.091684 -112.253953) (xy 449.055706 -112.298726) (xy 449.034916 -112.318546)
			(xy 449.027494 -112.326051) (xy 449.018981 -112.345343) (xy 449.018406 -112.355884) (xy 449.018406 -112.43056)
			(xy 449.018941 -112.441109) (xy 449.027472 -112.460405) (xy 449.034916 -112.467898) (xy 449.053967 -112.486058)
			(xy 449.087424 -112.526687) (xy 449.114983 -112.571527) (xy 449.136122 -112.619727) (xy 449.15044 -112.670373)
			(xy 449.157667 -112.722506) (xy 449.158106 -112.748822) (xy 449.15762 -112.776073) (xy 449.149864 -112.830021)
			(xy 449.134509 -112.882316) (xy 449.111867 -112.931893) (xy 449.082401 -112.977743) (xy 449.04671 -113.018934)
			(xy 449.005519 -113.054625) (xy 448.959669 -113.084091) (xy 448.910092 -113.106733) (xy 448.857797 -113.122088)
			(xy 448.803849 -113.129844) (xy 448.749347 -113.129844) (xy 448.695399 -113.122088) (xy 448.643104 -113.106733)
			(xy 448.593527 -113.084091) (xy 448.547677 -113.054625) (xy 448.506486 -113.018934) (xy 448.470795 -112.977743)
			(xy 448.441329 -112.931893) (xy 448.418687 -112.882316) (xy 448.403332 -112.830021) (xy 448.395576 -112.776073)
			(xy 448.39509 -112.748822) (xy 448.395575 -112.722509) (xy 448.402807 -112.670381) (xy 448.417123 -112.619739)
			(xy 448.438252 -112.57154) (xy 448.465795 -112.526696) (xy 448.49923 -112.486055) (xy 448.51828 -112.467898)
			(xy 448.525682 -112.460376) (xy 448.534207 -112.441096) (xy 448.53479 -112.43056) (xy 448.53479 -112.355884)
			(xy 448.534286 -112.345331) (xy 448.525734 -112.326036) (xy 448.51828 -112.318546) (xy 448.497514 -112.298704)
			(xy 448.461539 -112.253935) (xy 448.432679 -112.20428) (xy 448.411585 -112.150861) (xy 448.398734 -112.094885)
			(xy 448.394417 -112.037615) (xy 446.620598 -112.037615) (xy 446.61628 -112.094891) (xy 446.603427 -112.150872)
			(xy 446.58233 -112.204296) (xy 446.553465 -112.253954) (xy 446.517485 -112.298727) (xy 446.496694 -112.318546)
			(xy 446.489269 -112.326048) (xy 446.480759 -112.345343) (xy 446.480184 -112.355884) (xy 446.480184 -112.43056)
			(xy 446.480726 -112.441108) (xy 446.489253 -112.460403) (xy 446.496694 -112.467898) (xy 446.51574 -112.486063)
			(xy 446.549199 -112.52669) (xy 446.576759 -112.571529) (xy 446.597899 -112.619728) (xy 446.612218 -112.670374)
			(xy 446.619445 -112.722506) (xy 446.619884 -112.748822) (xy 446.619398 -112.776073) (xy 446.611642 -112.830021)
			(xy 446.596287 -112.882316) (xy 446.573645 -112.931893) (xy 446.544179 -112.977743) (xy 446.508488 -113.018934)
			(xy 446.467297 -113.054625) (xy 446.421447 -113.084091) (xy 446.37187 -113.106733) (xy 446.319575 -113.122088)
			(xy 446.265627 -113.129844) (xy 446.211125 -113.129844) (xy 446.157177 -113.122088) (xy 446.104882 -113.106733)
			(xy 446.055305 -113.084091) (xy 446.009455 -113.054625) (xy 445.968264 -113.018934) (xy 445.932573 -112.977743)
			(xy 445.903107 -112.931893) (xy 445.880465 -112.882316) (xy 445.86511 -112.830021) (xy 445.857354 -112.776073)
			(xy 445.856868 -112.748822) (xy 445.85736 -112.722509) (xy 445.864592 -112.670382) (xy 445.878906 -112.61974)
			(xy 445.900034 -112.571541) (xy 445.927575 -112.526697) (xy 445.961009 -112.486056) (xy 445.980058 -112.467898)
			(xy 445.987456 -112.460373) (xy 445.995984 -112.441096) (xy 445.996568 -112.43056) (xy 445.996568 -112.355884)
			(xy 445.99607 -112.34533) (xy 445.987514 -112.326035) (xy 445.980058 -112.318546) (xy 445.959293 -112.298703)
			(xy 445.92332 -112.253933) (xy 445.894462 -112.204279) (xy 445.873369 -112.15086) (xy 445.860519 -112.094884)
			(xy 445.856202 -112.037615) (xy 444.06285 -112.037615) (xy 444.094309 -112.075823) (xy 444.121867 -112.120665)
			(xy 444.143003 -112.168869) (xy 444.157317 -112.219519) (xy 444.164538 -112.271655) (xy 444.164974 -112.297972)
			(xy 444.164488 -112.325223) (xy 444.156732 -112.379171) (xy 444.141377 -112.431466) (xy 444.118735 -112.481043)
			(xy 444.089269 -112.526893) (xy 444.053578 -112.568084) (xy 444.012387 -112.603775) (xy 443.966537 -112.633241)
			(xy 443.91696 -112.655883) (xy 443.864665 -112.671238) (xy 443.810717 -112.678994) (xy 443.756215 -112.678994)
			(xy 443.702267 -112.671238) (xy 443.649972 -112.655883) (xy 443.600395 -112.633241) (xy 443.554545 -112.603775)
			(xy 443.513354 -112.568084) (xy 443.477663 -112.526893) (xy 443.448197 -112.481043) (xy 443.425555 -112.431466)
			(xy 443.4102 -112.379171) (xy 443.402444 -112.325223) (xy 443.401958 -112.297972) (xy 442.132974 -112.297972)
			(xy 442.132488 -112.325223) (xy 442.124732 -112.379171) (xy 442.109377 -112.431466) (xy 442.086735 -112.481043)
			(xy 442.057269 -112.526893) (xy 442.021578 -112.568084) (xy 441.980387 -112.603775) (xy 441.934537 -112.633241)
			(xy 441.88496 -112.655883) (xy 441.832665 -112.671238) (xy 441.778717 -112.678994) (xy 441.724215 -112.678994)
			(xy 441.670267 -112.671238) (xy 441.617972 -112.655883) (xy 441.568395 -112.633241) (xy 441.522545 -112.603775)
			(xy 441.481354 -112.568084) (xy 441.445663 -112.526893) (xy 441.416197 -112.481043) (xy 441.393555 -112.431466)
			(xy 441.3782 -112.379171) (xy 441.370444 -112.325223) (xy 441.369958 -112.297972) (xy 430.175454 -112.297972)
			(xy 429.820977 -114.084613) (xy 437.749383 -114.084613) (xy 437.749388 -114.030111) (xy 437.75715 -113.976165)
			(xy 437.77251 -113.923872) (xy 437.795156 -113.874298) (xy 437.824627 -113.828451) (xy 437.860322 -113.787265)
			(xy 437.901515 -113.751579) (xy 437.947368 -113.722118) (xy 437.996947 -113.699482) (xy 438.049243 -113.684133)
			(xy 438.103191 -113.676382) (xy 438.130442 -113.675922) (xy 438.130696 -113.675922) (xy 438.160133 -113.676472)
			(xy 438.218307 -113.685537) (xy 438.24652 -113.693956) (xy 438.258458 -113.697766) (xy 438.282334 -113.693956)
			(xy 438.358534 -113.637568) (xy 438.367806 -113.629826) (xy 438.37855 -113.608231) (xy 438.379108 -113.596166)
			(xy 438.379108 -113.591086) (xy 438.379542 -113.563832) (xy 438.387301 -113.509879) (xy 438.40266 -113.45758)
			(xy 438.425305 -113.407998) (xy 438.454776 -113.362145) (xy 438.490473 -113.320952) (xy 438.531669 -113.285258)
			(xy 438.577525 -113.255791) (xy 438.627108 -113.233149) (xy 438.679409 -113.217795) (xy 438.733362 -113.21004)
			(xy 438.760616 -113.209578) (xy 438.789532 -113.210127) (xy 438.846703 -113.218846) (xy 438.901903 -113.236096)
			(xy 438.953865 -113.261481) (xy 439.0014 -113.294421) (xy 439.043416 -113.33416) (xy 439.061606 -113.356644)
			(xy 439.069213 -113.365451) (xy 439.090114 -113.375633) (xy 439.101738 -113.376202) (xy 439.181494 -113.376202)
			(xy 439.193124 -113.375645) (xy 439.214033 -113.365469) (xy 439.221626 -113.356644) (xy 439.239813 -113.334157)
			(xy 439.281833 -113.29442) (xy 439.329368 -113.26148) (xy 439.38133 -113.236092) (xy 439.436529 -113.218837)
			(xy 439.4937 -113.210111) (xy 439.522616 -113.209578) (xy 439.549867 -113.210063) (xy 439.603814 -113.217821)
			(xy 439.656108 -113.233178) (xy 439.705684 -113.25582) (xy 439.751534 -113.285286) (xy 439.792724 -113.320978)
			(xy 439.828415 -113.362168) (xy 439.857881 -113.408017) (xy 439.880523 -113.457594) (xy 439.895879 -113.509888)
			(xy 439.903637 -113.563835) (xy 439.903725 -113.568734) (xy 459.189834 -113.568734) (xy 459.193905 -113.513112)
			(xy 459.206031 -113.458675) (xy 459.225954 -113.406584) (xy 459.25325 -113.357949) (xy 459.287336 -113.313806)
			(xy 459.327485 -113.275097) (xy 459.372843 -113.242646) (xy 459.422443 -113.217145) (xy 459.475227 -113.199138)
			(xy 459.53007 -113.189008) (xy 459.585804 -113.186971) (xy 459.641241 -113.193071) (xy 459.695198 -113.207177)
			(xy 459.746527 -113.228989) (xy 459.794133 -113.258043) (xy 459.837001 -113.293718) (xy 459.874218 -113.335255)
			(xy 459.904991 -113.381768) (xy 459.928663 -113.432265) (xy 459.944731 -113.485672) (xy 459.952851 -113.540848)
			(xy 459.95336 -113.568734) (xy 459.952851 -113.59662) (xy 459.944731 -113.651796) (xy 459.928663 -113.705203)
			(xy 459.904991 -113.7557) (xy 459.874218 -113.802213) (xy 459.837001 -113.84375) (xy 459.794133 -113.879425)
			(xy 459.746527 -113.908479) (xy 459.695198 -113.930291) (xy 459.641241 -113.944397) (xy 459.585804 -113.950497)
			(xy 459.53007 -113.94846) (xy 459.475227 -113.93833) (xy 459.422443 -113.920323) (xy 459.372843 -113.894822)
			(xy 459.327485 -113.862371) (xy 459.287336 -113.823662) (xy 459.25325 -113.779519) (xy 459.225954 -113.730884)
			(xy 459.206031 -113.678793) (xy 459.193905 -113.624356) (xy 459.189834 -113.568734) (xy 439.903725 -113.568734)
			(xy 439.904124 -113.591086) (xy 439.903696 -113.618491) (xy 439.895842 -113.672735) (xy 439.880307 -113.725297)
			(xy 439.857412 -113.775095) (xy 439.827627 -113.821106) (xy 439.791566 -113.862381) (xy 439.74997 -113.898072)
			(xy 439.727086 -113.913158) (xy 439.718067 -113.919608) (xy 439.706213 -113.938317) (xy 439.704226 -113.949226)
			(xy 439.692034 -114.037364) (xy 439.698638 -114.0587) (xy 439.706258 -114.067082) (xy 439.724546 -114.088672)
			(xy 439.73208 -114.097462) (xy 439.75286 -114.107627) (xy 439.764424 -114.10823) (xy 439.844434 -114.10823)
			(xy 439.85607 -114.107721) (xy 439.876981 -114.097513) (xy 439.884566 -114.088672) (xy 439.902769 -114.066199)
			(xy 439.944787 -114.026464) (xy 439.99232 -113.993525) (xy 440.044279 -113.968135) (xy 440.099474 -113.950876)
			(xy 440.156641 -113.942143) (xy 440.185556 -113.941606) (xy 440.212812 -113.942038) (xy 440.26677 -113.94979)
			(xy 440.319075 -113.965143) (xy 440.368662 -113.987784) (xy 440.414523 -114.017252) (xy 440.427475 -114.028474)
			(xy 453.305162 -114.028474) (xy 453.309233 -113.972852) (xy 453.321359 -113.918415) (xy 453.341282 -113.866324)
			(xy 453.368578 -113.817689) (xy 453.402664 -113.773546) (xy 453.442813 -113.734837) (xy 453.488171 -113.702386)
			(xy 453.537771 -113.676885) (xy 453.590555 -113.658878) (xy 453.645398 -113.648748) (xy 453.701132 -113.646711)
			(xy 453.756569 -113.652811) (xy 453.810526 -113.666917) (xy 453.861855 -113.688729) (xy 453.909461 -113.717783)
			(xy 453.952329 -113.753458) (xy 453.989546 -113.794995) (xy 454.020319 -113.841508) (xy 454.043991 -113.892005)
			(xy 454.060059 -113.945412) (xy 454.068179 -114.000588) (xy 454.068688 -114.028474) (xy 454.068179 -114.05636)
			(xy 454.060059 -114.111536) (xy 454.043991 -114.164943) (xy 454.020319 -114.21544) (xy 453.989546 -114.261953)
			(xy 453.952329 -114.30349) (xy 453.909461 -114.339165) (xy 453.861855 -114.368219) (xy 453.810526 -114.390031)
			(xy 453.756569 -114.404137) (xy 453.701132 -114.410237) (xy 453.645398 -114.4082) (xy 453.590555 -114.39807)
			(xy 453.537771 -114.380063) (xy 453.488171 -114.354562) (xy 453.442813 -114.322111) (xy 453.402664 -114.283402)
			(xy 453.368578 -114.239259) (xy 453.341282 -114.190624) (xy 453.321359 -114.138533) (xy 453.309233 -114.084096)
			(xy 453.305162 -114.028474) (xy 440.427475 -114.028474) (xy 440.455722 -114.052947) (xy 440.491422 -114.094142)
			(xy 440.520895 -114.139999) (xy 440.543542 -114.189584) (xy 440.558901 -114.241887) (xy 440.566659 -114.295844)
			(xy 440.566659 -114.350356) (xy 440.558901 -114.404313) (xy 440.543542 -114.456616) (xy 440.520895 -114.506201)
			(xy 440.491422 -114.552058) (xy 440.455722 -114.593253) (xy 440.414523 -114.628948) (xy 440.368662 -114.658416)
			(xy 440.319075 -114.681057) (xy 440.26677 -114.69641) (xy 440.212812 -114.704162) (xy 440.185556 -114.704622)
			(xy 440.156639 -114.704093) (xy 440.099467 -114.69537) (xy 440.044267 -114.678116) (xy 439.992305 -114.652727)
			(xy 439.944771 -114.619784) (xy 439.902755 -114.580042) (xy 439.884566 -114.557556) (xy 439.876971 -114.548736)
			(xy 439.856061 -114.538561) (xy 439.844434 -114.537998) (xy 439.764678 -114.537998) (xy 439.753046 -114.53854)
			(xy 439.732137 -114.548727) (xy 439.724546 -114.557556) (xy 439.706318 -114.580008) (xy 439.664307 -114.619747)
			(xy 439.61678 -114.652691) (xy 439.564826 -114.678086) (xy 439.509635 -114.695348) (xy 439.45247 -114.704084)
			(xy 439.423556 -114.704622) (xy 439.396304 -114.704163) (xy 439.342356 -114.696401) (xy 439.290062 -114.681041)
			(xy 439.240486 -114.658396) (xy 439.194636 -114.628926) (xy 439.153447 -114.593232) (xy 439.117756 -114.55204)
			(xy 439.08829 -114.506188) (xy 439.065648 -114.45661) (xy 439.050293 -114.404314) (xy 439.042535 -114.350366)
			(xy 439.042048 -114.323114) (xy 439.042489 -114.29571) (xy 439.050342 -114.241467) (xy 439.065876 -114.188906)
			(xy 439.088769 -114.139108) (xy 439.118552 -114.093098) (xy 439.154611 -114.051822) (xy 439.196204 -114.016129)
			(xy 439.219086 -114.001042) (xy 439.228118 -113.994609) (xy 439.239962 -113.975886) (xy 439.241946 -113.964974)
			(xy 439.254138 -113.876836) (xy 439.247534 -113.8555) (xy 439.239914 -113.847118) (xy 439.221626 -113.825528)
			(xy 439.214061 -113.81677) (xy 439.193304 -113.806588) (xy 439.181748 -113.80597) (xy 439.101738 -113.80597)
			(xy 439.0901 -113.806463) (xy 439.069189 -113.816682) (xy 439.061606 -113.825528) (xy 439.043419 -113.848014)
			(xy 439.001397 -113.887748) (xy 438.953861 -113.920686) (xy 438.9019 -113.946074) (xy 438.846702 -113.96333)
			(xy 438.789532 -113.972059) (xy 438.760616 -113.972594) (xy 438.760362 -113.972594) (xy 438.730925 -113.97203)
			(xy 438.672752 -113.962975) (xy 438.644538 -113.95456) (xy 438.6326 -113.95075) (xy 438.608724 -113.95456)
			(xy 438.532524 -114.010948) (xy 438.523238 -114.018675) (xy 438.512503 -114.040282) (xy 438.51195 -114.05235)
			(xy 438.51195 -114.05743) (xy 438.511413 -114.084681) (xy 438.503652 -114.138627) (xy 438.488293 -114.19092)
			(xy 438.465648 -114.240495) (xy 438.436178 -114.286342) (xy 438.400484 -114.327529) (xy 438.359291 -114.363217)
			(xy 438.313439 -114.392679) (xy 438.26386 -114.415315) (xy 438.211565 -114.430665) (xy 438.157617 -114.438417)
			(xy 438.103115 -114.438412) (xy 438.049169 -114.430651) (xy 437.996876 -114.415291) (xy 437.947302 -114.392646)
			(xy 437.901455 -114.363176) (xy 437.860268 -114.327481) (xy 437.824581 -114.286288) (xy 437.79512 -114.240435)
			(xy 437.772483 -114.190856) (xy 437.757134 -114.138561) (xy 437.749383 -114.084613) (xy 429.820977 -114.084613)
			(xy 429.264318 -116.890292) (xy 429.263302 -116.899436) (xy 429.26127 -117.074188) (xy 429.259746 -117.20703)
			(xy 429.249586 -118.077488) (xy 429.249834 -118.086046) (xy 429.255288 -118.102264) (xy 429.260254 -118.109238)
			(xy 429.265588 -118.116096) (xy 429.280066 -118.12524) (xy 429.288448 -118.127272) (xy 429.312396 -118.133528)
			(xy 429.358559 -118.151384) (xy 429.402034 -118.175046) (xy 429.422306 -118.189248) (xy 429.445266 -118.206521)
			(xy 429.486214 -118.246822) (xy 429.50384 -118.269512) (xy 429.509174 -118.276624) (xy 429.531526 -118.291356)
			(xy 429.535358 -118.293755) (xy 429.543659 -118.297335) (xy 429.548036 -118.298468) (xy 429.568864 -118.303294)
			(xy 429.573882 -118.304326) (xy 429.584122 -118.304589) (xy 429.589184 -118.303802) (xy 429.593461 -118.302919)
			(xy 429.601642 -118.299862) (xy 429.60544 -118.297706) (xy 429.631397 -118.283462) (xy 429.6862 -118.261043)
			(xy 429.743435 -118.24588) (xy 429.802149 -118.238225) (xy 429.831754 -118.237762) (xy 429.832262 -118.237762)
			(xy 429.862249 -118.238229) (xy 429.92171 -118.246053) (xy 429.97964 -118.261571) (xy 430.03505 -118.284519)
			(xy 430.086989 -118.314504) (xy 430.13457 -118.351012) (xy 430.176978 -118.393419) (xy 430.213488 -118.440999)
			(xy 430.243474 -118.492938) (xy 430.266424 -118.548346) (xy 430.281945 -118.606277) (xy 430.28977 -118.665737)
			(xy 430.290224 -118.695724) (xy 430.290224 -119.559324) (xy 430.289753 -119.589308) (xy 430.281923 -119.648762)
			(xy 430.266399 -119.706685) (xy 430.243447 -119.762086) (xy 430.21346 -119.814018) (xy 430.176951 -119.861591)
			(xy 430.134544 -119.903992) (xy 430.086966 -119.940494) (xy 430.035031 -119.970474) (xy 429.979626 -119.993419)
			(xy 429.921701 -120.008935) (xy 429.862246 -120.016757) (xy 429.832262 -120.017286) (xy 429.831754 -120.017286)
			(xy 429.802119 -120.016816) (xy 429.743343 -120.009169) (xy 429.686044 -119.994008) (xy 429.631178 -119.971586)
			(xy 429.605186 -119.957342) (xy 429.602392 -119.955818) (xy 429.594622 -119.952351) (xy 429.577747 -119.950263)
			(xy 429.569372 -119.951754) (xy 429.548036 -119.95658) (xy 429.543517 -119.957645) (xy 429.534954 -119.961229)
			(xy 429.531018 -119.963692) (xy 429.50892 -119.978424) (xy 429.50384 -119.985536) (xy 429.48631 -120.008028)
			(xy 429.445695 -120.048054) (xy 429.399582 -120.081599) (xy 429.348996 -120.107918) (xy 429.29506 -120.126425)
			(xy 429.267112 -120.132094) (xy 429.266858 -120.132094) (xy 429.260508 -120.133618) (xy 429.250611 -120.137408)
			(xy 429.234834 -120.151522) (xy 429.226073 -120.170792) (xy 429.225456 -120.18137) (xy 429.21171 -121.365772)
			(xy 432.016408 -121.365772) (xy 432.016408 -120.502172) (xy 432.016898 -120.472188) (xy 432.024726 -120.412732)
			(xy 432.040247 -120.354807) (xy 432.063196 -120.299403) (xy 432.09318 -120.247469) (xy 432.129686 -120.199893)
			(xy 432.172091 -120.157488) (xy 432.219667 -120.120982) (xy 432.271601 -120.090998) (xy 432.327005 -120.068049)
			(xy 432.38493 -120.052528) (xy 432.444386 -120.0447) (xy 432.504354 -120.0447) (xy 432.56381 -120.052528)
			(xy 432.621735 -120.068049) (xy 432.677139 -120.090998) (xy 432.729073 -120.120982) (xy 432.776649 -120.157488)
			(xy 432.819054 -120.199893) (xy 432.85556 -120.247469) (xy 432.885544 -120.299403) (xy 432.908493 -120.354807)
			(xy 432.924014 -120.412732) (xy 432.931842 -120.472188) (xy 432.932332 -120.502172) (xy 432.932332 -121.365772)
			(xy 432.931842 -121.395756) (xy 432.924014 -121.455212) (xy 432.908493 -121.513137) (xy 432.885544 -121.568541)
			(xy 432.85556 -121.620475) (xy 432.819054 -121.668051) (xy 432.776649 -121.710456) (xy 432.729073 -121.746962)
			(xy 432.677139 -121.776946) (xy 432.621735 -121.799895) (xy 432.56381 -121.815416) (xy 432.504354 -121.823244)
			(xy 432.444386 -121.823244) (xy 432.38493 -121.815416) (xy 432.327005 -121.799895) (xy 432.271601 -121.776946)
			(xy 432.219667 -121.746962) (xy 432.172091 -121.710456) (xy 432.129686 -121.668051) (xy 432.09318 -121.620475)
			(xy 432.063196 -121.568541) (xy 432.040247 -121.513137) (xy 432.024726 -121.455212) (xy 432.016898 -121.395756)
			(xy 432.016408 -121.365772) (xy 429.21171 -121.365772) (xy 429.208184 -121.669556) (xy 429.208428 -121.678127)
			(xy 429.213939 -121.694351) (xy 429.22452 -121.707828) (xy 429.231552 -121.712736) (xy 429.236168 -121.715565)
			(xy 429.246289 -121.719403) (xy 429.251618 -121.720356) (xy 429.251872 -121.720356) (xy 429.281565 -121.725118)
			(xy 429.33905 -121.742767) (xy 429.393052 -121.769222) (xy 429.44223 -121.803828) (xy 429.485364 -121.845726)
			(xy 429.50384 -121.869454) (xy 429.50892 -121.876566) (xy 429.531018 -121.891298) (xy 429.53497 -121.893729)
			(xy 429.54353 -121.897306) (xy 429.548036 -121.89841) (xy 429.571658 -121.903744) (xy 429.579574 -121.904746)
			(xy 429.595349 -121.902405) (xy 429.602646 -121.899172) (xy 429.628872 -121.884591) (xy 429.684305 -121.861616)
			(xy 429.742262 -121.846072) (xy 429.801751 -121.838223) (xy 429.831754 -121.837704) (xy 429.832262 -121.837704)
			(xy 429.86225 -121.838171) (xy 429.921714 -121.845994) (xy 429.979647 -121.861513) (xy 430.03506 -121.88446)
			(xy 430.087003 -121.914444) (xy 430.134588 -121.950951) (xy 430.177001 -121.993357) (xy 430.213516 -122.040937)
			(xy 430.243508 -122.092875) (xy 430.266464 -122.148284) (xy 430.281992 -122.206216) (xy 430.289825 -122.265678)
			(xy 430.290224 -122.295666) (xy 430.290224 -123.159266) (xy 430.289734 -123.18925) (xy 430.281906 -123.248706)
			(xy 430.266385 -123.306631) (xy 430.243436 -123.362035) (xy 430.213452 -123.413969) (xy 430.176946 -123.461545)
			(xy 430.134541 -123.50395) (xy 430.086965 -123.540456) (xy 430.035031 -123.57044) (xy 429.979627 -123.593389)
			(xy 429.921702 -123.60891) (xy 429.862246 -123.616738) (xy 429.802278 -123.616738) (xy 429.742822 -123.60891)
			(xy 429.684897 -123.593389) (xy 429.629493 -123.57044) (xy 429.577559 -123.540456) (xy 429.529983 -123.50395)
			(xy 429.487578 -123.461545) (xy 429.451072 -123.413969) (xy 429.421088 -123.362035) (xy 429.398139 -123.306631)
			(xy 429.382618 -123.248706) (xy 429.37479 -123.18925) (xy 429.3743 -123.159266) (xy 429.3743 -122.57532)
			(xy 429.373793 -122.564485) (xy 429.36483 -122.544758) (xy 429.357028 -122.53722) (xy 429.325786 -122.510296)
			(xy 429.2981 -122.486674) (xy 429.290902 -122.481027) (xy 429.273717 -122.474786) (xy 429.264572 -122.474482)
			(xy 429.257206 -122.47499) (xy 429.242982 -122.477022) (xy 429.233925 -122.478512) (xy 429.217649 -122.48697)
			(xy 429.211232 -122.493532) (xy 429.204882 -122.50039) (xy 429.198532 -122.517154) (xy 429.170223 -124.965714)
			(xy 432.016408 -124.965714) (xy 432.016408 -124.102114) (xy 432.016898 -124.07213) (xy 432.024726 -124.012674)
			(xy 432.040247 -123.954749) (xy 432.063196 -123.899345) (xy 432.09318 -123.847411) (xy 432.129686 -123.799835)
			(xy 432.172091 -123.75743) (xy 432.219667 -123.720924) (xy 432.271601 -123.69094) (xy 432.327005 -123.667991)
			(xy 432.38493 -123.65247) (xy 432.444386 -123.644642) (xy 432.504354 -123.644642) (xy 432.56381 -123.65247)
			(xy 432.621735 -123.667991) (xy 432.677139 -123.69094) (xy 432.729073 -123.720924) (xy 432.776649 -123.75743)
			(xy 432.819054 -123.799835) (xy 432.85556 -123.847411) (xy 432.885544 -123.899345) (xy 432.908493 -123.954749)
			(xy 432.924014 -124.012674) (xy 432.931842 -124.07213) (xy 432.932332 -124.102114) (xy 432.932332 -124.965714)
			(xy 432.931842 -124.995698) (xy 432.924014 -125.055154) (xy 432.908493 -125.113079) (xy 432.885544 -125.168483)
			(xy 432.85556 -125.220417) (xy 432.819054 -125.267993) (xy 432.776649 -125.310398) (xy 432.729073 -125.346904)
			(xy 432.677139 -125.376888) (xy 432.621735 -125.399837) (xy 432.56381 -125.415358) (xy 432.504354 -125.423186)
			(xy 432.444386 -125.423186) (xy 432.38493 -125.415358) (xy 432.327005 -125.399837) (xy 432.271601 -125.376888)
			(xy 432.219667 -125.346904) (xy 432.172091 -125.310398) (xy 432.129686 -125.267993) (xy 432.09318 -125.220417)
			(xy 432.063196 -125.168483) (xy 432.040247 -125.113079) (xy 432.024726 -125.055154) (xy 432.016898 -124.995698)
			(xy 432.016408 -124.965714) (xy 429.170223 -124.965714) (xy 429.103127 -130.769106) (xy 429.3743 -130.769106)
			(xy 429.3743 -129.905506) (xy 429.37479 -129.875522) (xy 429.382618 -129.816066) (xy 429.398139 -129.758141)
			(xy 429.421088 -129.702737) (xy 429.451072 -129.650803) (xy 429.487578 -129.603227) (xy 429.529983 -129.560822)
			(xy 429.577559 -129.524316) (xy 429.629493 -129.494332) (xy 429.684897 -129.471383) (xy 429.742822 -129.455862)
			(xy 429.802278 -129.448034) (xy 429.862246 -129.448034) (xy 429.921702 -129.455862) (xy 429.979627 -129.471383)
			(xy 430.035031 -129.494332) (xy 430.086965 -129.524316) (xy 430.134541 -129.560822) (xy 430.176946 -129.603227)
			(xy 430.213452 -129.650803) (xy 430.243436 -129.702737) (xy 430.266385 -129.758141) (xy 430.281906 -129.816066)
			(xy 430.289734 -129.875522) (xy 430.290224 -129.905506) (xy 430.290224 -130.769106) (xy 430.289734 -130.79909)
			(xy 430.281906 -130.858546) (xy 430.266385 -130.916471) (xy 430.243436 -130.971875) (xy 430.213452 -131.023809)
			(xy 430.176946 -131.071385) (xy 430.134541 -131.11379) (xy 430.086965 -131.150296) (xy 430.035031 -131.18028)
			(xy 429.979627 -131.203229) (xy 429.921702 -131.21875) (xy 429.862246 -131.226578) (xy 429.802278 -131.226578)
			(xy 429.742822 -131.21875) (xy 429.684897 -131.203229) (xy 429.629493 -131.18028) (xy 429.577559 -131.150296)
			(xy 429.529983 -131.11379) (xy 429.487578 -131.071385) (xy 429.451072 -131.023809) (xy 429.421088 -130.971875)
			(xy 429.398139 -130.916471) (xy 429.382618 -130.858546) (xy 429.37479 -130.79909) (xy 429.3743 -130.769106)
			(xy 429.103127 -130.769106) (xy 429.082239 -132.575808) (xy 432.016408 -132.575808) (xy 432.016408 -131.712208)
			(xy 432.016898 -131.682224) (xy 432.024726 -131.622768) (xy 432.040247 -131.564843) (xy 432.063196 -131.509439)
			(xy 432.09318 -131.457505) (xy 432.129686 -131.409929) (xy 432.172091 -131.367524) (xy 432.219667 -131.331018)
			(xy 432.271601 -131.301034) (xy 432.327005 -131.278085) (xy 432.38493 -131.262564) (xy 432.444386 -131.254736)
			(xy 432.504354 -131.254736) (xy 432.56381 -131.262564) (xy 432.621735 -131.278085) (xy 432.677139 -131.301034)
			(xy 432.729073 -131.331018) (xy 432.776649 -131.367524) (xy 432.819054 -131.409929) (xy 432.85556 -131.457505)
			(xy 432.885544 -131.509439) (xy 432.908493 -131.564843) (xy 432.924014 -131.622768) (xy 432.931842 -131.682224)
			(xy 432.932332 -131.712208) (xy 432.932332 -132.575808) (xy 432.931842 -132.605792) (xy 432.924014 -132.665248)
			(xy 432.908493 -132.723173) (xy 432.885544 -132.778577) (xy 432.85556 -132.830511) (xy 432.819054 -132.878087)
			(xy 432.776649 -132.920492) (xy 432.729073 -132.956998) (xy 432.677139 -132.986982) (xy 432.621735 -133.009931)
			(xy 432.56381 -133.025452) (xy 432.504354 -133.03328) (xy 432.444386 -133.03328) (xy 432.38493 -133.025452)
			(xy 432.327005 -133.009931) (xy 432.271601 -132.986982) (xy 432.219667 -132.956998) (xy 432.172091 -132.920492)
			(xy 432.129686 -132.878087) (xy 432.09318 -132.830511) (xy 432.063196 -132.778577) (xy 432.040247 -132.723173)
			(xy 432.024726 -132.665248) (xy 432.016898 -132.605792) (xy 432.016408 -132.575808) (xy 429.082239 -132.575808)
			(xy 429.061503 -134.369302) (xy 429.3743 -134.369302) (xy 429.3743 -133.505702) (xy 429.37479 -133.475718)
			(xy 429.382618 -133.416262) (xy 429.398139 -133.358337) (xy 429.421088 -133.302933) (xy 429.451072 -133.250999)
			(xy 429.487578 -133.203423) (xy 429.529983 -133.161018) (xy 429.577559 -133.124512) (xy 429.629493 -133.094528)
			(xy 429.684897 -133.071579) (xy 429.742822 -133.056058) (xy 429.802278 -133.04823) (xy 429.862246 -133.04823)
			(xy 429.921702 -133.056058) (xy 429.979627 -133.071579) (xy 430.035031 -133.094528) (xy 430.086965 -133.124512)
			(xy 430.134541 -133.161018) (xy 430.176946 -133.203423) (xy 430.213452 -133.250999) (xy 430.243436 -133.302933)
			(xy 430.266385 -133.358337) (xy 430.281906 -133.416262) (xy 430.289734 -133.475718) (xy 430.290224 -133.505702)
			(xy 430.290224 -134.369302) (xy 430.289734 -134.399286) (xy 430.281906 -134.458742) (xy 430.266385 -134.516667)
			(xy 430.243436 -134.572071) (xy 430.213452 -134.624005) (xy 430.176946 -134.671581) (xy 430.134541 -134.713986)
			(xy 430.086965 -134.750492) (xy 430.035031 -134.780476) (xy 429.979627 -134.803425) (xy 429.921702 -134.818946)
			(xy 429.862246 -134.826774) (xy 429.802278 -134.826774) (xy 429.742822 -134.818946) (xy 429.684897 -134.803425)
			(xy 429.629493 -134.780476) (xy 429.577559 -134.750492) (xy 429.529983 -134.713986) (xy 429.487578 -134.671581)
			(xy 429.451072 -134.624005) (xy 429.421088 -134.572071) (xy 429.398139 -134.516667) (xy 429.382618 -134.458742)
			(xy 429.37479 -134.399286) (xy 429.3743 -134.369302) (xy 429.061503 -134.369302) (xy 429.040618 -136.17575)
			(xy 432.016408 -136.17575) (xy 432.016408 -135.31215) (xy 432.016898 -135.282166) (xy 432.024726 -135.22271)
			(xy 432.040247 -135.164785) (xy 432.063196 -135.109381) (xy 432.09318 -135.057447) (xy 432.129686 -135.009871)
			(xy 432.172091 -134.967466) (xy 432.219667 -134.93096) (xy 432.271601 -134.900976) (xy 432.327005 -134.878027)
			(xy 432.38493 -134.862506) (xy 432.444386 -134.854678) (xy 432.504354 -134.854678) (xy 432.56381 -134.862506)
			(xy 432.621735 -134.878027) (xy 432.677139 -134.900976) (xy 432.729073 -134.93096) (xy 432.776649 -134.967466)
			(xy 432.819054 -135.009871) (xy 432.85556 -135.057447) (xy 432.885544 -135.109381) (xy 432.908493 -135.164785)
			(xy 432.924014 -135.22271) (xy 432.931842 -135.282166) (xy 432.932332 -135.31215) (xy 432.932332 -136.17575)
			(xy 432.931842 -136.205734) (xy 432.924014 -136.26519) (xy 432.908493 -136.323115) (xy 432.885544 -136.378519)
			(xy 432.85556 -136.430453) (xy 432.819054 -136.478029) (xy 432.776649 -136.520434) (xy 432.729073 -136.55694)
			(xy 432.677139 -136.586924) (xy 432.621735 -136.609873) (xy 432.56381 -136.625394) (xy 432.504354 -136.633222)
			(xy 432.444386 -136.633222) (xy 432.38493 -136.625394) (xy 432.327005 -136.609873) (xy 432.271601 -136.586924)
			(xy 432.219667 -136.55694) (xy 432.172091 -136.520434) (xy 432.129686 -136.478029) (xy 432.09318 -136.430453)
			(xy 432.063196 -136.378519) (xy 432.040247 -136.323115) (xy 432.024726 -136.26519) (xy 432.016898 -136.205734)
			(xy 432.016408 -136.17575) (xy 429.040618 -136.17575) (xy 429.037496 -136.445752) (xy 429.036734 -136.510014)
			(xy 429.036978 -136.518247) (xy 429.042043 -136.533911) (xy 429.04664 -136.540748) (xy 429.052482 -136.547352)
			(xy 429.055276 -136.549892) (xy 429.11649 -136.600184) (xy 429.121067 -136.603742) (xy 429.131454 -136.608885)
			(xy 429.137064 -136.610344) (xy 429.147986 -136.612884) (xy 429.153828 -136.611614) (xy 429.174819 -136.607179)
			(xy 429.217465 -136.602468) (xy 429.238918 -136.602216) (xy 429.23968 -136.602216) (xy 429.267096 -136.60268)
			(xy 429.321371 -136.610481) (xy 429.373984 -136.625927) (xy 429.423862 -136.648704) (xy 429.469991 -136.678347)
			(xy 429.511432 -136.714254) (xy 429.547341 -136.755693) (xy 429.576987 -136.80182) (xy 429.599766 -136.851698)
			(xy 429.615215 -136.904309) (xy 429.623018 -136.958584) (xy 429.623018 -137.013416) (xy 429.615215 -137.067691)
			(xy 429.599766 -137.120302) (xy 429.576987 -137.17018) (xy 429.547341 -137.216307) (xy 429.511432 -137.257746)
			(xy 429.469991 -137.293653) (xy 429.423862 -137.323296) (xy 429.373984 -137.346073) (xy 429.321371 -137.361519)
			(xy 429.267096 -137.36932) (xy 429.23968 -137.369804) (xy 429.239426 -137.369804) (xy 429.216985 -137.369425)
			(xy 429.17242 -137.364076) (xy 429.150526 -137.359136) (xy 429.14824 -137.358628) (xy 429.147732 -137.358628)
			(xy 429.13935 -137.356596) (xy 429.128682 -137.358882) (xy 429.123102 -137.360229) (xy 429.112713 -137.365105)
			(xy 429.108108 -137.368534) (xy 429.04537 -137.417556) (xy 429.036662 -137.424997) (xy 429.026487 -137.445492)
			(xy 429.025812 -137.456926) (xy 429.004984 -139.252198) (xy 429.005294 -139.261761) (xy 429.012075 -139.279639)
			(xy 429.018192 -139.286996) (xy 429.06442 -139.33805) (xy 429.067835 -139.341616) (xy 429.075767 -139.347494)
			(xy 429.080168 -139.349734) (xy 429.08855 -139.353798) (xy 429.098202 -139.35456) (xy 429.125419 -139.357319)
			(xy 429.178718 -139.369643) (xy 429.229707 -139.38946) (xy 429.27734 -139.416363) (xy 429.320637 -139.449799)
			(xy 429.34001 -139.469114) (xy 429.347122 -139.47648) (xy 429.373792 -139.48791) (xy 429.378473 -139.489754)
			(xy 429.388322 -139.491799) (xy 429.39335 -139.491974) (xy 429.447706 -139.491974) (xy 429.452803 -139.491861)
			(xy 429.462788 -139.489813) (xy 429.467518 -139.48791) (xy 429.494188 -139.47648) (xy 429.5013 -139.469114)
			(xy 429.519252 -139.451204) (xy 429.55907 -139.419804) (xy 429.602697 -139.393957) (xy 429.649365 -139.374119)
			(xy 429.698249 -139.360638) (xy 429.748489 -139.353754) (xy 429.773842 -139.35329) (xy 429.780192 -139.35329)
			(xy 429.796614 -139.3537) (xy 429.829299 -139.357003) (xy 429.84547 -139.359894) (xy 429.873366 -139.365625)
			(xy 429.927185 -139.384244) (xy 429.952658 -139.396978) (xy 429.953674 -139.397486) (xy 429.956976 -139.399264)
			(xy 429.96358 -139.40282) (xy 430.565052 -139.40282) (xy 430.574704 -139.401804) (xy 430.581945 -139.400171)
			(xy 430.595108 -139.393324) (xy 430.600612 -139.388342) (xy 433.720494 -136.26846) (xy 433.725481 -136.262961)
			(xy 433.732322 -136.249793) (xy 433.733956 -136.242552) (xy 433.734972 -136.2329) (xy 433.734972 -117.276626)
			(xy 433.735456 -117.250538) (xy 433.74362 -117.199005) (xy 433.75975 -117.149385) (xy 433.783449 -117.102903)
			(xy 433.814133 -117.060703) (xy 433.832254 -117.04193) (xy 435.57444 -115.299744) (xy 435.576472 -115.293648)
			(xy 435.577742 -115.290092) (xy 435.586056 -115.264342) (xy 435.608936 -115.215308) (xy 435.638513 -115.169998)
			(xy 435.674194 -115.12932) (xy 435.715262 -115.094089) (xy 435.760895 -115.065013) (xy 435.810178 -115.042673)
			(xy 435.862122 -115.027519) (xy 435.915686 -115.019854) (xy 435.94274 -115.019328) (xy 435.969988 -115.019817)
			(xy 436.02393 -115.027578) (xy 436.076218 -115.042937) (xy 436.125787 -115.065581) (xy 436.17163 -115.095049)
			(xy 436.212813 -115.130741) (xy 436.248497 -115.171931) (xy 436.277955 -115.217779) (xy 436.300589 -115.267354)
			(xy 436.315938 -115.319645) (xy 436.323224 -115.370356) (xy 437.661302 -115.370356) (xy 437.665373 -115.314734)
			(xy 437.677499 -115.260297) (xy 437.697422 -115.208206) (xy 437.724718 -115.159571) (xy 437.758804 -115.115428)
			(xy 437.798953 -115.076719) (xy 437.844311 -115.044268) (xy 437.893911 -115.018767) (xy 437.946695 -115.00076)
			(xy 438.001538 -114.99063) (xy 438.057272 -114.988593) (xy 438.112709 -114.994693) (xy 438.166666 -115.008799)
			(xy 438.171718 -115.010946) (xy 454.91984 -115.010946) (xy 454.923911 -114.955324) (xy 454.936037 -114.900887)
			(xy 454.95596 -114.848796) (xy 454.983256 -114.800161) (xy 455.017342 -114.756018) (xy 455.057491 -114.717309)
			(xy 455.102849 -114.684858) (xy 455.152449 -114.659357) (xy 455.205233 -114.64135) (xy 455.260076 -114.63122)
			(xy 455.31581 -114.629183) (xy 455.371247 -114.635283) (xy 455.425204 -114.649389) (xy 455.476533 -114.671201)
			(xy 455.524139 -114.700255) (xy 455.567007 -114.73593) (xy 455.604224 -114.777467) (xy 455.634997 -114.82398)
			(xy 455.658669 -114.874477) (xy 455.674737 -114.927884) (xy 455.682857 -114.98306) (xy 455.683366 -115.010946)
			(xy 455.682857 -115.038832) (xy 455.679933 -115.058698) (xy 456.28636 -115.058698) (xy 456.290431 -115.003076)
			(xy 456.302557 -114.948639) (xy 456.32248 -114.896548) (xy 456.349776 -114.847913) (xy 456.383862 -114.80377)
			(xy 456.424011 -114.765061) (xy 456.469369 -114.73261) (xy 456.518969 -114.707109) (xy 456.571753 -114.689102)
			(xy 456.626596 -114.678972) (xy 456.68233 -114.676935) (xy 456.737767 -114.683035) (xy 456.791724 -114.697141)
			(xy 456.843053 -114.718953) (xy 456.890659 -114.748007) (xy 456.933527 -114.783682) (xy 456.970744 -114.825219)
			(xy 457.001517 -114.871732) (xy 457.025189 -114.922229) (xy 457.041257 -114.975636) (xy 457.043426 -114.990372)
			(xy 457.665072 -114.990372) (xy 457.669143 -114.93475) (xy 457.681269 -114.880313) (xy 457.701192 -114.828222)
			(xy 457.728488 -114.779587) (xy 457.762574 -114.735444) (xy 457.802723 -114.696735) (xy 457.848081 -114.664284)
			(xy 457.897681 -114.638783) (xy 457.950465 -114.620776) (xy 458.005308 -114.610646) (xy 458.061042 -114.608609)
			(xy 458.116479 -114.614709) (xy 458.170436 -114.628815) (xy 458.221765 -114.650627) (xy 458.269371 -114.679681)
			(xy 458.312239 -114.715356) (xy 458.349456 -114.756893) (xy 458.380229 -114.803406) (xy 458.403901 -114.853903)
			(xy 458.419969 -114.90731) (xy 458.427819 -114.960654) (xy 459.191866 -114.960654) (xy 459.195937 -114.905032)
			(xy 459.208063 -114.850595) (xy 459.227986 -114.798504) (xy 459.255282 -114.749869) (xy 459.289368 -114.705726)
			(xy 459.329517 -114.667017) (xy 459.374875 -114.634566) (xy 459.424475 -114.609065) (xy 459.477259 -114.591058)
			(xy 459.532102 -114.580928) (xy 459.587836 -114.578891) (xy 459.643273 -114.584991) (xy 459.69723 -114.599097)
			(xy 459.748559 -114.620909) (xy 459.796165 -114.649963) (xy 459.839033 -114.685638) (xy 459.87625 -114.727175)
			(xy 459.907023 -114.773688) (xy 459.930695 -114.824185) (xy 459.946763 -114.877592) (xy 459.954883 -114.932768)
			(xy 459.955392 -114.960654) (xy 459.954883 -114.98854) (xy 459.946763 -115.043716) (xy 459.930695 -115.097123)
			(xy 459.907023 -115.14762) (xy 459.87625 -115.194133) (xy 459.839033 -115.23567) (xy 459.796165 -115.271345)
			(xy 459.748559 -115.300399) (xy 459.69723 -115.322211) (xy 459.643273 -115.336317) (xy 459.587836 -115.342417)
			(xy 459.532102 -115.34038) (xy 459.477259 -115.33025) (xy 459.424475 -115.312243) (xy 459.374875 -115.286742)
			(xy 459.329517 -115.254291) (xy 459.289368 -115.215582) (xy 459.255282 -115.171439) (xy 459.227986 -115.122804)
			(xy 459.208063 -115.070713) (xy 459.195937 -115.016276) (xy 459.191866 -114.960654) (xy 458.427819 -114.960654)
			(xy 458.428089 -114.962486) (xy 458.428598 -114.990372) (xy 458.428089 -115.018258) (xy 458.419969 -115.073434)
			(xy 458.403901 -115.126841) (xy 458.380229 -115.177338) (xy 458.349456 -115.223851) (xy 458.312239 -115.265388)
			(xy 458.269371 -115.301063) (xy 458.221765 -115.330117) (xy 458.170436 -115.351929) (xy 458.116479 -115.366035)
			(xy 458.061042 -115.372135) (xy 458.005308 -115.370098) (xy 457.950465 -115.359968) (xy 457.897681 -115.341961)
			(xy 457.848081 -115.31646) (xy 457.802723 -115.284009) (xy 457.762574 -115.2453) (xy 457.728488 -115.201157)
			(xy 457.701192 -115.152522) (xy 457.681269 -115.100431) (xy 457.669143 -115.045994) (xy 457.665072 -114.990372)
			(xy 457.043426 -114.990372) (xy 457.049377 -115.030812) (xy 457.049886 -115.058698) (xy 457.049377 -115.086584)
			(xy 457.041257 -115.14176) (xy 457.025189 -115.195167) (xy 457.001517 -115.245664) (xy 456.970744 -115.292177)
			(xy 456.933527 -115.333714) (xy 456.890659 -115.369389) (xy 456.843053 -115.398443) (xy 456.791724 -115.420255)
			(xy 456.737767 -115.434361) (xy 456.68233 -115.440461) (xy 456.626596 -115.438424) (xy 456.571753 -115.428294)
			(xy 456.518969 -115.410287) (xy 456.469369 -115.384786) (xy 456.424011 -115.352335) (xy 456.383862 -115.313626)
			(xy 456.349776 -115.269483) (xy 456.32248 -115.220848) (xy 456.302557 -115.168757) (xy 456.290431 -115.11432)
			(xy 456.28636 -115.058698) (xy 455.679933 -115.058698) (xy 455.674737 -115.094008) (xy 455.658669 -115.147415)
			(xy 455.634997 -115.197912) (xy 455.604224 -115.244425) (xy 455.567007 -115.285962) (xy 455.524139 -115.321637)
			(xy 455.476533 -115.350691) (xy 455.425204 -115.372503) (xy 455.371247 -115.386609) (xy 455.31581 -115.392709)
			(xy 455.260076 -115.390672) (xy 455.205233 -115.380542) (xy 455.152449 -115.362535) (xy 455.102849 -115.337034)
			(xy 455.057491 -115.304583) (xy 455.017342 -115.265874) (xy 454.983256 -115.221731) (xy 454.95596 -115.173096)
			(xy 454.936037 -115.121005) (xy 454.923911 -115.066568) (xy 454.91984 -115.010946) (xy 438.171718 -115.010946)
			(xy 438.217995 -115.030611) (xy 438.265601 -115.059665) (xy 438.308469 -115.09534) (xy 438.345686 -115.136877)
			(xy 438.376459 -115.18339) (xy 438.400131 -115.233887) (xy 438.416199 -115.287294) (xy 438.424319 -115.34247)
			(xy 438.424828 -115.370356) (xy 438.424319 -115.398242) (xy 438.416199 -115.453418) (xy 438.400131 -115.506825)
			(xy 438.376459 -115.557322) (xy 438.345686 -115.603835) (xy 438.308469 -115.645372) (xy 438.265601 -115.681047)
			(xy 438.217995 -115.710101) (xy 438.166666 -115.731913) (xy 438.112709 -115.746019) (xy 438.057272 -115.752119)
			(xy 438.001538 -115.750082) (xy 437.946695 -115.739952) (xy 437.893911 -115.721945) (xy 437.844311 -115.696444)
			(xy 437.798953 -115.663993) (xy 437.758804 -115.625284) (xy 437.724718 -115.581141) (xy 437.697422 -115.532506)
			(xy 437.677499 -115.480415) (xy 437.665373 -115.425978) (xy 437.661302 -115.370356) (xy 436.323224 -115.370356)
			(xy 436.323688 -115.373587) (xy 436.324248 -115.400836) (xy 436.32379 -115.42775) (xy 436.31623 -115.481043)
			(xy 436.30125 -115.532744) (xy 436.27915 -115.581825) (xy 436.250367 -115.627311) (xy 436.215475 -115.668297)
			(xy 436.175165 -115.703969) (xy 436.13024 -115.733619) (xy 436.081592 -115.756656) (xy 436.056024 -115.765072)
			(xy 436.052214 -115.766342) (xy 436.044848 -115.770152) (xy 436.03545 -115.777518) (xy 435.980332 -115.832636)
			(xy 441.279278 -115.832636) (xy 441.283349 -115.777014) (xy 441.295475 -115.722577) (xy 441.315398 -115.670486)
			(xy 441.342694 -115.621851) (xy 441.37678 -115.577708) (xy 441.416929 -115.538999) (xy 441.462287 -115.506548)
			(xy 441.511887 -115.481047) (xy 441.564671 -115.46304) (xy 441.619514 -115.45291) (xy 441.675248 -115.450873)
			(xy 441.730685 -115.456973) (xy 441.784642 -115.471079) (xy 441.835971 -115.492891) (xy 441.883577 -115.521945)
			(xy 441.926445 -115.55762) (xy 441.963662 -115.599157) (xy 441.994435 -115.64567) (xy 442.018107 -115.696167)
			(xy 442.034175 -115.749574) (xy 442.042295 -115.80475) (xy 442.042804 -115.832636) (xy 442.042295 -115.860522)
			(xy 442.034175 -115.915698) (xy 442.018107 -115.969105) (xy 441.994435 -116.019602) (xy 441.963662 -116.066115)
			(xy 441.926445 -116.107652) (xy 441.883577 -116.143327) (xy 441.835971 -116.172381) (xy 441.784642 -116.194193)
			(xy 441.730685 -116.208299) (xy 441.675248 -116.214399) (xy 441.619514 -116.212362) (xy 441.564671 -116.202232)
			(xy 441.511887 -116.184225) (xy 441.462287 -116.158724) (xy 441.416929 -116.126273) (xy 441.37678 -116.087564)
			(xy 441.342694 -116.043421) (xy 441.315398 -115.994786) (xy 441.295475 -115.942695) (xy 441.283349 -115.888258)
			(xy 441.279278 -115.832636) (xy 435.980332 -115.832636) (xy 435.143148 -116.66982) (xy 437.67324 -116.66982)
			(xy 437.677311 -116.614198) (xy 437.689437 -116.559761) (xy 437.70936 -116.50767) (xy 437.736656 -116.459035)
			(xy 437.770742 -116.414892) (xy 437.810891 -116.376183) (xy 437.856249 -116.343732) (xy 437.905849 -116.318231)
			(xy 437.958633 -116.300224) (xy 438.013476 -116.290094) (xy 438.06921 -116.288057) (xy 438.124647 -116.294157)
			(xy 438.178604 -116.308263) (xy 438.229933 -116.330075) (xy 438.277539 -116.359129) (xy 438.320407 -116.394804)
			(xy 438.357624 -116.436341) (xy 438.388397 -116.482854) (xy 438.412069 -116.533351) (xy 438.428137 -116.586758)
			(xy 438.43438 -116.62918) (xy 453.438004 -116.62918) (xy 453.442075 -116.573558) (xy 453.454201 -116.519121)
			(xy 453.474124 -116.46703) (xy 453.50142 -116.418395) (xy 453.535506 -116.374252) (xy 453.575655 -116.335543)
			(xy 453.621013 -116.303092) (xy 453.670613 -116.277591) (xy 453.723397 -116.259584) (xy 453.77824 -116.249454)
			(xy 453.833974 -116.247417) (xy 453.889411 -116.253517) (xy 453.943368 -116.267623) (xy 453.994697 -116.289435)
			(xy 454.042303 -116.318489) (xy 454.085171 -116.354164) (xy 454.122388 -116.395701) (xy 454.153161 -116.442214)
			(xy 454.176833 -116.492711) (xy 454.192901 -116.546118) (xy 454.201021 -116.601294) (xy 454.20153 -116.62918)
			(xy 454.201021 -116.657066) (xy 454.192901 -116.712242) (xy 454.176833 -116.765649) (xy 454.153161 -116.816146)
			(xy 454.122388 -116.862659) (xy 454.085171 -116.904196) (xy 454.042303 -116.939871) (xy 453.994697 -116.968925)
			(xy 453.943368 -116.990737) (xy 453.889411 -117.004843) (xy 453.833974 -117.010943) (xy 453.77824 -117.008906)
			(xy 453.723397 -116.998776) (xy 453.670613 -116.980769) (xy 453.621013 -116.955268) (xy 453.575655 -116.922817)
			(xy 453.535506 -116.884108) (xy 453.50142 -116.839965) (xy 453.474124 -116.79133) (xy 453.454201 -116.739239)
			(xy 453.442075 -116.684802) (xy 453.438004 -116.62918) (xy 438.43438 -116.62918) (xy 438.436257 -116.641934)
			(xy 438.436766 -116.66982) (xy 438.436257 -116.697706) (xy 438.428137 -116.752882) (xy 438.412069 -116.806289)
			(xy 438.388397 -116.856786) (xy 438.357624 -116.903299) (xy 438.320407 -116.944836) (xy 438.277539 -116.980511)
			(xy 438.229933 -117.009565) (xy 438.178604 -117.031377) (xy 438.124647 -117.045483) (xy 438.06921 -117.051583)
			(xy 438.013476 -117.049546) (xy 437.958633 -117.039416) (xy 437.905849 -117.021409) (xy 437.856249 -116.995908)
			(xy 437.810891 -116.963457) (xy 437.770742 -116.924748) (xy 437.736656 -116.880605) (xy 437.70936 -116.83197)
			(xy 437.689437 -116.779879) (xy 437.677311 -116.725442) (xy 437.67324 -116.66982) (xy 435.143148 -116.66982)
			(xy 434.422522 -117.390446) (xy 439.042618 -117.390446) (xy 439.042618 -117.335954) (xy 439.050373 -117.282015)
			(xy 439.065724 -117.22973) (xy 439.088359 -117.180161) (xy 439.117818 -117.134317) (xy 439.153501 -117.093133)
			(xy 439.194682 -117.057445) (xy 439.240522 -117.027981) (xy 439.290089 -117.005339) (xy 439.342372 -116.989982)
			(xy 439.39631 -116.982221) (xy 439.423556 -116.981732) (xy 439.452472 -116.98227) (xy 439.509643 -116.990993)
			(xy 439.564842 -117.008246) (xy 439.616804 -117.033634) (xy 439.664339 -117.066575) (xy 439.706356 -117.106314)
			(xy 439.724546 -117.128798) (xy 439.732143 -117.137616) (xy 439.753051 -117.147794) (xy 439.764678 -117.148356)
			(xy 439.844434 -117.148356) (xy 439.856069 -117.147838) (xy 439.876979 -117.137636) (xy 439.884566 -117.128798)
			(xy 439.902776 -117.10633) (xy 439.944792 -117.066594) (xy 439.992323 -117.033653) (xy 440.04428 -117.008262)
			(xy 440.099474 -116.991003) (xy 440.156641 -116.982269) (xy 440.185556 -116.981732) (xy 440.212814 -116.982112)
			(xy 440.266775 -116.989865) (xy 440.319084 -117.005218) (xy 440.368675 -117.027861) (xy 440.414538 -117.057331)
			(xy 440.455741 -117.093028) (xy 440.464067 -117.102636) (xy 441.279278 -117.102636) (xy 441.283349 -117.047014)
			(xy 441.295475 -116.992577) (xy 441.315398 -116.940486) (xy 441.342694 -116.891851) (xy 441.37678 -116.847708)
			(xy 441.416929 -116.808999) (xy 441.462287 -116.776548) (xy 441.511887 -116.751047) (xy 441.564671 -116.73304)
			(xy 441.619514 -116.72291) (xy 441.675248 -116.720873) (xy 441.730685 -116.726973) (xy 441.784642 -116.741079)
			(xy 441.835971 -116.762891) (xy 441.883577 -116.791945) (xy 441.926445 -116.82762) (xy 441.963662 -116.869157)
			(xy 441.994435 -116.91567) (xy 442.018107 -116.966167) (xy 442.034175 -117.019574) (xy 442.042295 -117.07475)
			(xy 442.042804 -117.102636) (xy 442.042295 -117.130522) (xy 442.034175 -117.185698) (xy 442.018107 -117.239105)
			(xy 442.013854 -117.248178) (xy 456.038964 -117.248178) (xy 456.043035 -117.192556) (xy 456.055161 -117.138119)
			(xy 456.075084 -117.086028) (xy 456.10238 -117.037393) (xy 456.136466 -116.99325) (xy 456.176615 -116.954541)
			(xy 456.221973 -116.92209) (xy 456.271573 -116.896589) (xy 456.324357 -116.878582) (xy 456.3792 -116.868452)
			(xy 456.434934 -116.866415) (xy 456.490371 -116.872515) (xy 456.544328 -116.886621) (xy 456.595657 -116.908433)
			(xy 456.643263 -116.937487) (xy 456.686131 -116.973162) (xy 456.723348 -117.014699) (xy 456.754121 -117.061212)
			(xy 456.777793 -117.111709) (xy 456.793861 -117.165116) (xy 456.801981 -117.220292) (xy 456.80249 -117.248178)
			(xy 457.054964 -117.248178) (xy 457.059035 -117.192556) (xy 457.071161 -117.138119) (xy 457.091084 -117.086028)
			(xy 457.11838 -117.037393) (xy 457.152466 -116.99325) (xy 457.192615 -116.954541) (xy 457.237973 -116.92209)
			(xy 457.287573 -116.896589) (xy 457.340357 -116.878582) (xy 457.3952 -116.868452) (xy 457.450934 -116.866415)
			(xy 457.506371 -116.872515) (xy 457.560328 -116.886621) (xy 457.611657 -116.908433) (xy 457.659263 -116.937487)
			(xy 457.702131 -116.973162) (xy 457.739348 -117.014699) (xy 457.770121 -117.061212) (xy 457.793793 -117.111709)
			(xy 457.809861 -117.165116) (xy 457.817981 -117.220292) (xy 457.81849 -117.248178) (xy 458.070964 -117.248178)
			(xy 458.075035 -117.192556) (xy 458.087161 -117.138119) (xy 458.107084 -117.086028) (xy 458.13438 -117.037393)
			(xy 458.168466 -116.99325) (xy 458.208615 -116.954541) (xy 458.253973 -116.92209) (xy 458.303573 -116.896589)
			(xy 458.356357 -116.878582) (xy 458.4112 -116.868452) (xy 458.466934 -116.866415) (xy 458.522371 -116.872515)
			(xy 458.576328 -116.886621) (xy 458.627657 -116.908433) (xy 458.675263 -116.937487) (xy 458.718131 -116.973162)
			(xy 458.755348 -117.014699) (xy 458.786121 -117.061212) (xy 458.809793 -117.111709) (xy 458.825861 -117.165116)
			(xy 458.833981 -117.220292) (xy 458.83449 -117.248178) (xy 458.833981 -117.276064) (xy 458.825861 -117.33124)
			(xy 458.809793 -117.384647) (xy 458.786121 -117.435144) (xy 458.755348 -117.481657) (xy 458.718131 -117.523194)
			(xy 458.675263 -117.558869) (xy 458.627657 -117.587923) (xy 458.576328 -117.609735) (xy 458.522371 -117.623841)
			(xy 458.466934 -117.629941) (xy 458.4112 -117.627904) (xy 458.356357 -117.617774) (xy 458.303573 -117.599767)
			(xy 458.253973 -117.574266) (xy 458.208615 -117.541815) (xy 458.168466 -117.503106) (xy 458.13438 -117.458963)
			(xy 458.107084 -117.410328) (xy 458.087161 -117.358237) (xy 458.075035 -117.3038) (xy 458.070964 -117.248178)
			(xy 457.81849 -117.248178) (xy 457.817981 -117.276064) (xy 457.809861 -117.33124) (xy 457.793793 -117.384647)
			(xy 457.770121 -117.435144) (xy 457.739348 -117.481657) (xy 457.702131 -117.523194) (xy 457.659263 -117.558869)
			(xy 457.611657 -117.587923) (xy 457.560328 -117.609735) (xy 457.506371 -117.623841) (xy 457.450934 -117.629941)
			(xy 457.3952 -117.627904) (xy 457.340357 -117.617774) (xy 457.287573 -117.599767) (xy 457.237973 -117.574266)
			(xy 457.192615 -117.541815) (xy 457.152466 -117.503106) (xy 457.11838 -117.458963) (xy 457.091084 -117.410328)
			(xy 457.071161 -117.358237) (xy 457.059035 -117.3038) (xy 457.054964 -117.248178) (xy 456.80249 -117.248178)
			(xy 456.801981 -117.276064) (xy 456.793861 -117.33124) (xy 456.777793 -117.384647) (xy 456.754121 -117.435144)
			(xy 456.723348 -117.481657) (xy 456.686131 -117.523194) (xy 456.643263 -117.558869) (xy 456.595657 -117.587923)
			(xy 456.544328 -117.609735) (xy 456.490371 -117.623841) (xy 456.434934 -117.629941) (xy 456.3792 -117.627904)
			(xy 456.324357 -117.617774) (xy 456.271573 -117.599767) (xy 456.221973 -117.574266) (xy 456.176615 -117.541815)
			(xy 456.136466 -117.503106) (xy 456.10238 -117.458963) (xy 456.075084 -117.410328) (xy 456.055161 -117.358237)
			(xy 456.043035 -117.3038) (xy 456.038964 -117.248178) (xy 442.013854 -117.248178) (xy 441.994435 -117.289602)
			(xy 441.963662 -117.336115) (xy 441.926445 -117.377652) (xy 441.883577 -117.413327) (xy 441.835971 -117.442381)
			(xy 441.784642 -117.464193) (xy 441.730685 -117.478299) (xy 441.675248 -117.484399) (xy 441.619514 -117.482362)
			(xy 441.564671 -117.472232) (xy 441.511887 -117.454225) (xy 441.462287 -117.428724) (xy 441.416929 -117.396273)
			(xy 441.37678 -117.357564) (xy 441.342694 -117.313421) (xy 441.315398 -117.264786) (xy 441.295475 -117.212695)
			(xy 441.283349 -117.158258) (xy 441.279278 -117.102636) (xy 440.464067 -117.102636) (xy 440.491443 -117.134226)
			(xy 440.520918 -117.180087) (xy 440.543566 -117.229675) (xy 440.558926 -117.281982) (xy 440.566685 -117.335942)
			(xy 440.566685 -117.390458) (xy 440.558926 -117.444418) (xy 440.543566 -117.496725) (xy 440.520918 -117.546313)
			(xy 440.491443 -117.592174) (xy 440.455741 -117.633372) (xy 440.414538 -117.669069) (xy 440.368675 -117.698539)
			(xy 440.319084 -117.721182) (xy 440.266775 -117.736535) (xy 440.212814 -117.744288) (xy 440.185556 -117.744748)
			(xy 440.15664 -117.744209) (xy 440.099468 -117.735487) (xy 440.044269 -117.718235) (xy 439.992307 -117.692847)
			(xy 439.944773 -117.659906) (xy 439.902756 -117.620167) (xy 439.884566 -117.597682) (xy 439.876967 -117.588866)
			(xy 439.85606 -117.578688) (xy 439.844434 -117.578124) (xy 439.764678 -117.578124) (xy 439.753045 -117.578656)
			(xy 439.732135 -117.588849) (xy 439.724546 -117.597682) (xy 439.706324 -117.62014) (xy 439.664312 -117.659877)
			(xy 439.616783 -117.69282) (xy 439.564828 -117.718213) (xy 439.509635 -117.735475) (xy 439.45247 -117.74421)
			(xy 439.423556 -117.744748) (xy 439.39631 -117.744179) (xy 439.342372 -117.736418) (xy 439.290089 -117.721061)
			(xy 439.240522 -117.698419) (xy 439.194682 -117.668955) (xy 439.153501 -117.633267) (xy 439.117818 -117.592083)
			(xy 439.088359 -117.546239) (xy 439.065724 -117.49667) (xy 439.050373 -117.444385) (xy 439.042618 -117.390446)
			(xy 434.422522 -117.390446) (xy 434.41366 -117.399308) (xy 434.410953 -117.402158) (xy 434.406359 -117.408536)
			(xy 434.404516 -117.412008) (xy 434.401928 -117.417434) (xy 434.399096 -117.429113) (xy 434.398928 -117.435122)
			(xy 434.398928 -118.467886) (xy 445.782444 -118.467886) (xy 445.786515 -118.412264) (xy 445.798641 -118.357827)
			(xy 445.818564 -118.305736) (xy 445.84586 -118.257101) (xy 445.879946 -118.212958) (xy 445.920095 -118.174249)
			(xy 445.965453 -118.141798) (xy 446.015053 -118.116297) (xy 446.067837 -118.09829) (xy 446.12268 -118.08816)
			(xy 446.178414 -118.086123) (xy 446.233851 -118.092223) (xy 446.287808 -118.106329) (xy 446.339137 -118.128141)
			(xy 446.386743 -118.157195) (xy 446.429611 -118.19287) (xy 446.466828 -118.234407) (xy 446.497601 -118.28092)
			(xy 446.521273 -118.331417) (xy 446.537341 -118.384824) (xy 446.545461 -118.44) (xy 446.54597 -118.467886)
			(xy 446.545461 -118.495772) (xy 446.537341 -118.550948) (xy 446.521273 -118.604355) (xy 446.497601 -118.654852)
			(xy 446.466828 -118.701365) (xy 446.429611 -118.742902) (xy 446.408777 -118.76024) (xy 448.838826 -118.76024)
			(xy 448.842897 -118.704618) (xy 448.855023 -118.650181) (xy 448.874946 -118.59809) (xy 448.902242 -118.549455)
			(xy 448.936328 -118.505312) (xy 448.976477 -118.466603) (xy 449.021835 -118.434152) (xy 449.071435 -118.408651)
			(xy 449.124219 -118.390644) (xy 449.179062 -118.380514) (xy 449.234796 -118.378477) (xy 449.290233 -118.384577)
			(xy 449.34419 -118.398683) (xy 449.395519 -118.420495) (xy 449.443125 -118.449549) (xy 449.485993 -118.485224)
			(xy 449.52321 -118.526761) (xy 449.553983 -118.573274) (xy 449.577655 -118.623771) (xy 449.593723 -118.677178)
			(xy 449.601843 -118.732354) (xy 449.602352 -118.76024) (xy 450.864476 -118.76024) (xy 450.868547 -118.704618)
			(xy 450.880673 -118.650181) (xy 450.900596 -118.59809) (xy 450.927892 -118.549455) (xy 450.961978 -118.505312)
			(xy 451.002127 -118.466603) (xy 451.047485 -118.434152) (xy 451.097085 -118.408651) (xy 451.149869 -118.390644)
			(xy 451.204712 -118.380514) (xy 451.260446 -118.378477) (xy 451.315883 -118.384577) (xy 451.36984 -118.398683)
			(xy 451.421169 -118.420495) (xy 451.468775 -118.449549) (xy 451.511643 -118.485224) (xy 451.54886 -118.526761)
			(xy 451.579633 -118.573274) (xy 451.603305 -118.623771) (xy 451.619373 -118.677178) (xy 451.627493 -118.732354)
			(xy 451.628002 -118.76024) (xy 451.627493 -118.788126) (xy 451.619373 -118.843302) (xy 451.603305 -118.896709)
			(xy 451.579633 -118.947206) (xy 451.54886 -118.993719) (xy 451.511643 -119.035256) (xy 451.468775 -119.070931)
			(xy 451.421169 -119.099985) (xy 451.36984 -119.121797) (xy 451.315883 -119.135903) (xy 451.260446 -119.142003)
			(xy 451.204712 -119.139966) (xy 451.149869 -119.129836) (xy 451.097085 -119.111829) (xy 451.047485 -119.086328)
			(xy 451.002127 -119.053877) (xy 450.961978 -119.015168) (xy 450.927892 -118.971025) (xy 450.900596 -118.92239)
			(xy 450.880673 -118.870299) (xy 450.868547 -118.815862) (xy 450.864476 -118.76024) (xy 449.602352 -118.76024)
			(xy 449.601843 -118.788126) (xy 449.593723 -118.843302) (xy 449.577655 -118.896709) (xy 449.553983 -118.947206)
			(xy 449.52321 -118.993719) (xy 449.485993 -119.035256) (xy 449.443125 -119.070931) (xy 449.395519 -119.099985)
			(xy 449.34419 -119.121797) (xy 449.290233 -119.135903) (xy 449.234796 -119.142003) (xy 449.179062 -119.139966)
			(xy 449.124219 -119.129836) (xy 449.071435 -119.111829) (xy 449.021835 -119.086328) (xy 448.976477 -119.053877)
			(xy 448.936328 -119.015168) (xy 448.902242 -118.971025) (xy 448.874946 -118.92239) (xy 448.855023 -118.870299)
			(xy 448.842897 -118.815862) (xy 448.838826 -118.76024) (xy 446.408777 -118.76024) (xy 446.386743 -118.778577)
			(xy 446.339137 -118.807631) (xy 446.287808 -118.829443) (xy 446.233851 -118.843549) (xy 446.178414 -118.849649)
			(xy 446.12268 -118.847612) (xy 446.067837 -118.837482) (xy 446.015053 -118.819475) (xy 445.965453 -118.793974)
			(xy 445.920095 -118.761523) (xy 445.879946 -118.722814) (xy 445.84586 -118.678671) (xy 445.818564 -118.630036)
			(xy 445.798641 -118.577945) (xy 445.786515 -118.523508) (xy 445.782444 -118.467886) (xy 434.398928 -118.467886)
			(xy 434.398928 -119.407557) (xy 442.799609 -119.407557) (xy 442.799609 -119.353043) (xy 442.807368 -119.299083)
			(xy 442.822727 -119.246777) (xy 442.845374 -119.197189) (xy 442.874848 -119.151329) (xy 442.910548 -119.110131)
			(xy 442.951749 -119.074433) (xy 442.99761 -119.044962) (xy 443.0472 -119.022318) (xy 443.099507 -119.006962)
			(xy 443.153467 -118.999207) (xy 443.180724 -118.998746) (xy 443.208095 -118.999187) (xy 443.262276 -119.007009)
			(xy 443.31478 -119.022503) (xy 443.364526 -119.045351) (xy 443.410492 -119.075082) (xy 443.431422 -119.092726)
			(xy 443.431676 -119.09298) (xy 443.438758 -119.098572) (xy 443.455679 -119.104813) (xy 443.464696 -119.105172)
			(xy 443.531752 -119.105172) (xy 443.540767 -119.104798) (xy 443.557685 -119.098563) (xy 443.564772 -119.09298)
			(xy 443.564772 -119.092726) (xy 443.565026 -119.092726) (xy 443.585979 -119.075112) (xy 443.631945 -119.045396)
			(xy 443.681688 -119.022554) (xy 443.734184 -119.007058) (xy 443.788356 -118.999223) (xy 443.815724 -118.998746)
			(xy 443.842971 -118.999326) (xy 443.896909 -119.007084) (xy 443.949195 -119.022439) (xy 443.998763 -119.045079)
			(xy 444.044605 -119.074543) (xy 444.085787 -119.11023) (xy 444.121472 -119.151414) (xy 444.150932 -119.197258)
			(xy 444.173569 -119.246828) (xy 444.188921 -119.299114) (xy 444.196676 -119.353053) (xy 444.196676 -119.407547)
			(xy 444.188921 -119.461486) (xy 444.184358 -119.477028) (xy 447.903344 -119.477028) (xy 447.907415 -119.421406)
			(xy 447.919541 -119.366969) (xy 447.939464 -119.314878) (xy 447.96676 -119.266243) (xy 448.000846 -119.2221)
			(xy 448.040995 -119.183391) (xy 448.086353 -119.15094) (xy 448.135953 -119.125439) (xy 448.188737 -119.107432)
			(xy 448.24358 -119.097302) (xy 448.299314 -119.095265) (xy 448.354751 -119.101365) (xy 448.408708 -119.115471)
			(xy 448.460037 -119.137283) (xy 448.507643 -119.166337) (xy 448.550511 -119.202012) (xy 448.587728 -119.243549)
			(xy 448.618501 -119.290062) (xy 448.642173 -119.340559) (xy 448.658241 -119.393966) (xy 448.666361 -119.449142)
			(xy 448.66687 -119.477028) (xy 448.666361 -119.504914) (xy 448.658241 -119.56009) (xy 448.642173 -119.613497)
			(xy 448.618501 -119.663994) (xy 448.587728 -119.710507) (xy 448.580265 -119.718836) (xy 455.836526 -119.718836)
			(xy 455.840597 -119.663214) (xy 455.852723 -119.608777) (xy 455.872646 -119.556686) (xy 455.899942 -119.508051)
			(xy 455.934028 -119.463908) (xy 455.974177 -119.425199) (xy 456.019535 -119.392748) (xy 456.069135 -119.367247)
			(xy 456.121919 -119.34924) (xy 456.176762 -119.33911) (xy 456.232496 -119.337073) (xy 456.287933 -119.343173)
			(xy 456.34189 -119.357279) (xy 456.393219 -119.379091) (xy 456.440825 -119.408145) (xy 456.483693 -119.44382)
			(xy 456.52091 -119.485357) (xy 456.551683 -119.53187) (xy 456.575355 -119.582367) (xy 456.591423 -119.635774)
			(xy 456.599543 -119.69095) (xy 456.600052 -119.718836) (xy 456.599543 -119.746722) (xy 456.591423 -119.801898)
			(xy 456.575355 -119.855305) (xy 456.551683 -119.905802) (xy 456.52091 -119.952315) (xy 456.483693 -119.993852)
			(xy 456.440825 -120.029527) (xy 456.393219 -120.058581) (xy 456.34189 -120.080393) (xy 456.287933 -120.094499)
			(xy 456.232496 -120.100599) (xy 456.176762 -120.098562) (xy 456.121919 -120.088432) (xy 456.069135 -120.070425)
			(xy 456.019535 -120.044924) (xy 455.974177 -120.012473) (xy 455.934028 -119.973764) (xy 455.899942 -119.929621)
			(xy 455.872646 -119.880986) (xy 455.852723 -119.828895) (xy 455.840597 -119.774458) (xy 455.836526 -119.718836)
			(xy 448.580265 -119.718836) (xy 448.550511 -119.752044) (xy 448.507643 -119.787719) (xy 448.460037 -119.816773)
			(xy 448.408708 -119.838585) (xy 448.354751 -119.852691) (xy 448.299314 -119.858791) (xy 448.24358 -119.856754)
			(xy 448.188737 -119.846624) (xy 448.135953 -119.828617) (xy 448.086353 -119.803116) (xy 448.040995 -119.770665)
			(xy 448.000846 -119.731956) (xy 447.96676 -119.687813) (xy 447.939464 -119.639178) (xy 447.919541 -119.587087)
			(xy 447.907415 -119.53265) (xy 447.903344 -119.477028) (xy 444.184358 -119.477028) (xy 444.173569 -119.513772)
			(xy 444.150932 -119.563342) (xy 444.121472 -119.609186) (xy 444.085787 -119.65037) (xy 444.044605 -119.686057)
			(xy 443.998763 -119.715521) (xy 443.949195 -119.738161) (xy 443.896909 -119.753516) (xy 443.842971 -119.761274)
			(xy 443.815724 -119.761762) (xy 443.788354 -119.761291) (xy 443.734175 -119.753476) (xy 443.681671 -119.737988)
			(xy 443.631924 -119.715148) (xy 443.585957 -119.685423) (xy 443.565026 -119.667782) (xy 443.564772 -119.667528)
			(xy 443.557675 -119.661957) (xy 443.540766 -119.655703) (xy 443.531752 -119.655336) (xy 443.464696 -119.655336)
			(xy 443.455678 -119.655683) (xy 443.438761 -119.661937) (xy 443.431676 -119.667528) (xy 443.431676 -119.667782)
			(xy 443.431422 -119.667782) (xy 443.41049 -119.685421) (xy 443.364518 -119.715134) (xy 443.31477 -119.73797)
			(xy 443.262269 -119.753461) (xy 443.208093 -119.761288) (xy 443.180724 -119.761762) (xy 443.153467 -119.761393)
			(xy 443.099507 -119.753638) (xy 443.0472 -119.738282) (xy 442.99761 -119.715638) (xy 442.951749 -119.686167)
			(xy 442.910548 -119.650469) (xy 442.874848 -119.609271) (xy 442.845374 -119.563411) (xy 442.822727 -119.513823)
			(xy 442.807368 -119.461517) (xy 442.799609 -119.407557) (xy 434.398928 -119.407557) (xy 434.398928 -119.89308)
			(xy 445.869058 -119.89308) (xy 445.873129 -119.837458) (xy 445.885255 -119.783021) (xy 445.905178 -119.73093)
			(xy 445.932474 -119.682295) (xy 445.96656 -119.638152) (xy 446.006709 -119.599443) (xy 446.052067 -119.566992)
			(xy 446.101667 -119.541491) (xy 446.154451 -119.523484) (xy 446.209294 -119.513354) (xy 446.265028 -119.511317)
			(xy 446.320465 -119.517417) (xy 446.374422 -119.531523) (xy 446.425751 -119.553335) (xy 446.473357 -119.582389)
			(xy 446.516225 -119.618064) (xy 446.553442 -119.659601) (xy 446.584215 -119.706114) (xy 446.607887 -119.756611)
			(xy 446.623955 -119.810018) (xy 446.632075 -119.865194) (xy 446.632584 -119.89308) (xy 446.632075 -119.920966)
			(xy 446.623955 -119.976142) (xy 446.607887 -120.029549) (xy 446.584215 -120.080046) (xy 446.553442 -120.126559)
			(xy 446.516225 -120.168096) (xy 446.473357 -120.203771) (xy 446.425751 -120.232825) (xy 446.374422 -120.254637)
			(xy 446.320465 -120.268743) (xy 446.265028 -120.274843) (xy 446.209294 -120.272806) (xy 446.154451 -120.262676)
			(xy 446.101667 -120.244669) (xy 446.052067 -120.219168) (xy 446.006709 -120.186717) (xy 445.96656 -120.148008)
			(xy 445.932474 -120.103865) (xy 445.905178 -120.05523) (xy 445.885255 -120.003139) (xy 445.873129 -119.948702)
			(xy 445.869058 -119.89308) (xy 434.398928 -119.89308) (xy 434.398928 -122.192034) (xy 437.750712 -122.192034)
			(xy 437.751195 -122.164664) (xy 437.759008 -122.110486) (xy 437.774493 -122.057983) (xy 437.797331 -122.008236)
			(xy 437.827052 -121.962268) (xy 437.844692 -121.941336) (xy 437.844946 -121.941082) (xy 437.850552 -121.934009)
			(xy 437.856786 -121.917082) (xy 437.857138 -121.908062) (xy 437.857138 -121.841006) (xy 437.85677 -121.83199)
			(xy 437.850529 -121.815074) (xy 437.844946 -121.807986) (xy 437.844692 -121.807986) (xy 437.844692 -121.807732)
			(xy 437.827086 -121.786772) (xy 437.797363 -121.740808) (xy 437.774517 -121.691066) (xy 437.75902 -121.638568)
			(xy 437.751189 -121.584394) (xy 437.751185 -121.529657) (xy 437.759009 -121.475482) (xy 437.774499 -121.422982)
			(xy 437.797338 -121.373237) (xy 437.827055 -121.327269) (xy 437.844692 -121.306336) (xy 437.844946 -121.306082)
			(xy 437.850552 -121.299009) (xy 437.856786 -121.282082) (xy 437.857138 -121.273062) (xy 437.857138 -121.206006)
			(xy 437.85677 -121.19699) (xy 437.850529 -121.180074) (xy 437.844946 -121.172986) (xy 437.844692 -121.172986)
			(xy 437.844692 -121.172732) (xy 437.827086 -121.151772) (xy 437.797363 -121.105808) (xy 437.774517 -121.056066)
			(xy 437.75902 -121.003568) (xy 437.751189 -120.949394) (xy 437.751185 -120.894657) (xy 437.759009 -120.840482)
			(xy 437.774499 -120.787982) (xy 437.797338 -120.738237) (xy 437.827055 -120.692269) (xy 437.844692 -120.671336)
			(xy 437.844946 -120.671082) (xy 437.850552 -120.664009) (xy 437.856786 -120.647082) (xy 437.857138 -120.638062)
			(xy 437.857138 -120.571006) (xy 437.85677 -120.56199) (xy 437.850529 -120.545074) (xy 437.844946 -120.537986)
			(xy 437.844692 -120.537986) (xy 437.844692 -120.537732) (xy 437.827053 -120.5168) (xy 437.797342 -120.470827)
			(xy 437.774506 -120.421079) (xy 437.759015 -120.368579) (xy 437.751186 -120.314403) (xy 437.750712 -120.287034)
			(xy 437.751198 -120.259783) (xy 437.758954 -120.205835) (xy 437.774309 -120.15354) (xy 437.796951 -120.103963)
			(xy 437.826417 -120.058113) (xy 437.862108 -120.016922) (xy 437.903299 -119.981231) (xy 437.949149 -119.951765)
			(xy 437.998726 -119.929123) (xy 438.051021 -119.913768) (xy 438.104969 -119.906012) (xy 438.159471 -119.906012)
			(xy 438.213419 -119.913768) (xy 438.265714 -119.929123) (xy 438.315291 -119.951765) (xy 438.361141 -119.981231)
			(xy 438.402332 -120.016922) (xy 438.438023 -120.058113) (xy 438.467489 -120.103963) (xy 438.490131 -120.15354)
			(xy 438.505486 -120.205835) (xy 438.513242 -120.259783) (xy 438.513728 -120.287034) (xy 438.513299 -120.314406)
			(xy 438.505475 -120.368587) (xy 438.489978 -120.421091) (xy 438.467128 -120.470838) (xy 438.452773 -120.493028)
			(xy 447.904106 -120.493028) (xy 447.908177 -120.437406) (xy 447.920303 -120.382969) (xy 447.940226 -120.330878)
			(xy 447.967522 -120.282243) (xy 448.001608 -120.2381) (xy 448.041757 -120.199391) (xy 448.087115 -120.16694)
			(xy 448.136715 -120.141439) (xy 448.189499 -120.123432) (xy 448.244342 -120.113302) (xy 448.300076 -120.111265)
			(xy 448.355513 -120.117365) (xy 448.40947 -120.131471) (xy 448.460799 -120.153283) (xy 448.508405 -120.182337)
			(xy 448.551273 -120.218012) (xy 448.58849 -120.259549) (xy 448.619263 -120.306062) (xy 448.642935 -120.356559)
			(xy 448.659003 -120.409966) (xy 448.667123 -120.465142) (xy 448.667632 -120.493028) (xy 448.667123 -120.520914)
			(xy 448.659003 -120.57609) (xy 448.642935 -120.629497) (xy 448.619263 -120.679994) (xy 448.58849 -120.726507)
			(xy 448.551273 -120.768044) (xy 448.522198 -120.79224) (xy 448.836032 -120.79224) (xy 448.840103 -120.736618)
			(xy 448.852229 -120.682181) (xy 448.872152 -120.63009) (xy 448.899448 -120.581455) (xy 448.933534 -120.537312)
			(xy 448.973683 -120.498603) (xy 449.019041 -120.466152) (xy 449.068641 -120.440651) (xy 449.121425 -120.422644)
			(xy 449.176268 -120.412514) (xy 449.232002 -120.410477) (xy 449.287439 -120.416577) (xy 449.341396 -120.430683)
			(xy 449.392725 -120.452495) (xy 449.440331 -120.481549) (xy 449.483199 -120.517224) (xy 449.520416 -120.558761)
			(xy 449.551189 -120.605274) (xy 449.574861 -120.655771) (xy 449.590929 -120.709178) (xy 449.599049 -120.764354)
			(xy 449.599558 -120.79224) (xy 450.991476 -120.79224) (xy 450.995547 -120.736618) (xy 451.007673 -120.682181)
			(xy 451.027596 -120.63009) (xy 451.054892 -120.581455) (xy 451.088978 -120.537312) (xy 451.129127 -120.498603)
			(xy 451.174485 -120.466152) (xy 451.224085 -120.440651) (xy 451.276869 -120.422644) (xy 451.331712 -120.412514)
			(xy 451.387446 -120.410477) (xy 451.442883 -120.416577) (xy 451.49684 -120.430683) (xy 451.548169 -120.452495)
			(xy 451.595775 -120.481549) (xy 451.638643 -120.517224) (xy 451.646777 -120.526302) (xy 454.293476 -120.526302)
			(xy 454.297547 -120.47068) (xy 454.309673 -120.416243) (xy 454.329596 -120.364152) (xy 454.356892 -120.315517)
			(xy 454.390978 -120.271374) (xy 454.431127 -120.232665) (xy 454.476485 -120.200214) (xy 454.526085 -120.174713)
			(xy 454.578869 -120.156706) (xy 454.633712 -120.146576) (xy 454.689446 -120.144539) (xy 454.744883 -120.150639)
			(xy 454.79884 -120.164745) (xy 454.850169 -120.186557) (xy 454.897775 -120.215611) (xy 454.940643 -120.251286)
			(xy 454.97786 -120.292823) (xy 455.008633 -120.339336) (xy 455.032305 -120.389833) (xy 455.048373 -120.44324)
			(xy 455.056493 -120.498416) (xy 455.057002 -120.526302) (xy 455.056493 -120.554188) (xy 455.048373 -120.609364)
			(xy 455.032305 -120.662771) (xy 455.008633 -120.713268) (xy 454.97786 -120.759781) (xy 454.940643 -120.801318)
			(xy 454.897775 -120.836993) (xy 454.850169 -120.866047) (xy 454.79884 -120.887859) (xy 454.744883 -120.901965)
			(xy 454.689446 -120.908065) (xy 454.633712 -120.906028) (xy 454.578869 -120.895898) (xy 454.526085 -120.877891)
			(xy 454.476485 -120.85239) (xy 454.431127 -120.819939) (xy 454.390978 -120.78123) (xy 454.356892 -120.737087)
			(xy 454.329596 -120.688452) (xy 454.309673 -120.636361) (xy 454.297547 -120.581924) (xy 454.293476 -120.526302)
			(xy 451.646777 -120.526302) (xy 451.67586 -120.558761) (xy 451.706633 -120.605274) (xy 451.730305 -120.655771)
			(xy 451.746373 -120.709178) (xy 451.754493 -120.764354) (xy 451.755002 -120.79224) (xy 451.754493 -120.820126)
			(xy 451.746373 -120.875302) (xy 451.730305 -120.928709) (xy 451.706633 -120.979206) (xy 451.67586 -121.025719)
			(xy 451.638643 -121.067256) (xy 451.595775 -121.102931) (xy 451.548169 -121.131985) (xy 451.49684 -121.153797)
			(xy 451.442883 -121.167903) (xy 451.387446 -121.174003) (xy 451.331712 -121.171966) (xy 451.276869 -121.161836)
			(xy 451.224085 -121.143829) (xy 451.174485 -121.118328) (xy 451.129127 -121.085877) (xy 451.088978 -121.047168)
			(xy 451.054892 -121.003025) (xy 451.027596 -120.95439) (xy 451.007673 -120.902299) (xy 450.995547 -120.847862)
			(xy 450.991476 -120.79224) (xy 449.599558 -120.79224) (xy 449.599049 -120.820126) (xy 449.590929 -120.875302)
			(xy 449.574861 -120.928709) (xy 449.551189 -120.979206) (xy 449.520416 -121.025719) (xy 449.483199 -121.067256)
			(xy 449.440331 -121.102931) (xy 449.392725 -121.131985) (xy 449.341396 -121.153797) (xy 449.287439 -121.167903)
			(xy 449.232002 -121.174003) (xy 449.176268 -121.171966) (xy 449.121425 -121.161836) (xy 449.068641 -121.143829)
			(xy 449.019041 -121.118328) (xy 448.973683 -121.085877) (xy 448.933534 -121.047168) (xy 448.899448 -121.003025)
			(xy 448.872152 -120.95439) (xy 448.852229 -120.902299) (xy 448.840103 -120.847862) (xy 448.836032 -120.79224)
			(xy 448.522198 -120.79224) (xy 448.508405 -120.803719) (xy 448.460799 -120.832773) (xy 448.40947 -120.854585)
			(xy 448.355513 -120.868691) (xy 448.300076 -120.874791) (xy 448.244342 -120.872754) (xy 448.189499 -120.862624)
			(xy 448.136715 -120.844617) (xy 448.087115 -120.819116) (xy 448.041757 -120.786665) (xy 448.001608 -120.747956)
			(xy 447.967522 -120.703813) (xy 447.940226 -120.655178) (xy 447.920303 -120.603087) (xy 447.908177 -120.54865)
			(xy 447.904106 -120.493028) (xy 438.452773 -120.493028) (xy 438.437394 -120.516802) (xy 438.419748 -120.537732)
			(xy 438.419494 -120.537986) (xy 438.413906 -120.545072) (xy 438.407661 -120.561989) (xy 438.407302 -120.571006)
			(xy 438.407302 -120.638062) (xy 438.407677 -120.647077) (xy 438.413912 -120.663994) (xy 438.419494 -120.671082)
			(xy 438.419748 -120.671082) (xy 438.419748 -120.671336) (xy 438.437423 -120.692241) (xy 438.467148 -120.738213)
			(xy 438.489993 -120.787964) (xy 438.505488 -120.84047) (xy 438.513314 -120.894653) (xy 438.51331 -120.949398)
			(xy 438.505477 -121.00358) (xy 438.489975 -121.056084) (xy 438.467124 -121.105832) (xy 438.437392 -121.1518)
			(xy 438.419748 -121.172732) (xy 438.419494 -121.172986) (xy 438.413906 -121.180072) (xy 438.407661 -121.196989)
			(xy 438.407591 -121.198756) (xy 438.785417 -121.198756) (xy 438.785417 -121.144244) (xy 438.793175 -121.090287)
			(xy 438.808533 -121.037983) (xy 438.831178 -120.988398) (xy 438.86065 -120.942539) (xy 438.896348 -120.901342)
			(xy 438.937546 -120.865645) (xy 438.983405 -120.836174) (xy 439.032991 -120.81353) (xy 439.085295 -120.798173)
			(xy 439.139252 -120.790416) (xy 439.166508 -120.789954) (xy 439.193879 -120.790402) (xy 439.248059 -120.798222)
			(xy 439.300563 -120.813715) (xy 439.35031 -120.836561) (xy 439.396275 -120.86629) (xy 439.417206 -120.883934)
			(xy 439.41746 -120.884188) (xy 439.424555 -120.889763) (xy 439.441465 -120.896017) (xy 439.45048 -120.89638)
			(xy 439.517536 -120.89638) (xy 439.526555 -120.896044) (xy 439.543472 -120.889782) (xy 439.550556 -120.884188)
			(xy 439.550556 -120.883934) (xy 439.55081 -120.883934) (xy 439.571732 -120.866282) (xy 439.617707 -120.836571)
			(xy 439.667457 -120.813737) (xy 439.71996 -120.798249) (xy 439.774138 -120.790425) (xy 439.801508 -120.789954)
			(xy 439.828756 -120.790517) (xy 439.882698 -120.798273) (xy 439.934986 -120.813628) (xy 439.984557 -120.836267)
			(xy 440.030402 -120.865731) (xy 440.071587 -120.901418) (xy 440.107274 -120.942604) (xy 440.136737 -120.98845)
			(xy 440.159375 -121.038021) (xy 440.174728 -121.09031) (xy 440.182484 -121.144252) (xy 440.182484 -121.198748)
			(xy 440.174728 -121.25269) (xy 440.159375 -121.304979) (xy 440.136737 -121.35455) (xy 440.107274 -121.400396)
			(xy 440.071587 -121.441582) (xy 440.030402 -121.477269) (xy 439.984557 -121.506733) (xy 439.934986 -121.529372)
			(xy 439.882698 -121.544727) (xy 439.828756 -121.552483) (xy 439.801508 -121.55297) (xy 439.774138 -121.552507)
			(xy 439.719958 -121.544689) (xy 439.667455 -121.5292) (xy 439.617708 -121.506357) (xy 439.571741 -121.476632)
			(xy 439.55081 -121.45899) (xy 439.550556 -121.458736) (xy 439.543463 -121.453159) (xy 439.526551 -121.446908)
			(xy 439.517536 -121.446544) (xy 439.45048 -121.446544) (xy 439.441461 -121.446882) (xy 439.424544 -121.453142)
			(xy 439.41746 -121.458736) (xy 439.41746 -121.45899) (xy 439.417206 -121.45899) (xy 439.396281 -121.476638)
			(xy 439.350307 -121.506349) (xy 439.300557 -121.529183) (xy 439.248055 -121.544672) (xy 439.193878 -121.552498)
			(xy 439.166508 -121.55297) (xy 439.139252 -121.552584) (xy 439.085295 -121.544827) (xy 439.032991 -121.52947)
			(xy 438.983405 -121.506826) (xy 438.937546 -121.477355) (xy 438.896348 -121.441658) (xy 438.86065 -121.400461)
			(xy 438.831178 -121.354602) (xy 438.808533 -121.305017) (xy 438.793175 -121.252713) (xy 438.785417 -121.198756)
			(xy 438.407591 -121.198756) (xy 438.407302 -121.206006) (xy 438.407302 -121.273062) (xy 438.407677 -121.282077)
			(xy 438.413912 -121.298994) (xy 438.419494 -121.306082) (xy 438.419748 -121.306082) (xy 438.419748 -121.306336)
			(xy 438.437423 -121.327241) (xy 438.467148 -121.373213) (xy 438.489993 -121.422964) (xy 438.505488 -121.47547)
			(xy 438.513314 -121.529653) (xy 438.51331 -121.584398) (xy 438.505477 -121.63858) (xy 438.489975 -121.691084)
			(xy 438.476179 -121.721118) (xy 440.2963 -121.721118) (xy 440.296777 -121.693748) (xy 440.304592 -121.63957)
			(xy 440.320079 -121.587067) (xy 440.342918 -121.537319) (xy 440.37264 -121.491352) (xy 440.39028 -121.47042)
			(xy 440.390534 -121.470166) (xy 440.396103 -121.463067) (xy 440.402359 -121.44616) (xy 440.402726 -121.437146)
			(xy 440.402726 -121.37009) (xy 440.402368 -121.361073) (xy 440.39612 -121.344157) (xy 440.390534 -121.33707)
			(xy 440.39028 -121.33707) (xy 440.39028 -121.336816) (xy 440.372632 -121.315891) (xy 440.342922 -121.269916)
			(xy 440.320088 -121.220167) (xy 440.304599 -121.167665) (xy 440.296773 -121.113488) (xy 440.2963 -121.086118)
			(xy 440.296772 -121.058865) (xy 440.304527 -121.004914) (xy 440.319881 -120.952616) (xy 440.342522 -120.903035)
			(xy 440.371989 -120.857182) (xy 440.407682 -120.815989) (xy 440.448874 -120.780295) (xy 440.494727 -120.750827)
			(xy 440.544307 -120.728184) (xy 440.596604 -120.712829) (xy 440.650555 -120.705073) (xy 440.677808 -120.70461)
			(xy 440.704687 -120.705028) (xy 440.757911 -120.712581) (xy 440.809546 -120.727536) (xy 440.858568 -120.749596)
			(xy 440.904005 -120.778325) (xy 440.944956 -120.813151) (xy 440.980608 -120.853384) (xy 440.995816 -120.875552)
			(xy 441.001846 -120.883889) (xy 441.019046 -120.895152) (xy 441.02909 -120.897396) (xy 441.111386 -120.912636)
			(xy 441.131452 -120.908064) (xy 441.139834 -120.901968) (xy 441.164289 -120.885159) (xy 441.217296 -120.858489)
			(xy 441.273792 -120.840343) (xy 441.332415 -120.831158) (xy 441.362084 -120.830594) (xy 441.389337 -120.83107)
			(xy 441.443287 -120.838825) (xy 441.495585 -120.854179) (xy 441.545165 -120.87682) (xy 441.591018 -120.906286)
			(xy 441.632211 -120.941979) (xy 441.667905 -120.98317) (xy 441.697373 -121.029023) (xy 441.720016 -121.078602)
			(xy 441.735372 -121.130899) (xy 441.743129 -121.184849) (xy 441.743592 -121.212102) (xy 441.743141 -121.238772)
			(xy 445.884298 -121.238772) (xy 445.888369 -121.18315) (xy 445.900495 -121.128713) (xy 445.920418 -121.076622)
			(xy 445.947714 -121.027987) (xy 445.9818 -120.983844) (xy 446.021949 -120.945135) (xy 446.067307 -120.912684)
			(xy 446.116907 -120.887183) (xy 446.169691 -120.869176) (xy 446.224534 -120.859046) (xy 446.280268 -120.857009)
			(xy 446.335705 -120.863109) (xy 446.389662 -120.877215) (xy 446.440991 -120.899027) (xy 446.488597 -120.928081)
			(xy 446.531465 -120.963756) (xy 446.568682 -121.005293) (xy 446.599455 -121.051806) (xy 446.623127 -121.102303)
			(xy 446.639195 -121.15571) (xy 446.647315 -121.210886) (xy 446.647824 -121.238772) (xy 446.647315 -121.266658)
			(xy 446.639195 -121.321834) (xy 446.623127 -121.375241) (xy 446.599455 -121.425738) (xy 446.568682 -121.472251)
			(xy 446.531465 -121.513788) (xy 446.488597 -121.549463) (xy 446.440991 -121.578517) (xy 446.389662 -121.600329)
			(xy 446.335705 -121.614435) (xy 446.280268 -121.620535) (xy 446.224534 -121.618498) (xy 446.169691 -121.608368)
			(xy 446.116907 -121.590361) (xy 446.067307 -121.56486) (xy 446.021949 -121.532409) (xy 445.9818 -121.4937)
			(xy 445.947714 -121.449557) (xy 445.920418 -121.400922) (xy 445.900495 -121.348831) (xy 445.888369 -121.294394)
			(xy 445.884298 -121.238772) (xy 441.743141 -121.238772) (xy 441.743129 -121.239472) (xy 441.735311 -121.293652)
			(xy 441.719821 -121.346155) (xy 441.696979 -121.395902) (xy 441.667253 -121.441868) (xy 441.649612 -121.4628)
			(xy 441.649358 -121.463054) (xy 441.643779 -121.470146) (xy 441.637529 -121.487059) (xy 441.637166 -121.496074)
			(xy 441.637166 -121.56313) (xy 441.637516 -121.572147) (xy 441.643769 -121.589064) (xy 441.649358 -121.59615)
			(xy 441.649612 -121.59615) (xy 441.649612 -121.596404) (xy 441.667268 -121.617322) (xy 441.696977 -121.663299)
			(xy 441.71981 -121.71305) (xy 441.735297 -121.765554) (xy 441.74312 -121.819732) (xy 441.743592 -121.847102)
			(xy 441.743146 -121.874356) (xy 441.735389 -121.928308) (xy 441.720032 -121.980607) (xy 441.697388 -122.030188)
			(xy 441.667918 -122.076042) (xy 441.632223 -122.117235) (xy 441.591028 -122.152929) (xy 441.545173 -122.182396)
			(xy 441.49559 -122.205038) (xy 441.44329 -122.220393) (xy 441.389338 -122.228148) (xy 441.362084 -122.22861)
			(xy 441.335206 -122.228189) (xy 441.281982 -122.220635) (xy 441.230347 -122.20568) (xy 441.181325 -122.18362)
			(xy 441.135888 -122.154893) (xy 441.094937 -122.120067) (xy 441.059284 -122.079835) (xy 441.044076 -122.057668)
			(xy 441.038004 -122.049367) (xy 441.020834 -122.038085) (xy 441.010802 -122.035824) (xy 440.928506 -122.020584)
			(xy 440.90844 -122.025156) (xy 440.900058 -122.031252) (xy 440.875599 -122.048055) (xy 440.822594 -122.074728)
			(xy 440.7661 -122.092877) (xy 440.707477 -122.102062) (xy 440.677808 -122.102626) (xy 440.650558 -122.102115)
			(xy 440.596612 -122.09436) (xy 440.544319 -122.079007) (xy 440.494743 -122.056368) (xy 440.448893 -122.026904)
			(xy 440.407703 -121.991215) (xy 440.372012 -121.950028) (xy 440.342545 -121.90418) (xy 440.319902 -121.854606)
			(xy 440.304546 -121.802314) (xy 440.296787 -121.748368) (xy 440.2963 -121.721118) (xy 438.476179 -121.721118)
			(xy 438.467124 -121.740832) (xy 438.437392 -121.7868) (xy 438.419748 -121.807732) (xy 438.419494 -121.807986)
			(xy 438.413906 -121.815072) (xy 438.407661 -121.831989) (xy 438.407302 -121.841006) (xy 438.407302 -121.908062)
			(xy 438.407677 -121.917077) (xy 438.413912 -121.933994) (xy 438.419494 -121.941082) (xy 438.419748 -121.941082)
			(xy 438.419748 -121.941336) (xy 438.437362 -121.962288) (xy 438.46708 -122.008255) (xy 438.489921 -122.057997)
			(xy 438.505418 -122.110493) (xy 438.513251 -122.164666) (xy 438.513728 -122.192034) (xy 438.513242 -122.219285)
			(xy 438.505486 -122.273233) (xy 438.490131 -122.325528) (xy 438.467489 -122.375105) (xy 438.438023 -122.420955)
			(xy 438.402332 -122.462146) (xy 438.361141 -122.497837) (xy 438.315291 -122.527303) (xy 438.265714 -122.549945)
			(xy 438.213419 -122.5653) (xy 438.159471 -122.573056) (xy 438.104969 -122.573056) (xy 438.051021 -122.5653)
			(xy 437.998726 -122.549945) (xy 437.949149 -122.527303) (xy 437.903299 -122.497837) (xy 437.862108 -122.462146)
			(xy 437.826417 -122.420955) (xy 437.796951 -122.375105) (xy 437.774309 -122.325528) (xy 437.758954 -122.273233)
			(xy 437.751198 -122.219285) (xy 437.750712 -122.192034) (xy 434.398928 -122.192034) (xy 434.398928 -123.364548)
			(xy 442.364398 -123.364548) (xy 442.364398 -123.310052) (xy 442.372153 -123.25611) (xy 442.387506 -123.20382)
			(xy 442.410144 -123.154248) (xy 442.439605 -123.108401) (xy 442.475292 -123.067214) (xy 442.516476 -123.031525)
			(xy 442.56232 -123.002059) (xy 442.61189 -122.979417) (xy 442.664178 -122.96406) (xy 442.71812 -122.9563)
			(xy 442.745368 -122.955812) (xy 442.772738 -122.956294) (xy 442.826916 -122.964107) (xy 442.879419 -122.979593)
			(xy 442.929166 -123.002431) (xy 442.975134 -123.032152) (xy 442.996066 -123.049792) (xy 442.99632 -123.050046)
			(xy 443.003393 -123.055653) (xy 443.02032 -123.061886) (xy 443.02934 -123.062238) (xy 443.096396 -123.062238)
			(xy 443.105412 -123.061871) (xy 443.122328 -123.055629) (xy 443.129416 -123.050046) (xy 443.129416 -123.049792)
			(xy 443.12967 -123.049792) (xy 443.150603 -123.032151) (xy 443.196571 -123.002427) (xy 443.246317 -122.979581)
			(xy 443.298819 -122.964085) (xy 443.352997 -122.956256) (xy 443.407739 -122.956256) (xy 443.461917 -122.964085)
			(xy 443.514419 -122.979581) (xy 443.564165 -123.002427) (xy 443.610133 -123.032151) (xy 443.631066 -123.049792)
			(xy 443.63132 -123.050046) (xy 443.638393 -123.055653) (xy 443.65532 -123.061886) (xy 443.66434 -123.062238)
			(xy 443.731396 -123.062238) (xy 443.740412 -123.061871) (xy 443.757328 -123.055629) (xy 443.764416 -123.050046)
			(xy 443.764416 -123.049792) (xy 443.76467 -123.049792) (xy 443.785602 -123.032152) (xy 443.831575 -123.002441)
			(xy 443.881322 -122.979605) (xy 443.933823 -122.964114) (xy 443.987999 -122.956286) (xy 444.015368 -122.955812)
			(xy 444.042624 -122.956233) (xy 444.096581 -122.963986) (xy 444.148886 -122.97934) (xy 444.198472 -123.001982)
			(xy 444.244332 -123.031451) (xy 444.285531 -123.067147) (xy 444.32123 -123.108342) (xy 444.350702 -123.154199)
			(xy 444.373348 -123.203784) (xy 444.388707 -123.256088) (xy 444.396465 -123.310044) (xy 444.396465 -123.364556)
			(xy 444.388707 -123.418512) (xy 444.373348 -123.470816) (xy 444.350702 -123.520401) (xy 444.32123 -123.566258)
			(xy 444.285531 -123.607453) (xy 444.244332 -123.643149) (xy 444.198472 -123.672618) (xy 444.148886 -123.69526)
			(xy 444.096581 -123.710614) (xy 444.042624 -123.718367) (xy 444.015368 -123.718828) (xy 443.987996 -123.718398)
			(xy 443.933815 -123.710574) (xy 443.881311 -123.695078) (xy 443.831564 -123.672227) (xy 443.7856 -123.642494)
			(xy 443.76467 -123.624848) (xy 443.764416 -123.624594) (xy 443.75733 -123.619007) (xy 443.740413 -123.612761)
			(xy 443.731396 -123.612402) (xy 443.66434 -123.612402) (xy 443.655325 -123.612778) (xy 443.638408 -123.619012)
			(xy 443.63132 -123.624594) (xy 443.631066 -123.624848) (xy 443.610133 -123.642489) (xy 443.564165 -123.672213)
			(xy 443.514419 -123.695059) (xy 443.461917 -123.710555) (xy 443.407739 -123.718384) (xy 443.352997 -123.718384)
			(xy 443.298819 -123.710555) (xy 443.246317 -123.695059) (xy 443.196571 -123.672213) (xy 443.150603 -123.642489)
			(xy 443.12967 -123.624848) (xy 443.129416 -123.624594) (xy 443.12233 -123.619007) (xy 443.105413 -123.612761)
			(xy 443.096396 -123.612402) (xy 443.02934 -123.612402) (xy 443.020325 -123.612778) (xy 443.003408 -123.619012)
			(xy 442.99632 -123.624594) (xy 442.99632 -123.624848) (xy 442.996066 -123.624848) (xy 442.975113 -123.642462)
			(xy 442.929147 -123.672179) (xy 442.879405 -123.695021) (xy 442.826908 -123.710518) (xy 442.772736 -123.718351)
			(xy 442.745368 -123.718828) (xy 442.71812 -123.7183) (xy 442.664178 -123.71054) (xy 442.61189 -123.695183)
			(xy 442.56232 -123.672541) (xy 442.516476 -123.643075) (xy 442.475292 -123.607386) (xy 442.439605 -123.566199)
			(xy 442.410144 -123.520352) (xy 442.387506 -123.47078) (xy 442.372153 -123.41849) (xy 442.364398 -123.364548)
			(xy 434.398928 -123.364548) (xy 434.398928 -124.215144) (xy 442.906656 -124.215144) (xy 442.910727 -124.159522)
			(xy 442.922853 -124.105085) (xy 442.942776 -124.052994) (xy 442.970072 -124.004359) (xy 443.004158 -123.960216)
			(xy 443.044307 -123.921507) (xy 443.089665 -123.889056) (xy 443.139265 -123.863555) (xy 443.192049 -123.845548)
			(xy 443.246892 -123.835418) (xy 443.302626 -123.833381) (xy 443.358063 -123.839481) (xy 443.41202 -123.853587)
			(xy 443.463349 -123.875399) (xy 443.510955 -123.904453) (xy 443.553823 -123.940128) (xy 443.59104 -123.981665)
			(xy 443.621813 -124.028178) (xy 443.645485 -124.078675) (xy 443.661553 -124.132082) (xy 443.669673 -124.187258)
			(xy 443.670182 -124.215144) (xy 443.669673 -124.24303) (xy 443.661553 -124.298206) (xy 443.645485 -124.351613)
			(xy 443.621813 -124.40211) (xy 443.59104 -124.448623) (xy 443.553823 -124.49016) (xy 443.510955 -124.525835)
			(xy 443.463349 -124.554889) (xy 443.41202 -124.576701) (xy 443.358063 -124.590807) (xy 443.302626 -124.596907)
			(xy 443.246892 -124.59487) (xy 443.192049 -124.58474) (xy 443.139265 -124.566733) (xy 443.089665 -124.541232)
			(xy 443.044307 -124.508781) (xy 443.004158 -124.470072) (xy 442.970072 -124.425929) (xy 442.942776 -124.377294)
			(xy 442.922853 -124.325203) (xy 442.910727 -124.270766) (xy 442.906656 -124.215144) (xy 434.398928 -124.215144)
			(xy 434.398928 -125.891544) (xy 443.47511 -125.891544) (xy 443.475537 -125.865229) (xy 443.48278 -125.813098)
			(xy 443.497106 -125.762455) (xy 443.518246 -125.714256) (xy 443.5458 -125.669413) (xy 443.579245 -125.628775)
			(xy 443.5983 -125.61062) (xy 443.605695 -125.603093) (xy 443.614223 -125.583817) (xy 443.61481 -125.573282)
			(xy 443.61481 -125.498606) (xy 443.614288 -125.488056) (xy 443.605748 -125.46876) (xy 443.5983 -125.461268)
			(xy 443.579236 -125.443121) (xy 443.54578 -125.402489) (xy 443.518222 -125.357647) (xy 443.497085 -125.309445)
			(xy 443.482769 -125.258796) (xy 443.475547 -125.206661) (xy 443.47511 -125.180344) (xy 443.475596 -125.153093)
			(xy 443.483352 -125.099145) (xy 443.498707 -125.04685) (xy 443.521349 -124.997273) (xy 443.550815 -124.951423)
			(xy 443.586506 -124.910232) (xy 443.627697 -124.874541) (xy 443.673547 -124.845075) (xy 443.723124 -124.822433)
			(xy 443.775419 -124.807078) (xy 443.829367 -124.799322) (xy 443.883869 -124.799322) (xy 443.937817 -124.807078)
			(xy 443.990112 -124.822433) (xy 444.039689 -124.845075) (xy 444.085539 -124.874541) (xy 444.12673 -124.910232)
			(xy 444.162421 -124.951423) (xy 444.191887 -124.997273) (xy 444.214529 -125.04685) (xy 444.229884 -125.099145)
			(xy 444.23764 -125.153093) (xy 444.238126 -125.180344) (xy 444.23768 -125.206659) (xy 444.230439 -125.258788)
			(xy 444.216115 -125.30943) (xy 444.194979 -125.357629) (xy 444.16743 -125.402472) (xy 444.133989 -125.443111)
			(xy 444.114936 -125.461268) (xy 444.107552 -125.468804) (xy 444.099016 -125.488073) (xy 444.098426 -125.498606)
			(xy 444.098426 -125.573282) (xy 444.098944 -125.583833) (xy 444.107486 -125.603129) (xy 444.114936 -125.61062)
			(xy 444.134001 -125.628766) (xy 444.167456 -125.669398) (xy 444.195013 -125.714241) (xy 444.216149 -125.762444)
			(xy 444.230465 -125.813092) (xy 444.237688 -125.865227) (xy 444.238126 -125.891544) (xy 444.23764 -125.918795)
			(xy 444.229884 -125.972743) (xy 444.214529 -126.025038) (xy 444.191887 -126.074615) (xy 444.162421 -126.120465)
			(xy 444.12673 -126.161656) (xy 444.085539 -126.197347) (xy 444.039689 -126.226813) (xy 443.990112 -126.249455)
			(xy 443.937817 -126.26481) (xy 443.883869 -126.272566) (xy 443.829367 -126.272566) (xy 443.775419 -126.26481)
			(xy 443.723124 -126.249455) (xy 443.673547 -126.226813) (xy 443.627697 -126.197347) (xy 443.586506 -126.161656)
			(xy 443.550815 -126.120465) (xy 443.521349 -126.074615) (xy 443.498707 -126.025038) (xy 443.483352 -125.972743)
			(xy 443.475596 -125.918795) (xy 443.47511 -125.891544) (xy 434.398928 -125.891544) (xy 434.398928 -136.391396)
			(xy 434.398743 -136.40576) (xy 434.396202 -136.434375) (xy 434.393848 -136.448546) (xy 434.38953 -136.469628)
			(xy 434.389022 -136.471914) (xy 434.387752 -136.47928) (xy 434.384872 -136.507517) (xy 434.370465 -136.562412)
			(xy 434.346658 -136.613932) (xy 434.31419 -136.660481) (xy 434.294534 -136.680956) (xy 431.705766 -139.26947)
			(xy 431.698737 -139.277409) (xy 431.691247 -139.297222) (xy 431.691288 -139.307824) (xy 431.692812 -139.338304)
			(xy 431.692812 -139.338812) (xy 431.69586 -139.387072) (xy 431.696453 -139.391355) (xy 431.698878 -139.399654)
			(xy 431.700686 -139.403582) (xy 431.705258 -139.412472) (xy 431.713894 -139.419584) (xy 431.714402 -139.420092)
			(xy 431.716434 -139.421616) (xy 431.737806 -139.439854) (xy 431.775485 -139.481528) (xy 431.806655 -139.528271)
			(xy 431.830644 -139.579075) (xy 431.846934 -139.632844) (xy 431.855175 -139.688419) (xy 431.855626 -139.71651)
			(xy 431.855626 -139.717018) (xy 431.855342 -139.737305) (xy 431.851012 -139.777649) (xy 431.84699 -139.797536)
			(xy 431.840331 -139.825541) (xy 431.819738 -139.879293) (xy 431.791315 -139.929349) (xy 431.755706 -139.974574)
			(xy 431.713716 -140.013947) (xy 431.666295 -140.046576) (xy 431.614517 -140.071724) (xy 431.559552 -140.08882)
			(xy 431.502645 -140.097478) (xy 431.473864 -140.098018) (xy 431.462942 -140.098018) (xy 431.435555 -140.096754)
			(xy 431.381542 -140.087356) (xy 431.329425 -140.070337) (xy 431.280274 -140.046049) (xy 431.235097 -140.014987)
			(xy 431.194821 -139.977791) (xy 431.177192 -139.956794) (xy 431.172874 -139.951714) (xy 431.165254 -139.945618)
			(xy 431.160936 -139.943332) (xy 431.157073 -139.941528) (xy 431.148902 -139.939099) (xy 431.14468 -139.938506)
			(xy 431.095658 -139.935458) (xy 431.09515 -139.935458) (xy 431.065178 -139.933934) (xy 431.054547 -139.93394)
			(xy 431.034727 -139.941555) (xy 431.026824 -139.948666) (xy 431.013108 -139.962382) (xy 430.992617 -139.982018)
			(xy 430.946071 -140.014481) (xy 430.894554 -140.038282) (xy 430.839663 -140.052683) (xy 430.811432 -140.0556)
			(xy 430.804066 -140.05687) (xy 430.80178 -140.057378) (xy 430.780698 -140.061696) (xy 430.766527 -140.06405)
			(xy 430.737912 -140.06659) (xy 430.723548 -140.066776) (xy 429.96358 -140.066776) (xy 429.956976 -140.070332)
			(xy 429.953674 -140.07211) (xy 429.952658 -140.072618) (xy 429.92719 -140.085365) (xy 429.873371 -140.103991)
			(xy 429.84547 -140.109702) (xy 429.829297 -140.112579) (xy 429.796613 -140.115885) (xy 429.780192 -140.116306)
			(xy 429.775112 -140.116306) (xy 429.749653 -140.115885) (xy 429.699187 -140.109115) (xy 429.650069 -140.095694)
			(xy 429.603172 -140.07586) (xy 429.55933 -140.049966) (xy 429.51932 -140.018471) (xy 429.5013 -140.000482)
			(xy 429.494188 -139.993116) (xy 429.467518 -139.981686) (xy 429.462779 -139.979815) (xy 429.452799 -139.977766)
			(xy 429.447706 -139.977622) (xy 429.39335 -139.977622) (xy 429.388254 -139.97774) (xy 429.378272 -139.979796)
			(xy 429.373538 -139.981686) (xy 429.346868 -139.993116) (xy 429.339756 -140.000482) (xy 429.321725 -140.018461)
			(xy 429.281722 -140.049965) (xy 429.237884 -140.075866) (xy 429.190988 -140.095705) (xy 429.14187 -140.109127)
			(xy 429.091403 -140.115894) (xy 429.065944 -140.116306) (xy 429.051212 -140.116052) (xy 429.04537 -140.116052)
			(xy 429.035426 -140.116532) (xy 429.017033 -140.124101) (xy 429.002897 -140.138092) (xy 428.995138 -140.156405)
			(xy 428.99457 -140.166344) (xy 428.956193 -143.479266) (xy 429.3743 -143.479266) (xy 429.3743 -142.615666)
			(xy 429.37479 -142.585682) (xy 429.382618 -142.526226) (xy 429.398139 -142.468301) (xy 429.421088 -142.412897)
			(xy 429.451072 -142.360963) (xy 429.487578 -142.313387) (xy 429.529983 -142.270982) (xy 429.577559 -142.234476)
			(xy 429.629493 -142.204492) (xy 429.684897 -142.181543) (xy 429.742822 -142.166022) (xy 429.802278 -142.158194)
			(xy 429.862246 -142.158194) (xy 429.921702 -142.166022) (xy 429.979627 -142.181543) (xy 430.035031 -142.204492)
			(xy 430.086965 -142.234476) (xy 430.134541 -142.270982) (xy 430.176946 -142.313387) (xy 430.213452 -142.360963)
			(xy 430.243436 -142.412897) (xy 430.266385 -142.468301) (xy 430.281906 -142.526226) (xy 430.289734 -142.585682)
			(xy 430.290224 -142.615666) (xy 430.290224 -143.479266) (xy 430.289734 -143.50925) (xy 430.281906 -143.568706)
			(xy 430.266385 -143.626631) (xy 430.243436 -143.682035) (xy 430.213452 -143.733969) (xy 430.176946 -143.781545)
			(xy 430.134541 -143.82395) (xy 430.086965 -143.860456) (xy 430.035031 -143.89044) (xy 429.979627 -143.913389)
			(xy 429.921702 -143.92891) (xy 429.862246 -143.936738) (xy 429.802278 -143.936738) (xy 429.742822 -143.92891)
			(xy 429.684897 -143.913389) (xy 429.629493 -143.89044) (xy 429.577559 -143.860456) (xy 429.529983 -143.82395)
			(xy 429.487578 -143.781545) (xy 429.451072 -143.733969) (xy 429.421088 -143.682035) (xy 429.398139 -143.626631)
			(xy 429.382618 -143.568706) (xy 429.37479 -143.50925) (xy 429.3743 -143.479266) (xy 428.956193 -143.479266)
			(xy 428.949358 -144.069308) (xy 428.948816 -144.098413) (xy 428.94475 -144.156489) (xy 428.94123 -144.185386)
			(xy 428.799487 -145.285714) (xy 432.016408 -145.285714) (xy 432.016408 -144.422114) (xy 432.016898 -144.39213)
			(xy 432.024726 -144.332674) (xy 432.040247 -144.274749) (xy 432.063196 -144.219345) (xy 432.09318 -144.167411)
			(xy 432.129686 -144.119835) (xy 432.172091 -144.07743) (xy 432.219667 -144.040924) (xy 432.271601 -144.01094)
			(xy 432.327005 -143.987991) (xy 432.38493 -143.97247) (xy 432.444386 -143.964642) (xy 432.504354 -143.964642)
			(xy 432.56381 -143.97247) (xy 432.621735 -143.987991) (xy 432.677139 -144.01094) (xy 432.729073 -144.040924)
			(xy 432.776649 -144.07743) (xy 432.819054 -144.119835) (xy 432.85556 -144.167411) (xy 432.885544 -144.219345)
			(xy 432.908493 -144.274749) (xy 432.924014 -144.332674) (xy 432.931842 -144.39213) (xy 432.932332 -144.422114)
			(xy 432.932332 -145.285714) (xy 432.931842 -145.315698) (xy 432.924014 -145.375154) (xy 432.908493 -145.433079)
			(xy 432.885544 -145.488483) (xy 432.85556 -145.540417) (xy 432.819054 -145.587993) (xy 432.776649 -145.630398)
			(xy 432.729073 -145.666904) (xy 432.677139 -145.696888) (xy 432.621735 -145.719837) (xy 432.56381 -145.735358)
			(xy 432.504354 -145.743186) (xy 432.444386 -145.743186) (xy 432.38493 -145.735358) (xy 432.327005 -145.719837)
			(xy 432.271601 -145.696888) (xy 432.219667 -145.666904) (xy 432.172091 -145.630398) (xy 432.129686 -145.587993)
			(xy 432.09318 -145.540417) (xy 432.063196 -145.488483) (xy 432.040247 -145.433079) (xy 432.024726 -145.375154)
			(xy 432.016898 -145.315698) (xy 432.016408 -145.285714) (xy 428.799487 -145.285714) (xy 428.568452 -147.079208)
			(xy 429.3743 -147.079208) (xy 429.3743 -146.215608) (xy 429.37479 -146.185624) (xy 429.382618 -146.126168)
			(xy 429.398139 -146.068243) (xy 429.421088 -146.012839) (xy 429.451072 -145.960905) (xy 429.487578 -145.913329)
			(xy 429.529983 -145.870924) (xy 429.577559 -145.834418) (xy 429.629493 -145.804434) (xy 429.684897 -145.781485)
			(xy 429.742822 -145.765964) (xy 429.802278 -145.758136) (xy 429.862246 -145.758136) (xy 429.921702 -145.765964)
			(xy 429.979627 -145.781485) (xy 430.035031 -145.804434) (xy 430.086965 -145.834418) (xy 430.134541 -145.870924)
			(xy 430.176946 -145.913329) (xy 430.213452 -145.960905) (xy 430.243436 -146.012839) (xy 430.266385 -146.068243)
			(xy 430.281906 -146.126168) (xy 430.289734 -146.185624) (xy 430.290224 -146.215608) (xy 430.290224 -147.079208)
			(xy 430.289734 -147.109192) (xy 430.281906 -147.168648) (xy 430.266385 -147.226573) (xy 430.243436 -147.281977)
			(xy 430.213452 -147.333911) (xy 430.176946 -147.381487) (xy 430.134541 -147.423892) (xy 430.086965 -147.460398)
			(xy 430.035031 -147.490382) (xy 429.979627 -147.513331) (xy 429.921702 -147.528852) (xy 429.862246 -147.53668)
			(xy 429.802278 -147.53668) (xy 429.742822 -147.528852) (xy 429.684897 -147.513331) (xy 429.629493 -147.490382)
			(xy 429.577559 -147.460398) (xy 429.529983 -147.423892) (xy 429.487578 -147.381487) (xy 429.451072 -147.333911)
			(xy 429.421088 -147.281977) (xy 429.398139 -147.226573) (xy 429.382618 -147.168648) (xy 429.37479 -147.109192)
			(xy 429.3743 -147.079208) (xy 428.568452 -147.079208) (xy 428.335715 -148.88591) (xy 432.016408 -148.88591)
			(xy 432.016408 -148.02231) (xy 432.016898 -147.992326) (xy 432.024726 -147.93287) (xy 432.040247 -147.874945)
			(xy 432.063196 -147.819541) (xy 432.09318 -147.767607) (xy 432.129686 -147.720031) (xy 432.172091 -147.677626)
			(xy 432.219667 -147.64112) (xy 432.271601 -147.611136) (xy 432.327005 -147.588187) (xy 432.38493 -147.572666)
			(xy 432.444386 -147.564838) (xy 432.504354 -147.564838) (xy 432.56381 -147.572666) (xy 432.621735 -147.588187)
			(xy 432.677139 -147.611136) (xy 432.729073 -147.64112) (xy 432.776649 -147.677626) (xy 432.819054 -147.720031)
			(xy 432.85556 -147.767607) (xy 432.885544 -147.819541) (xy 432.908493 -147.874945) (xy 432.924014 -147.93287)
			(xy 432.931842 -147.992326) (xy 432.932332 -148.02231) (xy 432.932332 -148.88591) (xy 432.931842 -148.915894)
			(xy 432.924014 -148.97535) (xy 432.908493 -149.033275) (xy 432.885544 -149.088679) (xy 432.85556 -149.140613)
			(xy 432.819054 -149.188189) (xy 432.776649 -149.230594) (xy 432.729073 -149.2671) (xy 432.677139 -149.297084)
			(xy 432.621735 -149.320033) (xy 432.56381 -149.335554) (xy 432.504354 -149.343382) (xy 432.444386 -149.343382)
			(xy 432.38493 -149.335554) (xy 432.327005 -149.320033) (xy 432.271601 -149.297084) (xy 432.219667 -149.2671)
			(xy 432.172091 -149.230594) (xy 432.129686 -149.188189) (xy 432.09318 -149.140613) (xy 432.063196 -149.088679)
			(xy 432.040247 -149.033275) (xy 432.024726 -148.97535) (xy 432.016898 -148.915894) (xy 432.016408 -148.88591)
			(xy 428.335715 -148.88591) (xy 428.104712 -150.67915) (xy 429.3743 -150.67915) (xy 429.3743 -149.81555)
			(xy 429.37479 -149.785566) (xy 429.382618 -149.72611) (xy 429.398139 -149.668185) (xy 429.421088 -149.612781)
			(xy 429.451072 -149.560847) (xy 429.487578 -149.513271) (xy 429.529983 -149.470866) (xy 429.577559 -149.43436)
			(xy 429.629493 -149.404376) (xy 429.684897 -149.381427) (xy 429.742822 -149.365906) (xy 429.802278 -149.358078)
			(xy 429.862246 -149.358078) (xy 429.921702 -149.365906) (xy 429.979627 -149.381427) (xy 430.035031 -149.404376)
			(xy 430.086965 -149.43436) (xy 430.134541 -149.470866) (xy 430.176946 -149.513271) (xy 430.213452 -149.560847)
			(xy 430.243436 -149.612781) (xy 430.266385 -149.668185) (xy 430.281906 -149.72611) (xy 430.289734 -149.785566)
			(xy 430.290224 -149.81555) (xy 430.290224 -150.67915) (xy 430.289734 -150.709134) (xy 430.281906 -150.76859)
			(xy 430.266385 -150.826515) (xy 430.243436 -150.881919) (xy 430.213452 -150.933853) (xy 430.176946 -150.981429)
			(xy 430.134541 -151.023834) (xy 430.086965 -151.06034) (xy 430.035031 -151.090324) (xy 429.979627 -151.113273)
			(xy 429.921702 -151.128794) (xy 429.862246 -151.136622) (xy 429.802278 -151.136622) (xy 429.742822 -151.128794)
			(xy 429.684897 -151.113273) (xy 429.629493 -151.090324) (xy 429.577559 -151.06034) (xy 429.529983 -151.023834)
			(xy 429.487578 -150.981429) (xy 429.451072 -150.933853) (xy 429.421088 -150.881919) (xy 429.398139 -150.826515)
			(xy 429.382618 -150.76859) (xy 429.37479 -150.709134) (xy 429.3743 -150.67915) (xy 428.104712 -150.67915)
			(xy 427.871975 -152.485852) (xy 432.016408 -152.485852) (xy 432.016408 -151.622252) (xy 432.016898 -151.592268)
			(xy 432.024726 -151.532812) (xy 432.040247 -151.474887) (xy 432.063196 -151.419483) (xy 432.09318 -151.367549)
			(xy 432.129686 -151.319973) (xy 432.172091 -151.277568) (xy 432.219667 -151.241062) (xy 432.271601 -151.211078)
			(xy 432.327005 -151.188129) (xy 432.38493 -151.172608) (xy 432.444386 -151.16478) (xy 432.504354 -151.16478)
			(xy 432.56381 -151.172608) (xy 432.621735 -151.188129) (xy 432.677139 -151.211078) (xy 432.729073 -151.241062)
			(xy 432.776649 -151.277568) (xy 432.819054 -151.319973) (xy 432.85556 -151.367549) (xy 432.885544 -151.419483)
			(xy 432.908493 -151.474887) (xy 432.924014 -151.532812) (xy 432.931842 -151.592268) (xy 432.932332 -151.622252)
			(xy 432.932332 -152.485852) (xy 432.931842 -152.515836) (xy 432.924014 -152.575292) (xy 432.908493 -152.633217)
			(xy 432.885544 -152.688621) (xy 432.85556 -152.740555) (xy 432.819054 -152.788131) (xy 432.776649 -152.830536)
			(xy 432.729073 -152.867042) (xy 432.677139 -152.897026) (xy 432.621735 -152.919975) (xy 432.56381 -152.935496)
			(xy 432.504354 -152.943324) (xy 432.444386 -152.943324) (xy 432.38493 -152.935496) (xy 432.327005 -152.919975)
			(xy 432.271601 -152.897026) (xy 432.219667 -152.867042) (xy 432.172091 -152.830536) (xy 432.129686 -152.788131)
			(xy 432.09318 -152.740555) (xy 432.063196 -152.688621) (xy 432.040247 -152.633217) (xy 432.024726 -152.575292)
			(xy 432.016898 -152.515836) (xy 432.016408 -152.485852) (xy 427.871975 -152.485852) (xy 427.640939 -154.279346)
			(xy 429.3743 -154.279346) (xy 429.3743 -153.415746) (xy 429.37479 -153.385762) (xy 429.382618 -153.326306)
			(xy 429.398139 -153.268381) (xy 429.421088 -153.212977) (xy 429.451072 -153.161043) (xy 429.487578 -153.113467)
			(xy 429.529983 -153.071062) (xy 429.577559 -153.034556) (xy 429.629493 -153.004572) (xy 429.684897 -152.981623)
			(xy 429.742822 -152.966102) (xy 429.802278 -152.958274) (xy 429.862246 -152.958274) (xy 429.921702 -152.966102)
			(xy 429.979627 -152.981623) (xy 430.035031 -153.004572) (xy 430.086965 -153.034556) (xy 430.134541 -153.071062)
			(xy 430.176946 -153.113467) (xy 430.213452 -153.161043) (xy 430.243436 -153.212977) (xy 430.266385 -153.268381)
			(xy 430.281906 -153.326306) (xy 430.289734 -153.385762) (xy 430.290224 -153.415746) (xy 430.290224 -154.279346)
			(xy 430.289734 -154.30933) (xy 430.281906 -154.368786) (xy 430.266385 -154.426711) (xy 430.243436 -154.482115)
			(xy 430.213452 -154.534049) (xy 430.176946 -154.581625) (xy 430.134541 -154.62403) (xy 430.086965 -154.660536)
			(xy 430.035031 -154.69052) (xy 429.979627 -154.713469) (xy 429.921702 -154.72899) (xy 429.862246 -154.736818)
			(xy 429.802278 -154.736818) (xy 429.742822 -154.72899) (xy 429.684897 -154.713469) (xy 429.629493 -154.69052)
			(xy 429.577559 -154.660536) (xy 429.529983 -154.62403) (xy 429.487578 -154.581625) (xy 429.451072 -154.534049)
			(xy 429.421088 -154.482115) (xy 429.398139 -154.426711) (xy 429.382618 -154.368786) (xy 429.37479 -154.30933)
			(xy 429.3743 -154.279346) (xy 427.640939 -154.279346) (xy 427.552104 -154.968956) (xy 427.5455 -155.012644)
			(xy 427.358608 -156.085794) (xy 432.016408 -156.085794) (xy 432.016408 -155.222194) (xy 432.016898 -155.19221)
			(xy 432.024726 -155.132754) (xy 432.040247 -155.074829) (xy 432.063196 -155.019425) (xy 432.09318 -154.967491)
			(xy 432.129686 -154.919915) (xy 432.172091 -154.87751) (xy 432.219667 -154.841004) (xy 432.271601 -154.81102)
			(xy 432.327005 -154.788071) (xy 432.38493 -154.77255) (xy 432.444386 -154.764722) (xy 432.504354 -154.764722)
			(xy 432.56381 -154.77255) (xy 432.621735 -154.788071) (xy 432.677139 -154.81102) (xy 432.729073 -154.841004)
			(xy 432.776649 -154.87751) (xy 432.819054 -154.919915) (xy 432.85556 -154.967491) (xy 432.885544 -155.019425)
			(xy 432.908493 -155.074829) (xy 432.924014 -155.132754) (xy 432.931842 -155.19221) (xy 432.932332 -155.222194)
			(xy 432.932332 -156.085794) (xy 432.931842 -156.115778) (xy 432.924014 -156.175234) (xy 432.908493 -156.233159)
			(xy 432.885544 -156.288563) (xy 432.85556 -156.340497) (xy 432.819054 -156.388073) (xy 432.776649 -156.430478)
			(xy 432.729073 -156.466984) (xy 432.677139 -156.496968) (xy 432.621735 -156.519917) (xy 432.56381 -156.535438)
			(xy 432.504354 -156.543266) (xy 432.444386 -156.543266) (xy 432.38493 -156.535438) (xy 432.327005 -156.519917)
			(xy 432.271601 -156.496968) (xy 432.219667 -156.466984) (xy 432.172091 -156.430478) (xy 432.129686 -156.388073)
			(xy 432.09318 -156.340497) (xy 432.063196 -156.288563) (xy 432.040247 -156.233159) (xy 432.024726 -156.175234)
			(xy 432.016898 -156.115778) (xy 432.016408 -156.085794) (xy 427.358608 -156.085794) (xy 426.986992 -158.219648)
			(xy 429.482248 -158.219648) (xy 429.486319 -158.164026) (xy 429.498445 -158.109589) (xy 429.518368 -158.057498)
			(xy 429.545664 -158.008863) (xy 429.57975 -157.96472) (xy 429.619899 -157.926011) (xy 429.665257 -157.89356)
			(xy 429.714857 -157.868059) (xy 429.767641 -157.850052) (xy 429.822484 -157.839922) (xy 429.878218 -157.837885)
			(xy 429.933655 -157.843985) (xy 429.987612 -157.858091) (xy 430.038941 -157.879903) (xy 430.086547 -157.908957)
			(xy 430.129415 -157.944632) (xy 430.166632 -157.986169) (xy 430.197405 -158.032682) (xy 430.221077 -158.083179)
			(xy 430.237145 -158.136586) (xy 430.245265 -158.191762) (xy 430.245774 -158.219648) (xy 430.245265 -158.247534)
			(xy 430.237145 -158.30271) (xy 430.221077 -158.356117) (xy 430.197405 -158.406614) (xy 430.166632 -158.453127)
			(xy 430.129415 -158.494664) (xy 430.086547 -158.530339) (xy 430.038941 -158.559393) (xy 429.987612 -158.581205)
			(xy 429.933655 -158.595311) (xy 429.878218 -158.601411) (xy 429.822484 -158.599374) (xy 429.767641 -158.589244)
			(xy 429.714857 -158.571237) (xy 429.665257 -158.545736) (xy 429.619899 -158.513285) (xy 429.57975 -158.474576)
			(xy 429.545664 -158.430433) (xy 429.518368 -158.381798) (xy 429.498445 -158.329707) (xy 429.486319 -158.27527)
			(xy 429.482248 -158.219648) (xy 426.986992 -158.219648) (xy 426.805316 -159.262848) (xy 429.641026 -159.262848)
			(xy 429.641026 -159.208352) (xy 429.648782 -159.154411) (xy 429.664135 -159.102123) (xy 429.686773 -159.052552)
			(xy 429.716236 -159.006708) (xy 429.751923 -158.965523) (xy 429.793108 -158.929836) (xy 429.838952 -158.900373)
			(xy 429.888523 -158.877735) (xy 429.940811 -158.862382) (xy 429.994752 -158.854626) (xy 430.022 -158.85414)
			(xy 430.052803 -158.854751) (xy 430.113604 -158.864675) (xy 430.172018 -158.884249) (xy 430.199546 -158.898082)
			(xy 430.205064 -158.90081) (xy 430.217014 -158.903759) (xy 430.223168 -158.903924) (xy 431.384202 -158.903924)
			(xy 431.394274 -158.90352) (xy 431.412873 -158.895786) (xy 431.42027 -158.888938) (xy 434.037486 -156.271722)
			(xy 434.044307 -156.264307) (xy 434.052038 -156.245719) (xy 434.052472 -156.235654) (xy 434.052472 -140.688822)
			(xy 434.052271 -140.682673) (xy 434.049322 -140.670732) (xy 434.04663 -140.6652) (xy 434.032792 -140.637674)
			(xy 434.013228 -140.579257) (xy 434.003296 -140.518457) (xy 434.002688 -140.487654) (xy 434.003174 -140.460403)
			(xy 434.01093 -140.406455) (xy 434.026285 -140.35416) (xy 434.048927 -140.304583) (xy 434.078393 -140.258733)
			(xy 434.114084 -140.217542) (xy 434.155275 -140.181851) (xy 434.201125 -140.152385) (xy 434.250702 -140.129743)
			(xy 434.302997 -140.114388) (xy 434.356945 -140.106632) (xy 434.411447 -140.106632) (xy 434.465395 -140.114388)
			(xy 434.51769 -140.129743) (xy 434.567267 -140.152385) (xy 434.613117 -140.181851) (xy 434.654308 -140.217542)
			(xy 434.689999 -140.258733) (xy 434.719465 -140.304583) (xy 434.742107 -140.35416) (xy 434.757462 -140.406455)
			(xy 434.765218 -140.460403) (xy 434.765704 -140.487654) (xy 434.765109 -140.518457) (xy 434.755177 -140.579259)
			(xy 434.735598 -140.637672) (xy 434.721762 -140.6652) (xy 434.719045 -140.670723) (xy 434.71609 -140.682669)
			(xy 434.71592 -140.688822) (xy 434.71592 -156.394658) (xy 434.715403 -156.420682) (xy 434.707234 -156.472086)
			(xy 434.691137 -156.521583) (xy 434.667508 -156.567959) (xy 434.636925 -156.610075) (xy 434.618892 -156.628846)
			(xy 431.777394 -159.470344) (xy 431.758604 -159.488355) (xy 431.716491 -159.518936) (xy 431.67012 -159.542567)
			(xy 431.620627 -159.558666) (xy 431.569228 -159.56684) (xy 431.543206 -159.567372) (xy 430.223168 -159.567372)
			(xy 430.217017 -159.56755) (xy 430.205076 -159.570514) (xy 430.199546 -159.573214) (xy 430.172014 -159.587039)
			(xy 430.1136 -159.606607) (xy 430.052802 -159.616544) (xy 430.022 -159.617156) (xy 429.994752 -159.616574)
			(xy 429.940811 -159.608818) (xy 429.888523 -159.593465) (xy 429.838952 -159.570827) (xy 429.793108 -159.541364)
			(xy 429.751923 -159.505677) (xy 429.716236 -159.464492) (xy 429.686773 -159.418648) (xy 429.664135 -159.369077)
			(xy 429.648782 -159.316789) (xy 429.641026 -159.262848) (xy 426.805316 -159.262848) (xy 420.660322 -194.547998)
			(xy 420.659641 -194.557461) (xy 420.664349 -194.575821) (xy 420.669466 -194.583812) (xy 420.711376 -194.64274)
			(xy 420.715736 -194.648372) (xy 420.726958 -194.657135) (xy 420.733474 -194.660012) (xy 420.736776 -194.661282)
			(xy 420.742872 -194.66306) (xy 420.744904 -194.663314) (xy 420.781101 -194.669673) (xy 420.851655 -194.690253)
			(xy 420.919077 -194.719507) (xy 420.982303 -194.756975) (xy 421.040339 -194.802066) (xy 421.066722 -194.827652)
			(xy 422.318434 -196.079364) (xy 422.341331 -196.102928) (xy 422.382285 -196.154312) (xy 422.417232 -196.209954)
			(xy 422.445734 -196.269158) (xy 422.467433 -196.331178) (xy 422.482057 -196.395238) (xy 422.489421 -196.460531)
			(xy 422.489884 -196.493384) (xy 422.489884 -212.39226) (xy 442.90234 -212.39226) (xy 442.90234 -129.84226)
			(xy 442.902865 -129.810627) (xy 442.911105 -129.747901) (xy 442.927466 -129.686789) (xy 442.951666 -129.628335)
			(xy 442.983292 -129.573542) (xy 443.021801 -129.523348) (xy 443.043818 -129.50063) (xy 446.857882 -125.68682)
			(xy 446.864703 -125.679405) (xy 446.872435 -125.660817) (xy 446.872868 -125.650752) (xy 446.872868 -124.10313)
			(xy 446.872435 -124.093061) (xy 446.86472 -124.074463) (xy 446.857882 -124.067062) (xy 446.656714 -123.865894)
			(xy 446.650252 -123.859981) (xy 446.634446 -123.852471) (xy 446.617037 -123.850696) (xy 446.608454 -123.852432)
			(xy 446.510918 -123.876816) (xy 446.491614 -123.89485) (xy 446.487804 -123.907804) (xy 446.479372 -123.9334)
			(xy 446.456355 -123.982127) (xy 446.42671 -124.027131) (xy 446.391027 -124.067515) (xy 446.350017 -124.102476)
			(xy 446.304495 -124.131319) (xy 446.255368 -124.153469) (xy 446.203612 -124.168486) (xy 446.150259 -124.176071)
			(xy 446.123314 -124.176536) (xy 446.096064 -124.176009) (xy 446.04212 -124.168255) (xy 445.989827 -124.152903)
			(xy 445.940252 -124.130266) (xy 445.894403 -124.100803) (xy 445.853214 -124.065116) (xy 445.817522 -124.023931)
			(xy 445.788055 -123.978085) (xy 445.765412 -123.928512) (xy 445.750054 -123.876221) (xy 445.742294 -123.822278)
			(xy 445.741806 -123.795028) (xy 445.742305 -123.76715) (xy 445.750417 -123.711988) (xy 445.766472 -123.658594)
			(xy 445.790129 -123.608105) (xy 445.820883 -123.561598) (xy 445.858079 -123.520063) (xy 445.900924 -123.484385)
			(xy 445.948507 -123.455323) (xy 445.999814 -123.433498) (xy 446.053751 -123.419373) (xy 446.081404 -123.415806)
			(xy 446.092326 -123.414536) (xy 446.111376 -123.403106) (xy 446.16751 -123.32081) (xy 446.171066 -123.298966)
			(xy 446.168018 -123.288044) (xy 446.159993 -123.256653) (xy 446.151454 -123.192425) (xy 446.151 -123.160028)
			(xy 446.151534 -123.128408) (xy 446.159783 -123.065709) (xy 446.176142 -123.004622) (xy 446.200333 -122.946192)
			(xy 446.231941 -122.891418) (xy 446.270427 -122.841238) (xy 446.315131 -122.796508) (xy 446.36529 -122.757994)
			(xy 446.420046 -122.726354) (xy 446.478462 -122.702131) (xy 446.53954 -122.685736) (xy 446.602234 -122.677452)
			(xy 446.633854 -122.67692) (xy 446.665487 -122.677442) (xy 446.728213 -122.685683) (xy 446.789325 -122.702045)
			(xy 446.847778 -122.726246) (xy 446.902571 -122.757872) (xy 446.952766 -122.796381) (xy 446.975484 -122.818398)
			(xy 447.697352 -123.540266) (xy 447.719269 -123.562978) (xy 447.757664 -123.613073) (xy 447.789211 -123.66774)
			(xy 447.813372 -123.726049) (xy 447.829737 -123.787007) (xy 447.838027 -123.849576) (xy 447.838576 -123.881134)
			(xy 447.838576 -124.640594) (xy 449.232272 -124.640594) (xy 449.236343 -124.584972) (xy 449.248469 -124.530535)
			(xy 449.268392 -124.478444) (xy 449.295688 -124.429809) (xy 449.329774 -124.385666) (xy 449.369923 -124.346957)
			(xy 449.415281 -124.314506) (xy 449.464881 -124.289005) (xy 449.517665 -124.270998) (xy 449.572508 -124.260868)
			(xy 449.628242 -124.258831) (xy 449.683679 -124.264931) (xy 449.737636 -124.279037) (xy 449.788965 -124.300849)
			(xy 449.836571 -124.329903) (xy 449.879439 -124.365578) (xy 449.916656 -124.407115) (xy 449.947429 -124.453628)
			(xy 449.971101 -124.504125) (xy 449.987169 -124.557532) (xy 449.995289 -124.612708) (xy 449.995798 -124.640594)
			(xy 449.995289 -124.66848) (xy 449.987169 -124.723656) (xy 449.971101 -124.777063) (xy 449.947429 -124.82756)
			(xy 449.916656 -124.874073) (xy 449.879439 -124.91561) (xy 449.836571 -124.951285) (xy 449.788965 -124.980339)
			(xy 449.737636 -125.002151) (xy 449.683679 -125.016257) (xy 449.628242 -125.022357) (xy 449.572508 -125.02032)
			(xy 449.517665 -125.01019) (xy 449.464881 -124.992183) (xy 449.415281 -124.966682) (xy 449.369923 -124.934231)
			(xy 449.329774 -124.895522) (xy 449.295688 -124.851379) (xy 449.268392 -124.802744) (xy 449.248469 -124.750653)
			(xy 449.236343 -124.696216) (xy 449.232272 -124.640594) (xy 447.838576 -124.640594) (xy 447.838576 -125.872748)
			(xy 447.837995 -125.904306) (xy 447.829728 -125.96688) (xy 447.813378 -126.027842) (xy 447.789226 -126.086156)
			(xy 447.757683 -126.140826) (xy 447.719287 -126.190921) (xy 447.697352 -126.213616) (xy 443.883542 -130.027426)
			(xy 443.876704 -130.034828) (xy 443.868982 -130.053426) (xy 443.868556 -130.063494) (xy 443.868556 -137.65276)
			(xy 444.341248 -137.65276) (xy 444.345319 -137.597138) (xy 444.357445 -137.542701) (xy 444.377368 -137.49061)
			(xy 444.404664 -137.441975) (xy 444.43875 -137.397832) (xy 444.478899 -137.359123) (xy 444.524257 -137.326672)
			(xy 444.573857 -137.301171) (xy 444.626641 -137.283164) (xy 444.681484 -137.273034) (xy 444.737218 -137.270997)
			(xy 444.792655 -137.277097) (xy 444.846612 -137.291203) (xy 444.897941 -137.313015) (xy 444.945547 -137.342069)
			(xy 444.988415 -137.377744) (xy 445.025632 -137.419281) (xy 445.056405 -137.465794) (xy 445.080077 -137.516291)
			(xy 445.096145 -137.569698) (xy 445.104265 -137.624874) (xy 445.104774 -137.65276) (xy 445.104265 -137.680646)
			(xy 445.096145 -137.735822) (xy 445.080077 -137.789229) (xy 445.056405 -137.839726) (xy 445.025632 -137.886239)
			(xy 444.988415 -137.927776) (xy 444.977268 -137.937053) (xy 445.665563 -137.937053) (xy 445.665563 -137.882547)
			(xy 445.67332 -137.828597) (xy 445.688676 -137.7763) (xy 445.711319 -137.72672) (xy 445.740787 -137.680868)
			(xy 445.77648 -137.639676) (xy 445.817673 -137.603983) (xy 445.863526 -137.574516) (xy 445.913106 -137.551874)
			(xy 445.965403 -137.536519) (xy 446.019353 -137.528763) (xy 446.046606 -137.5283) (xy 446.074709 -137.528782)
			(xy 446.130306 -137.537029) (xy 446.184092 -137.553344) (xy 446.234901 -137.577374) (xy 446.281636 -137.608598)
			(xy 446.323284 -137.646341) (xy 446.3415 -137.667746) (xy 446.348803 -137.675928) (xy 446.368414 -137.685684)
			(xy 446.379346 -137.686542) (xy 446.466976 -137.689082) (xy 446.487296 -137.680446) (xy 446.494662 -137.672318)
			(xy 446.512803 -137.653333) (xy 446.553392 -137.620017) (xy 446.598162 -137.592577) (xy 446.64627 -137.571529)
			(xy 446.696808 -137.557272) (xy 446.748823 -137.550074) (xy 446.775078 -137.549636) (xy 446.802335 -137.550009)
			(xy 446.856295 -137.557765) (xy 446.908601 -137.573121) (xy 446.95819 -137.595765) (xy 447.004051 -137.625235)
			(xy 447.045251 -137.660933) (xy 447.080951 -137.702131) (xy 447.110425 -137.747991) (xy 447.133072 -137.797578)
			(xy 447.148431 -137.849884) (xy 447.156189 -137.903843) (xy 447.156189 -137.958357) (xy 447.148431 -138.012316)
			(xy 447.133072 -138.064622) (xy 447.110425 -138.114209) (xy 447.080951 -138.160069) (xy 447.045251 -138.201267)
			(xy 447.004051 -138.236965) (xy 446.95819 -138.266435) (xy 446.908601 -138.289079) (xy 446.856295 -138.304435)
			(xy 446.802335 -138.312191) (xy 446.775078 -138.312652) (xy 446.746976 -138.312128) (xy 446.69138 -138.303892)
			(xy 446.637595 -138.287587) (xy 446.586784 -138.263565) (xy 446.540049 -138.232347) (xy 446.4984 -138.194609)
			(xy 446.480184 -138.173206) (xy 446.472879 -138.165026) (xy 446.45327 -138.155267) (xy 446.442338 -138.15441)
			(xy 446.354708 -138.15187) (xy 446.334388 -138.160506) (xy 446.327022 -138.168634) (xy 446.308879 -138.187617)
			(xy 446.268292 -138.220935) (xy 446.223523 -138.248377) (xy 446.175415 -138.269425) (xy 446.124877 -138.283682)
			(xy 446.072861 -138.290879) (xy 446.046606 -138.291316) (xy 446.019353 -138.290837) (xy 445.965403 -138.283081)
			(xy 445.913106 -138.267726) (xy 445.863526 -138.245084) (xy 445.817673 -138.215617) (xy 445.77648 -138.179924)
			(xy 445.740787 -138.138732) (xy 445.711319 -138.09288) (xy 445.688676 -138.0433) (xy 445.67332 -137.991003)
			(xy 445.665563 -137.937053) (xy 444.977268 -137.937053) (xy 444.945547 -137.963451) (xy 444.897941 -137.992505)
			(xy 444.846612 -138.014317) (xy 444.792655 -138.028423) (xy 444.737218 -138.034523) (xy 444.681484 -138.032486)
			(xy 444.626641 -138.022356) (xy 444.573857 -138.004349) (xy 444.524257 -137.978848) (xy 444.478899 -137.946397)
			(xy 444.43875 -137.907688) (xy 444.404664 -137.863545) (xy 444.377368 -137.81491) (xy 444.357445 -137.762819)
			(xy 444.345319 -137.708382) (xy 444.341248 -137.65276) (xy 443.868556 -137.65276) (xy 443.868556 -207.97393)
			(xy 454.542396 -207.97393) (xy 454.546467 -207.918308) (xy 454.558593 -207.863871) (xy 454.578516 -207.81178)
			(xy 454.605812 -207.763145) (xy 454.639898 -207.719002) (xy 454.680047 -207.680293) (xy 454.725405 -207.647842)
			(xy 454.775005 -207.622341) (xy 454.827789 -207.604334) (xy 454.882632 -207.594204) (xy 454.938366 -207.592167)
			(xy 454.993803 -207.598267) (xy 455.04776 -207.612373) (xy 455.099089 -207.634185) (xy 455.146695 -207.663239)
			(xy 455.189563 -207.698914) (xy 455.22678 -207.740451) (xy 455.257553 -207.786964) (xy 455.281225 -207.837461)
			(xy 455.297293 -207.890868) (xy 455.305413 -207.946044) (xy 455.305922 -207.97393) (xy 455.305413 -208.001816)
			(xy 455.297293 -208.056992) (xy 455.281225 -208.110399) (xy 455.257553 -208.160896) (xy 455.22678 -208.207409)
			(xy 455.189563 -208.248946) (xy 455.146695 -208.284621) (xy 455.099089 -208.313675) (xy 455.04776 -208.335487)
			(xy 454.993803 -208.349593) (xy 454.938366 -208.355693) (xy 454.882632 -208.353656) (xy 454.827789 -208.343526)
			(xy 454.775005 -208.325519) (xy 454.725405 -208.300018) (xy 454.680047 -208.267567) (xy 454.639898 -208.228858)
			(xy 454.605812 -208.184715) (xy 454.578516 -208.13608) (xy 454.558593 -208.083989) (xy 454.546467 -208.029552)
			(xy 454.542396 -207.97393) (xy 443.868556 -207.97393) (xy 443.868556 -209.380836) (xy 445.288416 -209.380836)
			(xy 445.288416 -208.517236) (xy 445.288906 -208.487268) (xy 445.296729 -208.427846) (xy 445.312242 -208.369953)
			(xy 445.335178 -208.31458) (xy 445.365145 -208.262674) (xy 445.401632 -208.215124) (xy 445.444012 -208.172744)
			(xy 445.491562 -208.136257) (xy 445.543468 -208.10629) (xy 445.598841 -208.083354) (xy 445.656734 -208.067841)
			(xy 445.716156 -208.060018) (xy 445.776092 -208.060018) (xy 445.835514 -208.067841) (xy 445.893407 -208.083354)
			(xy 445.94878 -208.10629) (xy 446.000686 -208.136257) (xy 446.048236 -208.172744) (xy 446.090616 -208.215124)
			(xy 446.127103 -208.262674) (xy 446.15707 -208.31458) (xy 446.180006 -208.369953) (xy 446.195519 -208.427846)
			(xy 446.203342 -208.487268) (xy 446.203832 -208.517236) (xy 446.203832 -209.380836) (xy 446.203342 -209.410804)
			(xy 446.195519 -209.470226) (xy 446.180006 -209.528119) (xy 446.15707 -209.583492) (xy 446.127103 -209.635398)
			(xy 446.090616 -209.682948) (xy 446.048236 -209.725328) (xy 446.000686 -209.761815) (xy 445.94878 -209.791782)
			(xy 445.893407 -209.814718) (xy 445.835514 -209.830231) (xy 445.776092 -209.838054) (xy 445.716156 -209.838054)
			(xy 445.656734 -209.830231) (xy 445.598841 -209.814718) (xy 445.543468 -209.791782) (xy 445.491562 -209.761815)
			(xy 445.444012 -209.725328) (xy 445.401632 -209.682948) (xy 445.365145 -209.635398) (xy 445.335178 -209.583492)
			(xy 445.312242 -209.528119) (xy 445.296729 -209.470226) (xy 445.288906 -209.410804) (xy 445.288416 -209.380836)
			(xy 443.868556 -209.380836) (xy 443.868556 -209.94878) (xy 451.586598 -209.94878) (xy 451.590669 -209.893158)
			(xy 451.602795 -209.838721) (xy 451.622718 -209.78663) (xy 451.650014 -209.737995) (xy 451.6841 -209.693852)
			(xy 451.724249 -209.655143) (xy 451.769607 -209.622692) (xy 451.819207 -209.597191) (xy 451.871991 -209.579184)
			(xy 451.926834 -209.569054) (xy 451.982568 -209.567017) (xy 452.038005 -209.573117) (xy 452.091962 -209.587223)
			(xy 452.143291 -209.609035) (xy 452.190897 -209.638089) (xy 452.233765 -209.673764) (xy 452.270982 -209.715301)
			(xy 452.301755 -209.761814) (xy 452.325427 -209.812311) (xy 452.341495 -209.865718) (xy 452.349615 -209.920894)
			(xy 452.350124 -209.94878) (xy 452.349615 -209.976666) (xy 452.341495 -210.031842) (xy 452.325427 -210.085249)
			(xy 452.301755 -210.135746) (xy 452.270982 -210.182259) (xy 452.233765 -210.223796) (xy 452.190897 -210.259471)
			(xy 452.143291 -210.288525) (xy 452.091962 -210.310337) (xy 452.038005 -210.324443) (xy 451.982568 -210.330543)
			(xy 451.926834 -210.328506) (xy 451.871991 -210.318376) (xy 451.819207 -210.300369) (xy 451.769607 -210.274868)
			(xy 451.724249 -210.242417) (xy 451.6841 -210.203708) (xy 451.650014 -210.159565) (xy 451.622718 -210.11093)
			(xy 451.602795 -210.058839) (xy 451.590669 -210.004402) (xy 451.586598 -209.94878) (xy 443.868556 -209.94878)
			(xy 443.868556 -212.171026) (xy 443.868953 -212.181099) (xy 443.876692 -212.199697) (xy 443.883542 -212.207094)
			(xy 449.844668 -218.16822) (xy 449.866614 -218.190905) (xy 449.905006 -218.241006) (xy 449.936548 -218.295679)
			(xy 449.960704 -218.353993) (xy 449.977063 -218.414956) (xy 449.985347 -218.477529) (xy 449.985892 -218.509088)
			(xy 449.985892 -222.0976) (xy 451.742046 -222.0976) (xy 451.746117 -222.041978) (xy 451.758243 -221.987541)
			(xy 451.778166 -221.93545) (xy 451.805462 -221.886815) (xy 451.839548 -221.842672) (xy 451.879697 -221.803963)
			(xy 451.925055 -221.771512) (xy 451.974655 -221.746011) (xy 452.027439 -221.728004) (xy 452.082282 -221.717874)
			(xy 452.138016 -221.715837) (xy 452.193453 -221.721937) (xy 452.24741 -221.736043) (xy 452.298739 -221.757855)
			(xy 452.346345 -221.786909) (xy 452.389213 -221.822584) (xy 452.42643 -221.864121) (xy 452.457203 -221.910634)
			(xy 452.480875 -221.961131) (xy 452.496943 -222.014538) (xy 452.505063 -222.069714) (xy 452.505572 -222.0976)
			(xy 452.505063 -222.125486) (xy 452.496943 -222.180662) (xy 452.480875 -222.234069) (xy 452.457203 -222.284566)
			(xy 452.42643 -222.331079) (xy 452.389213 -222.372616) (xy 452.346345 -222.408291) (xy 452.298739 -222.437345)
			(xy 452.24741 -222.459157) (xy 452.193453 -222.473263) (xy 452.138016 -222.479363) (xy 452.082282 -222.477326)
			(xy 452.027439 -222.467196) (xy 451.974655 -222.449189) (xy 451.925055 -222.423688) (xy 451.879697 -222.391237)
			(xy 451.839548 -222.352528) (xy 451.805462 -222.308385) (xy 451.778166 -222.25975) (xy 451.758243 -222.207659)
			(xy 451.746117 -222.153222) (xy 451.742046 -222.0976) (xy 449.985892 -222.0976) (xy 449.985892 -226.681538)
			(xy 457.325982 -226.681538) (xy 457.330053 -226.625916) (xy 457.342179 -226.571479) (xy 457.362102 -226.519388)
			(xy 457.389398 -226.470753) (xy 457.423484 -226.42661) (xy 457.463633 -226.387901) (xy 457.508991 -226.35545)
			(xy 457.558591 -226.329949) (xy 457.611375 -226.311942) (xy 457.666218 -226.301812) (xy 457.721952 -226.299775)
			(xy 457.777389 -226.305875) (xy 457.831346 -226.319981) (xy 457.882675 -226.341793) (xy 457.930281 -226.370847)
			(xy 457.973149 -226.406522) (xy 458.010366 -226.448059) (xy 458.041139 -226.494572) (xy 458.064811 -226.545069)
			(xy 458.080879 -226.598476) (xy 458.088999 -226.653652) (xy 458.089508 -226.681538) (xy 458.088999 -226.709424)
			(xy 458.080879 -226.7646) (xy 458.064811 -226.818007) (xy 458.041139 -226.868504) (xy 458.010366 -226.915017)
			(xy 457.973149 -226.956554) (xy 457.930281 -226.992229) (xy 457.882675 -227.021283) (xy 457.831346 -227.043095)
			(xy 457.777389 -227.057201) (xy 457.721952 -227.063301) (xy 457.666218 -227.061264) (xy 457.611375 -227.051134)
			(xy 457.558591 -227.033127) (xy 457.508991 -227.007626) (xy 457.463633 -226.975175) (xy 457.423484 -226.936466)
			(xy 457.389398 -226.892323) (xy 457.362102 -226.843688) (xy 457.342179 -226.791597) (xy 457.330053 -226.73716)
			(xy 457.325982 -226.681538) (xy 449.985892 -226.681538) (xy 449.985892 -231.496616) (xy 449.985379 -231.528177)
			(xy 449.977101 -231.590754) (xy 449.96074 -231.651719) (xy 449.936576 -231.710033) (xy 449.905019 -231.764701)
			(xy 449.866609 -231.814792) (xy 449.844668 -231.837484) (xy 448.987672 -232.69448) (xy 451.24192 -232.69448)
			(xy 451.245991 -232.638858) (xy 451.258117 -232.584421) (xy 451.27804 -232.53233) (xy 451.305336 -232.483695)
			(xy 451.339422 -232.439552) (xy 451.379571 -232.400843) (xy 451.424929 -232.368392) (xy 451.474529 -232.342891)
			(xy 451.527313 -232.324884) (xy 451.582156 -232.314754) (xy 451.63789 -232.312717) (xy 451.693327 -232.318817)
			(xy 451.747284 -232.332923) (xy 451.798613 -232.354735) (xy 451.846219 -232.383789) (xy 451.889087 -232.419464)
			(xy 451.926304 -232.461001) (xy 451.957077 -232.507514) (xy 451.980749 -232.558011) (xy 451.996817 -232.611418)
			(xy 452.004937 -232.666594) (xy 452.005446 -232.69448) (xy 452.004937 -232.722366) (xy 451.996817 -232.777542)
			(xy 451.980749 -232.830949) (xy 451.957077 -232.881446) (xy 451.926304 -232.927959) (xy 451.889087 -232.969496)
			(xy 451.846219 -233.005171) (xy 451.798613 -233.034225) (xy 451.747284 -233.056037) (xy 451.693327 -233.070143)
			(xy 451.63789 -233.076243) (xy 451.582156 -233.074206) (xy 451.527313 -233.064076) (xy 451.474529 -233.046069)
			(xy 451.424929 -233.020568) (xy 451.379571 -232.988117) (xy 451.339422 -232.949408) (xy 451.305336 -232.905265)
			(xy 451.27804 -232.85663) (xy 451.258117 -232.804539) (xy 451.245991 -232.750102) (xy 451.24192 -232.69448)
			(xy 448.987672 -232.69448) (xy 447.733166 -233.948986) (xy 447.726335 -233.956393) (xy 447.718611 -233.974987)
			(xy 447.71818 -233.985054) (xy 447.71818 -234.655869) (xy 448.021157 -234.655869) (xy 448.021157 -234.595931)
			(xy 448.028981 -234.536505) (xy 448.044494 -234.478608) (xy 448.067432 -234.423232) (xy 448.097401 -234.371324)
			(xy 448.13389 -234.323771) (xy 448.176273 -234.281388) (xy 448.223825 -234.2449) (xy 448.275734 -234.214931)
			(xy 448.33111 -234.191993) (xy 448.389007 -234.17648) (xy 448.448433 -234.168657) (xy 448.478402 -234.168188)
			(xy 449.342002 -234.168188) (xy 449.371969 -234.168686) (xy 449.431391 -234.176509) (xy 449.489283 -234.192022)
			(xy 449.544656 -234.214958) (xy 449.596561 -234.244925) (xy 449.64411 -234.281411) (xy 449.68649 -234.323792)
			(xy 449.722976 -234.371341) (xy 449.752943 -234.423246) (xy 449.775879 -234.478618) (xy 449.791391 -234.536511)
			(xy 449.799214 -234.595933) (xy 449.799214 -234.655867) (xy 449.791391 -234.715289) (xy 449.775879 -234.773182)
			(xy 449.752943 -234.828554) (xy 449.749404 -234.834684) (xy 450.697598 -234.834684) (xy 450.701669 -234.779062)
			(xy 450.713795 -234.724625) (xy 450.733718 -234.672534) (xy 450.761014 -234.623899) (xy 450.7951 -234.579756)
			(xy 450.835249 -234.541047) (xy 450.880607 -234.508596) (xy 450.930207 -234.483095) (xy 450.982991 -234.465088)
			(xy 451.037834 -234.454958) (xy 451.093568 -234.452921) (xy 451.149005 -234.459021) (xy 451.202962 -234.473127)
			(xy 451.254291 -234.494939) (xy 451.301897 -234.523993) (xy 451.344765 -234.559668) (xy 451.381982 -234.601205)
			(xy 451.412755 -234.647718) (xy 451.436427 -234.698215) (xy 451.452495 -234.751622) (xy 451.460615 -234.806798)
			(xy 451.461124 -234.834684) (xy 451.460615 -234.86257) (xy 451.452495 -234.917746) (xy 451.436427 -234.971153)
			(xy 451.412755 -235.02165) (xy 451.381982 -235.068163) (xy 451.344765 -235.1097) (xy 451.301897 -235.145375)
			(xy 451.254291 -235.174429) (xy 451.202962 -235.196241) (xy 451.149005 -235.210347) (xy 451.093568 -235.216447)
			(xy 451.037834 -235.21441) (xy 450.982991 -235.20428) (xy 450.930207 -235.186273) (xy 450.880607 -235.160772)
			(xy 450.835249 -235.128321) (xy 450.7951 -235.089612) (xy 450.761014 -235.045469) (xy 450.733718 -234.996834)
			(xy 450.713795 -234.944743) (xy 450.701669 -234.890306) (xy 450.697598 -234.834684) (xy 449.749404 -234.834684)
			(xy 449.722976 -234.880459) (xy 449.68649 -234.928008) (xy 449.64411 -234.970389) (xy 449.596561 -235.006875)
			(xy 449.544656 -235.036842) (xy 449.489283 -235.059778) (xy 449.431391 -235.075291) (xy 449.371969 -235.083114)
			(xy 449.342002 -235.083604) (xy 448.478402 -235.083604) (xy 448.448433 -235.083143) (xy 448.389007 -235.07532)
			(xy 448.33111 -235.059807) (xy 448.275734 -235.036869) (xy 448.223825 -235.0069) (xy 448.176273 -234.970412)
			(xy 448.13389 -234.928029) (xy 448.097401 -234.880476) (xy 448.067432 -234.828568) (xy 448.044494 -234.773192)
			(xy 448.028981 -234.715295) (xy 448.021157 -234.655869) (xy 447.71818 -234.655869) (xy 447.71818 -235.275882)
			(xy 447.718594 -235.285953) (xy 447.72632 -235.304552) (xy 447.733166 -235.31195) (xy 448.809618 -236.388402)
			(xy 450.160898 -236.388402) (xy 450.161419 -236.359485) (xy 450.170147 -236.302314) (xy 450.187405 -236.247115)
			(xy 450.212796 -236.195154) (xy 450.245739 -236.14762) (xy 450.285479 -236.105603) (xy 450.307964 -236.087412)
			(xy 450.316766 -236.079801) (xy 450.32695 -236.058903) (xy 450.327522 -236.04728) (xy 450.327522 -235.967524)
			(xy 450.326947 -235.955897) (xy 450.316783 -235.934987) (xy 450.307964 -235.927392) (xy 450.285469 -235.909215)
			(xy 450.245736 -235.867191) (xy 450.2128 -235.819653) (xy 450.187414 -235.767689) (xy 450.170159 -235.71249)
			(xy 450.161432 -235.655319) (xy 450.160898 -235.626402) (xy 450.161384 -235.599151) (xy 450.16914 -235.545203)
			(xy 450.184495 -235.492908) (xy 450.207137 -235.443331) (xy 450.236603 -235.397481) (xy 450.272294 -235.35629)
			(xy 450.313485 -235.320599) (xy 450.359335 -235.291133) (xy 450.408912 -235.268491) (xy 450.461207 -235.253136)
			(xy 450.515155 -235.24538) (xy 450.569657 -235.24538) (xy 450.623605 -235.253136) (xy 450.6759 -235.268491)
			(xy 450.725477 -235.291133) (xy 450.771327 -235.320599) (xy 450.812518 -235.35629) (xy 450.848209 -235.397481)
			(xy 450.877675 -235.443331) (xy 450.900317 -235.492908) (xy 450.915672 -235.545203) (xy 450.923428 -235.599151)
			(xy 450.923914 -235.626402) (xy 450.92343 -235.655321) (xy 450.914698 -235.712495) (xy 450.897436 -235.767696)
			(xy 450.872038 -235.819658) (xy 450.839087 -235.867191) (xy 450.799338 -235.909204) (xy 450.776848 -235.927392)
			(xy 450.768046 -235.935003) (xy 450.757861 -235.955901) (xy 450.75729 -235.967524) (xy 450.75729 -236.04728)
			(xy 450.757859 -236.058908) (xy 450.768027 -236.079818) (xy 450.776848 -236.087412) (xy 450.799347 -236.105584)
			(xy 450.839079 -236.147609) (xy 450.872015 -236.195149) (xy 450.8974 -236.247113) (xy 450.914654 -236.302313)
			(xy 450.921397 -236.346492) (xy 454.16038 -236.346492) (xy 454.164451 -236.29087) (xy 454.176577 -236.236433)
			(xy 454.1965 -236.184342) (xy 454.223796 -236.135707) (xy 454.257882 -236.091564) (xy 454.298031 -236.052855)
			(xy 454.343389 -236.020404) (xy 454.392989 -235.994903) (xy 454.445773 -235.976896) (xy 454.500616 -235.966766)
			(xy 454.55635 -235.964729) (xy 454.611787 -235.970829) (xy 454.665744 -235.984935) (xy 454.717073 -236.006747)
			(xy 454.764679 -236.035801) (xy 454.807547 -236.071476) (xy 454.844764 -236.113013) (xy 454.875537 -236.159526)
			(xy 454.899209 -236.210023) (xy 454.915277 -236.26343) (xy 454.922866 -236.314996) (xy 455.160378 -236.314996)
			(xy 455.164449 -236.259374) (xy 455.176575 -236.204937) (xy 455.196498 -236.152846) (xy 455.223794 -236.104211)
			(xy 455.25788 -236.060068) (xy 455.298029 -236.021359) (xy 455.343387 -235.988908) (xy 455.392987 -235.963407)
			(xy 455.445771 -235.9454) (xy 455.500614 -235.93527) (xy 455.556348 -235.933233) (xy 455.611785 -235.939333)
			(xy 455.665742 -235.953439) (xy 455.717071 -235.975251) (xy 455.764677 -236.004305) (xy 455.807545 -236.03998)
			(xy 455.844762 -236.081517) (xy 455.875535 -236.12803) (xy 455.899207 -236.178527) (xy 455.915275 -236.231934)
			(xy 455.923395 -236.28711) (xy 455.923904 -236.314996) (xy 455.923395 -236.342882) (xy 455.915275 -236.398058)
			(xy 455.910691 -236.413294) (xy 456.148692 -236.413294) (xy 456.152763 -236.357672) (xy 456.164889 -236.303235)
			(xy 456.184812 -236.251144) (xy 456.212108 -236.202509) (xy 456.246194 -236.158366) (xy 456.286343 -236.119657)
			(xy 456.331701 -236.087206) (xy 456.381301 -236.061705) (xy 456.434085 -236.043698) (xy 456.488928 -236.033568)
			(xy 456.544662 -236.031531) (xy 456.600099 -236.037631) (xy 456.654056 -236.051737) (xy 456.705385 -236.073549)
			(xy 456.752991 -236.102603) (xy 456.795859 -236.138278) (xy 456.833076 -236.179815) (xy 456.863849 -236.226328)
			(xy 456.887521 -236.276825) (xy 456.903589 -236.330232) (xy 456.911709 -236.385408) (xy 456.912218 -236.413294)
			(xy 456.911709 -236.44118) (xy 456.903589 -236.496356) (xy 456.887521 -236.549763) (xy 456.863849 -236.60026)
			(xy 456.833076 -236.646773) (xy 456.795859 -236.68831) (xy 456.752991 -236.723985) (xy 456.705385 -236.753039)
			(xy 456.654056 -236.774851) (xy 456.600099 -236.788957) (xy 456.544662 -236.795057) (xy 456.488928 -236.79302)
			(xy 456.434085 -236.78289) (xy 456.381301 -236.764883) (xy 456.331701 -236.739382) (xy 456.286343 -236.706931)
			(xy 456.246194 -236.668222) (xy 456.212108 -236.624079) (xy 456.184812 -236.575444) (xy 456.164889 -236.523353)
			(xy 456.152763 -236.468916) (xy 456.148692 -236.413294) (xy 455.910691 -236.413294) (xy 455.899207 -236.451465)
			(xy 455.875535 -236.501962) (xy 455.844762 -236.548475) (xy 455.807545 -236.590012) (xy 455.764677 -236.625687)
			(xy 455.717071 -236.654741) (xy 455.665742 -236.676553) (xy 455.611785 -236.690659) (xy 455.556348 -236.696759)
			(xy 455.500614 -236.694722) (xy 455.445771 -236.684592) (xy 455.392987 -236.666585) (xy 455.343387 -236.641084)
			(xy 455.298029 -236.608633) (xy 455.25788 -236.569924) (xy 455.223794 -236.525781) (xy 455.196498 -236.477146)
			(xy 455.176575 -236.425055) (xy 455.164449 -236.370618) (xy 455.160378 -236.314996) (xy 454.922866 -236.314996)
			(xy 454.923397 -236.318606) (xy 454.923906 -236.346492) (xy 454.923397 -236.374378) (xy 454.915277 -236.429554)
			(xy 454.899209 -236.482961) (xy 454.875537 -236.533458) (xy 454.844764 -236.579971) (xy 454.807547 -236.621508)
			(xy 454.764679 -236.657183) (xy 454.717073 -236.686237) (xy 454.665744 -236.708049) (xy 454.611787 -236.722155)
			(xy 454.55635 -236.728255) (xy 454.500616 -236.726218) (xy 454.445773 -236.716088) (xy 454.392989 -236.698081)
			(xy 454.343389 -236.67258) (xy 454.298031 -236.640129) (xy 454.257882 -236.60142) (xy 454.223796 -236.557277)
			(xy 454.1965 -236.508642) (xy 454.176577 -236.456551) (xy 454.164451 -236.402114) (xy 454.16038 -236.346492)
			(xy 450.921397 -236.346492) (xy 450.92338 -236.359485) (xy 450.923914 -236.388402) (xy 450.923428 -236.415653)
			(xy 450.915672 -236.469601) (xy 450.900317 -236.521896) (xy 450.877675 -236.571473) (xy 450.848209 -236.617323)
			(xy 450.812518 -236.658514) (xy 450.771327 -236.694205) (xy 450.725477 -236.723671) (xy 450.6759 -236.746313)
			(xy 450.623605 -236.761668) (xy 450.569657 -236.769424) (xy 450.515155 -236.769424) (xy 450.461207 -236.761668)
			(xy 450.408912 -236.746313) (xy 450.359335 -236.723671) (xy 450.313485 -236.694205) (xy 450.272294 -236.658514)
			(xy 450.236603 -236.617323) (xy 450.207137 -236.571473) (xy 450.184495 -236.521896) (xy 450.16914 -236.469601)
			(xy 450.161384 -236.415653) (xy 450.160898 -236.388402) (xy 448.809618 -236.388402) (xy 449.844668 -237.423452)
			(xy 449.866581 -237.446168) (xy 449.904976 -237.496262) (xy 449.936523 -237.550929) (xy 449.960685 -237.609237)
			(xy 449.977051 -237.670194) (xy 449.985342 -237.732763) (xy 449.985892 -237.76432) (xy 449.985892 -242.84813)
			(xy 451.778624 -242.84813) (xy 451.779037 -242.821814) (xy 451.786282 -242.769683) (xy 451.800611 -242.719039)
			(xy 451.821754 -242.67084) (xy 451.84931 -242.625998) (xy 451.882758 -242.585361) (xy 451.901814 -242.567206)
			(xy 451.909217 -242.559686) (xy 451.91774 -242.540405) (xy 451.918324 -242.529868) (xy 451.918324 -242.455192)
			(xy 451.917806 -242.444641) (xy 451.909262 -242.425346) (xy 451.901814 -242.417854) (xy 451.882746 -242.399711)
			(xy 451.849289 -242.359079) (xy 451.821732 -242.314236) (xy 451.800595 -242.266033) (xy 451.786281 -242.215383)
			(xy 451.77906 -242.163247) (xy 451.778624 -242.13693) (xy 451.779083 -242.109676) (xy 451.786837 -242.055724)
			(xy 451.802191 -242.003424) (xy 451.824832 -241.953842) (xy 451.8543 -241.907987) (xy 451.889994 -241.866793)
			(xy 451.931188 -241.831099) (xy 451.977043 -241.801631) (xy 452.026626 -241.77899) (xy 452.078926 -241.763637)
			(xy 452.132878 -241.755883) (xy 452.160132 -241.755422) (xy 452.186447 -241.755861) (xy 452.238577 -241.763101)
			(xy 452.289221 -241.777425) (xy 452.33742 -241.798563) (xy 452.382262 -241.826114) (xy 452.4229 -241.859558)
			(xy 452.441056 -241.878612) (xy 452.44859 -241.885998) (xy 452.467861 -241.894531) (xy 452.478394 -241.895122)
			(xy 452.55307 -241.895122) (xy 452.563618 -241.894583) (xy 452.582913 -241.886054) (xy 452.590408 -241.878612)
			(xy 452.610228 -241.857824) (xy 452.655 -241.821849) (xy 452.704658 -241.792989) (xy 452.75808 -241.771896)
			(xy 452.814059 -241.759047) (xy 452.871332 -241.754732) (xy 452.928605 -241.759047) (xy 452.984584 -241.771896)
			(xy 453.038006 -241.792989) (xy 453.087664 -241.821849) (xy 453.132436 -241.857824) (xy 453.152256 -241.878612)
			(xy 453.15979 -241.885998) (xy 453.179061 -241.894531) (xy 453.189594 -241.895122) (xy 453.26427 -241.895122)
			(xy 453.274818 -241.894583) (xy 453.294113 -241.886054) (xy 453.301608 -241.878612) (xy 453.319769 -241.859562)
			(xy 453.360397 -241.826104) (xy 453.405236 -241.798544) (xy 453.453436 -241.777404) (xy 453.504083 -241.763086)
			(xy 453.556216 -241.755861) (xy 453.582532 -241.755422) (xy 453.609785 -241.755848) (xy 453.663737 -241.76361)
			(xy 453.716035 -241.77897) (xy 453.765614 -241.801618) (xy 453.811466 -241.83109) (xy 453.852656 -241.866788)
			(xy 453.888347 -241.907984) (xy 453.917812 -241.953841) (xy 453.940451 -242.003424) (xy 453.955803 -242.055724)
			(xy 453.963556 -242.109677) (xy 453.96404 -242.13693) (xy 453.963612 -242.163246) (xy 453.956372 -242.215376)
			(xy 453.942046 -242.266021) (xy 453.920906 -242.31422) (xy 453.893352 -242.359062) (xy 453.859906 -242.399699)
			(xy 453.84085 -242.417854) (xy 453.83343 -242.42536) (xy 453.824915 -242.444652) (xy 453.82434 -242.455192)
			(xy 453.82434 -242.529868) (xy 453.824861 -242.540419) (xy 453.833401 -242.559715) (xy 453.84085 -242.567206)
			(xy 453.859911 -242.585356) (xy 453.893366 -242.625988) (xy 453.920923 -242.67083) (xy 453.94206 -242.719031)
			(xy 453.956377 -242.769679) (xy 453.963601 -242.821814) (xy 453.96404 -242.84813) (xy 453.96355 -242.875381)
			(xy 453.95579 -242.929326) (xy 453.940433 -242.981619) (xy 453.917791 -243.031194) (xy 453.888324 -243.077043)
			(xy 453.852634 -243.118232) (xy 453.811445 -243.153923) (xy 453.765596 -243.18339) (xy 453.716021 -243.206032)
			(xy 453.663728 -243.22139) (xy 453.609783 -243.22915) (xy 453.582532 -243.229638) (xy 453.556216 -243.229236)
			(xy 453.504083 -243.22199) (xy 453.453439 -243.20766) (xy 453.40524 -243.186515) (xy 453.360398 -243.158957)
			(xy 453.319762 -243.125506) (xy 453.301608 -243.106448) (xy 453.294079 -243.099055) (xy 453.274805 -243.090524)
			(xy 453.26427 -243.089938) (xy 453.189594 -243.089938) (xy 453.179041 -243.090439) (xy 453.159745 -243.098993)
			(xy 453.152256 -243.106448) (xy 453.132436 -243.127236) (xy 453.087664 -243.163211) (xy 453.038006 -243.192071)
			(xy 452.984584 -243.213164) (xy 452.928605 -243.226013) (xy 452.871332 -243.230328) (xy 452.814059 -243.226013)
			(xy 452.75808 -243.213164) (xy 452.704658 -243.192071) (xy 452.655 -243.163211) (xy 452.610228 -243.127236)
			(xy 452.590408 -243.106448) (xy 452.582879 -243.099055) (xy 452.563605 -243.090524) (xy 452.55307 -243.089938)
			(xy 452.478394 -243.089938) (xy 452.467841 -243.090439) (xy 452.448545 -243.098993) (xy 452.441056 -243.106448)
			(xy 452.422924 -243.125527) (xy 452.382288 -243.15898) (xy 452.337443 -243.186535) (xy 452.289237 -243.207669)
			(xy 452.238586 -243.221982) (xy 452.186449 -243.229202) (xy 452.160132 -243.229638) (xy 452.132881 -243.229115)
			(xy 452.078934 -243.221363) (xy 452.026639 -243.206013) (xy 451.977061 -243.183376) (xy 451.931209 -243.153914)
			(xy 451.890017 -243.118227) (xy 451.854323 -243.07704) (xy 451.824854 -243.031193) (xy 451.802209 -242.981619)
			(xy 451.78685 -242.929327) (xy 451.779089 -242.875381) (xy 451.778624 -242.84813) (xy 449.985892 -242.84813)
			(xy 449.985892 -244.990874) (xy 449.986306 -245.000945) (xy 449.994032 -245.019544) (xy 450.000878 -245.026942)
			(xy 450.642736 -245.668546) (xy 450.650124 -245.675401) (xy 450.668733 -245.68311) (xy 450.678804 -245.683532)
			(xy 454.498202 -245.683532) (xy 454.529835 -245.683969) (xy 454.59256 -245.692227) (xy 454.653671 -245.708602)
			(xy 454.712121 -245.732813) (xy 454.766912 -245.764447) (xy 454.817104 -245.802961) (xy 454.86184 -245.847697)
			(xy 454.900354 -245.89789) (xy 454.931988 -245.95268) (xy 454.956199 -246.011131) (xy 454.972573 -246.072242)
			(xy 454.980831 -246.134967) (xy 454.980831 -246.198233) (xy 454.972573 -246.260958) (xy 454.956199 -246.322069)
			(xy 454.931988 -246.38052) (xy 454.900354 -246.43531) (xy 454.86184 -246.485503) (xy 454.817104 -246.530239)
			(xy 454.766912 -246.568753) (xy 454.712121 -246.600387) (xy 454.653671 -246.624598) (xy 454.59256 -246.640973)
			(xy 454.529835 -246.649231) (xy 454.498202 -246.649748) (xy 450.45757 -246.649748) (xy 450.425935 -246.649284)
			(xy 450.363207 -246.641032) (xy 450.302093 -246.62466) (xy 450.243639 -246.600448) (xy 450.188848 -246.568812)
			(xy 450.138656 -246.530292) (xy 450.11594 -246.50827) (xy 449.161408 -245.553738) (xy 449.139485 -245.531031)
			(xy 449.101092 -245.480934) (xy 449.069547 -245.426266) (xy 449.045387 -245.367956) (xy 449.029023 -245.306998)
			(xy 449.020733 -245.244428) (xy 449.020184 -245.21287) (xy 449.020184 -237.986316) (xy 449.019754 -237.976247)
			(xy 449.012037 -237.957649) (xy 449.005198 -237.950248) (xy 446.893442 -235.838746) (xy 446.871429 -235.816025)
			(xy 446.832929 -235.765825) (xy 446.801308 -235.711031) (xy 446.777107 -235.65258) (xy 446.760738 -235.59147)
			(xy 446.752482 -235.528748) (xy 446.751964 -235.497116) (xy 446.751964 -233.76382) (xy 446.752456 -233.732186)
			(xy 446.760702 -233.669459) (xy 446.777068 -233.608345) (xy 446.801275 -233.549892) (xy 446.832907 -233.495099)
			(xy 446.871422 -233.444907) (xy 446.893442 -233.42219) (xy 449.005198 -231.310688) (xy 449.012036 -231.303286)
			(xy 449.019757 -231.284688) (xy 449.020184 -231.27462) (xy 449.020184 -218.731084) (xy 449.019771 -218.721013)
			(xy 449.012042 -218.702415) (xy 449.005198 -218.695016) (xy 443.043818 -212.73389) (xy 443.02184 -212.711136)
			(xy 442.983334 -212.660945) (xy 442.951707 -212.606158) (xy 442.927498 -212.547713) (xy 442.911123 -212.486609)
			(xy 442.902861 -212.42389) (xy 442.90234 -212.39226) (xy 422.489884 -212.39226) (xy 422.489884 -223.316546)
			(xy 443.32982 -223.316546) (xy 443.333891 -223.260924) (xy 443.346017 -223.206487) (xy 443.36594 -223.154396)
			(xy 443.393236 -223.105761) (xy 443.427322 -223.061618) (xy 443.467471 -223.022909) (xy 443.512829 -222.990458)
			(xy 443.562429 -222.964957) (xy 443.615213 -222.94695) (xy 443.670056 -222.93682) (xy 443.72579 -222.934783)
			(xy 443.781227 -222.940883) (xy 443.835184 -222.954989) (xy 443.886513 -222.976801) (xy 443.934119 -223.005855)
			(xy 443.976987 -223.04153) (xy 444.014204 -223.083067) (xy 444.044977 -223.12958) (xy 444.068649 -223.180077)
			(xy 444.084717 -223.233484) (xy 444.092837 -223.28866) (xy 444.093346 -223.316546) (xy 444.092837 -223.344432)
			(xy 444.084717 -223.399608) (xy 444.068649 -223.453015) (xy 444.044977 -223.503512) (xy 444.014204 -223.550025)
			(xy 443.976987 -223.591562) (xy 443.934119 -223.627237) (xy 443.886513 -223.656291) (xy 443.835184 -223.678103)
			(xy 443.781227 -223.692209) (xy 443.72579 -223.698309) (xy 443.670056 -223.696272) (xy 443.615213 -223.686142)
			(xy 443.562429 -223.668135) (xy 443.512829 -223.642634) (xy 443.467471 -223.610183) (xy 443.427322 -223.571474)
			(xy 443.393236 -223.527331) (xy 443.36594 -223.478696) (xy 443.346017 -223.426605) (xy 443.333891 -223.372168)
			(xy 443.32982 -223.316546) (xy 422.489884 -223.316546) (xy 422.489884 -224.700846) (xy 443.326518 -224.700846)
			(xy 443.330589 -224.645224) (xy 443.342715 -224.590787) (xy 443.362638 -224.538696) (xy 443.389934 -224.490061)
			(xy 443.42402 -224.445918) (xy 443.464169 -224.407209) (xy 443.509527 -224.374758) (xy 443.559127 -224.349257)
			(xy 443.611911 -224.33125) (xy 443.666754 -224.32112) (xy 443.722488 -224.319083) (xy 443.777925 -224.325183)
			(xy 443.831882 -224.339289) (xy 443.883211 -224.361101) (xy 443.930817 -224.390155) (xy 443.973685 -224.42583)
			(xy 444.010902 -224.467367) (xy 444.041675 -224.51388) (xy 444.065347 -224.564377) (xy 444.081415 -224.617784)
			(xy 444.089535 -224.67296) (xy 444.090044 -224.700846) (xy 444.089535 -224.728732) (xy 444.081415 -224.783908)
			(xy 444.065347 -224.837315) (xy 444.041675 -224.887812) (xy 444.010902 -224.934325) (xy 443.973685 -224.975862)
			(xy 443.930817 -225.011537) (xy 443.883211 -225.040591) (xy 443.831882 -225.062403) (xy 443.777925 -225.076509)
			(xy 443.722488 -225.082609) (xy 443.666754 -225.080572) (xy 443.611911 -225.070442) (xy 443.559127 -225.052435)
			(xy 443.509527 -225.026934) (xy 443.464169 -224.994483) (xy 443.42402 -224.955774) (xy 443.389934 -224.911631)
			(xy 443.362638 -224.862996) (xy 443.342715 -224.810905) (xy 443.330589 -224.756468) (xy 443.326518 -224.700846)
			(xy 422.489884 -224.700846) (xy 422.489884 -228.667848) (xy 442.823618 -228.667848) (xy 442.823618 -228.613352)
			(xy 442.831374 -228.55941) (xy 442.846727 -228.50712) (xy 442.869366 -228.457548) (xy 442.898829 -228.411703)
			(xy 442.934517 -228.370517) (xy 442.975703 -228.334829) (xy 443.021548 -228.305366) (xy 443.07112 -228.282727)
			(xy 443.12341 -228.267374) (xy 443.177352 -228.259618) (xy 443.2046 -228.259132) (xy 443.233517 -228.259638)
			(xy 443.29069 -228.268368) (xy 443.345889 -228.285628) (xy 443.397851 -228.311022) (xy 443.445385 -228.343968)
			(xy 443.487401 -228.383711) (xy 443.50559 -228.406198) (xy 443.513212 -228.41499) (xy 443.534101 -228.425182)
			(xy 443.545722 -228.425756) (xy 443.625478 -228.425756) (xy 443.637109 -228.425205) (xy 443.658019 -228.415026)
			(xy 443.66561 -228.406198) (xy 443.683795 -228.383709) (xy 443.725816 -228.343975) (xy 443.773352 -228.311036)
			(xy 443.825315 -228.285649) (xy 443.880513 -228.268394) (xy 443.937684 -228.259666) (xy 443.9666 -228.259132)
			(xy 443.993854 -228.259538) (xy 444.047807 -228.267295) (xy 444.100108 -228.282652) (xy 444.14969 -228.305295)
			(xy 444.195545 -228.334765) (xy 444.23674 -228.37046) (xy 444.272435 -228.411655) (xy 444.301905 -228.45751)
			(xy 444.324548 -228.507092) (xy 444.339905 -228.559393) (xy 444.347662 -228.613346) (xy 444.347662 -228.667854)
			(xy 444.339905 -228.721807) (xy 444.324548 -228.774108) (xy 444.301905 -228.82369) (xy 444.272435 -228.869545)
			(xy 444.23674 -228.91074) (xy 444.195545 -228.946435) (xy 444.14969 -228.975905) (xy 444.100108 -228.998548)
			(xy 444.047807 -229.013905) (xy 443.993854 -229.021662) (xy 443.9666 -229.022148) (xy 443.937682 -229.021649)
			(xy 443.880509 -229.012919) (xy 443.825309 -228.995658) (xy 443.773347 -228.970263) (xy 443.725814 -228.937315)
			(xy 443.683799 -228.89757) (xy 443.66561 -228.875082) (xy 443.657992 -228.866286) (xy 443.637099 -228.856097)
			(xy 443.625478 -228.855524) (xy 443.545722 -228.855524) (xy 443.534092 -228.856082) (xy 443.513182 -228.866256)
			(xy 443.50559 -228.875082) (xy 443.4874 -228.897567) (xy 443.445381 -228.937302) (xy 443.397846 -228.970242)
			(xy 443.345884 -228.99563) (xy 443.290686 -229.012886) (xy 443.233516 -229.021614) (xy 443.2046 -229.022148)
			(xy 443.177352 -229.021582) (xy 443.12341 -229.013826) (xy 443.07112 -228.998473) (xy 443.021548 -228.975834)
			(xy 442.975703 -228.946371) (xy 442.934517 -228.910683) (xy 442.898829 -228.869497) (xy 442.869366 -228.823652)
			(xy 442.846727 -228.77408) (xy 442.831374 -228.72179) (xy 442.823618 -228.667848) (xy 422.489884 -228.667848)
			(xy 422.489884 -229.12197) (xy 444.350392 -229.12197) (xy 444.354463 -229.066348) (xy 444.366589 -229.011911)
			(xy 444.386512 -228.95982) (xy 444.413808 -228.911185) (xy 444.447894 -228.867042) (xy 444.488043 -228.828333)
			(xy 444.533401 -228.795882) (xy 444.583001 -228.770381) (xy 444.635785 -228.752374) (xy 444.690628 -228.742244)
			(xy 444.746362 -228.740207) (xy 444.801799 -228.746307) (xy 444.855756 -228.760413) (xy 444.907085 -228.782225)
			(xy 444.954691 -228.811279) (xy 444.997559 -228.846954) (xy 445.034776 -228.888491) (xy 445.065549 -228.935004)
			(xy 445.089221 -228.985501) (xy 445.105289 -229.038908) (xy 445.113409 -229.094084) (xy 445.113918 -229.12197)
			(xy 445.113409 -229.149856) (xy 445.105289 -229.205032) (xy 445.089221 -229.258439) (xy 445.065549 -229.308936)
			(xy 445.034776 -229.355449) (xy 444.997559 -229.396986) (xy 444.954691 -229.432661) (xy 444.907085 -229.461715)
			(xy 444.855756 -229.483527) (xy 444.801799 -229.497633) (xy 444.746362 -229.503733) (xy 444.690628 -229.501696)
			(xy 444.635785 -229.491566) (xy 444.583001 -229.473559) (xy 444.533401 -229.448058) (xy 444.488043 -229.415607)
			(xy 444.447894 -229.376898) (xy 444.413808 -229.332755) (xy 444.386512 -229.28412) (xy 444.366589 -229.232029)
			(xy 444.354463 -229.177592) (xy 444.350392 -229.12197) (xy 422.489884 -229.12197) (xy 422.489884 -229.841298)
			(xy 422.490057 -229.847306) (xy 422.49289 -229.858984) (xy 422.495472 -229.864412) (xy 422.49731 -229.867887)
			(xy 422.501901 -229.874268) (xy 422.504616 -229.877112) (xy 425.774104 -233.1466) (xy 442.035182 -233.1466)
			(xy 442.039253 -233.090978) (xy 442.051379 -233.036541) (xy 442.071302 -232.98445) (xy 442.098598 -232.935815)
			(xy 442.132684 -232.891672) (xy 442.172833 -232.852963) (xy 442.218191 -232.820512) (xy 442.267791 -232.795011)
			(xy 442.320575 -232.777004) (xy 442.375418 -232.766874) (xy 442.431152 -232.764837) (xy 442.486589 -232.770937)
			(xy 442.540546 -232.785043) (xy 442.591875 -232.806855) (xy 442.639481 -232.835909) (xy 442.682349 -232.871584)
			(xy 442.719566 -232.913121) (xy 442.750339 -232.959634) (xy 442.774011 -233.010131) (xy 442.790079 -233.063538)
			(xy 442.798199 -233.118714) (xy 442.798708 -233.1466) (xy 442.798199 -233.174486) (xy 442.790079 -233.229662)
			(xy 442.775866 -233.276902) (xy 443.9318 -233.276902) (xy 443.935871 -233.22128) (xy 443.947997 -233.166843)
			(xy 443.96792 -233.114752) (xy 443.995216 -233.066117) (xy 444.029302 -233.021974) (xy 444.069451 -232.983265)
			(xy 444.114809 -232.950814) (xy 444.164409 -232.925313) (xy 444.217193 -232.907306) (xy 444.272036 -232.897176)
			(xy 444.32777 -232.895139) (xy 444.383207 -232.901239) (xy 444.437164 -232.915345) (xy 444.488493 -232.937157)
			(xy 444.536099 -232.966211) (xy 444.578967 -233.001886) (xy 444.616184 -233.043423) (xy 444.646957 -233.089936)
			(xy 444.670629 -233.140433) (xy 444.686697 -233.19384) (xy 444.694817 -233.249016) (xy 444.695326 -233.276902)
			(xy 444.694817 -233.304788) (xy 444.686697 -233.359964) (xy 444.670629 -233.413371) (xy 444.646957 -233.463868)
			(xy 444.616184 -233.510381) (xy 444.578967 -233.551918) (xy 444.536099 -233.587593) (xy 444.488493 -233.616647)
			(xy 444.437164 -233.638459) (xy 444.383207 -233.652565) (xy 444.32777 -233.658665) (xy 444.272036 -233.656628)
			(xy 444.217193 -233.646498) (xy 444.164409 -233.628491) (xy 444.114809 -233.60299) (xy 444.069451 -233.570539)
			(xy 444.029302 -233.53183) (xy 443.995216 -233.487687) (xy 443.96792 -233.439052) (xy 443.947997 -233.386961)
			(xy 443.935871 -233.332524) (xy 443.9318 -233.276902) (xy 442.775866 -233.276902) (xy 442.774011 -233.283069)
			(xy 442.750339 -233.333566) (xy 442.719566 -233.380079) (xy 442.682349 -233.421616) (xy 442.639481 -233.457291)
			(xy 442.591875 -233.486345) (xy 442.540546 -233.508157) (xy 442.486589 -233.522263) (xy 442.431152 -233.528363)
			(xy 442.375418 -233.526326) (xy 442.320575 -233.516196) (xy 442.267791 -233.498189) (xy 442.218191 -233.472688)
			(xy 442.172833 -233.440237) (xy 442.132684 -233.401528) (xy 442.098598 -233.357385) (xy 442.071302 -233.30875)
			(xy 442.051379 -233.256659) (xy 442.039253 -233.202222) (xy 442.035182 -233.1466) (xy 425.774104 -233.1466)
			(xy 429.126904 -236.4994) (xy 444.422782 -236.4994) (xy 444.426853 -236.443778) (xy 444.438979 -236.389341)
			(xy 444.458902 -236.33725) (xy 444.486198 -236.288615) (xy 444.520284 -236.244472) (xy 444.560433 -236.205763)
			(xy 444.605791 -236.173312) (xy 444.655391 -236.147811) (xy 444.708175 -236.129804) (xy 444.763018 -236.119674)
			(xy 444.818752 -236.117637) (xy 444.874189 -236.123737) (xy 444.928146 -236.137843) (xy 444.979475 -236.159655)
			(xy 445.027081 -236.188709) (xy 445.069949 -236.224384) (xy 445.107166 -236.265921) (xy 445.137939 -236.312434)
			(xy 445.161611 -236.362931) (xy 445.177679 -236.416338) (xy 445.185799 -236.471514) (xy 445.186308 -236.4994)
			(xy 445.185799 -236.527286) (xy 445.177679 -236.582462) (xy 445.161611 -236.635869) (xy 445.137939 -236.686366)
			(xy 445.107166 -236.732879) (xy 445.069949 -236.774416) (xy 445.027081 -236.810091) (xy 444.979475 -236.839145)
			(xy 444.928146 -236.860957) (xy 444.874189 -236.875063) (xy 444.818752 -236.881163) (xy 444.763018 -236.879126)
			(xy 444.708175 -236.868996) (xy 444.655391 -236.850989) (xy 444.605791 -236.825488) (xy 444.560433 -236.793037)
			(xy 444.520284 -236.754328) (xy 444.486198 -236.710185) (xy 444.458902 -236.66155) (xy 444.438979 -236.609459)
			(xy 444.426853 -236.555022) (xy 444.422782 -236.4994) (xy 429.126904 -236.4994) (xy 430.142904 -237.5154)
			(xy 443.254382 -237.5154) (xy 443.258453 -237.459778) (xy 443.270579 -237.405341) (xy 443.290502 -237.35325)
			(xy 443.317798 -237.304615) (xy 443.351884 -237.260472) (xy 443.392033 -237.221763) (xy 443.437391 -237.189312)
			(xy 443.486991 -237.163811) (xy 443.539775 -237.145804) (xy 443.594618 -237.135674) (xy 443.650352 -237.133637)
			(xy 443.705789 -237.139737) (xy 443.759746 -237.153843) (xy 443.811075 -237.175655) (xy 443.858681 -237.204709)
			(xy 443.901549 -237.240384) (xy 443.938766 -237.281921) (xy 443.969539 -237.328434) (xy 443.993211 -237.378931)
			(xy 444.009279 -237.432338) (xy 444.017399 -237.487514) (xy 444.017908 -237.5154) (xy 444.017399 -237.543286)
			(xy 444.009279 -237.598462) (xy 443.993211 -237.651869) (xy 443.969539 -237.702366) (xy 443.938766 -237.748879)
			(xy 443.901549 -237.790416) (xy 443.858681 -237.826091) (xy 443.811075 -237.855145) (xy 443.759746 -237.876957)
			(xy 443.705789 -237.891063) (xy 443.650352 -237.897163) (xy 443.594618 -237.895126) (xy 443.539775 -237.884996)
			(xy 443.486991 -237.866989) (xy 443.437391 -237.841488) (xy 443.392033 -237.809037) (xy 443.351884 -237.770328)
			(xy 443.317798 -237.726185) (xy 443.290502 -237.67755) (xy 443.270579 -237.625459) (xy 443.258453 -237.571022)
			(xy 443.254382 -237.5154) (xy 430.142904 -237.5154) (xy 439.386472 -246.758968) (xy 457.037948 -246.758968)
			(xy 457.037948 -243.415312) (xy 457.038367 -243.405242) (xy 457.046091 -243.386643) (xy 457.052934 -243.379244)
			(xy 457.425806 -243.006118) (xy 457.433212 -242.999285) (xy 457.451807 -242.991561) (xy 457.461874 -242.991132)
			(xy 459.66253 -242.991132) (xy 459.672602 -242.991534) (xy 459.6912 -242.99927) (xy 459.698598 -243.006118)
			(xy 460.07147 -243.379244) (xy 460.078318 -243.386638) (xy 460.086034 -243.405242) (xy 460.086456 -243.415312)
			(xy 460.086456 -246.504968) (xy 460.086025 -246.515037) (xy 460.07831 -246.533635) (xy 460.07147 -246.541036)
			(xy 459.571598 -247.041162) (xy 459.564188 -247.04799) (xy 459.545597 -247.055718) (xy 459.53553 -247.056148)
			(xy 457.334874 -247.056148) (xy 457.324801 -247.05575) (xy 457.306203 -247.048012) (xy 457.298806 -247.041162)
			(xy 457.052934 -246.795036) (xy 457.046122 -246.787614) (xy 457.038385 -246.769032) (xy 457.037948 -246.758968)
			(xy 439.386472 -246.758968) (xy 440.345068 -247.717564) (xy 440.347918 -247.720271) (xy 440.354294 -247.724868)
			(xy 440.357768 -247.726708) (xy 440.363196 -247.729288) (xy 440.374875 -247.732106) (xy 440.380882 -247.732296)
			(xy 444.448946 -247.732296) (xy 444.483804 -247.732737) (xy 444.553038 -247.740896) (xy 444.620813 -247.757225)
			(xy 444.65367 -247.768872) (xy 444.662306 -247.772174) (xy 444.696088 -247.772174) (xy 444.70616 -247.772594)
			(xy 444.72477 -247.780303) (xy 444.732156 -247.78716) (xy 444.775336 -247.83034) (xy 444.782448 -247.836182)
			(xy 444.783972 -247.837198) (xy 444.805042 -247.852278) (xy 444.844722 -247.885603) (xy 444.86322 -247.903746)
			(xy 445.820324 -248.86085) (xy 451.577195 -248.86085) (xy 451.577195 -248.80635) (xy 451.584951 -248.752404)
			(xy 451.600306 -248.700112) (xy 451.622946 -248.650537) (xy 451.652411 -248.604688) (xy 451.688101 -248.5635)
			(xy 451.72929 -248.52781) (xy 451.775139 -248.498345) (xy 451.824714 -248.475705) (xy 451.877006 -248.460351)
			(xy 451.930952 -248.452595) (xy 451.958202 -248.452132) (xy 451.985446 -248.45261) (xy 452.03938 -248.460367)
			(xy 452.091659 -248.475724) (xy 452.14122 -248.498367) (xy 452.187053 -248.527835) (xy 452.228223 -248.563527)
			(xy 452.263893 -248.604718) (xy 452.279004 -248.627392) (xy 452.283877 -248.634398) (xy 452.297271 -248.644952)
			(xy 452.313402 -248.650485) (xy 452.32193 -248.65076) (xy 452.407274 -248.65076) (xy 452.415794 -248.650449)
			(xy 452.431903 -248.644892) (xy 452.445314 -248.634379) (xy 452.4502 -248.627392) (xy 452.46533 -248.60473)
			(xy 452.500993 -248.563533) (xy 452.542158 -248.527834) (xy 452.587987 -248.498361) (xy 452.637546 -248.475714)
			(xy 452.689825 -248.460354) (xy 452.743758 -248.452595) (xy 452.771002 -248.452132) (xy 452.796977 -248.45258)
			(xy 452.848448 -248.459623) (xy 452.898485 -248.473591) (xy 452.946161 -248.494226) (xy 452.990592 -248.521146)
			(xy 453.030956 -248.55385) (xy 453.066503 -248.591734) (xy 453.081898 -248.61266) (xy 453.089508 -248.622172)
			(xy 453.111137 -248.633305) (xy 453.1233 -248.633996) (xy 453.206104 -248.633996) (xy 453.218266 -248.633301)
			(xy 453.23989 -248.622167) (xy 453.247506 -248.61266) (xy 453.262889 -248.591726) (xy 453.298445 -248.553849)
			(xy 453.338813 -248.521149) (xy 453.383246 -248.494232) (xy 453.430922 -248.473596) (xy 453.480957 -248.459623)
			(xy 453.532427 -248.452571) (xy 453.558402 -248.452132) (xy 453.585656 -248.452538) (xy 453.639609 -248.460296)
			(xy 453.691909 -248.475652) (xy 453.741491 -248.498296) (xy 453.787346 -248.527766) (xy 453.828541 -248.563461)
			(xy 453.864236 -248.604655) (xy 453.893705 -248.65051) (xy 453.916348 -248.700093) (xy 453.931705 -248.752393)
			(xy 453.939462 -248.806346) (xy 453.939462 -248.860854) (xy 453.931705 -248.914807) (xy 453.916348 -248.967107)
			(xy 453.893705 -249.01669) (xy 453.864236 -249.062545) (xy 453.828541 -249.103739) (xy 453.787346 -249.139434)
			(xy 453.741491 -249.168904) (xy 453.691909 -249.191548) (xy 453.639609 -249.206904) (xy 453.585656 -249.214662)
			(xy 453.558402 -249.215148) (xy 453.532427 -249.214705) (xy 453.480956 -249.207663) (xy 453.430918 -249.193694)
			(xy 453.383242 -249.173058) (xy 453.33881 -249.146138) (xy 453.298447 -249.113432) (xy 453.2629 -249.075547)
			(xy 453.247506 -249.05462) (xy 453.239898 -249.045106) (xy 453.218267 -249.033975) (xy 453.206104 -249.033284)
			(xy 453.1233 -249.033284) (xy 453.111139 -249.03399) (xy 453.089516 -249.045117) (xy 453.081898 -249.05462)
			(xy 453.066507 -249.075548) (xy 453.030953 -249.113426) (xy 452.990587 -249.146127) (xy 452.946155 -249.173045)
			(xy 452.89848 -249.193682) (xy 452.848446 -249.207656) (xy 452.796977 -249.214709) (xy 452.771002 -249.215148)
			(xy 452.743757 -249.214676) (xy 452.689823 -249.206919) (xy 452.637543 -249.191562) (xy 452.587982 -249.168918)
			(xy 452.54215 -249.139449) (xy 452.500979 -249.103755) (xy 452.46531 -249.062563) (xy 452.4502 -249.039888)
			(xy 452.445331 -249.03288) (xy 452.431934 -249.022327) (xy 452.415803 -249.016795) (xy 452.407274 -249.01652)
			(xy 452.32193 -249.01652) (xy 452.313406 -249.016798) (xy 452.297293 -249.022364) (xy 452.283885 -249.032893)
			(xy 452.279004 -249.039888) (xy 452.263898 -249.062566) (xy 452.228228 -249.103759) (xy 452.187058 -249.139454)
			(xy 452.141225 -249.168924) (xy 452.091663 -249.191569) (xy 452.039382 -249.206926) (xy 451.985447 -249.214684)
			(xy 451.958202 -249.215148) (xy 451.930952 -249.214605) (xy 451.877006 -249.206849) (xy 451.824714 -249.191495)
			(xy 451.775139 -249.168855) (xy 451.72929 -249.13939) (xy 451.688101 -249.1037) (xy 451.652411 -249.062512)
			(xy 451.622946 -249.016663) (xy 451.600306 -248.967088) (xy 451.584951 -248.914796) (xy 451.577195 -248.86085)
			(xy 445.820324 -248.86085) (xy 446.786254 -249.82678) (xy 446.80915 -249.850345) (xy 446.850101 -249.901729)
			(xy 446.885045 -249.957372) (xy 446.913545 -250.016576) (xy 446.935241 -250.078596) (xy 446.949863 -250.142655)
			(xy 446.95692 -250.20524) (xy 453.481184 -250.20524) (xy 453.485255 -250.149618) (xy 453.497381 -250.095181)
			(xy 453.517304 -250.04309) (xy 453.5446 -249.994455) (xy 453.578686 -249.950312) (xy 453.618835 -249.911603)
			(xy 453.664193 -249.879152) (xy 453.713793 -249.853651) (xy 453.766577 -249.835644) (xy 453.82142 -249.825514)
			(xy 453.877154 -249.823477) (xy 453.932591 -249.829577) (xy 453.986548 -249.843683) (xy 454.037877 -249.865495)
			(xy 454.085483 -249.894549) (xy 454.128351 -249.930224) (xy 454.165568 -249.971761) (xy 454.196341 -250.018274)
			(xy 454.220013 -250.068771) (xy 454.236081 -250.122178) (xy 454.239782 -250.147328) (xy 458.853538 -250.147328)
			(xy 458.857609 -250.091706) (xy 458.869735 -250.037269) (xy 458.889658 -249.985178) (xy 458.916954 -249.936543)
			(xy 458.95104 -249.8924) (xy 458.991189 -249.853691) (xy 459.036547 -249.82124) (xy 459.086147 -249.795739)
			(xy 459.138931 -249.777732) (xy 459.193774 -249.767602) (xy 459.249508 -249.765565) (xy 459.304945 -249.771665)
			(xy 459.358902 -249.785771) (xy 459.410231 -249.807583) (xy 459.457837 -249.836637) (xy 459.500705 -249.872312)
			(xy 459.537922 -249.913849) (xy 459.568695 -249.960362) (xy 459.592367 -250.010859) (xy 459.608435 -250.064266)
			(xy 459.616555 -250.119442) (xy 459.617064 -250.147328) (xy 459.616555 -250.175214) (xy 459.608435 -250.23039)
			(xy 459.592367 -250.283797) (xy 459.568695 -250.334294) (xy 459.537922 -250.380807) (xy 459.500705 -250.422344)
			(xy 459.457837 -250.458019) (xy 459.410231 -250.487073) (xy 459.358902 -250.508885) (xy 459.304945 -250.522991)
			(xy 459.249508 -250.529091) (xy 459.193774 -250.527054) (xy 459.138931 -250.516924) (xy 459.086147 -250.498917)
			(xy 459.036547 -250.473416) (xy 458.991189 -250.440965) (xy 458.95104 -250.402256) (xy 458.916954 -250.358113)
			(xy 458.889658 -250.309478) (xy 458.869735 -250.257387) (xy 458.857609 -250.20295) (xy 458.853538 -250.147328)
			(xy 454.239782 -250.147328) (xy 454.244201 -250.177354) (xy 454.24471 -250.20524) (xy 454.244201 -250.233126)
			(xy 454.236081 -250.288302) (xy 454.220013 -250.341709) (xy 454.196341 -250.392206) (xy 454.165568 -250.438719)
			(xy 454.128351 -250.480256) (xy 454.085483 -250.515931) (xy 454.037877 -250.544985) (xy 453.986548 -250.566797)
			(xy 453.932591 -250.580903) (xy 453.877154 -250.587003) (xy 453.82142 -250.584966) (xy 453.766577 -250.574836)
			(xy 453.713793 -250.556829) (xy 453.664193 -250.531328) (xy 453.618835 -250.498877) (xy 453.578686 -250.460168)
			(xy 453.5446 -250.416025) (xy 453.517304 -250.36739) (xy 453.497381 -250.315299) (xy 453.485255 -250.260862)
			(xy 453.481184 -250.20524) (xy 446.95692 -250.20524) (xy 446.957225 -250.207947) (xy 446.957704 -250.2408)
			(xy 446.957704 -251.637546) (xy 446.964054 -251.644658) (xy 446.992502 -251.670566) (xy 447.013584 -251.690124)
			(xy 447.015108 -251.69114) (xy 447.022982 -251.697998) (xy 447.026413 -251.700565) (xy 447.033948 -251.704643)
			(xy 447.037968 -251.706126) (xy 447.047112 -251.709174) (xy 447.05778 -251.708412) (xy 447.085466 -251.707142)
			(xy 447.100198 -251.707142) (xy 447.110197 -251.707447) (xy 447.130146 -251.708972) (xy 447.140076 -251.71019)
			(xy 447.153792 -251.712222) (xy 447.159126 -251.713238) (xy 447.160904 -251.713492) (xy 447.161158 -251.713492)
			(xy 447.164206 -251.714) (xy 447.169794 -251.71527) (xy 447.17081 -251.715524) (xy 447.171064 -251.715524)
			(xy 447.171572 -251.715778) (xy 447.172334 -251.715778) (xy 447.17335 -251.716032) (xy 447.175128 -251.716286)
			(xy 447.186558 -251.717556) (xy 447.195618 -251.717094) (xy 447.212533 -251.710574) (xy 447.219578 -251.704856)
			(xy 447.234564 -251.690378) (xy 447.282824 -251.643388) (xy 447.286842 -251.639101) (xy 447.292995 -251.629094)
			(xy 447.295016 -251.623576) (xy 447.297048 -251.617734) (xy 447.29781 -251.605034) (xy 447.29654 -251.59843)
			(xy 447.29344 -251.580814) (xy 447.290136 -251.545196) (xy 447.289936 -251.52731) (xy 447.289936 -251.524008)
			(xy 447.290558 -251.496851) (xy 447.298544 -251.443121) (xy 447.314071 -251.391068) (xy 447.336826 -251.341743)
			(xy 447.366347 -251.296145) (xy 447.402038 -251.255196) (xy 447.443177 -251.219724) (xy 447.488932 -251.190447)
			(xy 447.538377 -251.167956) (xy 447.590512 -251.152707) (xy 447.644284 -251.145008) (xy 447.671444 -251.144532)
			(xy 447.69869 -251.145021) (xy 447.752628 -251.152782) (xy 447.804911 -251.168139) (xy 447.854478 -251.190781)
			(xy 447.900318 -251.220245) (xy 447.941499 -251.255933) (xy 447.977182 -251.297117) (xy 448.006641 -251.342961)
			(xy 448.029276 -251.39253) (xy 448.044627 -251.444815) (xy 448.052382 -251.498754) (xy 448.052382 -251.553246)
			(xy 448.044627 -251.607185) (xy 448.029276 -251.65947) (xy 448.025137 -251.668534) (xy 450.165722 -251.668534)
			(xy 450.169793 -251.612912) (xy 450.181919 -251.558475) (xy 450.201842 -251.506384) (xy 450.229138 -251.457749)
			(xy 450.263224 -251.413606) (xy 450.303373 -251.374897) (xy 450.348731 -251.342446) (xy 450.398331 -251.316945)
			(xy 450.451115 -251.298938) (xy 450.505958 -251.288808) (xy 450.561692 -251.286771) (xy 450.617129 -251.292871)
			(xy 450.671086 -251.306977) (xy 450.722415 -251.328789) (xy 450.770021 -251.357843) (xy 450.789003 -251.37364)
			(xy 457.418184 -251.37364) (xy 457.422255 -251.318018) (xy 457.434381 -251.263581) (xy 457.454304 -251.21149)
			(xy 457.4816 -251.162855) (xy 457.515686 -251.118712) (xy 457.555835 -251.080003) (xy 457.601193 -251.047552)
			(xy 457.650793 -251.022051) (xy 457.703577 -251.004044) (xy 457.75842 -250.993914) (xy 457.814154 -250.991877)
			(xy 457.869591 -250.997977) (xy 457.923548 -251.012083) (xy 457.974877 -251.033895) (xy 458.022483 -251.062949)
			(xy 458.065351 -251.098624) (xy 458.102568 -251.140161) (xy 458.133341 -251.186674) (xy 458.157013 -251.237171)
			(xy 458.173081 -251.290578) (xy 458.181201 -251.345754) (xy 458.18171 -251.37364) (xy 458.181201 -251.401526)
			(xy 458.173081 -251.456702) (xy 458.157013 -251.510109) (xy 458.133341 -251.560606) (xy 458.102568 -251.607119)
			(xy 458.065351 -251.648656) (xy 458.022483 -251.684331) (xy 457.974877 -251.713385) (xy 457.923548 -251.735197)
			(xy 457.869591 -251.749303) (xy 457.814154 -251.755403) (xy 457.75842 -251.753366) (xy 457.703577 -251.743236)
			(xy 457.650793 -251.725229) (xy 457.601193 -251.699728) (xy 457.555835 -251.667277) (xy 457.515686 -251.628568)
			(xy 457.4816 -251.584425) (xy 457.454304 -251.53579) (xy 457.434381 -251.483699) (xy 457.422255 -251.429262)
			(xy 457.418184 -251.37364) (xy 450.789003 -251.37364) (xy 450.812889 -251.393518) (xy 450.850106 -251.435055)
			(xy 450.880879 -251.481568) (xy 450.904551 -251.532065) (xy 450.920619 -251.585472) (xy 450.928739 -251.640648)
			(xy 450.929248 -251.668534) (xy 450.928739 -251.69642) (xy 450.920619 -251.751596) (xy 450.904551 -251.805003)
			(xy 450.880879 -251.8555) (xy 450.850106 -251.902013) (xy 450.812889 -251.94355) (xy 450.770021 -251.979225)
			(xy 450.722415 -252.008279) (xy 450.671086 -252.030091) (xy 450.617129 -252.044197) (xy 450.561692 -252.050297)
			(xy 450.505958 -252.04826) (xy 450.451115 -252.03813) (xy 450.398331 -252.020123) (xy 450.348731 -251.994622)
			(xy 450.303373 -251.962171) (xy 450.263224 -251.923462) (xy 450.229138 -251.879319) (xy 450.201842 -251.830684)
			(xy 450.181919 -251.778593) (xy 450.169793 -251.724156) (xy 450.165722 -251.668534) (xy 448.025137 -251.668534)
			(xy 448.006641 -251.709039) (xy 447.977182 -251.754883) (xy 447.941499 -251.796067) (xy 447.900318 -251.831755)
			(xy 447.854478 -251.861219) (xy 447.804911 -251.883861) (xy 447.752628 -251.899218) (xy 447.69869 -251.906979)
			(xy 447.671444 -251.907548) (xy 447.67119 -251.907548) (xy 447.650577 -251.907283) (xy 447.609591 -251.902828)
			(xy 447.589402 -251.898658) (xy 447.580766 -251.89688) (xy 447.572638 -251.897896) (xy 447.562986 -251.898912)
			(xy 447.55054 -251.905516) (xy 447.543174 -251.909072) (xy 447.523616 -251.928376) (xy 447.523108 -251.928884)
			(xy 447.480182 -251.97054) (xy 447.47942 -251.971302) (xy 447.475262 -251.975737) (xy 447.468965 -251.986132)
			(xy 447.466974 -251.991876) (xy 447.463418 -252.003052) (xy 447.464942 -252.011688) (xy 447.465958 -252.016768)
			(xy 447.46672 -252.021594) (xy 447.46672 -252.021848) (xy 447.466974 -252.024134) (xy 447.467228 -252.024896)
			(xy 447.467228 -252.02515) (xy 447.467482 -252.025912) (xy 447.467482 -252.026166) (xy 447.468752 -252.033278)
			(xy 447.470551 -252.046731) (xy 447.472455 -252.073808) (xy 447.472562 -252.08738) (xy 447.472562 -252.087888)
			(xy 447.472562 -252.089412) (xy 447.472562 -252.090936) (xy 447.472472 -252.102971) (xy 447.47095 -252.126993)
			(xy 447.469514 -252.138942) (xy 447.469514 -252.13945) (xy 447.467736 -252.150626) (xy 447.467482 -252.15342)
			(xy 447.465196 -252.166882) (xy 447.462656 -252.177296) (xy 447.460189 -252.187205) (xy 447.454343 -252.206773)
			(xy 447.450972 -252.216412) (xy 447.450464 -252.217174) (xy 447.440304 -252.2474) (xy 447.440558 -252.247654)
			(xy 447.436494 -252.254512) (xy 447.421508 -252.279912) (xy 447.421254 -252.280166) (xy 447.41973 -252.282706)
			(xy 447.41846 -252.284992) (xy 447.403359 -252.309103) (xy 447.367139 -252.352974) (xy 447.346324 -252.372368)
			(xy 447.338928 -252.378938) (xy 447.323553 -252.39139) (xy 447.31559 -252.39726) (xy 447.302382 -252.406912)
			(xy 447.295524 -252.410976) (xy 447.27114 -252.4252) (xy 447.261488 -252.43028) (xy 447.248534 -252.44679)
			(xy 447.245486 -252.458728) (xy 447.227198 -252.532642) (xy 447.226182 -252.54077) (xy 447.238374 -252.55855)
			(xy 447.257241 -252.586838) (xy 447.289032 -252.646947) (xy 447.313644 -252.710335) (xy 447.330743 -252.776148)
			(xy 447.33591 -252.809756) (xy 447.33972 -252.837696) (xy 447.347141 -252.844823) (xy 447.366019 -252.852958)
			(xy 447.376296 -252.853444) (xy 450.233796 -252.853444) (xy 450.243194 -252.852428) (xy 450.243702 -252.852428)
			(xy 450.250861 -252.850722) (xy 450.263886 -252.843889) (xy 450.269356 -252.838966) (xy 450.270372 -252.83795)
			(xy 450.322696 -252.783848) (xy 450.328475 -252.776692) (xy 450.334996 -252.759508) (xy 450.335396 -252.75032)
			(xy 450.335396 -252.742446) (xy 450.335882 -252.715195) (xy 450.343638 -252.661247) (xy 450.358993 -252.608952)
			(xy 450.381635 -252.559375) (xy 450.411101 -252.513525) (xy 450.446792 -252.472334) (xy 450.487983 -252.436643)
			(xy 450.533833 -252.407177) (xy 450.58341 -252.384535) (xy 450.635705 -252.36918) (xy 450.689653 -252.361424)
			(xy 450.744155 -252.361424) (xy 450.798103 -252.36918) (xy 450.850398 -252.384535) (xy 450.899975 -252.407177)
			(xy 450.945825 -252.436643) (xy 450.987016 -252.472334) (xy 451.022707 -252.513525) (xy 451.052173 -252.559375)
			(xy 451.074815 -252.608952) (xy 451.09017 -252.661247) (xy 451.097926 -252.715195) (xy 451.098412 -252.742446)
			(xy 451.098412 -252.750574) (xy 451.098808 -252.759763) (xy 451.105335 -252.776943) (xy 451.111112 -252.784102)
			(xy 451.122542 -252.795786) (xy 451.12305 -252.796294) (xy 451.163436 -252.83795) (xy 451.165468 -252.839728)
			(xy 451.165468 -252.839982) (xy 451.170626 -252.844453) (xy 451.182725 -252.850761) (xy 451.189344 -252.852428)
			(xy 451.198996 -252.853444) (xy 451.42023 -252.853444) (xy 451.427873 -252.853181) (xy 451.442471 -252.848647)
			(xy 451.448932 -252.844554) (xy 451.45198 -252.842522) (xy 451.500748 -252.796548) (xy 451.507606 -252.78715)
			(xy 451.521322 -252.758194) (xy 451.522084 -252.74905) (xy 451.525038 -252.72085) (xy 451.538215 -252.665704)
			(xy 451.559403 -252.613113) (xy 451.588134 -252.564233) (xy 451.623778 -252.52014) (xy 451.66555 -252.481801)
			(xy 451.712532 -252.450062) (xy 451.763691 -252.425618) (xy 451.817902 -252.409009) (xy 451.873973 -252.400598)
			(xy 451.902322 -252.400054) (xy 451.931116 -252.400581) (xy 451.988049 -252.409241) (xy 452.043034 -252.426361)
			(xy 452.09482 -252.451552) (xy 452.142231 -252.484241) (xy 452.184189 -252.523686) (xy 452.219741 -252.568989)
			(xy 452.248079 -252.619123) (xy 452.268559 -252.672946) (xy 452.280715 -252.729236) (xy 452.283068 -252.75794)
			(xy 452.283322 -252.760988) (xy 452.28383 -252.768354) (xy 452.28764 -252.776482) (xy 452.289788 -252.780727)
			(xy 452.295413 -252.788398) (xy 452.298816 -252.791722) (xy 452.3232 -252.814836) (xy 452.350886 -252.840744)
			(xy 452.354696 -252.843792) (xy 452.359522 -252.847094) (xy 452.365016 -252.849941) (xy 452.376963 -252.853154)
			(xy 452.383144 -252.853444) (xy 452.715122 -252.853444) (xy 452.725189 -252.853872) (xy 452.743784 -252.861597)
			(xy 452.75119 -252.86843) (xy 453.583294 -253.700534) (xy 453.588973 -253.705727) (xy 453.602679 -253.712708)
			(xy 453.610218 -253.71425) (xy 453.610726 -253.71425) (xy 453.618854 -253.715012) (xy 458.746098 -253.715012)
			(xy 458.754226 -253.71425) (xy 458.754734 -253.71425) (xy 458.762254 -253.712651) (xy 458.775946 -253.705679)
			(xy 458.781658 -253.700534) (xy 461.807306 -250.674886) (xy 461.8125 -250.669207) (xy 461.819479 -250.655501)
			(xy 461.821022 -250.647962) (xy 461.821022 -250.647454) (xy 461.821784 -250.639326) (xy 461.821784 -239.411256)
			(xy 461.821459 -239.402977) (xy 461.816136 -239.3873) (xy 461.81137 -239.380522) (xy 461.809338 -239.378236)
			(xy 461.80756 -239.376458) (xy 461.804258 -239.372648) (xy 461.447388 -239.015778) (xy 461.440535 -239.008383)
			(xy 461.432795 -238.989783) (xy 461.432402 -238.97971) (xy 461.432402 -113.930684) (xy 461.432242 -113.924817)
			(xy 461.429557 -113.913393) (xy 461.427068 -113.908078) (xy 461.42402 -113.902236) (xy 461.414622 -113.883694)
			(xy 461.411066 -113.879376) (xy 461.406748 -113.874042) (xy 461.401414 -113.869978) (xy 461.38082 -113.854102)
			(xy 461.343707 -113.817679) (xy 461.311883 -113.776554) (xy 461.285938 -113.73149) (xy 461.26635 -113.683321)
			(xy 461.253484 -113.632938) (xy 461.247577 -113.581275) (xy 461.247744 -113.555272) (xy 461.248881 -113.526502)
			(xy 461.25874 -113.469777) (xy 461.277008 -113.415177) (xy 461.30327 -113.36394) (xy 461.33693 -113.317229)
			(xy 461.377226 -113.276105) (xy 461.39989 -113.258346) (xy 461.402684 -113.256314) (xy 461.408272 -113.250726)
			(xy 461.410979 -113.247876) (xy 461.415574 -113.241498) (xy 461.417416 -113.238026) (xy 461.42402 -113.225326)
			(xy 461.42402 -113.224818) (xy 461.42656 -113.220246) (xy 461.428937 -113.215474) (xy 461.431883 -113.205231)
			(xy 461.432402 -113.199926) (xy 461.432402 -108.1151) (xy 461.43217 -108.108728) (xy 461.428955 -108.096393)
			(xy 461.426052 -108.090716) (xy 461.420464 -108.081572) (xy 461.402648 -108.057441) (xy 461.37397 -108.004762)
			(xy 461.353886 -107.948246) (xy 461.342889 -107.889284) (xy 461.34147 -107.859322) (xy 461.341149 -107.833254)
			(xy 461.346776 -107.781424) (xy 461.359419 -107.730846) (xy 461.378842 -107.682466) (xy 461.404682 -107.637186)
			(xy 461.42021 -107.616244) (xy 461.421988 -107.613958) (xy 461.425544 -107.608116) (xy 461.425544 -107.607862)
			(xy 461.428688 -107.601985) (xy 461.432163 -107.589123) (xy 461.432402 -107.582462) (xy 461.432402 -85.967062)
			(xy 461.432832 -85.956995) (xy 461.440557 -85.938401) (xy 461.447388 -85.930994) (xy 463.37982 -83.998562)
			(xy 463.38501 -83.992882) (xy 463.391981 -83.979174) (xy 463.393536 -83.971638) (xy 463.393536 -83.97113)
			(xy 463.394298 -83.963002) (xy 463.394298 -82.869278) (xy 463.394725 -82.85921) (xy 463.402445 -82.840611)
			(xy 463.409284 -82.83321) (xy 465.796122 -80.446372) (xy 465.801313 -80.440692) (xy 465.808286 -80.426985)
			(xy 465.809838 -80.419448) (xy 465.809838 -80.41894) (xy 465.8106 -80.410812) (xy 465.8106 -0.986282)
			(xy 465.810173 -0.976213) (xy 465.802454 -0.957614) (xy 465.795614 -0.950214) (xy 465.546186 -0.700786)
			(xy 465.538791 -0.693932) (xy 465.520192 -0.68619) (xy 465.510118 -0.6858) (xy 446.019682 -0.6858)
			(xy 446.009613 -0.686227) (xy 445.991014 -0.693946) (xy 445.983614 -0.700786) (xy 445.569594 -1.114806)
			(xy 445.562749 -1.122205) (xy 445.555018 -1.140803) (xy 445.554608 -1.150874) (xy 445.554608 -1.200404)
			(xy 445.554727 -1.205358) (xy 445.556647 -1.215079) (xy 445.558418 -1.219708) (xy 445.569238 -1.247507)
			(xy 445.583084 -1.305528) (xy 445.587738 -1.364996) (xy 445.583085 -1.424465) (xy 445.56924 -1.482486)
			(xy 445.558418 -1.510284) (xy 445.556644 -1.514912) (xy 445.554722 -1.524633) (xy 445.554608 -1.529588)
			(xy 445.554608 -12.863322) (xy 445.556894 -12.874752) (xy 445.558164 -12.882372) (xy 445.569594 -12.903962)
			(xy 445.569594 -12.910566) (xy 445.568753 -12.919971) (xy 445.561063 -12.937203) (xy 445.554608 -12.944094)
			(xy 445.137032 -13.36167) (xy 445.13131 -13.368027) (xy 445.124094 -13.383524) (xy 445.122378 -13.400532)
			(xy 445.124078 -13.408914) (xy 445.134238 -13.43914) (xy 445.134238 -13.439648) (xy 445.155828 -13.502386)
			(xy 445.159892 -13.51026) (xy 445.160654 -13.511022) (xy 445.160654 -13.511276) (xy 445.176402 -13.521182)
			(xy 445.17691 -13.52169) (xy 445.183768 -13.526008) (xy 445.187324 -13.52804) (xy 445.191167 -13.53033)
			(xy 445.199471 -13.533656) (xy 445.203834 -13.534644) (xy 445.20739 -13.535152) (xy 445.207644 -13.535152)
			(xy 445.273579 -13.544643) (xy 445.404209 -13.570808) (xy 445.532953 -13.605069) (xy 445.65931 -13.647293)
			(xy 445.782786 -13.697316) (xy 445.902903 -13.754944) (xy 446.019191 -13.81995) (xy 446.131199 -13.892083)
			(xy 446.238489 -13.971062) (xy 446.340645 -14.056579) (xy 446.386704 -14.100302) (xy 451.54291 -14.100302)
			(xy 451.546981 -14.04468) (xy 451.559107 -13.990243) (xy 451.57903 -13.938152) (xy 451.606326 -13.889517)
			(xy 451.640412 -13.845374) (xy 451.680561 -13.806665) (xy 451.725919 -13.774214) (xy 451.775519 -13.748713)
			(xy 451.828303 -13.730706) (xy 451.883146 -13.720576) (xy 451.93888 -13.718539) (xy 451.994317 -13.724639)
			(xy 452.048274 -13.738745) (xy 452.099603 -13.760557) (xy 452.147209 -13.789611) (xy 452.190077 -13.825286)
			(xy 452.227294 -13.866823) (xy 452.258067 -13.913336) (xy 452.281739 -13.963833) (xy 452.297807 -14.01724)
			(xy 452.305927 -14.072416) (xy 452.306436 -14.100302) (xy 452.305927 -14.128188) (xy 452.297807 -14.183364)
			(xy 452.281739 -14.236771) (xy 452.258067 -14.287268) (xy 452.227294 -14.333781) (xy 452.190077 -14.375318)
			(xy 452.147209 -14.410993) (xy 452.099603 -14.440047) (xy 452.048274 -14.461859) (xy 451.994317 -14.475965)
			(xy 451.93888 -14.482065) (xy 451.883146 -14.480028) (xy 451.828303 -14.469898) (xy 451.775519 -14.451891)
			(xy 451.725919 -14.42639) (xy 451.680561 -14.393939) (xy 451.640412 -14.35523) (xy 451.606326 -14.311087)
			(xy 451.57903 -14.262452) (xy 451.559107 -14.210361) (xy 451.546981 -14.155924) (xy 451.54291 -14.100302)
			(xy 446.386704 -14.100302) (xy 446.437267 -14.148301) (xy 446.527981 -14.24587) (xy 446.612433 -14.348908)
			(xy 446.690294 -14.457012) (xy 446.761261 -14.569762) (xy 446.825057 -14.686719) (xy 446.881435 -14.807427)
			(xy 446.930174 -14.931416) (xy 446.971085 -15.058204) (xy 447.004008 -15.187297) (xy 447.028815 -15.318192)
			(xy 447.035357 -15.370302) (xy 452.20331 -15.370302) (xy 452.207381 -15.31468) (xy 452.219507 -15.260243)
			(xy 452.23943 -15.208152) (xy 452.266726 -15.159517) (xy 452.300812 -15.115374) (xy 452.340961 -15.076665)
			(xy 452.386319 -15.044214) (xy 452.435919 -15.018713) (xy 452.488703 -15.000706) (xy 452.543546 -14.990576)
			(xy 452.59928 -14.988539) (xy 452.654717 -14.994639) (xy 452.708674 -15.008745) (xy 452.760003 -15.030557)
			(xy 452.807609 -15.059611) (xy 452.850477 -15.095286) (xy 452.887694 -15.136823) (xy 452.918467 -15.183336)
			(xy 452.942139 -15.233833) (xy 452.958207 -15.28724) (xy 452.966327 -15.342416) (xy 452.966836 -15.370302)
			(xy 452.966327 -15.398188) (xy 452.964936 -15.40764) (xy 453.070466 -15.40764) (xy 453.074537 -15.352018)
			(xy 453.086663 -15.297581) (xy 453.106586 -15.24549) (xy 453.133882 -15.196855) (xy 453.167968 -15.152712)
			(xy 453.208117 -15.114003) (xy 453.253475 -15.081552) (xy 453.303075 -15.056051) (xy 453.355859 -15.038044)
			(xy 453.410702 -15.027914) (xy 453.466436 -15.025877) (xy 453.521873 -15.031977) (xy 453.57583 -15.046083)
			(xy 453.627159 -15.067895) (xy 453.674765 -15.096949) (xy 453.717633 -15.132624) (xy 453.75485 -15.174161)
			(xy 453.772026 -15.200122) (xy 459.541372 -15.200122) (xy 459.541372 -13.599922) (xy 459.54188 -13.535242)
			(xy 459.550003 -13.406136) (xy 459.566216 -13.277796) (xy 459.590456 -13.150726) (xy 459.622626 -13.02543)
			(xy 459.662601 -12.9024) (xy 459.710222 -12.782124) (xy 459.765301 -12.665075) (xy 459.827621 -12.551715)
			(xy 459.896936 -12.442492) (xy 459.972972 -12.337837) (xy 460.05543 -12.238163) (xy 460.143983 -12.143863)
			(xy 460.238283 -12.05531) (xy 460.337957 -11.972852) (xy 460.442612 -11.896816) (xy 460.551835 -11.827501)
			(xy 460.665195 -11.765181) (xy 460.782244 -11.710102) (xy 460.90252 -11.662481) (xy 461.02555 -11.622506)
			(xy 461.150846 -11.590336) (xy 461.277916 -11.566096) (xy 461.406256 -11.549883) (xy 461.535362 -11.54176)
			(xy 461.664722 -11.54176) (xy 461.793828 -11.549883) (xy 461.922168 -11.566096) (xy 462.049238 -11.590336)
			(xy 462.174534 -11.622506) (xy 462.297564 -11.662481) (xy 462.41784 -11.710102) (xy 462.534889 -11.765181)
			(xy 462.648249 -11.827501) (xy 462.757472 -11.896816) (xy 462.862127 -11.972852) (xy 462.961801 -12.05531)
			(xy 463.056101 -12.143863) (xy 463.144654 -12.238163) (xy 463.227112 -12.337837) (xy 463.303148 -12.442492)
			(xy 463.372463 -12.551715) (xy 463.434783 -12.665075) (xy 463.489862 -12.782124) (xy 463.537483 -12.9024)
			(xy 463.577458 -13.02543) (xy 463.609628 -13.150726) (xy 463.633868 -13.277796) (xy 463.650081 -13.406136)
			(xy 463.658204 -13.535242) (xy 463.658712 -13.599922) (xy 463.658712 -15.200122) (xy 463.658204 -15.264802)
			(xy 463.650081 -15.393908) (xy 463.633868 -15.522248) (xy 463.609628 -15.649318) (xy 463.577458 -15.774614)
			(xy 463.537483 -15.897644) (xy 463.489862 -16.01792) (xy 463.434783 -16.134969) (xy 463.372463 -16.248329)
			(xy 463.303148 -16.357552) (xy 463.227112 -16.462207) (xy 463.144654 -16.561881) (xy 463.056101 -16.656181)
			(xy 462.961801 -16.744734) (xy 462.862127 -16.827192) (xy 462.757472 -16.903228) (xy 462.648249 -16.972543)
			(xy 462.534889 -17.034863) (xy 462.41784 -17.089942) (xy 462.297564 -17.137563) (xy 462.174534 -17.177538)
			(xy 462.049238 -17.209708) (xy 461.922168 -17.233948) (xy 461.793828 -17.250161) (xy 461.664722 -17.258284)
			(xy 461.535362 -17.258284) (xy 461.406256 -17.250161) (xy 461.277916 -17.233948) (xy 461.150846 -17.209708)
			(xy 461.02555 -17.177538) (xy 460.90252 -17.137563) (xy 460.782244 -17.089942) (xy 460.665195 -17.034863)
			(xy 460.551835 -16.972543) (xy 460.442612 -16.903228) (xy 460.337957 -16.827192) (xy 460.238283 -16.744734)
			(xy 460.143983 -16.656181) (xy 460.05543 -16.561881) (xy 459.972972 -16.462207) (xy 459.896936 -16.357552)
			(xy 459.827621 -16.248329) (xy 459.765301 -16.134969) (xy 459.710222 -16.01792) (xy 459.662601 -15.897644)
			(xy 459.622626 -15.774614) (xy 459.590456 -15.649318) (xy 459.566216 -15.522248) (xy 459.550003 -15.393908)
			(xy 459.54188 -15.264802) (xy 459.541372 -15.200122) (xy 453.772026 -15.200122) (xy 453.785623 -15.220674)
			(xy 453.809295 -15.271171) (xy 453.825363 -15.324578) (xy 453.833483 -15.379754) (xy 453.833992 -15.40764)
			(xy 453.833483 -15.435526) (xy 453.825363 -15.490702) (xy 453.809295 -15.544109) (xy 453.785623 -15.594606)
			(xy 453.75485 -15.641119) (xy 453.717633 -15.682656) (xy 453.674765 -15.718331) (xy 453.627159 -15.747385)
			(xy 453.57583 -15.769197) (xy 453.521873 -15.783303) (xy 453.466436 -15.789403) (xy 453.410702 -15.787366)
			(xy 453.355859 -15.777236) (xy 453.303075 -15.759229) (xy 453.253475 -15.733728) (xy 453.208117 -15.701277)
			(xy 453.167968 -15.662568) (xy 453.133882 -15.618425) (xy 453.106586 -15.56979) (xy 453.086663 -15.517699)
			(xy 453.074537 -15.463262) (xy 453.070466 -15.40764) (xy 452.964936 -15.40764) (xy 452.958207 -15.453364)
			(xy 452.942139 -15.506771) (xy 452.918467 -15.557268) (xy 452.887694 -15.603781) (xy 452.850477 -15.645318)
			(xy 452.807609 -15.680993) (xy 452.760003 -15.710047) (xy 452.708674 -15.731859) (xy 452.654717 -15.745965)
			(xy 452.59928 -15.752065) (xy 452.543546 -15.750028) (xy 452.488703 -15.739898) (xy 452.435919 -15.721891)
			(xy 452.386319 -15.69639) (xy 452.340961 -15.663939) (xy 452.300812 -15.62523) (xy 452.266726 -15.581087)
			(xy 452.23943 -15.532452) (xy 452.219507 -15.480361) (xy 452.207381 -15.425924) (xy 452.20331 -15.370302)
			(xy 447.035357 -15.370302) (xy 447.045411 -15.450379) (xy 447.053729 -15.583344) (xy 447.054224 -15.649956)
			(xy 447.053718 -15.715692) (xy 447.045625 -15.846913) (xy 447.029468 -15.977388) (xy 447.005311 -16.106621)
			(xy 446.973243 -16.234121) (xy 446.933387 -16.359405) (xy 446.885894 -16.481999) (xy 446.830945 -16.601436)
			(xy 446.768746 -16.717263) (xy 446.699536 -16.829042) (xy 446.623575 -16.936349) (xy 446.541153 -17.038775)
			(xy 446.452581 -17.135934) (xy 446.358196 -17.227455) (xy 446.258357 -17.312993) (xy 446.15344 -17.392222)
			(xy 446.112162 -17.419574) (xy 450.58406 -17.419574) (xy 450.588131 -17.363952) (xy 450.600257 -17.309515)
			(xy 450.62018 -17.257424) (xy 450.647476 -17.208789) (xy 450.681562 -17.164646) (xy 450.721711 -17.125937)
			(xy 450.767069 -17.093486) (xy 450.816669 -17.067985) (xy 450.869453 -17.049978) (xy 450.924296 -17.039848)
			(xy 450.98003 -17.037811) (xy 451.035467 -17.043911) (xy 451.089424 -17.058017) (xy 451.140753 -17.079829)
			(xy 451.188359 -17.108883) (xy 451.231227 -17.144558) (xy 451.268444 -17.186095) (xy 451.299217 -17.232608)
			(xy 451.322889 -17.283105) (xy 451.338957 -17.336512) (xy 451.347077 -17.391688) (xy 451.347586 -17.419574)
			(xy 451.347077 -17.44746) (xy 451.338957 -17.502636) (xy 451.322889 -17.556043) (xy 451.299217 -17.60654)
			(xy 451.268444 -17.653053) (xy 451.231227 -17.69459) (xy 451.188359 -17.730265) (xy 451.140753 -17.759319)
			(xy 451.089424 -17.781131) (xy 451.035467 -17.795237) (xy 450.98003 -17.801337) (xy 450.924296 -17.7993)
			(xy 450.869453 -17.78917) (xy 450.816669 -17.771163) (xy 450.767069 -17.745662) (xy 450.721711 -17.713211)
			(xy 450.681562 -17.674502) (xy 450.647476 -17.630359) (xy 450.62018 -17.581724) (xy 450.600257 -17.529633)
			(xy 450.588131 -17.475196) (xy 450.58406 -17.419574) (xy 446.112162 -17.419574) (xy 446.043846 -17.464842)
			(xy 445.929988 -17.530577) (xy 445.8123 -17.589179) (xy 445.691228 -17.640425) (xy 445.56723 -17.68412)
			(xy 445.440778 -17.720099) (xy 445.31235 -17.748225) (xy 445.182435 -17.768391) (xy 445.051525 -17.780522)
			(xy 444.920116 -17.784571) (xy 444.788707 -17.780522) (xy 444.657797 -17.768391) (xy 444.527882 -17.748225)
			(xy 444.399454 -17.720099) (xy 444.273002 -17.68412) (xy 444.149004 -17.640425) (xy 444.027932 -17.589179)
			(xy 443.910244 -17.530577) (xy 443.796386 -17.464842) (xy 443.686792 -17.392222) (xy 443.581875 -17.312993)
			(xy 443.482036 -17.227455) (xy 443.387651 -17.135934) (xy 443.299079 -17.038775) (xy 443.216657 -16.936349)
			(xy 443.140696 -16.829042) (xy 443.071486 -16.717263) (xy 443.009287 -16.601436) (xy 442.954338 -16.481999)
			(xy 442.906845 -16.359405) (xy 442.866989 -16.234121) (xy 442.834921 -16.106621) (xy 442.810764 -15.977388)
			(xy 442.794607 -15.846913) (xy 442.786514 -15.715692) (xy 442.786008 -15.649956) (xy 442.786519 -15.583443)
			(xy 442.794807 -15.450676) (xy 442.811349 -15.318683) (xy 442.836079 -15.187976) (xy 442.868903 -15.059063)
			(xy 442.909692 -14.932445) (xy 442.958289 -14.808614) (xy 443.014504 -14.68805) (xy 443.04585 -14.629384)
			(xy 443.079386 -14.568875) (xy 443.15323 -14.451872) (xy 443.234501 -14.3399) (xy 443.322858 -14.23343)
			(xy 443.41793 -14.132911) (xy 443.519316 -14.038764) (xy 443.62659 -13.951386) (xy 443.682628 -13.910818)
			(xy 443.689486 -13.905738) (xy 443.698884 -13.893292) (xy 443.701424 -13.885418) (xy 443.703538 -13.878161)
			(xy 443.703924 -13.863057) (xy 443.702186 -13.8557) (xy 443.685422 -13.803884) (xy 443.684152 -13.79982)
			(xy 443.683898 -13.799058) (xy 443.673738 -13.763498) (xy 443.671831 -13.757644) (xy 443.665663 -13.746994)
			(xy 443.661546 -13.742416) (xy 443.654124 -13.735293) (xy 443.635245 -13.727168) (xy 443.62497 -13.726668)
			(xy 442.984128 -13.726668) (xy 442.974114 -13.727151) (xy 442.955607 -13.734804) (xy 442.941438 -13.748957)
			(xy 442.933763 -13.767455) (xy 442.933328 -13.777468) (xy 442.933328 -13.913358) (xy 442.932895 -13.923424)
			(xy 442.925169 -13.942016) (xy 442.918342 -13.949426) (xy 442.762894 -14.104874) (xy 442.755496 -14.111722)
			(xy 442.736898 -14.119459) (xy 442.726826 -14.11986) (xy 435.265068 -14.11986) (xy 435.198036 -14.119373)
			(xy 435.064207 -14.111467) (xy 434.931077 -14.095672) (xy 434.799113 -14.072043) (xy 434.668774 -14.040663)
			(xy 434.540516 -14.001641) (xy 434.414785 -13.955113) (xy 434.292022 -13.901243) (xy 434.172653 -13.840217)
			(xy 434.057097 -13.772249) (xy 434.001164 -13.735304) (xy 434.001164 -13.713714) (xy 434.00085 -13.705431)
			(xy 433.995547 -13.689738) (xy 433.99075 -13.68298) (xy 433.988718 -13.680694) (xy 433.98694 -13.678916)
			(xy 433.983638 -13.675106) (xy 432.821842 -12.51331) (xy 432.81499 -12.505914) (xy 432.807245 -12.487316)
			(xy 432.806856 -12.477242) (xy 432.806856 -1.308608) (xy 432.80203 -1.298448) (xy 432.78865 -1.268632)
			(xy 432.771151 -1.205671) (xy 432.767232 -1.173226) (xy 432.765902 -1.164041) (xy 432.757602 -1.147459)
			(xy 432.743942 -1.134918) (xy 432.726713 -1.128062) (xy 432.717448 -1.127506) (xy 429.197516 -1.127506)
			(xy 429.190658 -1.129538) (xy 429.165393 -1.136164) (xy 429.11365 -1.143301) (xy 429.087534 -1.143762)
			(xy 429.086518 -1.143762) (xy 429.060399 -1.143338) (xy 429.00865 -1.136208) (xy 428.983394 -1.129538)
			(xy 428.976536 -1.127506) (xy 424.117516 -1.127506) (xy 424.110658 -1.129538) (xy 424.085393 -1.136164)
			(xy 424.03365 -1.143301) (xy 424.007534 -1.143762) (xy 424.006518 -1.143762) (xy 423.980399 -1.143338)
			(xy 423.92865 -1.136208) (xy 423.903394 -1.129538) (xy 423.896536 -1.127506) (xy 420.228522 -1.127506)
			(xy 420.220239 -1.12782) (xy 420.204549 -1.133127) (xy 420.197788 -1.13792) (xy 420.195502 -1.139952)
			(xy 420.193724 -1.14173) (xy 420.189914 -1.145032) (xy 419.37051 -1.964436) (xy 419.366989 -1.968166)
			(xy 419.36136 -1.976741) (xy 419.359334 -1.981454) (xy 419.355778 -1.99009) (xy 419.355778 -6.072632)
			(xy 419.357048 -6.0833) (xy 419.36162 -6.100826) (xy 419.364922 -6.106668) (xy 419.37796 -6.131125)
			(xy 419.397617 -6.182944) (xy 419.409576 -6.23706) (xy 419.413587 -6.292337) (xy 419.409565 -6.347613)
			(xy 419.397595 -6.401726) (xy 419.377929 -6.453541) (xy 419.364922 -6.478016) (xy 419.36162 -6.483858)
			(xy 419.357048 -6.501384) (xy 419.355778 -6.512052) (xy 419.355778 -11.152632) (xy 419.357048 -11.1633)
			(xy 419.36162 -11.180826) (xy 419.364922 -11.186668) (xy 419.37796 -11.211125) (xy 419.397617 -11.262944)
			(xy 419.409576 -11.31706) (xy 419.413587 -11.372337) (xy 419.409565 -11.427613) (xy 419.397595 -11.481726)
			(xy 419.377929 -11.533541) (xy 419.364922 -11.558016) (xy 419.36162 -11.563858) (xy 419.357048 -11.581384)
			(xy 419.355778 -11.592052) (xy 419.355778 -13.50137) (xy 419.357302 -13.513562) (xy 419.35781 -13.515594)
			(xy 419.359226 -13.52067) (xy 419.363827 -13.530149) (xy 419.366954 -13.53439) (xy 419.382702 -13.55471)
			(xy 419.385332 -13.557929) (xy 419.391462 -13.563541) (xy 419.394894 -13.565886) (xy 419.402514 -13.570966)
			(xy 419.411404 -13.572998) (xy 419.474469 -13.588433) (xy 419.598774 -13.625975) (xy 419.720565 -13.671004)
			(xy 419.839394 -13.723355) (xy 419.954821 -13.782833) (xy 420.066418 -13.849219) (xy 420.173772 -13.922266)
			(xy 420.276487 -14.001706) (xy 420.374182 -14.087243) (xy 420.387383 -14.100302) (xy 425.542962 -14.100302)
			(xy 425.547033 -14.04468) (xy 425.559159 -13.990243) (xy 425.579082 -13.938152) (xy 425.606378 -13.889517)
			(xy 425.640464 -13.845374) (xy 425.680613 -13.806665) (xy 425.725971 -13.774214) (xy 425.775571 -13.748713)
			(xy 425.828355 -13.730706) (xy 425.883198 -13.720576) (xy 425.938932 -13.718539) (xy 425.994369 -13.724639)
			(xy 426.048326 -13.738745) (xy 426.099655 -13.760557) (xy 426.147261 -13.789611) (xy 426.190129 -13.825286)
			(xy 426.227346 -13.866823) (xy 426.258119 -13.913336) (xy 426.281791 -13.963833) (xy 426.297859 -14.01724)
			(xy 426.305979 -14.072416) (xy 426.306488 -14.100302) (xy 426.305979 -14.128188) (xy 426.297859 -14.183364)
			(xy 426.281791 -14.236771) (xy 426.258119 -14.287268) (xy 426.227346 -14.333781) (xy 426.190129 -14.375318)
			(xy 426.147261 -14.410993) (xy 426.099655 -14.440047) (xy 426.048326 -14.461859) (xy 425.994369 -14.475965)
			(xy 425.938932 -14.482065) (xy 425.883198 -14.480028) (xy 425.828355 -14.469898) (xy 425.775571 -14.451891)
			(xy 425.725971 -14.42639) (xy 425.680613 -14.393939) (xy 425.640464 -14.35523) (xy 425.606378 -14.311087)
			(xy 425.579082 -14.262452) (xy 425.559159 -14.210361) (xy 425.547033 -14.155924) (xy 425.542962 -14.100302)
			(xy 420.387383 -14.100302) (xy 420.466496 -14.178561) (xy 420.553087 -14.275323) (xy 420.633635 -14.377171)
			(xy 420.707843 -14.483727) (xy 420.775434 -14.594597) (xy 420.836161 -14.709372) (xy 420.889797 -14.827626)
			(xy 420.936144 -14.948923) (xy 420.975031 -15.072813) (xy 421.006314 -15.198838) (xy 421.029877 -15.326531)
			(xy 421.038559 -15.39755) (xy 426.20438 -15.39755) (xy 426.20438 -15.34305) (xy 426.212136 -15.289104)
			(xy 426.22749 -15.236811) (xy 426.250129 -15.187236) (xy 426.279594 -15.141386) (xy 426.315283 -15.100197)
			(xy 426.35647 -15.064506) (xy 426.402318 -15.035039) (xy 426.451892 -15.012397) (xy 426.504185 -14.99704)
			(xy 426.55813 -14.989281) (xy 426.58538 -14.988794) (xy 426.611615 -14.989267) (xy 426.663591 -14.996459)
			(xy 426.714089 -15.010711) (xy 426.762155 -15.031753) (xy 426.806882 -15.059187) (xy 426.847425 -15.092496)
			(xy 426.865542 -15.111476) (xy 426.865796 -15.11173) (xy 426.873514 -15.119129) (xy 426.893208 -15.127394)
			(xy 426.903896 -15.127732) (xy 426.99178 -15.125446) (xy 427.011338 -15.116048) (xy 427.01845 -15.107412)
			(xy 427.036662 -15.086262) (xy 427.078202 -15.048987) (xy 427.124731 -15.018165) (xy 427.175256 -14.994454)
			(xy 427.228698 -14.978361) (xy 427.283914 -14.970229) (xy 427.31182 -14.969744) (xy 427.339067 -14.970328)
			(xy 427.393006 -14.978085) (xy 427.445291 -14.99344) (xy 427.49486 -15.01608) (xy 427.540702 -15.045543)
			(xy 427.581884 -15.08123) (xy 427.617569 -15.122414) (xy 427.64703 -15.168258) (xy 427.669667 -15.217827)
			(xy 427.685019 -15.270114) (xy 427.692774 -15.324053) (xy 427.692774 -15.378547) (xy 427.685019 -15.432486)
			(xy 427.669667 -15.484773) (xy 427.64703 -15.534342) (xy 427.617569 -15.580186) (xy 427.581884 -15.62137)
			(xy 427.540702 -15.657057) (xy 427.49486 -15.68652) (xy 427.445291 -15.70916) (xy 427.393006 -15.724515)
			(xy 427.339067 -15.732272) (xy 427.31182 -15.73276) (xy 427.285584 -15.732302) (xy 427.233608 -15.725108)
			(xy 427.183109 -15.710855) (xy 427.135042 -15.68981) (xy 427.090315 -15.662373) (xy 427.049774 -15.62906)
			(xy 427.031658 -15.610078) (xy 427.031404 -15.609824) (xy 427.023691 -15.602418) (xy 427.003993 -15.594159)
			(xy 426.993304 -15.593822) (xy 426.90542 -15.596108) (xy 426.885862 -15.605506) (xy 426.87875 -15.614142)
			(xy 426.860528 -15.635283) (xy 426.818991 -15.67256) (xy 426.772464 -15.703385) (xy 426.721941 -15.727097)
			(xy 426.668501 -15.743192) (xy 426.613286 -15.751325) (xy 426.58538 -15.75181) (xy 426.55813 -15.751319)
			(xy 426.504185 -15.74356) (xy 426.451892 -15.728203) (xy 426.402318 -15.705561) (xy 426.35647 -15.676094)
			(xy 426.315283 -15.640403) (xy 426.279594 -15.599214) (xy 426.250129 -15.553364) (xy 426.22749 -15.503789)
			(xy 426.212136 -15.451496) (xy 426.20438 -15.39755) (xy 421.038559 -15.39755) (xy 421.045633 -15.455422)
			(xy 421.053524 -15.585031) (xy 421.054022 -15.649956) (xy 421.053516 -15.715692) (xy 421.045423 -15.846913)
			(xy 421.029266 -15.977388) (xy 421.005109 -16.106621) (xy 420.973041 -16.234121) (xy 420.933185 -16.359405)
			(xy 420.885692 -16.481999) (xy 420.830743 -16.601436) (xy 420.768544 -16.717263) (xy 420.699334 -16.829042)
			(xy 420.623373 -16.936349) (xy 420.596299 -16.969994) (xy 440.048149 -16.969994) (xy 440.052154 -16.882086)
			(xy 440.064137 -16.794906) (xy 440.083997 -16.709177) (xy 440.111572 -16.625609) (xy 440.146631 -16.544895)
			(xy 440.188884 -16.467703) (xy 440.237982 -16.394674) (xy 440.293518 -16.326412) (xy 440.35503 -16.263482)
			(xy 440.422011 -16.206408) (xy 440.493904 -16.15566) (xy 440.570113 -16.11166) (xy 440.650008 -16.074773)
			(xy 440.732927 -16.045304) (xy 440.818182 -16.023497) (xy 440.905066 -16.009533) (xy 440.99286 -16.003527)
			(xy 441.080837 -16.005531) (xy 441.168267 -16.015526) (xy 441.254426 -16.03343) (xy 441.3386 -16.059094)
			(xy 441.420091 -16.092307) (xy 441.498225 -16.132793) (xy 441.572353 -16.180215) (xy 441.641861 -16.234182)
			(xy 441.706175 -16.294247) (xy 441.764759 -16.359911) (xy 441.81713 -16.43063) (xy 441.862853 -16.505818)
			(xy 441.90155 -16.584853) (xy 441.932899 -16.667079) (xy 441.956641 -16.751815) (xy 441.972579 -16.838359)
			(xy 441.980581 -16.925994) (xy 441.981082 -16.969994) (xy 441.980581 -17.013994) (xy 441.972579 -17.101629)
			(xy 441.956641 -17.188173) (xy 441.932899 -17.272909) (xy 441.90155 -17.355135) (xy 441.862853 -17.43417)
			(xy 441.81713 -17.509358) (xy 441.764759 -17.580077) (xy 441.706175 -17.645741) (xy 441.641861 -17.705806)
			(xy 441.572353 -17.759773) (xy 441.498225 -17.807195) (xy 441.420091 -17.847681) (xy 441.3386 -17.880894)
			(xy 441.254426 -17.906558) (xy 441.168267 -17.924462) (xy 441.080837 -17.934457) (xy 440.99286 -17.936461)
			(xy 440.905066 -17.930455) (xy 440.818182 -17.916491) (xy 440.732927 -17.894684) (xy 440.650008 -17.865215)
			(xy 440.570113 -17.828328) (xy 440.493904 -17.784328) (xy 440.422011 -17.73358) (xy 440.35503 -17.676506)
			(xy 440.293518 -17.613576) (xy 440.237982 -17.545314) (xy 440.188884 -17.472285) (xy 440.146631 -17.395093)
			(xy 440.111572 -17.314379) (xy 440.083997 -17.230811) (xy 440.064137 -17.145082) (xy 440.052154 -17.057902)
			(xy 440.048149 -16.969994) (xy 420.596299 -16.969994) (xy 420.540951 -17.038775) (xy 420.452379 -17.135934)
			(xy 420.357994 -17.227455) (xy 420.258155 -17.312993) (xy 420.153238 -17.392222) (xy 420.11196 -17.419574)
			(xy 424.584112 -17.419574) (xy 424.588183 -17.363952) (xy 424.600309 -17.309515) (xy 424.620232 -17.257424)
			(xy 424.647528 -17.208789) (xy 424.681614 -17.164646) (xy 424.721763 -17.125937) (xy 424.767121 -17.093486)
			(xy 424.816721 -17.067985) (xy 424.869505 -17.049978) (xy 424.924348 -17.039848) (xy 424.980082 -17.037811)
			(xy 425.035519 -17.043911) (xy 425.089476 -17.058017) (xy 425.140805 -17.079829) (xy 425.188411 -17.108883)
			(xy 425.231279 -17.144558) (xy 425.268496 -17.186095) (xy 425.299269 -17.232608) (xy 425.322941 -17.283105)
			(xy 425.339009 -17.336512) (xy 425.347129 -17.391688) (xy 425.347638 -17.419574) (xy 425.347129 -17.44746)
			(xy 425.339009 -17.502636) (xy 425.322941 -17.556043) (xy 425.299269 -17.60654) (xy 425.268496 -17.653053)
			(xy 425.231279 -17.69459) (xy 425.188411 -17.730265) (xy 425.140805 -17.759319) (xy 425.089476 -17.781131)
			(xy 425.035519 -17.795237) (xy 424.980082 -17.801337) (xy 424.924348 -17.7993) (xy 424.869505 -17.78917)
			(xy 424.816721 -17.771163) (xy 424.767121 -17.745662) (xy 424.721763 -17.713211) (xy 424.681614 -17.674502)
			(xy 424.647528 -17.630359) (xy 424.620232 -17.581724) (xy 424.600309 -17.529633) (xy 424.588183 -17.475196)
			(xy 424.584112 -17.419574) (xy 420.11196 -17.419574) (xy 420.043644 -17.464842) (xy 419.929786 -17.530577)
			(xy 419.812098 -17.589179) (xy 419.691026 -17.640425) (xy 419.567028 -17.68412) (xy 419.440576 -17.720099)
			(xy 419.312148 -17.748225) (xy 419.182233 -17.768391) (xy 419.051323 -17.780522) (xy 418.919914 -17.784571)
			(xy 418.788505 -17.780522) (xy 418.657595 -17.768391) (xy 418.52768 -17.748225) (xy 418.399252 -17.720099)
			(xy 418.2728 -17.68412) (xy 418.148802 -17.640425) (xy 418.02773 -17.589179) (xy 417.910042 -17.530577)
			(xy 417.796184 -17.464842) (xy 417.68659 -17.392222) (xy 417.581673 -17.312993) (xy 417.481834 -17.227455)
			(xy 417.387449 -17.135934) (xy 417.298877 -17.038775) (xy 417.216455 -16.936349) (xy 417.140494 -16.829042)
			(xy 417.071284 -16.717263) (xy 417.009085 -16.601436) (xy 416.954136 -16.481999) (xy 416.906643 -16.359405)
			(xy 416.866787 -16.234121) (xy 416.834719 -16.106621) (xy 416.810562 -15.977388) (xy 416.794405 -15.846913)
			(xy 416.786312 -15.715692) (xy 416.785806 -15.649956) (xy 416.786314 -15.599156) (xy 416.788358 -15.533738)
			(xy 416.799468 -15.403315) (xy 416.818552 -15.273817) (xy 416.845538 -15.145733) (xy 416.880324 -15.019545)
			(xy 416.92278 -14.895725) (xy 416.972747 -14.774741) (xy 417.030035 -14.657048) (xy 417.09443 -14.543087)
			(xy 417.16569 -14.433288) (xy 417.243546 -14.328064) (xy 417.327705 -14.22781) (xy 417.417852 -14.132903)
			(xy 417.513647 -14.043701) (xy 417.61473 -13.960538) (xy 417.66744 -13.92174) (xy 417.67252 -13.918184)
			(xy 417.684204 -13.904468) (xy 417.688522 -13.899642) (xy 417.696142 -13.884148) (xy 417.699877 -13.875567)
			(xy 417.701556 -13.856944) (xy 417.699444 -13.847826) (xy 417.698936 -13.846302) (xy 417.68522 -13.80363)
			(xy 417.683696 -13.799058) (xy 417.673536 -13.763498) (xy 417.671629 -13.757645) (xy 417.665461 -13.746994)
			(xy 417.661344 -13.742416) (xy 417.653922 -13.735293) (xy 417.635043 -13.727169) (xy 417.624768 -13.726668)
			(xy 416.7632 -13.726668) (xy 416.75319 -13.727156) (xy 416.734693 -13.734814) (xy 416.720532 -13.748966)
			(xy 416.712862 -13.767458) (xy 416.7124 -13.777468) (xy 416.7124 -13.900658) (xy 416.711915 -13.910621)
			(xy 416.70433 -13.929047) (xy 416.697668 -13.936472) (xy 416.529266 -14.104874) (xy 416.521867 -14.111718)
			(xy 416.503269 -14.119444) (xy 416.493198 -14.11986) (xy 409.26512 -14.11986) (xy 409.198089 -14.119372)
			(xy 409.06426 -14.111463) (xy 408.931132 -14.095665) (xy 408.799169 -14.072033) (xy 408.668831 -14.040651)
			(xy 408.540574 -14.001627) (xy 408.414846 -13.955097) (xy 408.292084 -13.901225) (xy 408.172717 -13.840197)
			(xy 408.057163 -13.772228) (xy 408.001216 -13.735304) (xy 408.001216 -13.249148) (xy 408.000891 -13.240869)
			(xy 407.995568 -13.225192) (xy 407.990802 -13.218414) (xy 407.98877 -13.216128) (xy 407.986992 -13.21435)
			(xy 407.98369 -13.21054) (xy 407.504646 -12.731496) (xy 407.497795 -12.724099) (xy 407.490055 -12.705501)
			(xy 407.48966 -12.695428) (xy 407.48966 -11.799316) (xy 407.488898 -11.791188) (xy 407.487417 -11.784615)
			(xy 407.481488 -11.772521) (xy 407.477214 -11.767312) (xy 407.471372 -11.760708) (xy 407.454862 -11.752072)
			(xy 407.44521 -11.750802) (xy 407.417889 -11.746897) (xy 407.364684 -11.732234) (xy 407.314147 -11.710057)
			(xy 407.267334 -11.680829) (xy 407.225222 -11.645159) (xy 407.18869 -11.603793) (xy 407.1585 -11.557593)
			(xy 407.135284 -11.507526) (xy 407.119525 -11.454635) (xy 407.111553 -11.400025) (xy 407.111534 -11.344837)
			(xy 407.119468 -11.290222) (xy 407.135191 -11.23732) (xy 407.158373 -11.187237) (xy 407.188531 -11.141017)
			(xy 407.225034 -11.099625) (xy 407.267122 -11.063926) (xy 407.313915 -11.034666) (xy 407.364436 -11.012454)
			(xy 407.417631 -10.997755) (xy 407.444956 -10.993882) (xy 407.44521 -10.993882) (xy 407.446988 -10.993628)
			(xy 407.458811 -10.991012) (xy 407.478301 -10.976699) (xy 407.484326 -10.966196) (xy 407.486337 -10.961929)
			(xy 407.488901 -10.952852) (xy 407.489406 -10.948162) (xy 407.489406 -10.947654) (xy 407.48966 -10.94359)
			(xy 407.48966 -1.802384) (xy 407.489341 -1.794103) (xy 407.484031 -1.778416) (xy 407.479246 -1.77165)
			(xy 407.477214 -1.769364) (xy 407.475436 -1.767586) (xy 407.472134 -1.763776) (xy 406.59304 -0.884682)
			(xy 406.589308 -0.881164) (xy 406.58073 -0.875542) (xy 406.576022 -0.873506) (xy 406.567386 -0.86995)
			(xy 393.88161 -0.86995) (xy 393.873327 -0.870265) (xy 393.857636 -0.87557) (xy 393.850876 -0.880364)
			(xy 393.84859 -0.882396) (xy 393.846812 -0.884174) (xy 393.843002 -0.887476) (xy 393.2809 -1.449578)
			(xy 393.277375 -1.453306) (xy 393.271739 -1.461878) (xy 393.269724 -1.466596) (xy 393.266168 -1.475232)
			(xy 393.266168 -11.040364) (xy 393.266676 -11.04392) (xy 393.267692 -11.05154) (xy 393.283694 -11.08583)
			(xy 393.29106 -11.092688) (xy 393.311656 -11.112493) (xy 393.347277 -11.15717) (xy 393.375838 -11.206658)
			(xy 393.396701 -11.259851) (xy 393.4094 -11.31556) (xy 393.413651 -11.37254) (xy 393.409358 -11.429517)
			(xy 393.396618 -11.485217) (xy 393.375716 -11.538395) (xy 393.347119 -11.587862) (xy 393.311465 -11.632512)
			(xy 393.290806 -11.65225) (xy 393.290552 -11.652504) (xy 393.285726 -11.657076) (xy 393.278868 -11.667744)
			(xy 393.276836 -11.673586) (xy 393.27074 -11.687048) (xy 393.266168 -11.697208) (xy 393.266168 -13.482828)
			(xy 393.266559 -13.491749) (xy 393.272665 -13.508514) (xy 393.278106 -13.515594) (xy 393.289536 -13.529056)
			(xy 393.291314 -13.531342) (xy 393.293805 -13.53403) (xy 393.299415 -13.538747) (xy 393.30249 -13.54074)
			(xy 393.314428 -13.547598) (xy 393.318746 -13.550138) (xy 393.333732 -13.556234) (xy 393.334494 -13.556234)
			(xy 393.398058 -13.569321) (xy 393.52361 -13.602223) (xy 393.64693 -13.642695) (xy 393.767563 -13.690586)
			(xy 393.885062 -13.745719) (xy 393.998994 -13.80789) (xy 394.108937 -13.87687) (xy 394.214486 -13.952404)
			(xy 394.315249 -14.034212) (xy 394.410854 -14.121992) (xy 394.500948 -14.215421) (xy 394.585199 -14.314151)
			(xy 394.663293 -14.417818) (xy 394.734944 -14.52604) (xy 394.799886 -14.638416) (xy 394.848274 -14.735302)
			(xy 398.879312 -14.735302) (xy 398.883383 -14.67968) (xy 398.895509 -14.625243) (xy 398.915432 -14.573152)
			(xy 398.942728 -14.524517) (xy 398.976814 -14.480374) (xy 399.016963 -14.441665) (xy 399.062321 -14.409214)
			(xy 399.111921 -14.383713) (xy 399.164705 -14.365706) (xy 399.219548 -14.355576) (xy 399.275282 -14.353539)
			(xy 399.330719 -14.359639) (xy 399.384676 -14.373745) (xy 399.436005 -14.395557) (xy 399.483611 -14.424611)
			(xy 399.526479 -14.460286) (xy 399.563696 -14.501823) (xy 399.594469 -14.548336) (xy 399.618141 -14.598833)
			(xy 399.634209 -14.65224) (xy 399.642329 -14.707416) (xy 399.642838 -14.735302) (xy 399.642329 -14.763188)
			(xy 399.634209 -14.818364) (xy 399.618141 -14.871771) (xy 399.594469 -14.922268) (xy 399.563696 -14.968781)
			(xy 399.526479 -15.010318) (xy 399.483611 -15.045993) (xy 399.436005 -15.075047) (xy 399.384676 -15.096859)
			(xy 399.330719 -15.110965) (xy 399.275282 -15.117065) (xy 399.219548 -15.115028) (xy 399.164705 -15.104898)
			(xy 399.111921 -15.086891) (xy 399.062321 -15.06139) (xy 399.016963 -15.028939) (xy 398.976814 -14.99023)
			(xy 398.942728 -14.946087) (xy 398.915432 -14.897452) (xy 398.895509 -14.845361) (xy 398.883383 -14.790924)
			(xy 398.879312 -14.735302) (xy 394.848274 -14.735302) (xy 394.857878 -14.754531) (xy 394.908707 -14.873955)
			(xy 394.930884 -14.934946) (xy 394.950802 -14.992284) (xy 394.984877 -15.108799) (xy 395.012276 -15.227062)
			(xy 395.03291 -15.346691) (xy 395.038731 -15.397554) (xy 400.204357 -15.397554) (xy 400.204357 -15.343046)
			(xy 400.212115 -15.289092) (xy 400.227473 -15.236792) (xy 400.250117 -15.18721) (xy 400.279588 -15.141356)
			(xy 400.315285 -15.100163) (xy 400.356482 -15.064469) (xy 400.402338 -15.035002) (xy 400.451922 -15.012362)
			(xy 400.504224 -14.997008) (xy 400.558178 -14.989255) (xy 400.585432 -14.988794) (xy 400.611668 -14.989232)
			(xy 400.663645 -14.996432) (xy 400.714144 -15.01069) (xy 400.76221 -15.031739) (xy 400.806937 -15.059179)
			(xy 400.847478 -15.092493) (xy 400.865594 -15.111476) (xy 400.865848 -15.11173) (xy 400.873584 -15.119107)
			(xy 400.893265 -15.127384) (xy 400.903948 -15.127732) (xy 400.991832 -15.125446) (xy 401.01139 -15.116048)
			(xy 401.018502 -15.107412) (xy 401.036686 -15.086237) (xy 401.078232 -15.048964) (xy 401.124767 -15.018145)
			(xy 401.175297 -14.994439) (xy 401.228744 -14.978351) (xy 401.283964 -14.970225) (xy 401.311872 -14.969744)
			(xy 401.339123 -14.970301) (xy 401.39307 -14.978054) (xy 401.445365 -14.993406) (xy 401.494942 -15.016044)
			(xy 401.540793 -15.045507) (xy 401.581984 -15.081197) (xy 401.617676 -15.122385) (xy 401.647143 -15.168233)
			(xy 401.669784 -15.217809) (xy 401.68514 -15.270103) (xy 401.692897 -15.324049) (xy 401.692897 -15.378551)
			(xy 401.68514 -15.432497) (xy 401.669784 -15.484791) (xy 401.647143 -15.534367) (xy 401.617676 -15.580215)
			(xy 401.581984 -15.621403) (xy 401.540793 -15.657093) (xy 401.494942 -15.686556) (xy 401.445365 -15.709194)
			(xy 401.39307 -15.724546) (xy 401.339123 -15.732299) (xy 401.311872 -15.73276) (xy 401.285635 -15.732334)
			(xy 401.233657 -15.725134) (xy 401.183158 -15.710874) (xy 401.135091 -15.689823) (xy 401.090365 -15.66238)
			(xy 401.049825 -15.629063) (xy 401.03171 -15.610078) (xy 401.031456 -15.609824) (xy 401.023724 -15.602442)
			(xy 401.00404 -15.594169) (xy 400.993356 -15.593822) (xy 400.905472 -15.596108) (xy 400.885914 -15.605506)
			(xy 400.878802 -15.614142) (xy 400.860605 -15.635306) (xy 400.819064 -15.672582) (xy 400.772531 -15.703403)
			(xy 400.722003 -15.727112) (xy 400.668558 -15.743202) (xy 400.613339 -15.751328) (xy 400.585432 -15.75181)
			(xy 400.558178 -15.751345) (xy 400.504224 -15.743592) (xy 400.451922 -15.728238) (xy 400.402338 -15.705598)
			(xy 400.356481 -15.676131) (xy 400.315285 -15.640437) (xy 400.279588 -15.599244) (xy 400.250117 -15.55339)
			(xy 400.227473 -15.503808) (xy 400.212115 -15.451508) (xy 400.204357 -15.397554) (xy 395.038731 -15.397554)
			(xy 395.046713 -15.467299) (xy 395.05364 -15.588496) (xy 395.054074 -15.649194) (xy 395.054074 -15.649956)
			(xy 395.053568 -15.715692) (xy 395.045475 -15.846913) (xy 395.029318 -15.977388) (xy 395.005161 -16.106621)
			(xy 394.973093 -16.234121) (xy 394.933237 -16.359405) (xy 394.885744 -16.481999) (xy 394.830795 -16.601436)
			(xy 394.768596 -16.717263) (xy 394.699386 -16.829042) (xy 394.623425 -16.936349) (xy 394.596351 -16.969994)
			(xy 414.048201 -16.969994) (xy 414.052206 -16.882086) (xy 414.064189 -16.794906) (xy 414.084049 -16.709177)
			(xy 414.111624 -16.625609) (xy 414.146683 -16.544895) (xy 414.188936 -16.467703) (xy 414.238034 -16.394674)
			(xy 414.29357 -16.326412) (xy 414.355082 -16.263482) (xy 414.422063 -16.206408) (xy 414.493956 -16.15566)
			(xy 414.570165 -16.11166) (xy 414.65006 -16.074773) (xy 414.732979 -16.045304) (xy 414.818234 -16.023497)
			(xy 414.905118 -16.009533) (xy 414.992912 -16.003527) (xy 415.080889 -16.005531) (xy 415.168319 -16.015526)
			(xy 415.254478 -16.03343) (xy 415.338652 -16.059094) (xy 415.420143 -16.092307) (xy 415.498277 -16.132793)
			(xy 415.572405 -16.180215) (xy 415.641913 -16.234182) (xy 415.706227 -16.294247) (xy 415.764811 -16.359911)
			(xy 415.817182 -16.43063) (xy 415.862905 -16.505818) (xy 415.901602 -16.584853) (xy 415.932951 -16.667079)
			(xy 415.956693 -16.751815) (xy 415.972631 -16.838359) (xy 415.980633 -16.925994) (xy 415.981134 -16.969994)
			(xy 415.980633 -17.013994) (xy 415.972631 -17.101629) (xy 415.956693 -17.188173) (xy 415.932951 -17.272909)
			(xy 415.901602 -17.355135) (xy 415.862905 -17.43417) (xy 415.817182 -17.509358) (xy 415.764811 -17.580077)
			(xy 415.706227 -17.645741) (xy 415.641913 -17.705806) (xy 415.572405 -17.759773) (xy 415.498277 -17.807195)
			(xy 415.420143 -17.847681) (xy 415.338652 -17.880894) (xy 415.254478 -17.906558) (xy 415.168319 -17.924462)
			(xy 415.080889 -17.934457) (xy 414.992912 -17.936461) (xy 414.905118 -17.930455) (xy 414.818234 -17.916491)
			(xy 414.732979 -17.894684) (xy 414.65006 -17.865215) (xy 414.570165 -17.828328) (xy 414.493956 -17.784328)
			(xy 414.422063 -17.73358) (xy 414.355082 -17.676506) (xy 414.29357 -17.613576) (xy 414.238034 -17.545314)
			(xy 414.188936 -17.472285) (xy 414.146683 -17.395093) (xy 414.111624 -17.314379) (xy 414.084049 -17.230811)
			(xy 414.064189 -17.145082) (xy 414.052206 -17.057902) (xy 414.048201 -16.969994) (xy 394.596351 -16.969994)
			(xy 394.541003 -17.038775) (xy 394.452431 -17.135934) (xy 394.358046 -17.227455) (xy 394.258207 -17.312993)
			(xy 394.15329 -17.392222) (xy 394.112012 -17.419574) (xy 398.584164 -17.419574) (xy 398.588235 -17.363952)
			(xy 398.600361 -17.309515) (xy 398.620284 -17.257424) (xy 398.64758 -17.208789) (xy 398.681666 -17.164646)
			(xy 398.721815 -17.125937) (xy 398.767173 -17.093486) (xy 398.816773 -17.067985) (xy 398.869557 -17.049978)
			(xy 398.9244 -17.039848) (xy 398.980134 -17.037811) (xy 399.035571 -17.043911) (xy 399.089528 -17.058017)
			(xy 399.140857 -17.079829) (xy 399.188463 -17.108883) (xy 399.231331 -17.144558) (xy 399.268548 -17.186095)
			(xy 399.299321 -17.232608) (xy 399.322993 -17.283105) (xy 399.339061 -17.336512) (xy 399.347181 -17.391688)
			(xy 399.34769 -17.419574) (xy 399.347181 -17.44746) (xy 399.339061 -17.502636) (xy 399.322993 -17.556043)
			(xy 399.299321 -17.60654) (xy 399.268548 -17.653053) (xy 399.231331 -17.69459) (xy 399.188463 -17.730265)
			(xy 399.140857 -17.759319) (xy 399.089528 -17.781131) (xy 399.035571 -17.795237) (xy 398.980134 -17.801337)
			(xy 398.9244 -17.7993) (xy 398.869557 -17.78917) (xy 398.816773 -17.771163) (xy 398.767173 -17.745662)
			(xy 398.721815 -17.713211) (xy 398.681666 -17.674502) (xy 398.64758 -17.630359) (xy 398.620284 -17.581724)
			(xy 398.600361 -17.529633) (xy 398.588235 -17.475196) (xy 398.584164 -17.419574) (xy 394.112012 -17.419574)
			(xy 394.043696 -17.464842) (xy 393.929838 -17.530577) (xy 393.81215 -17.589179) (xy 393.691078 -17.640425)
			(xy 393.56708 -17.68412) (xy 393.440628 -17.720099) (xy 393.3122 -17.748225) (xy 393.182285 -17.768391)
			(xy 393.051375 -17.780522) (xy 392.919966 -17.784571) (xy 392.788557 -17.780522) (xy 392.657647 -17.768391)
			(xy 392.527732 -17.748225) (xy 392.399304 -17.720099) (xy 392.272852 -17.68412) (xy 392.148854 -17.640425)
			(xy 392.027782 -17.589179) (xy 391.910094 -17.530577) (xy 391.796236 -17.464842) (xy 391.686642 -17.392222)
			(xy 391.581725 -17.312993) (xy 391.481886 -17.227455) (xy 391.387501 -17.135934) (xy 391.298929 -17.038775)
			(xy 391.216507 -16.936349) (xy 391.140546 -16.829042) (xy 391.071336 -16.717263) (xy 391.009137 -16.601436)
			(xy 390.954188 -16.481999) (xy 390.906695 -16.359405) (xy 390.866839 -16.234121) (xy 390.834771 -16.106621)
			(xy 390.810614 -15.977388) (xy 390.794457 -15.846913) (xy 390.786364 -15.715692) (xy 390.785858 -15.649956)
			(xy 390.785858 -15.649702) (xy 390.786331 -15.585782) (xy 390.79399 -15.458171) (xy 390.809275 -15.331248)
			(xy 390.83213 -15.205467) (xy 390.862474 -15.081281) (xy 390.900199 -14.959133) (xy 390.945168 -14.839463)
			(xy 390.99722 -14.7227) (xy 391.056169 -14.609262) (xy 391.121803 -14.499556) (xy 391.15746 -14.446504)
			(xy 391.17016 -14.427708) (xy 391.171176 -14.426184) (xy 391.180574 -14.413484) (xy 391.180574 -14.412976)
			(xy 391.199624 -14.38656) (xy 391.200132 -14.386052) (xy 391.220198 -14.357604) (xy 391.256433 -14.310794)
			(xy 391.333364 -14.220807) (xy 391.415167 -14.135225) (xy 391.501592 -14.054314) (xy 391.592372 -13.97832)
			(xy 391.639552 -13.942568) (xy 391.678414 -13.91412) (xy 391.679176 -13.913612) (xy 391.679684 -13.913358)
			(xy 391.68197 -13.91158) (xy 391.688574 -13.904976) (xy 391.694813 -13.898103) (xy 391.702351 -13.881156)
			(xy 391.703409 -13.862638) (xy 391.70102 -13.853668) (xy 391.686542 -13.808202) (xy 391.686542 -13.807694)
			(xy 391.675112 -13.772896) (xy 391.675112 -13.772388) (xy 391.670286 -13.758418) (xy 391.670032 -13.757656)
			(xy 391.667123 -13.751371) (xy 391.658504 -13.74054) (xy 391.653014 -13.73632) (xy 391.65276 -13.73632)
			(xy 391.64613 -13.73191) (xy 391.630997 -13.726987) (xy 391.623042 -13.726668) (xy 390.8044 -13.726668)
			(xy 390.79439 -13.727156) (xy 390.775893 -13.734814) (xy 390.761732 -13.748966) (xy 390.754062 -13.767458)
			(xy 390.7536 -13.777468) (xy 390.7536 -13.895324) (xy 390.753172 -13.905392) (xy 390.745452 -13.92399)
			(xy 390.738614 -13.931392) (xy 390.565132 -14.104874) (xy 390.557731 -14.111712) (xy 390.539133 -14.119426)
			(xy 390.529064 -14.11986) (xy 383.264918 -14.11986) (xy 383.197888 -14.119361) (xy 383.064062 -14.111433)
			(xy 382.930938 -14.095622) (xy 382.798978 -14.071982) (xy 382.668644 -14.040596) (xy 382.540388 -14.001574)
			(xy 382.414659 -13.955051) (xy 382.291895 -13.90119) (xy 382.172523 -13.840178) (xy 382.056959 -13.772228)
			(xy 382.001014 -13.735304) (xy 382.001014 -13.12037) (xy 382.000692 -13.11209) (xy 381.995375 -13.096408)
			(xy 381.9906 -13.089636) (xy 381.988568 -13.08735) (xy 381.98679 -13.085572) (xy 381.983488 -13.081762)
			(xy 381.534162 -12.632436) (xy 381.527319 -12.625037) (xy 381.519598 -12.606438) (xy 381.519176 -12.596368)
			(xy 381.519176 -1.822196) (xy 381.518858 -1.813915) (xy 381.513543 -1.798231) (xy 381.508762 -1.791462)
			(xy 381.50673 -1.789176) (xy 381.504952 -1.787398) (xy 381.50165 -1.783588) (xy 381.244856 -1.526794)
			(xy 381.240568 -1.522777) (xy 381.23056 -1.516628) (xy 381.225044 -1.514602) (xy 381.213614 -1.510792)
			(xy 381.201676 -1.51257) (xy 381.188038 -1.514458) (xy 381.160579 -1.516489) (xy 381.146812 -1.516634)
			(xy 381.11956 -1.516149) (xy 381.065609 -1.508394) (xy 381.013311 -1.49304) (xy 380.963731 -1.4704)
			(xy 380.917877 -1.440935) (xy 380.876683 -1.405243) (xy 380.840988 -1.364053) (xy 380.811518 -1.318202)
			(xy 380.788873 -1.268624) (xy 380.773514 -1.216328) (xy 380.765754 -1.162378) (xy 380.765304 -1.135126)
			(xy 380.765456 -1.121359) (xy 380.76749 -1.093901) (xy 380.769368 -1.080262) (xy 380.771146 -1.068324)
			(xy 380.767336 -1.056894) (xy 380.765325 -1.051373) (xy 380.759158 -1.041374) (xy 380.755144 -1.037082)
			(xy 380.464314 -0.746252) (xy 380.460584 -0.74273) (xy 380.45201 -0.7371) (xy 380.447296 -0.735076)
			(xy 380.43866 -0.73152) (xy 367.970054 -0.73152) (xy 367.961776 -0.731845) (xy 367.946099 -0.737169)
			(xy 367.93932 -0.741934) (xy 367.937034 -0.743966) (xy 367.935256 -0.745744) (xy 367.931446 -0.749046)
			(xy 367.55324 -1.127252) (xy 367.545396 -1.13656) (xy 367.53861 -1.159902) (xy 367.540286 -1.171956)
			(xy 367.544096 -1.187958) (xy 367.54689 -1.193546) (xy 367.559634 -1.22022) (xy 367.577643 -1.276523)
			(xy 367.58675 -1.334931) (xy 367.587276 -1.364488) (xy 367.587276 -1.364996) (xy 367.586781 -1.392699)
			(xy 367.578771 -1.447522) (xy 367.562918 -1.500611) (xy 367.539556 -1.55085) (xy 367.509175 -1.597183)
			(xy 367.472414 -1.638636) (xy 367.430046 -1.674339) (xy 367.382961 -1.703541) (xy 367.332148 -1.725627)
			(xy 367.278676 -1.740135) (xy 367.251234 -1.743964) (xy 367.242598 -1.74498) (xy 367.212372 -1.759712)
			(xy 367.206022 -1.766062) (xy 367.190274 -1.782064) (xy 367.185407 -1.787666) (xy 367.178821 -1.800958)
			(xy 367.17732 -1.808226) (xy 367.176558 -1.816862) (xy 367.176558 -4.48183) (xy 377.965206 -4.48183)
			(xy 377.969277 -4.426208) (xy 377.981403 -4.371771) (xy 378.001326 -4.31968) (xy 378.028622 -4.271045)
			(xy 378.062708 -4.226902) (xy 378.102857 -4.188193) (xy 378.148215 -4.155742) (xy 378.197815 -4.130241)
			(xy 378.250599 -4.112234) (xy 378.305442 -4.102104) (xy 378.361176 -4.100067) (xy 378.416613 -4.106167)
			(xy 378.47057 -4.120273) (xy 378.521899 -4.142085) (xy 378.569505 -4.171139) (xy 378.612373 -4.206814)
			(xy 378.64959 -4.248351) (xy 378.680363 -4.294864) (xy 378.704035 -4.345361) (xy 378.720103 -4.398768)
			(xy 378.728223 -4.453944) (xy 378.728732 -4.48183) (xy 378.728223 -4.509716) (xy 378.720103 -4.564892)
			(xy 378.704035 -4.618299) (xy 378.680363 -4.668796) (xy 378.64959 -4.715309) (xy 378.612373 -4.756846)
			(xy 378.569505 -4.792521) (xy 378.521899 -4.821575) (xy 378.485784 -4.836922) (xy 380.267716 -4.836922)
			(xy 380.271787 -4.7813) (xy 380.283913 -4.726863) (xy 380.303836 -4.674772) (xy 380.331132 -4.626137)
			(xy 380.365218 -4.581994) (xy 380.405367 -4.543285) (xy 380.450725 -4.510834) (xy 380.500325 -4.485333)
			(xy 380.553109 -4.467326) (xy 380.607952 -4.457196) (xy 380.663686 -4.455159) (xy 380.719123 -4.461259)
			(xy 380.77308 -4.475365) (xy 380.824409 -4.497177) (xy 380.872015 -4.526231) (xy 380.914883 -4.561906)
			(xy 380.9521 -4.603443) (xy 380.982873 -4.649956) (xy 381.006545 -4.700453) (xy 381.022613 -4.75386)
			(xy 381.030733 -4.809036) (xy 381.031242 -4.836922) (xy 381.030733 -4.864808) (xy 381.022613 -4.919984)
			(xy 381.006545 -4.973391) (xy 380.982873 -5.023888) (xy 380.9521 -5.070401) (xy 380.914883 -5.111938)
			(xy 380.872015 -5.147613) (xy 380.824409 -5.176667) (xy 380.77308 -5.198479) (xy 380.719123 -5.212585)
			(xy 380.663686 -5.218685) (xy 380.607952 -5.216648) (xy 380.553109 -5.206518) (xy 380.500325 -5.188511)
			(xy 380.450725 -5.16301) (xy 380.405367 -5.130559) (xy 380.365218 -5.09185) (xy 380.331132 -5.047707)
			(xy 380.303836 -4.999072) (xy 380.283913 -4.946981) (xy 380.271787 -4.892544) (xy 380.267716 -4.836922)
			(xy 378.485784 -4.836922) (xy 378.47057 -4.843387) (xy 378.416613 -4.857493) (xy 378.361176 -4.863593)
			(xy 378.305442 -4.861556) (xy 378.250599 -4.851426) (xy 378.197815 -4.833419) (xy 378.148215 -4.807918)
			(xy 378.102857 -4.775467) (xy 378.062708 -4.736758) (xy 378.028622 -4.692615) (xy 378.001326 -4.64398)
			(xy 377.981403 -4.591889) (xy 377.969277 -4.537452) (xy 377.965206 -4.48183) (xy 367.176558 -4.48183)
			(xy 367.176558 -5.852922) (xy 378.220984 -5.852922) (xy 378.225055 -5.7973) (xy 378.237181 -5.742863)
			(xy 378.257104 -5.690772) (xy 378.2844 -5.642137) (xy 378.318486 -5.597994) (xy 378.358635 -5.559285)
			(xy 378.403993 -5.526834) (xy 378.453593 -5.501333) (xy 378.506377 -5.483326) (xy 378.56122 -5.473196)
			(xy 378.616954 -5.471159) (xy 378.672391 -5.477259) (xy 378.726348 -5.491365) (xy 378.777677 -5.513177)
			(xy 378.825283 -5.542231) (xy 378.868151 -5.577906) (xy 378.905368 -5.619443) (xy 378.936141 -5.665956)
			(xy 378.959813 -5.716453) (xy 378.975881 -5.76986) (xy 378.984001 -5.825036) (xy 378.98451 -5.852922)
			(xy 380.267716 -5.852922) (xy 380.271787 -5.7973) (xy 380.283913 -5.742863) (xy 380.303836 -5.690772)
			(xy 380.331132 -5.642137) (xy 380.365218 -5.597994) (xy 380.405367 -5.559285) (xy 380.450725 -5.526834)
			(xy 380.500325 -5.501333) (xy 380.553109 -5.483326) (xy 380.607952 -5.473196) (xy 380.663686 -5.471159)
			(xy 380.719123 -5.477259) (xy 380.77308 -5.491365) (xy 380.824409 -5.513177) (xy 380.872015 -5.542231)
			(xy 380.914883 -5.577906) (xy 380.9521 -5.619443) (xy 380.982873 -5.665956) (xy 381.006545 -5.716453)
			(xy 381.022613 -5.76986) (xy 381.030733 -5.825036) (xy 381.031242 -5.852922) (xy 381.030733 -5.880808)
			(xy 381.022613 -5.935984) (xy 381.006545 -5.989391) (xy 380.982873 -6.039888) (xy 380.9521 -6.086401)
			(xy 380.914883 -6.127938) (xy 380.872015 -6.163613) (xy 380.824409 -6.192667) (xy 380.77308 -6.214479)
			(xy 380.719123 -6.228585) (xy 380.663686 -6.234685) (xy 380.607952 -6.232648) (xy 380.553109 -6.222518)
			(xy 380.500325 -6.204511) (xy 380.450725 -6.17901) (xy 380.405367 -6.146559) (xy 380.365218 -6.10785)
			(xy 380.331132 -6.063707) (xy 380.303836 -6.015072) (xy 380.283913 -5.962981) (xy 380.271787 -5.908544)
			(xy 380.267716 -5.852922) (xy 378.98451 -5.852922) (xy 378.984001 -5.880808) (xy 378.975881 -5.935984)
			(xy 378.959813 -5.989391) (xy 378.936141 -6.039888) (xy 378.905368 -6.086401) (xy 378.868151 -6.127938)
			(xy 378.825283 -6.163613) (xy 378.777677 -6.192667) (xy 378.726348 -6.214479) (xy 378.672391 -6.228585)
			(xy 378.616954 -6.234685) (xy 378.56122 -6.232648) (xy 378.506377 -6.222518) (xy 378.453593 -6.204511)
			(xy 378.403993 -6.17901) (xy 378.358635 -6.146559) (xy 378.318486 -6.10785) (xy 378.2844 -6.063707)
			(xy 378.257104 -6.015072) (xy 378.237181 -5.962981) (xy 378.225055 -5.908544) (xy 378.220984 -5.852922)
			(xy 367.176558 -5.852922) (xy 367.176558 -5.903468) (xy 367.17732 -5.911596) (xy 367.17732 -5.912104)
			(xy 367.178918 -5.919624) (xy 367.185891 -5.933316) (xy 367.191036 -5.939028) (xy 367.20399 -5.951982)
			(xy 367.210848 -5.955538) (xy 367.234931 -5.968929) (xy 367.279318 -6.001579) (xy 367.31855 -6.040271)
			(xy 367.351813 -6.084201) (xy 367.378414 -6.132457) (xy 367.397801 -6.184035) (xy 367.409572 -6.237866)
			(xy 367.413482 -6.292829) (xy 367.409449 -6.347783) (xy 367.397557 -6.401587) (xy 367.378054 -6.453122)
			(xy 367.351345 -6.501318) (xy 367.317984 -6.545174) (xy 367.278665 -6.583777) (xy 367.234204 -6.616327)
			(xy 367.210086 -6.629654) (xy 367.204244 -6.632702) (xy 367.192814 -6.642862) (xy 367.19129 -6.644386)
			(xy 367.190782 -6.644894) (xy 367.189512 -6.646164) (xy 367.186015 -6.650271) (xy 367.180636 -6.659618)
			(xy 367.178844 -6.664706) (xy 367.178844 -6.66496) (xy 367.176558 -6.672072) (xy 367.176558 -6.71195)
			(xy 369.906548 -6.71195) (xy 369.910619 -6.656328) (xy 369.922745 -6.601891) (xy 369.942668 -6.5498)
			(xy 369.969964 -6.501165) (xy 370.00405 -6.457022) (xy 370.044199 -6.418313) (xy 370.089557 -6.385862)
			(xy 370.139157 -6.360361) (xy 370.191941 -6.342354) (xy 370.246784 -6.332224) (xy 370.302518 -6.330187)
			(xy 370.357955 -6.336287) (xy 370.411912 -6.350393) (xy 370.463241 -6.372205) (xy 370.510847 -6.401259)
			(xy 370.553715 -6.436934) (xy 370.590932 -6.478471) (xy 370.621705 -6.524984) (xy 370.645377 -6.575481)
			(xy 370.661445 -6.628888) (xy 370.669565 -6.684064) (xy 370.670074 -6.71195) (xy 370.669565 -6.739836)
			(xy 370.661445 -6.795012) (xy 370.645377 -6.848419) (xy 370.621705 -6.898916) (xy 370.590932 -6.945429)
			(xy 370.553715 -6.986966) (xy 370.510847 -7.022641) (xy 370.463241 -7.051695) (xy 370.411912 -7.073507)
			(xy 370.357955 -7.087613) (xy 370.302518 -7.093713) (xy 370.246784 -7.091676) (xy 370.191941 -7.081546)
			(xy 370.139157 -7.063539) (xy 370.089557 -7.038038) (xy 370.044199 -7.005587) (xy 370.00405 -6.966878)
			(xy 369.969964 -6.922735) (xy 369.942668 -6.8741) (xy 369.922745 -6.822009) (xy 369.910619 -6.767572)
			(xy 369.906548 -6.71195) (xy 367.176558 -6.71195) (xy 367.176558 -7.473696) (xy 378.034548 -7.473696)
			(xy 378.038619 -7.418074) (xy 378.050745 -7.363637) (xy 378.070668 -7.311546) (xy 378.097964 -7.262911)
			(xy 378.13205 -7.218768) (xy 378.172199 -7.180059) (xy 378.217557 -7.147608) (xy 378.267157 -7.122107)
			(xy 378.319941 -7.1041) (xy 378.374784 -7.09397) (xy 378.430518 -7.091933) (xy 378.485955 -7.098033)
			(xy 378.539912 -7.112139) (xy 378.591241 -7.133951) (xy 378.638847 -7.163005) (xy 378.681715 -7.19868)
			(xy 378.718932 -7.240217) (xy 378.749705 -7.28673) (xy 378.773377 -7.337227) (xy 378.789445 -7.390634)
			(xy 378.797565 -7.44581) (xy 378.798074 -7.473696) (xy 378.797565 -7.501582) (xy 378.789445 -7.556758)
			(xy 378.773377 -7.610165) (xy 378.749705 -7.660662) (xy 378.718932 -7.707175) (xy 378.681715 -7.748712)
			(xy 378.638847 -7.784387) (xy 378.591241 -7.813441) (xy 378.539912 -7.835253) (xy 378.485955 -7.849359)
			(xy 378.430518 -7.855459) (xy 378.374784 -7.853422) (xy 378.319941 -7.843292) (xy 378.267157 -7.825285)
			(xy 378.217557 -7.799784) (xy 378.172199 -7.767333) (xy 378.13205 -7.728624) (xy 378.097964 -7.684481)
			(xy 378.070668 -7.635846) (xy 378.050745 -7.583755) (xy 378.038619 -7.529318) (xy 378.034548 -7.473696)
			(xy 367.176558 -7.473696) (xy 367.176558 -8.005572) (xy 369.78412 -8.005572) (xy 369.788191 -7.94995)
			(xy 369.800317 -7.895513) (xy 369.82024 -7.843422) (xy 369.847536 -7.794787) (xy 369.881622 -7.750644)
			(xy 369.921771 -7.711935) (xy 369.967129 -7.679484) (xy 370.016729 -7.653983) (xy 370.069513 -7.635976)
			(xy 370.124356 -7.625846) (xy 370.18009 -7.623809) (xy 370.235527 -7.629909) (xy 370.289484 -7.644015)
			(xy 370.340813 -7.665827) (xy 370.388419 -7.694881) (xy 370.431287 -7.730556) (xy 370.468504 -7.772093)
			(xy 370.499277 -7.818606) (xy 370.522949 -7.869103) (xy 370.527708 -7.884922) (xy 380.267716 -7.884922)
			(xy 380.271787 -7.8293) (xy 380.283913 -7.774863) (xy 380.303836 -7.722772) (xy 380.331132 -7.674137)
			(xy 380.365218 -7.629994) (xy 380.405367 -7.591285) (xy 380.450725 -7.558834) (xy 380.500325 -7.533333)
			(xy 380.553109 -7.515326) (xy 380.607952 -7.505196) (xy 380.663686 -7.503159) (xy 380.719123 -7.509259)
			(xy 380.77308 -7.523365) (xy 380.824409 -7.545177) (xy 380.872015 -7.574231) (xy 380.914883 -7.609906)
			(xy 380.9521 -7.651443) (xy 380.982873 -7.697956) (xy 381.006545 -7.748453) (xy 381.022613 -7.80186)
			(xy 381.030733 -7.857036) (xy 381.031242 -7.884922) (xy 381.030733 -7.912808) (xy 381.022613 -7.967984)
			(xy 381.006545 -8.021391) (xy 380.982873 -8.071888) (xy 380.9521 -8.118401) (xy 380.914883 -8.159938)
			(xy 380.872015 -8.195613) (xy 380.824409 -8.224667) (xy 380.77308 -8.246479) (xy 380.719123 -8.260585)
			(xy 380.663686 -8.266685) (xy 380.607952 -8.264648) (xy 380.553109 -8.254518) (xy 380.500325 -8.236511)
			(xy 380.450725 -8.21101) (xy 380.405367 -8.178559) (xy 380.365218 -8.13985) (xy 380.331132 -8.095707)
			(xy 380.303836 -8.047072) (xy 380.283913 -7.994981) (xy 380.271787 -7.940544) (xy 380.267716 -7.884922)
			(xy 370.527708 -7.884922) (xy 370.539017 -7.92251) (xy 370.547137 -7.977686) (xy 370.547646 -8.005572)
			(xy 370.547137 -8.033458) (xy 370.539017 -8.088634) (xy 370.522949 -8.142041) (xy 370.499277 -8.192538)
			(xy 370.468504 -8.239051) (xy 370.431287 -8.280588) (xy 370.388419 -8.316263) (xy 370.340813 -8.345317)
			(xy 370.289484 -8.367129) (xy 370.235527 -8.381235) (xy 370.18009 -8.387335) (xy 370.124356 -8.385298)
			(xy 370.069513 -8.375168) (xy 370.016729 -8.357161) (xy 369.967129 -8.33166) (xy 369.921771 -8.299209)
			(xy 369.881622 -8.2605) (xy 369.847536 -8.216357) (xy 369.82024 -8.167722) (xy 369.800317 -8.115631)
			(xy 369.788191 -8.061194) (xy 369.78412 -8.005572) (xy 367.176558 -8.005572) (xy 367.176558 -8.72115)
			(xy 367.83899 -8.72115) (xy 367.83899 -8.66665) (xy 367.846746 -8.612705) (xy 367.8621 -8.560413)
			(xy 367.88474 -8.510838) (xy 367.914204 -8.464989) (xy 367.949894 -8.423801) (xy 367.991081 -8.38811)
			(xy 368.036929 -8.358645) (xy 368.086503 -8.336004) (xy 368.138795 -8.320648) (xy 368.19274 -8.312891)
			(xy 368.21999 -8.312404) (xy 368.247564 -8.312875) (xy 368.302137 -8.320826) (xy 368.354997 -8.33655)
			(xy 368.405043 -8.359719) (xy 368.451233 -8.389851) (xy 368.492604 -8.426317) (xy 368.51082 -8.447024)
			(xy 368.51989 -8.456921) (xy 368.54202 -8.472092) (xy 368.567338 -8.480975) (xy 368.594096 -8.482959)
			(xy 368.620447 -8.477904) (xy 368.644572 -8.466161) (xy 368.664807 -8.448541) (xy 368.672618 -8.437626)
			(xy 368.687907 -8.415612) (xy 368.723579 -8.375614) (xy 368.764497 -8.341) (xy 368.809855 -8.312452)
			(xy 368.858762 -8.290531) (xy 368.910255 -8.27567) (xy 368.963321 -8.268159) (xy 368.990118 -8.2677)
			(xy 369.017369 -8.268171) (xy 369.071316 -8.27593) (xy 369.12361 -8.291287) (xy 369.173186 -8.313929)
			(xy 369.219035 -8.343397) (xy 369.260224 -8.379089) (xy 369.295914 -8.42028) (xy 369.325379 -8.46613)
			(xy 369.34802 -8.515707) (xy 369.363374 -8.568002) (xy 369.37113 -8.621949) (xy 369.37113 -8.676451)
			(xy 369.363374 -8.730398) (xy 369.34802 -8.782693) (xy 369.325379 -8.83227) (xy 369.295914 -8.87812)
			(xy 369.260224 -8.919311) (xy 369.219035 -8.955003) (xy 369.173186 -8.984471) (xy 369.12361 -9.007113)
			(xy 369.071316 -9.02247) (xy 369.017369 -9.030229) (xy 368.990118 -9.030716) (xy 368.962544 -9.030232)
			(xy 368.907972 -9.022283) (xy 368.855113 -9.006561) (xy 368.805067 -8.983394) (xy 368.758877 -8.953265)
			(xy 368.717505 -8.916801) (xy 368.699288 -8.896096) (xy 368.69032 -8.886099) (xy 368.668165 -8.870927)
			(xy 368.642823 -8.86205) (xy 368.616044 -8.86008) (xy 368.589676 -8.865153) (xy 368.565539 -8.876919)
			(xy 368.5453 -8.894566) (xy 368.53749 -8.905494) (xy 368.522266 -8.927555) (xy 368.486583 -8.967552)
			(xy 368.445653 -9.002161) (xy 368.400284 -9.030704) (xy 368.351366 -9.052616) (xy 368.299864 -9.067468)
			(xy 368.24679 -9.074967) (xy 368.21999 -9.07542) (xy 368.19274 -9.074909) (xy 368.138795 -9.067152)
			(xy 368.086503 -9.051796) (xy 368.036929 -9.029155) (xy 367.991081 -8.99969) (xy 367.949894 -8.963999)
			(xy 367.914204 -8.922811) (xy 367.88474 -8.876962) (xy 367.8621 -8.827387) (xy 367.846746 -8.775095)
			(xy 367.83899 -8.72115) (xy 367.176558 -8.72115) (xy 367.176558 -10.35812) (xy 375.53087 -10.35812)
			(xy 375.534941 -10.302498) (xy 375.547067 -10.248061) (xy 375.56699 -10.19597) (xy 375.594286 -10.147335)
			(xy 375.628372 -10.103192) (xy 375.668521 -10.064483) (xy 375.713879 -10.032032) (xy 375.763479 -10.006531)
			(xy 375.816263 -9.988524) (xy 375.871106 -9.978394) (xy 375.92684 -9.976357) (xy 375.982277 -9.982457)
			(xy 376.036234 -9.996563) (xy 376.087563 -10.018375) (xy 376.135169 -10.047429) (xy 376.178037 -10.083104)
			(xy 376.215254 -10.124641) (xy 376.246027 -10.171154) (xy 376.269699 -10.221651) (xy 376.285767 -10.275058)
			(xy 376.293887 -10.330234) (xy 376.294396 -10.35812) (xy 376.293887 -10.386006) (xy 376.285767 -10.441182)
			(xy 376.269699 -10.494589) (xy 376.246027 -10.545086) (xy 376.215254 -10.591599) (xy 376.178037 -10.633136)
			(xy 376.135169 -10.668811) (xy 376.087563 -10.697865) (xy 376.036234 -10.719677) (xy 375.982277 -10.733783)
			(xy 375.92684 -10.739883) (xy 375.871106 -10.737846) (xy 375.816263 -10.727716) (xy 375.763479 -10.709709)
			(xy 375.713879 -10.684208) (xy 375.668521 -10.651757) (xy 375.628372 -10.613048) (xy 375.594286 -10.568905)
			(xy 375.56699 -10.52027) (xy 375.547067 -10.468179) (xy 375.534941 -10.413742) (xy 375.53087 -10.35812)
			(xy 367.176558 -10.35812) (xy 367.176558 -10.954512) (xy 369.191284 -10.954512) (xy 369.195355 -10.89889)
			(xy 369.207481 -10.844453) (xy 369.227404 -10.792362) (xy 369.2547 -10.743727) (xy 369.288786 -10.699584)
			(xy 369.328935 -10.660875) (xy 369.374293 -10.628424) (xy 369.423893 -10.602923) (xy 369.476677 -10.584916)
			(xy 369.53152 -10.574786) (xy 369.587254 -10.572749) (xy 369.642691 -10.578849) (xy 369.696648 -10.592955)
			(xy 369.747977 -10.614767) (xy 369.795583 -10.643821) (xy 369.838451 -10.679496) (xy 369.875668 -10.721033)
			(xy 369.906441 -10.767546) (xy 369.930113 -10.818043) (xy 369.946181 -10.87145) (xy 369.954301 -10.926626)
			(xy 369.95481 -10.954512) (xy 369.954301 -10.982398) (xy 369.946181 -11.037574) (xy 369.930113 -11.090981)
			(xy 369.906441 -11.141478) (xy 369.875668 -11.187991) (xy 369.838451 -11.229528) (xy 369.795583 -11.265203)
			(xy 369.747977 -11.294257) (xy 369.696648 -11.316069) (xy 369.642691 -11.330175) (xy 369.587254 -11.336275)
			(xy 369.53152 -11.334238) (xy 369.476677 -11.324108) (xy 369.423893 -11.306101) (xy 369.374293 -11.2806)
			(xy 369.328935 -11.248149) (xy 369.288786 -11.20944) (xy 369.2547 -11.165297) (xy 369.227404 -11.116662)
			(xy 369.207481 -11.064571) (xy 369.195355 -11.010134) (xy 369.191284 -10.954512) (xy 367.176558 -10.954512)
			(xy 367.176558 -10.983468) (xy 367.17732 -10.991596) (xy 367.17732 -10.992104) (xy 367.178918 -10.999624)
			(xy 367.185891 -11.013316) (xy 367.191036 -11.019028) (xy 367.20399 -11.031982) (xy 367.210848 -11.035538)
			(xy 367.234931 -11.048929) (xy 367.279318 -11.081579) (xy 367.31855 -11.120271) (xy 367.351813 -11.164201)
			(xy 367.378414 -11.212457) (xy 367.397801 -11.264035) (xy 367.409572 -11.317866) (xy 367.413482 -11.372829)
			(xy 367.409449 -11.427783) (xy 367.397557 -11.481587) (xy 367.378054 -11.533122) (xy 367.351345 -11.581318)
			(xy 367.317984 -11.625174) (xy 367.278665 -11.663777) (xy 367.234204 -11.696327) (xy 367.210086 -11.709654)
			(xy 367.204244 -11.712702) (xy 367.192814 -11.722862) (xy 367.19129 -11.724386) (xy 367.190782 -11.724894)
			(xy 367.189512 -11.726164) (xy 367.186015 -11.730271) (xy 367.180636 -11.739618) (xy 367.178844 -11.744706)
			(xy 367.178844 -11.74496) (xy 367.176558 -11.752072) (xy 367.176558 -13.486638) (xy 367.177026 -13.497292)
			(xy 367.185726 -13.516742) (xy 367.193322 -13.52423) (xy 367.19855 -13.528667) (xy 367.210776 -13.534862)
			(xy 367.217452 -13.536422) (xy 367.220246 -13.53693) (xy 367.285848 -13.546761) (xy 367.415784 -13.573528)
			(xy 367.543806 -13.608317) (xy 367.669419 -13.650992) (xy 367.792138 -13.701389) (xy 367.911489 -13.759313)
			(xy 368.027011 -13.824541) (xy 368.138257 -13.896819) (xy 368.244797 -13.97587) (xy 368.34622 -14.061388)
			(xy 368.386943 -14.100302) (xy 373.543066 -14.100302) (xy 373.547137 -14.04468) (xy 373.559263 -13.990243)
			(xy 373.579186 -13.938152) (xy 373.606482 -13.889517) (xy 373.640568 -13.845374) (xy 373.680717 -13.806665)
			(xy 373.726075 -13.774214) (xy 373.775675 -13.748713) (xy 373.828459 -13.730706) (xy 373.883302 -13.720576)
			(xy 373.939036 -13.718539) (xy 373.994473 -13.724639) (xy 374.04843 -13.738745) (xy 374.099759 -13.760557)
			(xy 374.147365 -13.789611) (xy 374.190233 -13.825286) (xy 374.22745 -13.866823) (xy 374.258223 -13.913336)
			(xy 374.281895 -13.963833) (xy 374.297963 -14.01724) (xy 374.306083 -14.072416) (xy 374.306592 -14.100302)
			(xy 374.306083 -14.128188) (xy 374.297963 -14.183364) (xy 374.281895 -14.236771) (xy 374.258223 -14.287268)
			(xy 374.22745 -14.333781) (xy 374.190233 -14.375318) (xy 374.147365 -14.410993) (xy 374.099759 -14.440047)
			(xy 374.04843 -14.461859) (xy 373.994473 -14.475965) (xy 373.939036 -14.482065) (xy 373.883302 -14.480028)
			(xy 373.828459 -14.469898) (xy 373.775675 -14.451891) (xy 373.726075 -14.42639) (xy 373.680717 -14.393939)
			(xy 373.640568 -14.35523) (xy 373.606482 -14.311087) (xy 373.579186 -14.262452) (xy 373.559263 -14.210361)
			(xy 373.547137 -14.155924) (xy 373.543066 -14.100302) (xy 368.386943 -14.100302) (xy 368.442134 -14.153041)
			(xy 368.532168 -14.250477) (xy 368.615975 -14.353318) (xy 368.693231 -14.461167) (xy 368.763636 -14.573608)
			(xy 368.82692 -14.690205) (xy 368.882837 -14.81051) (xy 368.931172 -14.934056) (xy 368.971737 -15.060366)
			(xy 369.004377 -15.188953) (xy 369.028965 -15.319319) (xy 369.038735 -15.39755) (xy 374.20448 -15.39755)
			(xy 374.20448 -15.34305) (xy 374.212236 -15.289104) (xy 374.22759 -15.23681) (xy 374.25023 -15.187234)
			(xy 374.279695 -15.141385) (xy 374.315384 -15.100195) (xy 374.356572 -15.064504) (xy 374.40242 -15.035038)
			(xy 374.451995 -15.012396) (xy 374.504288 -14.997039) (xy 374.558234 -14.989281) (xy 374.585484 -14.988794)
			(xy 374.611719 -14.989264) (xy 374.663695 -14.996457) (xy 374.714193 -15.01071) (xy 374.762259 -15.031752)
			(xy 374.806986 -15.059187) (xy 374.847529 -15.092496) (xy 374.865646 -15.111476) (xy 374.8659 -15.11173)
			(xy 374.873617 -15.119131) (xy 374.893312 -15.127394) (xy 374.904 -15.127732) (xy 374.991884 -15.125446)
			(xy 375.011442 -15.116048) (xy 375.018554 -15.107412) (xy 375.036763 -15.08626) (xy 375.078304 -15.048985)
			(xy 375.124834 -15.018164) (xy 375.175359 -14.994453) (xy 375.228801 -14.97836) (xy 375.284018 -14.970229)
			(xy 375.311924 -14.969744) (xy 375.339171 -14.970328) (xy 375.393109 -14.978086) (xy 375.445394 -14.993441)
			(xy 375.494962 -15.016081) (xy 375.540804 -15.045544) (xy 375.581986 -15.081231) (xy 375.61767 -15.122416)
			(xy 375.647131 -15.168259) (xy 375.669767 -15.217828) (xy 375.685119 -15.270115) (xy 375.692874 -15.324053)
			(xy 375.692874 -15.378547) (xy 375.685119 -15.432485) (xy 375.669767 -15.484772) (xy 375.647131 -15.534341)
			(xy 375.61767 -15.580184) (xy 375.581986 -15.621369) (xy 375.540804 -15.657056) (xy 375.494962 -15.686519)
			(xy 375.445394 -15.709159) (xy 375.393109 -15.724514) (xy 375.339171 -15.732272) (xy 375.311924 -15.73276)
			(xy 375.285688 -15.732299) (xy 375.233712 -15.725106) (xy 375.183213 -15.710853) (xy 375.135146 -15.689809)
			(xy 375.090419 -15.662372) (xy 375.049878 -15.62906) (xy 375.031762 -15.610078) (xy 375.031508 -15.609824)
			(xy 375.023794 -15.60242) (xy 375.004096 -15.59416) (xy 374.993408 -15.593822) (xy 374.905524 -15.596108)
			(xy 374.885966 -15.605506) (xy 374.878854 -15.614142) (xy 374.86063 -15.635281) (xy 374.819094 -15.672558)
			(xy 374.772567 -15.703383) (xy 374.722044 -15.727096) (xy 374.668605 -15.743191) (xy 374.613389 -15.751325)
			(xy 374.585484 -15.75181) (xy 374.558234 -15.751319) (xy 374.504288 -15.743561) (xy 374.451995 -15.728204)
			(xy 374.40242 -15.705562) (xy 374.356572 -15.676096) (xy 374.315384 -15.640405) (xy 374.279695 -15.599215)
			(xy 374.25023 -15.553366) (xy 374.22759 -15.50379) (xy 374.212236 -15.451496) (xy 374.20448 -15.39755)
			(xy 369.038735 -15.39755) (xy 369.045405 -15.450961) (xy 369.053635 -15.58337) (xy 369.054126 -15.649702)
			(xy 369.054126 -15.649956) (xy 369.05362 -15.715692) (xy 369.045527 -15.846913) (xy 369.02937 -15.977388)
			(xy 369.005213 -16.106621) (xy 368.973145 -16.234121) (xy 368.933289 -16.359405) (xy 368.885796 -16.481999)
			(xy 368.830847 -16.601436) (xy 368.768648 -16.717263) (xy 368.699438 -16.829042) (xy 368.623477 -16.936349)
			(xy 368.596403 -16.969994) (xy 388.048253 -16.969994) (xy 388.052258 -16.882086) (xy 388.064241 -16.794906)
			(xy 388.084101 -16.709177) (xy 388.111676 -16.625609) (xy 388.146735 -16.544895) (xy 388.188988 -16.467703)
			(xy 388.238086 -16.394674) (xy 388.293622 -16.326412) (xy 388.355134 -16.263482) (xy 388.422115 -16.206408)
			(xy 388.494008 -16.15566) (xy 388.570217 -16.11166) (xy 388.650112 -16.074773) (xy 388.733031 -16.045304)
			(xy 388.818286 -16.023497) (xy 388.90517 -16.009533) (xy 388.992964 -16.003527) (xy 389.080941 -16.005531)
			(xy 389.168371 -16.015526) (xy 389.25453 -16.03343) (xy 389.338704 -16.059094) (xy 389.420195 -16.092307)
			(xy 389.498329 -16.132793) (xy 389.572457 -16.180215) (xy 389.641965 -16.234182) (xy 389.706279 -16.294247)
			(xy 389.764863 -16.359911) (xy 389.817234 -16.43063) (xy 389.862957 -16.505818) (xy 389.901654 -16.584853)
			(xy 389.933003 -16.667079) (xy 389.956745 -16.751815) (xy 389.972683 -16.838359) (xy 389.980685 -16.925994)
			(xy 389.981186 -16.969994) (xy 389.980685 -17.013994) (xy 389.972683 -17.101629) (xy 389.956745 -17.188173)
			(xy 389.933003 -17.272909) (xy 389.901654 -17.355135) (xy 389.862957 -17.43417) (xy 389.817234 -17.509358)
			(xy 389.764863 -17.580077) (xy 389.706279 -17.645741) (xy 389.641965 -17.705806) (xy 389.572457 -17.759773)
			(xy 389.498329 -17.807195) (xy 389.420195 -17.847681) (xy 389.338704 -17.880894) (xy 389.25453 -17.906558)
			(xy 389.168371 -17.924462) (xy 389.080941 -17.934457) (xy 388.992964 -17.936461) (xy 388.90517 -17.930455)
			(xy 388.818286 -17.916491) (xy 388.733031 -17.894684) (xy 388.650112 -17.865215) (xy 388.570217 -17.828328)
			(xy 388.494008 -17.784328) (xy 388.422115 -17.73358) (xy 388.355134 -17.676506) (xy 388.293622 -17.613576)
			(xy 388.238086 -17.545314) (xy 388.188988 -17.472285) (xy 388.146735 -17.395093) (xy 388.111676 -17.314379)
			(xy 388.084101 -17.230811) (xy 388.064241 -17.145082) (xy 388.052258 -17.057902) (xy 388.048253 -16.969994)
			(xy 368.596403 -16.969994) (xy 368.541055 -17.038775) (xy 368.452483 -17.135934) (xy 368.358098 -17.227455)
			(xy 368.258259 -17.312993) (xy 368.153342 -17.392222) (xy 368.112064 -17.419574) (xy 372.584216 -17.419574)
			(xy 372.588287 -17.363952) (xy 372.600413 -17.309515) (xy 372.620336 -17.257424) (xy 372.647632 -17.208789)
			(xy 372.681718 -17.164646) (xy 372.721867 -17.125937) (xy 372.767225 -17.093486) (xy 372.816825 -17.067985)
			(xy 372.869609 -17.049978) (xy 372.924452 -17.039848) (xy 372.980186 -17.037811) (xy 373.035623 -17.043911)
			(xy 373.08958 -17.058017) (xy 373.140909 -17.079829) (xy 373.188515 -17.108883) (xy 373.231383 -17.144558)
			(xy 373.2686 -17.186095) (xy 373.299373 -17.232608) (xy 373.323045 -17.283105) (xy 373.339113 -17.336512)
			(xy 373.347233 -17.391688) (xy 373.347742 -17.419574) (xy 373.347233 -17.44746) (xy 373.339113 -17.502636)
			(xy 373.323045 -17.556043) (xy 373.299373 -17.60654) (xy 373.2686 -17.653053) (xy 373.231383 -17.69459)
			(xy 373.188515 -17.730265) (xy 373.140909 -17.759319) (xy 373.08958 -17.781131) (xy 373.035623 -17.795237)
			(xy 372.980186 -17.801337) (xy 372.924452 -17.7993) (xy 372.869609 -17.78917) (xy 372.816825 -17.771163)
			(xy 372.767225 -17.745662) (xy 372.721867 -17.713211) (xy 372.681718 -17.674502) (xy 372.647632 -17.630359)
			(xy 372.620336 -17.581724) (xy 372.600413 -17.529633) (xy 372.588287 -17.475196) (xy 372.584216 -17.419574)
			(xy 368.112064 -17.419574) (xy 368.043748 -17.464842) (xy 367.92989 -17.530577) (xy 367.812202 -17.589179)
			(xy 367.69113 -17.640425) (xy 367.567132 -17.68412) (xy 367.44068 -17.720099) (xy 367.312252 -17.748225)
			(xy 367.182337 -17.768391) (xy 367.051427 -17.780522) (xy 366.920018 -17.784571) (xy 366.788609 -17.780522)
			(xy 366.657699 -17.768391) (xy 366.527784 -17.748225) (xy 366.399356 -17.720099) (xy 366.272904 -17.68412)
			(xy 366.148906 -17.640425) (xy 366.027834 -17.589179) (xy 365.910146 -17.530577) (xy 365.796288 -17.464842)
			(xy 365.686694 -17.392222) (xy 365.581777 -17.312993) (xy 365.481938 -17.227455) (xy 365.387553 -17.135934)
			(xy 365.298981 -17.038775) (xy 365.216559 -16.936349) (xy 365.140598 -16.829042) (xy 365.071388 -16.717263)
			(xy 365.009189 -16.601436) (xy 364.95424 -16.481999) (xy 364.906747 -16.359405) (xy 364.866891 -16.234121)
			(xy 364.834823 -16.106621) (xy 364.810666 -15.977388) (xy 364.794509 -15.846913) (xy 364.786416 -15.715692)
			(xy 364.78591 -15.649956) (xy 364.78591 -15.649702) (xy 364.786383 -15.585782) (xy 364.794042 -15.458171)
			(xy 364.809326 -15.331248) (xy 364.832181 -15.205467) (xy 364.862525 -15.08128) (xy 364.900248 -14.959132)
			(xy 364.945216 -14.839461) (xy 364.997268 -14.722697) (xy 365.056216 -14.609259) (xy 365.121848 -14.499552)
			(xy 365.157512 -14.446504) (xy 365.170212 -14.427708) (xy 365.171228 -14.426184) (xy 365.180626 -14.413484)
			(xy 365.180626 -14.412976) (xy 365.199676 -14.38656) (xy 365.200184 -14.386052) (xy 365.22025 -14.357604)
			(xy 365.256485 -14.310793) (xy 365.333414 -14.220805) (xy 365.415216 -14.135222) (xy 365.50164 -14.054309)
			(xy 365.592419 -13.978314) (xy 365.639604 -13.942568) (xy 365.678466 -13.91412) (xy 365.679228 -13.913612)
			(xy 365.679736 -13.913358) (xy 365.682022 -13.91158) (xy 365.688626 -13.904976) (xy 365.69486 -13.898101)
			(xy 365.70239 -13.881154) (xy 365.703447 -13.86264) (xy 365.701072 -13.853668) (xy 365.686594 -13.808202)
			(xy 365.686594 -13.807694) (xy 365.677958 -13.781024) (xy 365.677958 -13.780516) (xy 365.672624 -13.764514)
			(xy 365.669165 -13.753467) (xy 365.654115 -13.735911) (xy 365.632893 -13.726725) (xy 365.621316 -13.726668)
			(xy 365.021368 -13.726668) (xy 365.011362 -13.727161) (xy 364.992876 -13.734825) (xy 364.978725 -13.748976)
			(xy 364.971061 -13.767462) (xy 364.970568 -13.777468) (xy 364.970568 -13.85443) (xy 364.970139 -13.864497)
			(xy 364.962413 -13.883091) (xy 364.955582 -13.890498) (xy 364.741206 -14.104874) (xy 364.733809 -14.111724)
			(xy 364.715211 -14.119465) (xy 364.705138 -14.11986) (xy 357.26497 -14.11986) (xy 357.199017 -14.119369)
			(xy 357.067336 -14.111682) (xy 356.936324 -14.096359) (xy 356.806423 -14.073452) (xy 356.678071 -14.043037)
			(xy 356.551704 -14.005218) (xy 356.427746 -13.960123) (xy 356.306617 -13.907904) (xy 356.188726 -13.848736)
			(xy 356.074471 -13.782821) (xy 356.0191 -13.746988) (xy 356.01783 -13.746226) (xy 356.007924 -13.740638)
			(xy 356.002659 -13.738195) (xy 355.991373 -13.735492) (xy 355.985572 -13.735304) (xy 355.715824 -13.735304)
			(xy 355.710591 -13.735142) (xy 355.700355 -13.732957) (xy 355.695504 -13.730986) (xy 355.685598 -13.726668)
			(xy 354.43033 -13.726668) (xy 354.420307 -13.726253) (xy 354.401785 -13.718587) (xy 354.387612 -13.704413)
			(xy 354.379947 -13.685891) (xy 354.37953 -13.675868) (xy 354.37953 -2.119376) (xy 354.37921 -2.111096)
			(xy 354.373895 -2.095412) (xy 354.369116 -2.088642) (xy 354.367084 -2.086356) (xy 354.365306 -2.084578)
			(xy 354.362004 -2.080768) (xy 354.097082 -1.815846) (xy 354.09335 -1.812327) (xy 354.084774 -1.806702)
			(xy 354.080064 -1.80467) (xy 354.071428 -1.801114) (xy 330.19238 -1.801114) (xy 330.1841 -1.801435)
			(xy 330.168418 -1.806752) (xy 330.161646 -1.811528) (xy 330.15936 -1.81356) (xy 330.157582 -1.815338)
			(xy 330.153772 -1.81864) (xy 329.611736 -2.360676) (xy 329.608209 -2.364403) (xy 329.602569 -2.372973)
			(xy 329.60056 -2.377694) (xy 329.597004 -2.38633) (xy 329.597004 -5.776468) (xy 335.944462 -5.776468)
			(xy 335.948533 -5.720846) (xy 335.960659 -5.666409) (xy 335.980582 -5.614318) (xy 336.007878 -5.565683)
			(xy 336.041964 -5.52154) (xy 336.082113 -5.482831) (xy 336.127471 -5.45038) (xy 336.177071 -5.424879)
			(xy 336.229855 -5.406872) (xy 336.284698 -5.396742) (xy 336.340432 -5.394705) (xy 336.395869 -5.400805)
			(xy 336.449826 -5.414911) (xy 336.501155 -5.436723) (xy 336.548761 -5.465777) (xy 336.591629 -5.501452)
			(xy 336.628846 -5.542989) (xy 336.659619 -5.589502) (xy 336.683291 -5.639999) (xy 336.699359 -5.693406)
			(xy 336.707284 -5.747258) (xy 339.126066 -5.747258) (xy 339.130137 -5.691636) (xy 339.142263 -5.637199)
			(xy 339.162186 -5.585108) (xy 339.189482 -5.536473) (xy 339.223568 -5.49233) (xy 339.263717 -5.453621)
			(xy 339.309075 -5.42117) (xy 339.358675 -5.395669) (xy 339.411459 -5.377662) (xy 339.466302 -5.367532)
			(xy 339.522036 -5.365495) (xy 339.577473 -5.371595) (xy 339.63143 -5.385701) (xy 339.682759 -5.407513)
			(xy 339.730365 -5.436567) (xy 339.773233 -5.472242) (xy 339.81045 -5.513779) (xy 339.841223 -5.560292)
			(xy 339.864895 -5.610789) (xy 339.880963 -5.664196) (xy 339.889083 -5.719372) (xy 339.889592 -5.747258)
			(xy 339.889083 -5.775144) (xy 339.880963 -5.83032) (xy 339.864895 -5.883727) (xy 339.841223 -5.934224)
			(xy 339.81045 -5.980737) (xy 339.773233 -6.022274) (xy 339.730365 -6.057949) (xy 339.682759 -6.087003)
			(xy 339.63143 -6.108815) (xy 339.577473 -6.122921) (xy 339.522036 -6.129021) (xy 339.466302 -6.126984)
			(xy 339.411459 -6.116854) (xy 339.358675 -6.098847) (xy 339.309075 -6.073346) (xy 339.263717 -6.040895)
			(xy 339.223568 -6.002186) (xy 339.189482 -5.958043) (xy 339.162186 -5.909408) (xy 339.142263 -5.857317)
			(xy 339.130137 -5.80288) (xy 339.126066 -5.747258) (xy 336.707284 -5.747258) (xy 336.707479 -5.748582)
			(xy 336.707988 -5.776468) (xy 336.707479 -5.804354) (xy 336.699359 -5.85953) (xy 336.683291 -5.912937)
			(xy 336.659619 -5.963434) (xy 336.628846 -6.009947) (xy 336.591629 -6.051484) (xy 336.548761 -6.087159)
			(xy 336.501155 -6.116213) (xy 336.449826 -6.138025) (xy 336.395869 -6.152131) (xy 336.340432 -6.158231)
			(xy 336.284698 -6.156194) (xy 336.229855 -6.146064) (xy 336.177071 -6.128057) (xy 336.127471 -6.102556)
			(xy 336.082113 -6.070105) (xy 336.041964 -6.031396) (xy 336.007878 -5.987253) (xy 335.980582 -5.938618)
			(xy 335.960659 -5.886527) (xy 335.948533 -5.83209) (xy 335.944462 -5.776468) (xy 329.597004 -5.776468)
			(xy 329.597004 -6.68655) (xy 330.361288 -6.68655) (xy 330.365359 -6.630928) (xy 330.377485 -6.576491)
			(xy 330.397408 -6.5244) (xy 330.424704 -6.475765) (xy 330.45879 -6.431622) (xy 330.498939 -6.392913)
			(xy 330.544297 -6.360462) (xy 330.593897 -6.334961) (xy 330.646681 -6.316954) (xy 330.701524 -6.306824)
			(xy 330.757258 -6.304787) (xy 330.812695 -6.310887) (xy 330.866652 -6.324993) (xy 330.917981 -6.346805)
			(xy 330.965587 -6.375859) (xy 331.008455 -6.411534) (xy 331.045672 -6.453071) (xy 331.076445 -6.499584)
			(xy 331.100117 -6.550081) (xy 331.116185 -6.603488) (xy 331.124305 -6.658664) (xy 331.124814 -6.68655)
			(xy 331.124305 -6.714436) (xy 331.116185 -6.769612) (xy 331.100117 -6.823019) (xy 331.076445 -6.873516)
			(xy 331.045672 -6.920029) (xy 331.025465 -6.942582) (xy 337.010754 -6.942582) (xy 337.014825 -6.88696)
			(xy 337.026951 -6.832523) (xy 337.046874 -6.780432) (xy 337.07417 -6.731797) (xy 337.108256 -6.687654)
			(xy 337.148405 -6.648945) (xy 337.193763 -6.616494) (xy 337.243363 -6.590993) (xy 337.296147 -6.572986)
			(xy 337.35099 -6.562856) (xy 337.406724 -6.560819) (xy 337.462161 -6.566919) (xy 337.516118 -6.581025)
			(xy 337.567447 -6.602837) (xy 337.615053 -6.631891) (xy 337.657921 -6.667566) (xy 337.695138 -6.709103)
			(xy 337.715339 -6.739636) (xy 339.101936 -6.739636) (xy 339.106007 -6.684014) (xy 339.118133 -6.629577)
			(xy 339.138056 -6.577486) (xy 339.165352 -6.528851) (xy 339.199438 -6.484708) (xy 339.239587 -6.445999)
			(xy 339.284945 -6.413548) (xy 339.334545 -6.388047) (xy 339.387329 -6.37004) (xy 339.442172 -6.35991)
			(xy 339.497906 -6.357873) (xy 339.553343 -6.363973) (xy 339.6073 -6.378079) (xy 339.658629 -6.399891)
			(xy 339.706235 -6.428945) (xy 339.749103 -6.46462) (xy 339.78632 -6.506157) (xy 339.817093 -6.55267)
			(xy 339.840765 -6.603167) (xy 339.856833 -6.656574) (xy 339.864953 -6.71175) (xy 339.865462 -6.739636)
			(xy 339.864953 -6.767522) (xy 339.856833 -6.822698) (xy 339.840765 -6.876105) (xy 339.817093 -6.926602)
			(xy 339.78632 -6.973115) (xy 339.749103 -7.014652) (xy 339.706235 -7.050327) (xy 339.658629 -7.079381)
			(xy 339.6073 -7.101193) (xy 339.553343 -7.115299) (xy 339.497906 -7.121399) (xy 339.442172 -7.119362)
			(xy 339.387329 -7.109232) (xy 339.334545 -7.091225) (xy 339.284945 -7.065724) (xy 339.239587 -7.033273)
			(xy 339.199438 -6.994564) (xy 339.165352 -6.950421) (xy 339.138056 -6.901786) (xy 339.118133 -6.849695)
			(xy 339.106007 -6.795258) (xy 339.101936 -6.739636) (xy 337.715339 -6.739636) (xy 337.725911 -6.755616)
			(xy 337.749583 -6.806113) (xy 337.765651 -6.85952) (xy 337.773771 -6.914696) (xy 337.77428 -6.942582)
			(xy 337.773771 -6.970468) (xy 337.765651 -7.025644) (xy 337.749583 -7.079051) (xy 337.725911 -7.129548)
			(xy 337.695138 -7.176061) (xy 337.657921 -7.217598) (xy 337.615053 -7.253273) (xy 337.567447 -7.282327)
			(xy 337.516118 -7.304139) (xy 337.462161 -7.318245) (xy 337.406724 -7.324345) (xy 337.35099 -7.322308)
			(xy 337.296147 -7.312178) (xy 337.243363 -7.294171) (xy 337.193763 -7.26867) (xy 337.148405 -7.236219)
			(xy 337.108256 -7.19751) (xy 337.07417 -7.153367) (xy 337.046874 -7.104732) (xy 337.026951 -7.052641)
			(xy 337.014825 -6.998204) (xy 337.010754 -6.942582) (xy 331.025465 -6.942582) (xy 331.008455 -6.961566)
			(xy 330.965587 -6.997241) (xy 330.917981 -7.026295) (xy 330.866652 -7.048107) (xy 330.812695 -7.062213)
			(xy 330.757258 -7.068313) (xy 330.701524 -7.066276) (xy 330.646681 -7.056146) (xy 330.593897 -7.038139)
			(xy 330.544297 -7.012638) (xy 330.498939 -6.980187) (xy 330.45879 -6.941478) (xy 330.424704 -6.897335)
			(xy 330.397408 -6.8487) (xy 330.377485 -6.796609) (xy 330.365359 -6.742172) (xy 330.361288 -6.68655)
			(xy 329.597004 -6.68655) (xy 329.597004 -7.916672) (xy 330.525372 -7.916672) (xy 330.529443 -7.86105)
			(xy 330.541569 -7.806613) (xy 330.561492 -7.754522) (xy 330.588788 -7.705887) (xy 330.622874 -7.661744)
			(xy 330.663023 -7.623035) (xy 330.708381 -7.590584) (xy 330.757981 -7.565083) (xy 330.810765 -7.547076)
			(xy 330.865608 -7.536946) (xy 330.921342 -7.534909) (xy 330.976779 -7.541009) (xy 331.030736 -7.555115)
			(xy 331.082065 -7.576927) (xy 331.129671 -7.605981) (xy 331.172539 -7.641656) (xy 331.209756 -7.683193)
			(xy 331.240529 -7.729706) (xy 331.246612 -7.742682) (xy 339.120224 -7.742682) (xy 339.124295 -7.68706)
			(xy 339.136421 -7.632623) (xy 339.156344 -7.580532) (xy 339.18364 -7.531897) (xy 339.217726 -7.487754)
			(xy 339.257875 -7.449045) (xy 339.303233 -7.416594) (xy 339.352833 -7.391093) (xy 339.405617 -7.373086)
			(xy 339.46046 -7.362956) (xy 339.516194 -7.360919) (xy 339.571631 -7.367019) (xy 339.625588 -7.381125)
			(xy 339.676917 -7.402937) (xy 339.724523 -7.431991) (xy 339.767391 -7.467666) (xy 339.804608 -7.509203)
			(xy 339.835381 -7.555716) (xy 339.859053 -7.606213) (xy 339.875121 -7.65962) (xy 339.883241 -7.714796)
			(xy 339.88375 -7.742682) (xy 339.883241 -7.770568) (xy 339.875121 -7.825744) (xy 339.859053 -7.879151)
			(xy 339.835381 -7.929648) (xy 339.804608 -7.976161) (xy 339.767391 -8.017698) (xy 339.724523 -8.053373)
			(xy 339.676917 -8.082427) (xy 339.625588 -8.104239) (xy 339.571631 -8.118345) (xy 339.516194 -8.124445)
			(xy 339.46046 -8.122408) (xy 339.405617 -8.112278) (xy 339.352833 -8.094271) (xy 339.303233 -8.06877)
			(xy 339.257875 -8.036319) (xy 339.217726 -7.99761) (xy 339.18364 -7.953467) (xy 339.156344 -7.904832)
			(xy 339.136421 -7.852741) (xy 339.124295 -7.798304) (xy 339.120224 -7.742682) (xy 331.246612 -7.742682)
			(xy 331.264201 -7.780203) (xy 331.280269 -7.83361) (xy 331.288389 -7.888786) (xy 331.288898 -7.916672)
			(xy 331.288389 -7.944558) (xy 331.280269 -7.999734) (xy 331.264201 -8.053141) (xy 331.240529 -8.103638)
			(xy 331.209756 -8.150151) (xy 331.172539 -8.191688) (xy 331.129671 -8.227363) (xy 331.082065 -8.256417)
			(xy 331.079159 -8.257652) (xy 336.93174 -8.257652) (xy 336.93174 -8.203148) (xy 336.939496 -8.149198)
			(xy 336.954851 -8.096901) (xy 336.977491 -8.047321) (xy 337.006957 -8.001468) (xy 337.042648 -7.960275)
			(xy 337.083838 -7.92458) (xy 337.129688 -7.89511) (xy 337.179265 -7.872464) (xy 337.231561 -7.857104)
			(xy 337.28551 -7.849342) (xy 337.312762 -7.848854) (xy 337.340914 -7.849367) (xy 337.396609 -7.857623)
			(xy 337.450485 -7.873978) (xy 337.501372 -7.898075) (xy 337.548163 -7.929391) (xy 337.589843 -7.967245)
			(xy 337.625504 -8.010815) (xy 337.654374 -8.059155) (xy 337.675823 -8.111213) (xy 337.683094 -8.138414)
			(xy 337.687124 -8.152573) (xy 337.702124 -8.177891) (xy 337.723719 -8.197883) (xy 337.750117 -8.210889)
			(xy 337.779127 -8.215831) (xy 337.808343 -8.212299) (xy 337.835339 -8.200585) (xy 337.846924 -8.1915)
			(xy 337.867602 -8.174655) (xy 337.912819 -8.146369) (xy 337.961536 -8.12466) (xy 338.012804 -8.109952)
			(xy 338.06562 -8.102531) (xy 338.092288 -8.102092) (xy 338.092542 -8.102092) (xy 338.119791 -8.102581)
			(xy 338.173734 -8.110342) (xy 338.226024 -8.125701) (xy 338.275596 -8.148344) (xy 338.321441 -8.177812)
			(xy 338.362626 -8.213503) (xy 338.398313 -8.254692) (xy 338.427776 -8.300541) (xy 338.450414 -8.350115)
			(xy 338.465767 -8.402407) (xy 338.473522 -8.456351) (xy 338.473522 -8.510849) (xy 338.465767 -8.564793)
			(xy 338.450414 -8.617085) (xy 338.427776 -8.666659) (xy 338.398313 -8.712508) (xy 338.362626 -8.753697)
			(xy 338.321441 -8.789388) (xy 338.275596 -8.818856) (xy 338.226024 -8.841499) (xy 338.173734 -8.856858)
			(xy 338.119791 -8.864619) (xy 338.092542 -8.865108) (xy 338.064389 -8.864621) (xy 338.008691 -8.856363)
			(xy 337.954813 -8.840007) (xy 337.903924 -8.815908) (xy 337.857132 -8.784589) (xy 337.815453 -8.746731)
			(xy 337.779792 -8.703157) (xy 337.750925 -8.654813) (xy 337.729479 -8.602751) (xy 337.72221 -8.575548)
			(xy 337.718189 -8.561387) (xy 337.703183 -8.536074) (xy 337.681585 -8.516087) (xy 337.655187 -8.503084)
			(xy 337.626178 -8.498142) (xy 337.596964 -8.501671) (xy 337.569966 -8.51338) (xy 337.55838 -8.522462)
			(xy 337.537696 -8.539299) (xy 337.492481 -8.567588) (xy 337.443766 -8.589299) (xy 337.392499 -8.604009)
			(xy 337.339683 -8.61143) (xy 337.313016 -8.61187) (xy 337.312762 -8.61187) (xy 337.28551 -8.611458)
			(xy 337.231561 -8.603696) (xy 337.179265 -8.588336) (xy 337.129688 -8.56569) (xy 337.083838 -8.53622)
			(xy 337.042648 -8.500525) (xy 337.006957 -8.459332) (xy 336.977491 -8.413479) (xy 336.954851 -8.363899)
			(xy 336.939496 -8.311602) (xy 336.93174 -8.257652) (xy 331.079159 -8.257652) (xy 331.030736 -8.278229)
			(xy 330.976779 -8.292335) (xy 330.921342 -8.298435) (xy 330.865608 -8.296398) (xy 330.810765 -8.286268)
			(xy 330.757981 -8.268261) (xy 330.708381 -8.24276) (xy 330.663023 -8.210309) (xy 330.622874 -8.1716)
			(xy 330.588788 -8.127457) (xy 330.561492 -8.078822) (xy 330.541569 -8.026731) (xy 330.529443 -7.972294)
			(xy 330.525372 -7.916672) (xy 329.597004 -7.916672) (xy 329.597004 -8.12419) (xy 329.597766 -8.132826)
			(xy 329.599246 -8.140101) (xy 329.605839 -8.153394) (xy 329.61072 -8.158988) (xy 329.626214 -8.174736)
			(xy 329.626722 -8.175244) (xy 329.632056 -8.180832) (xy 329.632818 -8.181594) (xy 329.638639 -8.186979)
			(xy 329.652737 -8.194219) (xy 329.660504 -8.195818) (xy 329.664568 -8.196326) (xy 329.664822 -8.196326)
			(xy 329.665838 -8.19658) (xy 329.667108 -8.19658) (xy 329.696152 -8.199404) (xy 329.752958 -8.212751)
			(xy 329.807068 -8.234592) (xy 329.857223 -8.264416) (xy 329.902252 -8.301529) (xy 329.941105 -8.345065)
			(xy 329.972877 -8.394009) (xy 329.996827 -8.44722) (xy 330.012396 -8.503457) (xy 330.016358 -8.532368)
			(xy 330.018136 -8.548624) (xy 330.019152 -8.577072) (xy 330.018652 -8.605216) (xy 330.010393 -8.660895)
			(xy 329.99405 -8.714757) (xy 329.969977 -8.765638) (xy 329.938695 -8.812433) (xy 329.900882 -8.854128)
			(xy 329.857358 -8.889821) (xy 329.809066 -8.918738) (xy 329.757052 -8.940252) (xy 329.702443 -8.953898)
			(xy 329.674474 -8.957056) (xy 329.673458 -8.957056) (xy 329.670156 -8.957564) (xy 329.66152 -8.959596)
			(xy 329.655932 -8.960866) (xy 329.644248 -8.966454) (xy 329.640946 -8.968486) (xy 329.639422 -8.969248)
			(xy 329.631802 -8.97382) (xy 329.61453 -8.991346) (xy 329.614276 -8.991854) (xy 329.61072 -8.99541)
			(xy 329.607736 -8.998757) (xy 329.602886 -9.006297) (xy 329.601068 -9.010396) (xy 329.599199 -9.015136)
			(xy 329.597153 -9.025115) (xy 329.597004 -9.030208) (xy 329.597004 -9.535922) (xy 332.574644 -9.535922)
			(xy 332.578715 -9.4803) (xy 332.590841 -9.425863) (xy 332.610764 -9.373772) (xy 332.63806 -9.325137)
			(xy 332.672146 -9.280994) (xy 332.712295 -9.242285) (xy 332.757653 -9.209834) (xy 332.807253 -9.184333)
			(xy 332.860037 -9.166326) (xy 332.91488 -9.156196) (xy 332.970614 -9.154159) (xy 333.026051 -9.160259)
			(xy 333.080008 -9.174365) (xy 333.131337 -9.196177) (xy 333.178943 -9.225231) (xy 333.221811 -9.260906)
			(xy 333.259028 -9.302443) (xy 333.289801 -9.348956) (xy 333.313473 -9.399453) (xy 333.329541 -9.45286)
			(xy 333.337661 -9.508036) (xy 333.33811 -9.53262) (xy 335.622644 -9.53262) (xy 335.626715 -9.476998)
			(xy 335.638841 -9.422561) (xy 335.658764 -9.37047) (xy 335.68606 -9.321835) (xy 335.720146 -9.277692)
			(xy 335.760295 -9.238983) (xy 335.805653 -9.206532) (xy 335.855253 -9.181031) (xy 335.908037 -9.163024)
			(xy 335.96288 -9.152894) (xy 336.018614 -9.150857) (xy 336.074051 -9.156957) (xy 336.128008 -9.171063)
			(xy 336.179337 -9.192875) (xy 336.226943 -9.221929) (xy 336.269811 -9.257604) (xy 336.307028 -9.299141)
			(xy 336.337801 -9.345654) (xy 336.361473 -9.396151) (xy 336.377541 -9.449558) (xy 336.385661 -9.504734)
			(xy 336.38617 -9.53262) (xy 336.385661 -9.560506) (xy 336.377541 -9.615682) (xy 336.361473 -9.669089)
			(xy 336.337801 -9.719586) (xy 336.307028 -9.766099) (xy 336.269811 -9.807636) (xy 336.226943 -9.843311)
			(xy 336.179337 -9.872365) (xy 336.128008 -9.894177) (xy 336.074051 -9.908283) (xy 336.018614 -9.914383)
			(xy 335.96288 -9.912346) (xy 335.908037 -9.902216) (xy 335.855253 -9.884209) (xy 335.805653 -9.858708)
			(xy 335.760295 -9.826257) (xy 335.720146 -9.787548) (xy 335.68606 -9.743405) (xy 335.658764 -9.69477)
			(xy 335.638841 -9.642679) (xy 335.626715 -9.588242) (xy 335.622644 -9.53262) (xy 333.33811 -9.53262)
			(xy 333.33817 -9.535922) (xy 333.337661 -9.563808) (xy 333.329541 -9.618984) (xy 333.313473 -9.672391)
			(xy 333.289801 -9.722888) (xy 333.259028 -9.769401) (xy 333.221811 -9.810938) (xy 333.178943 -9.846613)
			(xy 333.131337 -9.875667) (xy 333.080008 -9.897479) (xy 333.026051 -9.911585) (xy 332.970614 -9.917685)
			(xy 332.91488 -9.915648) (xy 332.860037 -9.905518) (xy 332.807253 -9.887511) (xy 332.757653 -9.86201)
			(xy 332.712295 -9.829559) (xy 332.672146 -9.79085) (xy 332.63806 -9.746707) (xy 332.610764 -9.698072)
			(xy 332.590841 -9.645981) (xy 332.578715 -9.591544) (xy 332.574644 -9.535922) (xy 329.597004 -9.535922)
			(xy 329.597004 -11.543792) (xy 333.59928 -11.543792) (xy 333.603351 -11.48817) (xy 333.615477 -11.433733)
			(xy 333.6354 -11.381642) (xy 333.662696 -11.333007) (xy 333.696782 -11.288864) (xy 333.736931 -11.250155)
			(xy 333.782289 -11.217704) (xy 333.831889 -11.192203) (xy 333.884673 -11.174196) (xy 333.939516 -11.164066)
			(xy 333.99525 -11.162029) (xy 334.050687 -11.168129) (xy 334.104644 -11.182235) (xy 334.155973 -11.204047)
			(xy 334.203579 -11.233101) (xy 334.246447 -11.268776) (xy 334.283664 -11.310313) (xy 334.314437 -11.356826)
			(xy 334.338109 -11.407323) (xy 334.354177 -11.46073) (xy 334.362297 -11.515906) (xy 334.362806 -11.543792)
			(xy 334.608168 -11.543792) (xy 334.612239 -11.48817) (xy 334.624365 -11.433733) (xy 334.644288 -11.381642)
			(xy 334.671584 -11.333007) (xy 334.70567 -11.288864) (xy 334.745819 -11.250155) (xy 334.791177 -11.217704)
			(xy 334.840777 -11.192203) (xy 334.893561 -11.174196) (xy 334.948404 -11.164066) (xy 335.004138 -11.162029)
			(xy 335.059575 -11.168129) (xy 335.113532 -11.182235) (xy 335.164861 -11.204047) (xy 335.212467 -11.233101)
			(xy 335.255335 -11.268776) (xy 335.292552 -11.310313) (xy 335.323325 -11.356826) (xy 335.346997 -11.407323)
			(xy 335.363065 -11.46073) (xy 335.371185 -11.515906) (xy 335.371694 -11.543792) (xy 335.371185 -11.571678)
			(xy 335.363065 -11.626854) (xy 335.346997 -11.680261) (xy 335.323325 -11.730758) (xy 335.292552 -11.777271)
			(xy 335.255335 -11.818808) (xy 335.212467 -11.854483) (xy 335.164861 -11.883537) (xy 335.113532 -11.905349)
			(xy 335.059575 -11.919455) (xy 335.004138 -11.925555) (xy 334.948404 -11.923518) (xy 334.893561 -11.913388)
			(xy 334.840777 -11.895381) (xy 334.791177 -11.86988) (xy 334.745819 -11.837429) (xy 334.70567 -11.79872)
			(xy 334.671584 -11.754577) (xy 334.644288 -11.705942) (xy 334.624365 -11.653851) (xy 334.612239 -11.599414)
			(xy 334.608168 -11.543792) (xy 334.362806 -11.543792) (xy 334.362297 -11.571678) (xy 334.354177 -11.626854)
			(xy 334.338109 -11.680261) (xy 334.314437 -11.730758) (xy 334.283664 -11.777271) (xy 334.246447 -11.818808)
			(xy 334.203579 -11.854483) (xy 334.155973 -11.883537) (xy 334.104644 -11.905349) (xy 334.050687 -11.919455)
			(xy 333.99525 -11.925555) (xy 333.939516 -11.923518) (xy 333.884673 -11.913388) (xy 333.831889 -11.895381)
			(xy 333.782289 -11.86988) (xy 333.736931 -11.837429) (xy 333.696782 -11.79872) (xy 333.662696 -11.754577)
			(xy 333.6354 -11.705942) (xy 333.615477 -11.653851) (xy 333.603351 -11.599414) (xy 333.59928 -11.543792)
			(xy 329.597004 -11.543792) (xy 329.597004 -13.05179) (xy 329.596583 -13.061861) (xy 329.588871 -13.080468)
			(xy 329.582018 -13.087858) (xy 329.265534 -13.404342) (xy 329.259946 -13.4112) (xy 329.254572 -13.42033)
			(xy 329.25103 -13.441194) (xy 329.253088 -13.451586) (xy 329.265534 -13.49502) (xy 329.27798 -13.538962)
			(xy 329.28124 -13.547431) (xy 329.292699 -13.561486) (xy 329.300332 -13.566394) (xy 329.307444 -13.570204)
			(xy 329.315572 -13.574014) (xy 329.320906 -13.575284) (xy 329.383687 -13.590949) (xy 329.507403 -13.628902)
			(xy 329.628593 -13.674281) (xy 329.74681 -13.726919) (xy 329.861622 -13.786623) (xy 329.972605 -13.853174)
			(xy 330.079352 -13.926326) (xy 330.18147 -14.005812) (xy 330.278586 -14.091338) (xy 330.370341 -14.182592)
			(xy 330.456398 -14.279237) (xy 330.536443 -14.380918) (xy 330.610179 -14.487263) (xy 330.677337 -14.597879)
			(xy 330.73767 -14.712361) (xy 330.790955 -14.830289) (xy 330.836998 -14.951228) (xy 330.875629 -15.074734)
			(xy 330.906706 -15.200354) (xy 330.930114 -15.327627) (xy 330.945769 -15.456083) (xy 330.953612 -15.585252)
			(xy 330.954126 -15.649956) (xy 330.95362 -15.715692) (xy 330.945527 -15.846913) (xy 330.92937 -15.977388)
			(xy 330.905213 -16.106621) (xy 330.873145 -16.234121) (xy 330.833289 -16.359405) (xy 330.785796 -16.481999)
			(xy 330.730847 -16.601436) (xy 330.668648 -16.717263) (xy 330.599438 -16.829042) (xy 330.523477 -16.936349)
			(xy 330.496403 -16.969994) (xy 362.048305 -16.969994) (xy 362.05231 -16.882086) (xy 362.064293 -16.794906)
			(xy 362.084153 -16.709177) (xy 362.111728 -16.625609) (xy 362.146787 -16.544895) (xy 362.18904 -16.467703)
			(xy 362.238138 -16.394674) (xy 362.293674 -16.326412) (xy 362.355186 -16.263482) (xy 362.422167 -16.206408)
			(xy 362.49406 -16.15566) (xy 362.570269 -16.11166) (xy 362.650164 -16.074773) (xy 362.733083 -16.045304)
			(xy 362.818338 -16.023497) (xy 362.905222 -16.009533) (xy 362.993016 -16.003527) (xy 363.080993 -16.005531)
			(xy 363.168423 -16.015526) (xy 363.254582 -16.03343) (xy 363.338756 -16.059094) (xy 363.420247 -16.092307)
			(xy 363.498381 -16.132793) (xy 363.572509 -16.180215) (xy 363.642017 -16.234182) (xy 363.706331 -16.294247)
			(xy 363.764915 -16.359911) (xy 363.817286 -16.43063) (xy 363.863009 -16.505818) (xy 363.901706 -16.584853)
			(xy 363.933055 -16.667079) (xy 363.956797 -16.751815) (xy 363.972735 -16.838359) (xy 363.980737 -16.925994)
			(xy 363.981238 -16.969994) (xy 363.980737 -17.013994) (xy 363.972735 -17.101629) (xy 363.956797 -17.188173)
			(xy 363.933055 -17.272909) (xy 363.901706 -17.355135) (xy 363.863009 -17.43417) (xy 363.817286 -17.509358)
			(xy 363.764915 -17.580077) (xy 363.706331 -17.645741) (xy 363.642017 -17.705806) (xy 363.572509 -17.759773)
			(xy 363.498381 -17.807195) (xy 363.420247 -17.847681) (xy 363.338756 -17.880894) (xy 363.254582 -17.906558)
			(xy 363.168423 -17.924462) (xy 363.080993 -17.934457) (xy 362.993016 -17.936461) (xy 362.905222 -17.930455)
			(xy 362.818338 -17.916491) (xy 362.733083 -17.894684) (xy 362.650164 -17.865215) (xy 362.570269 -17.828328)
			(xy 362.49406 -17.784328) (xy 362.422167 -17.73358) (xy 362.355186 -17.676506) (xy 362.293674 -17.613576)
			(xy 362.238138 -17.545314) (xy 362.18904 -17.472285) (xy 362.146787 -17.395093) (xy 362.111728 -17.314379)
			(xy 362.084153 -17.230811) (xy 362.064293 -17.145082) (xy 362.05231 -17.057902) (xy 362.048305 -16.969994)
			(xy 330.496403 -16.969994) (xy 330.441055 -17.038775) (xy 330.352483 -17.135934) (xy 330.258098 -17.227455)
			(xy 330.158259 -17.312993) (xy 330.053342 -17.392222) (xy 329.943748 -17.464842) (xy 329.82989 -17.530577)
			(xy 329.712202 -17.589179) (xy 329.59113 -17.640425) (xy 329.467132 -17.68412) (xy 329.34068 -17.720099)
			(xy 329.212252 -17.748225) (xy 329.082337 -17.768391) (xy 328.951427 -17.780522) (xy 328.820018 -17.784571)
			(xy 328.688609 -17.780522) (xy 328.557699 -17.768391) (xy 328.427784 -17.748225) (xy 328.299356 -17.720099)
			(xy 328.172904 -17.68412) (xy 328.048906 -17.640425) (xy 327.927834 -17.589179) (xy 327.810146 -17.530577)
			(xy 327.696288 -17.464842) (xy 327.586694 -17.392222) (xy 327.481777 -17.312993) (xy 327.381938 -17.227455)
			(xy 327.287553 -17.135934) (xy 327.198981 -17.038775) (xy 327.116559 -16.936349) (xy 327.040598 -16.829042)
			(xy 326.971388 -16.717263) (xy 326.909189 -16.601436) (xy 326.85424 -16.481999) (xy 326.806747 -16.359405)
			(xy 326.766891 -16.234121) (xy 326.734823 -16.106621) (xy 326.710666 -15.977388) (xy 326.694509 -15.846913)
			(xy 326.686416 -15.715692) (xy 326.68591 -15.649956) (xy 326.686429 -15.582843) (xy 326.694867 -15.448883)
			(xy 326.711706 -15.315718) (xy 326.736879 -15.183874) (xy 326.770288 -15.053872) (xy 326.811801 -14.926227)
			(xy 326.861253 -14.801443) (xy 326.918448 -14.680013) (xy 326.983161 -14.562418) (xy 327.055136 -14.449121)
			(xy 327.134088 -14.340571) (xy 327.219706 -14.237197) (xy 327.265284 -14.187932) (xy 327.265538 -14.187678)
			(xy 327.279762 -14.172692) (xy 327.307448 -14.144498) (xy 327.342461 -14.109631) (xy 327.415262 -14.042803)
			(xy 327.45299 -14.010894) (xy 327.484341 -13.984868) (xy 327.548748 -13.934945) (xy 327.581768 -13.911072)
			(xy 327.582022 -13.910818) (xy 327.58949 -13.904956) (xy 327.599795 -13.889027) (xy 327.603608 -13.870441)
			(xy 327.602342 -13.861034) (xy 327.60158 -13.856716) (xy 327.600818 -13.851128) (xy 327.586848 -13.808202)
			(xy 327.586848 -13.807694) (xy 327.5711 -13.758672) (xy 327.567109 -13.749802) (xy 327.553732 -13.735705)
			(xy 327.536079 -13.72758) (xy 327.526396 -13.726668) (xy 326.764904 -13.726668) (xy 326.754893 -13.727155)
			(xy 326.736395 -13.734813) (xy 326.722233 -13.748965) (xy 326.714562 -13.767458) (xy 326.714104 -13.777468)
			(xy 326.714104 -13.937488) (xy 326.713614 -13.947448) (xy 326.706021 -13.965868) (xy 326.699372 -13.973302)
			(xy 326.5678 -14.104874) (xy 326.560403 -14.111723) (xy 326.541804 -14.119462) (xy 326.531732 -14.11986)
			(xy 319.16497 -14.11986) (xy 319.098322 -14.119382) (xy 318.965256 -14.111562) (xy 318.832879 -14.095944)
			(xy 318.701647 -14.072583) (xy 318.572012 -14.041559) (xy 318.444422 -14.00298) (xy 318.319316 -13.956977)
			(xy 318.197126 -13.90371) (xy 318.078274 -13.843363) (xy 317.963169 -13.776143) (xy 317.907416 -13.739622)
			(xy 317.90132 -13.735558) (xy 317.879984 -13.728954) (xy 317.876327 -13.727898) (xy 317.868803 -13.726744)
			(xy 317.864998 -13.726668) (xy 317.652908 -13.726668) (xy 317.642838 -13.726246) (xy 317.624234 -13.71853)
			(xy 317.61684 -13.711682) (xy 316.992762 -13.087604) (xy 316.989031 -13.084083) (xy 316.980456 -13.078455)
			(xy 316.975744 -13.076428) (xy 316.967108 -13.072872) (xy 316.93993 -13.072872) (xy 316.929866 -13.072435)
			(xy 316.911283 -13.0647) (xy 316.903862 -13.057886) (xy 316.834774 -12.988798) (xy 316.82792 -12.981403)
			(xy 316.820175 -12.962804) (xy 316.819788 -12.95273) (xy 316.819788 -2.198624) (xy 316.819474 -2.190341)
			(xy 316.814168 -2.174651) (xy 316.809374 -2.16789) (xy 316.807342 -2.165604) (xy 316.805564 -2.163826)
			(xy 316.802262 -2.160016) (xy 316.33922 -1.696974) (xy 316.335491 -1.693451) (xy 316.326918 -1.687817)
			(xy 316.322202 -1.685798) (xy 316.313566 -1.682242) (xy 303.706784 -1.682242) (xy 303.698503 -1.682561)
			(xy 303.682816 -1.687871) (xy 303.67605 -1.692656) (xy 303.673764 -1.694688) (xy 303.671986 -1.696466)
			(xy 303.668176 -1.699768) (xy 303.56175 -1.806194) (xy 303.558229 -1.809925) (xy 303.5526 -1.818499)
			(xy 303.550574 -1.823212) (xy 303.547018 -1.831848) (xy 303.547018 -12.675108) (xy 303.546594 -12.685178)
			(xy 303.53888 -12.703782) (xy 303.532032 -12.711176) (xy 302.896016 -13.347192) (xy 302.891435 -13.352141)
			(xy 302.884755 -13.363849) (xy 302.882808 -13.370306) (xy 302.882808 -13.396468) (xy 302.883316 -13.398246)
			(xy 302.90643 -13.459714) (xy 302.91278 -13.476478) (xy 302.915453 -13.482266) (xy 302.923163 -13.492414)
			(xy 302.92802 -13.496544) (xy 302.948594 -13.51153) (xy 302.955198 -13.51407) (xy 302.97501 -13.521436)
			(xy 302.982122 -13.521944) (xy 303.048357 -13.527497) (xy 303.18002 -13.545821) (xy 303.310286 -13.572304)
			(xy 303.438652 -13.606845) (xy 303.564618 -13.649309) (xy 303.687697 -13.699532) (xy 303.807411 -13.757318)
			(xy 303.923297 -13.822444) (xy 304.034903 -13.894657) (xy 304.141798 -13.973678) (xy 304.243567 -14.059199)
			(xy 304.286714 -14.100302) (xy 309.442864 -14.100302) (xy 309.446935 -14.04468) (xy 309.459061 -13.990243)
			(xy 309.478984 -13.938152) (xy 309.50628 -13.889517) (xy 309.540366 -13.845374) (xy 309.580515 -13.806665)
			(xy 309.625873 -13.774214) (xy 309.675473 -13.748713) (xy 309.728257 -13.730706) (xy 309.7831 -13.720576)
			(xy 309.838834 -13.718539) (xy 309.894271 -13.724639) (xy 309.948228 -13.738745) (xy 309.999557 -13.760557)
			(xy 310.047163 -13.789611) (xy 310.090031 -13.825286) (xy 310.127248 -13.866823) (xy 310.158021 -13.913336)
			(xy 310.181693 -13.963833) (xy 310.197761 -14.01724) (xy 310.205881 -14.072416) (xy 310.20639 -14.100302)
			(xy 310.205881 -14.128188) (xy 310.197761 -14.183364) (xy 310.181693 -14.236771) (xy 310.158021 -14.287268)
			(xy 310.127248 -14.333781) (xy 310.090031 -14.375318) (xy 310.047163 -14.410993) (xy 309.999557 -14.440047)
			(xy 309.948228 -14.461859) (xy 309.894271 -14.475965) (xy 309.838834 -14.482065) (xy 309.7831 -14.480028)
			(xy 309.728257 -14.469898) (xy 309.675473 -14.451891) (xy 309.625873 -14.42639) (xy 309.580515 -14.393939)
			(xy 309.540366 -14.35523) (xy 309.50628 -14.311087) (xy 309.478984 -14.262452) (xy 309.459061 -14.210361)
			(xy 309.446935 -14.155924) (xy 309.442864 -14.100302) (xy 304.286714 -14.100302) (xy 304.339816 -14.150888)
			(xy 304.43017 -14.248391) (xy 304.51428 -14.351329) (xy 304.591819 -14.459303) (xy 304.662488 -14.571895)
			(xy 304.72601 -14.688666) (xy 304.782141 -14.809166) (xy 304.830663 -14.932925) (xy 304.871387 -15.059465)
			(xy 304.904155 -15.188294) (xy 304.92884 -15.318914) (xy 304.938682 -15.39755) (xy 310.10428 -15.39755)
			(xy 310.10428 -15.34305) (xy 310.112036 -15.289104) (xy 310.12739 -15.236811) (xy 310.15003 -15.187235)
			(xy 310.179494 -15.141386) (xy 310.215183 -15.100196) (xy 310.256371 -15.064505) (xy 310.302219 -15.035038)
			(xy 310.351794 -15.012396) (xy 310.404086 -14.99704) (xy 310.458032 -14.989281) (xy 310.485282 -14.988794)
			(xy 310.511517 -14.989266) (xy 310.563493 -14.996458) (xy 310.613991 -15.01071) (xy 310.662057 -15.031752)
			(xy 310.706784 -15.059187) (xy 310.747327 -15.092496) (xy 310.765444 -15.111476) (xy 310.765698 -15.11173)
			(xy 310.773416 -15.11913) (xy 310.79311 -15.127394) (xy 310.803798 -15.127732) (xy 310.891682 -15.125446)
			(xy 310.91124 -15.116048) (xy 310.918352 -15.107412) (xy 310.936563 -15.086261) (xy 310.978103 -15.048986)
			(xy 311.024632 -15.018164) (xy 311.075158 -14.994454) (xy 311.128599 -14.978361) (xy 311.183816 -14.970229)
			(xy 311.211722 -14.969744) (xy 311.238969 -14.970328) (xy 311.292907 -14.978086) (xy 311.345193 -14.993441)
			(xy 311.394761 -15.01608) (xy 311.440603 -15.045543) (xy 311.481785 -15.08123) (xy 311.51747 -15.122415)
			(xy 311.54693 -15.168258) (xy 311.569567 -15.217828) (xy 311.584919 -15.270114) (xy 311.592674 -15.324053)
			(xy 311.592674 -15.378547) (xy 311.584919 -15.432486) (xy 311.569567 -15.484772) (xy 311.54693 -15.534342)
			(xy 311.51747 -15.580185) (xy 311.481785 -15.62137) (xy 311.440603 -15.657057) (xy 311.394761 -15.68652)
			(xy 311.345193 -15.709159) (xy 311.292907 -15.724514) (xy 311.238969 -15.732272) (xy 311.211722 -15.73276)
			(xy 311.185486 -15.7323) (xy 311.13351 -15.725107) (xy 311.083011 -15.710854) (xy 311.034944 -15.68981)
			(xy 310.990217 -15.662372) (xy 310.949676 -15.62906) (xy 310.93156 -15.610078) (xy 310.931306 -15.609824)
			(xy 310.923593 -15.602419) (xy 310.903894 -15.59416) (xy 310.893206 -15.593822) (xy 310.805322 -15.596108)
			(xy 310.785764 -15.605506) (xy 310.778652 -15.614142) (xy 310.760429 -15.635282) (xy 310.718892 -15.672559)
			(xy 310.672366 -15.703384) (xy 310.621843 -15.727097) (xy 310.568403 -15.743192) (xy 310.513188 -15.751325)
			(xy 310.485282 -15.75181) (xy 310.458032 -15.751319) (xy 310.404086 -15.74356) (xy 310.351794 -15.728204)
			(xy 310.302219 -15.705562) (xy 310.256371 -15.676095) (xy 310.215183 -15.640404) (xy 310.179494 -15.599214)
			(xy 310.15003 -15.553365) (xy 310.12739 -15.503789) (xy 310.112036 -15.451496) (xy 310.10428 -15.39755)
			(xy 304.938682 -15.39755) (xy 304.945348 -15.450816) (xy 304.953612 -15.58349) (xy 304.954178 -15.649956)
			(xy 304.953672 -15.715692) (xy 304.945579 -15.846913) (xy 304.929422 -15.977388) (xy 304.905265 -16.106621)
			(xy 304.873197 -16.234121) (xy 304.833341 -16.359405) (xy 304.785848 -16.481999) (xy 304.730899 -16.601436)
			(xy 304.6687 -16.717263) (xy 304.59949 -16.829042) (xy 304.523529 -16.936349) (xy 304.496455 -16.969994)
			(xy 323.948051 -16.969994) (xy 323.952056 -16.882086) (xy 323.964039 -16.794906) (xy 323.983899 -16.709177)
			(xy 324.011474 -16.625609) (xy 324.046533 -16.544895) (xy 324.088786 -16.467703) (xy 324.137884 -16.394674)
			(xy 324.19342 -16.326412) (xy 324.254932 -16.263482) (xy 324.321913 -16.206408) (xy 324.393806 -16.15566)
			(xy 324.470015 -16.11166) (xy 324.54991 -16.074773) (xy 324.632829 -16.045304) (xy 324.718084 -16.023497)
			(xy 324.804968 -16.009533) (xy 324.892762 -16.003527) (xy 324.980739 -16.005531) (xy 325.068169 -16.015526)
			(xy 325.154328 -16.03343) (xy 325.238502 -16.059094) (xy 325.319993 -16.092307) (xy 325.398127 -16.132793)
			(xy 325.472255 -16.180215) (xy 325.541763 -16.234182) (xy 325.606077 -16.294247) (xy 325.664661 -16.359911)
			(xy 325.717032 -16.43063) (xy 325.762755 -16.505818) (xy 325.801452 -16.584853) (xy 325.832801 -16.667079)
			(xy 325.856543 -16.751815) (xy 325.872481 -16.838359) (xy 325.880483 -16.925994) (xy 325.880984 -16.969994)
			(xy 325.880483 -17.013994) (xy 325.872481 -17.101629) (xy 325.856543 -17.188173) (xy 325.832801 -17.272909)
			(xy 325.801452 -17.355135) (xy 325.762755 -17.43417) (xy 325.717032 -17.509358) (xy 325.664661 -17.580077)
			(xy 325.606077 -17.645741) (xy 325.541763 -17.705806) (xy 325.472255 -17.759773) (xy 325.398127 -17.807195)
			(xy 325.319993 -17.847681) (xy 325.238502 -17.880894) (xy 325.154328 -17.906558) (xy 325.068169 -17.924462)
			(xy 324.980739 -17.934457) (xy 324.892762 -17.936461) (xy 324.804968 -17.930455) (xy 324.718084 -17.916491)
			(xy 324.632829 -17.894684) (xy 324.54991 -17.865215) (xy 324.470015 -17.828328) (xy 324.393806 -17.784328)
			(xy 324.321913 -17.73358) (xy 324.254932 -17.676506) (xy 324.19342 -17.613576) (xy 324.137884 -17.545314)
			(xy 324.088786 -17.472285) (xy 324.046533 -17.395093) (xy 324.011474 -17.314379) (xy 323.983899 -17.230811)
			(xy 323.964039 -17.145082) (xy 323.952056 -17.057902) (xy 323.948051 -16.969994) (xy 304.496455 -16.969994)
			(xy 304.441107 -17.038775) (xy 304.352535 -17.135934) (xy 304.25815 -17.227455) (xy 304.158311 -17.312993)
			(xy 304.053394 -17.392222) (xy 304.012116 -17.419574) (xy 308.484014 -17.419574) (xy 308.488085 -17.363952)
			(xy 308.500211 -17.309515) (xy 308.520134 -17.257424) (xy 308.54743 -17.208789) (xy 308.581516 -17.164646)
			(xy 308.621665 -17.125937) (xy 308.667023 -17.093486) (xy 308.716623 -17.067985) (xy 308.769407 -17.049978)
			(xy 308.82425 -17.039848) (xy 308.879984 -17.037811) (xy 308.935421 -17.043911) (xy 308.989378 -17.058017)
			(xy 309.040707 -17.079829) (xy 309.088313 -17.108883) (xy 309.131181 -17.144558) (xy 309.168398 -17.186095)
			(xy 309.199171 -17.232608) (xy 309.222843 -17.283105) (xy 309.238911 -17.336512) (xy 309.247031 -17.391688)
			(xy 309.24754 -17.419574) (xy 309.247031 -17.44746) (xy 309.238911 -17.502636) (xy 309.222843 -17.556043)
			(xy 309.199171 -17.60654) (xy 309.168398 -17.653053) (xy 309.131181 -17.69459) (xy 309.088313 -17.730265)
			(xy 309.040707 -17.759319) (xy 308.989378 -17.781131) (xy 308.935421 -17.795237) (xy 308.879984 -17.801337)
			(xy 308.82425 -17.7993) (xy 308.769407 -17.78917) (xy 308.716623 -17.771163) (xy 308.667023 -17.745662)
			(xy 308.621665 -17.713211) (xy 308.581516 -17.674502) (xy 308.54743 -17.630359) (xy 308.520134 -17.581724)
			(xy 308.500211 -17.529633) (xy 308.488085 -17.475196) (xy 308.484014 -17.419574) (xy 304.012116 -17.419574)
			(xy 303.9438 -17.464842) (xy 303.829942 -17.530577) (xy 303.712254 -17.589179) (xy 303.591182 -17.640425)
			(xy 303.467184 -17.68412) (xy 303.340732 -17.720099) (xy 303.212304 -17.748225) (xy 303.082389 -17.768391)
			(xy 302.951479 -17.780522) (xy 302.82007 -17.784571) (xy 302.688661 -17.780522) (xy 302.557751 -17.768391)
			(xy 302.427836 -17.748225) (xy 302.299408 -17.720099) (xy 302.172956 -17.68412) (xy 302.048958 -17.640425)
			(xy 301.927886 -17.589179) (xy 301.810198 -17.530577) (xy 301.69634 -17.464842) (xy 301.586746 -17.392222)
			(xy 301.481829 -17.312993) (xy 301.38199 -17.227455) (xy 301.287605 -17.135934) (xy 301.199033 -17.038775)
			(xy 301.116611 -16.936349) (xy 301.04065 -16.829042) (xy 300.97144 -16.717263) (xy 300.909241 -16.601436)
			(xy 300.854292 -16.481999) (xy 300.806799 -16.359405) (xy 300.766943 -16.234121) (xy 300.734875 -16.106621)
			(xy 300.710718 -15.977388) (xy 300.694561 -15.846913) (xy 300.686468 -15.715692) (xy 300.685962 -15.649956)
			(xy 300.685962 -15.649702) (xy 300.686495 -15.582473) (xy 300.69498 -15.448282) (xy 300.711892 -15.314891)
			(xy 300.737164 -15.182829) (xy 300.770695 -15.052618) (xy 300.812352 -14.924775) (xy 300.861971 -14.799807)
			(xy 300.919355 -14.678208) (xy 300.984277 -14.560462) (xy 301.056478 -14.447033) (xy 301.095664 -14.392402)
			(xy 301.135763 -14.338311) (xy 301.221814 -14.23473) (xy 301.314223 -14.136779) (xy 301.412622 -14.044847)
			(xy 301.516621 -13.959301) (xy 301.570898 -13.919454) (xy 301.576486 -13.91539) (xy 301.587154 -13.902182)
			(xy 301.58944 -13.89761) (xy 301.596298 -13.88491) (xy 301.598247 -13.880754) (xy 301.600806 -13.871939)
			(xy 301.601378 -13.867384) (xy 301.602394 -13.857224) (xy 301.585376 -13.80363) (xy 301.583852 -13.799058)
			(xy 301.57293 -13.761212) (xy 301.569724 -13.752831) (xy 301.558463 -13.738876) (xy 301.54307 -13.729679)
			(xy 301.534322 -13.727684) (xy 301.528988 -13.726668) (xy 300.820836 -13.726668) (xy 300.810808 -13.727081)
			(xy 300.792273 -13.734743) (xy 300.778081 -13.748916) (xy 300.770394 -13.76744) (xy 300.770036 -13.777468)
			(xy 300.770036 -13.838428) (xy 300.769606 -13.848495) (xy 300.761877 -13.867086) (xy 300.75505 -13.874496)
			(xy 300.524926 -14.104874) (xy 300.517525 -14.111712) (xy 300.498926 -14.119423) (xy 300.488858 -14.11986)
			(xy 293.165022 -14.11986) (xy 293.098374 -14.119383) (xy 292.965307 -14.111566) (xy 292.832928 -14.095952)
			(xy 292.701695 -14.072593) (xy 292.572058 -14.041572) (xy 292.444466 -14.002995) (xy 292.319359 -13.956994)
			(xy 292.197167 -13.903729) (xy 292.078313 -13.843384) (xy 291.963206 -13.776166) (xy 291.907468 -13.739622)
			(xy 290.438586 -12.27074) (xy 290.43174 -12.263342) (xy 290.424014 -12.244743) (xy 290.4236 -12.234672)
			(xy 290.4236 -1.138682) (xy 290.423173 -1.128613) (xy 290.415454 -1.110014) (xy 290.408614 -1.102614)
			(xy 289.981386 -0.675386) (xy 289.973991 -0.668532) (xy 289.955392 -0.66079) (xy 289.945318 -0.6604)
			(xy 278.303482 -0.6604) (xy 278.293413 -0.660827) (xy 278.274814 -0.668546) (xy 278.267414 -0.675386)
			(xy 278.092916 -0.849884) (xy 278.086081 -0.857286) (xy 278.078375 -0.875885) (xy 278.07793 -0.885952)
			(xy 278.07793 -13.725144) (xy 278.077876 -13.729216) (xy 278.0766 -13.737258) (xy 278.07539 -13.741146)
			(xy 278.062182 -13.780516) (xy 278.062182 -13.781024) (xy 278.053546 -13.807694) (xy 278.053546 -13.808202)
			(xy 278.041608 -13.845794) (xy 278.040463 -13.849567) (xy 278.039189 -13.857347) (xy 278.039068 -13.861288)
			(xy 278.039068 -13.884402) (xy 278.041059 -13.890146) (xy 278.047356 -13.90054) (xy 278.051514 -13.904976)
			(xy 278.057356 -13.910818) (xy 278.060912 -13.913358) (xy 278.112212 -13.950587) (xy 278.210794 -14.030284)
			(xy 278.304472 -14.115693) (xy 278.392914 -14.206511) (xy 278.47581 -14.30242) (xy 278.552865 -14.40308)
			(xy 278.62381 -14.508136) (xy 278.688394 -14.617219) (xy 278.746388 -14.729943) (xy 278.748754 -14.735302)
			(xy 282.772356 -14.735302) (xy 282.776427 -14.67968) (xy 282.788553 -14.625243) (xy 282.808476 -14.573152)
			(xy 282.835772 -14.524517) (xy 282.869858 -14.480374) (xy 282.910007 -14.441665) (xy 282.955365 -14.409214)
			(xy 283.004965 -14.383713) (xy 283.057749 -14.365706) (xy 283.112592 -14.355576) (xy 283.168326 -14.353539)
			(xy 283.223763 -14.359639) (xy 283.27772 -14.373745) (xy 283.329049 -14.395557) (xy 283.376655 -14.424611)
			(xy 283.419523 -14.460286) (xy 283.45674 -14.501823) (xy 283.487513 -14.548336) (xy 283.511185 -14.598833)
			(xy 283.527253 -14.65224) (xy 283.535373 -14.707416) (xy 283.535882 -14.735302) (xy 283.535373 -14.763188)
			(xy 283.527253 -14.818364) (xy 283.511185 -14.871771) (xy 283.487513 -14.922268) (xy 283.45674 -14.968781)
			(xy 283.419523 -15.010318) (xy 283.376655 -15.045993) (xy 283.329049 -15.075047) (xy 283.27772 -15.096859)
			(xy 283.223763 -15.110965) (xy 283.168326 -15.117065) (xy 283.112592 -15.115028) (xy 283.057749 -15.104898)
			(xy 283.004965 -15.086891) (xy 282.955365 -15.06139) (xy 282.910007 -15.028939) (xy 282.869858 -14.99023)
			(xy 282.835772 -14.946087) (xy 282.808476 -14.897452) (xy 282.788553 -14.845361) (xy 282.776427 -14.790924)
			(xy 282.772356 -14.735302) (xy 278.748754 -14.735302) (xy 278.797589 -14.845911) (xy 278.841815 -14.964714)
			(xy 278.878911 -15.085932) (xy 278.908747 -15.209139) (xy 278.931215 -15.3339) (xy 278.938813 -15.397554)
			(xy 284.104257 -15.397554) (xy 284.104257 -15.343046) (xy 284.112015 -15.289092) (xy 284.127373 -15.236792)
			(xy 284.150018 -15.18721) (xy 284.179489 -15.141355) (xy 284.215186 -15.100162) (xy 284.256382 -15.064468)
			(xy 284.30224 -15.035001) (xy 284.351824 -15.012361) (xy 284.404125 -14.997008) (xy 284.45808 -14.989255)
			(xy 284.485334 -14.988794) (xy 284.511571 -14.989231) (xy 284.563547 -14.996431) (xy 284.614046 -15.01069)
			(xy 284.662112 -15.031738) (xy 284.706839 -15.059179) (xy 284.74738 -15.092493) (xy 284.765496 -15.111476)
			(xy 284.76575 -15.11173) (xy 284.773486 -15.119108) (xy 284.793167 -15.127385) (xy 284.80385 -15.127732)
			(xy 284.891734 -15.125446) (xy 284.911292 -15.116048) (xy 284.918404 -15.107412) (xy 284.936587 -15.086236)
			(xy 284.978133 -15.048963) (xy 285.024668 -15.018144) (xy 285.075199 -14.994438) (xy 285.128646 -14.97835)
			(xy 285.183866 -14.970225) (xy 285.211774 -14.969744) (xy 285.239025 -14.970301) (xy 285.292972 -14.978054)
			(xy 285.345266 -14.993406) (xy 285.394843 -15.016044) (xy 285.440694 -15.045508) (xy 285.481884 -15.081197)
			(xy 285.517576 -15.122385) (xy 285.547043 -15.168234) (xy 285.569685 -15.21781) (xy 285.58504 -15.270103)
			(xy 285.592797 -15.324049) (xy 285.592797 -15.378551) (xy 285.58504 -15.432497) (xy 285.569685 -15.48479)
			(xy 285.547043 -15.534366) (xy 285.517576 -15.580215) (xy 285.481884 -15.621403) (xy 285.440694 -15.657092)
			(xy 285.394843 -15.686556) (xy 285.345266 -15.709194) (xy 285.292972 -15.724546) (xy 285.239025 -15.732299)
			(xy 285.211774 -15.73276) (xy 285.185537 -15.732332) (xy 285.133559 -15.725133) (xy 285.08306 -15.710873)
			(xy 285.034993 -15.689823) (xy 284.990267 -15.66238) (xy 284.949727 -15.629063) (xy 284.931612 -15.610078)
			(xy 284.931358 -15.609824) (xy 284.923625 -15.602443) (xy 284.903942 -15.59417) (xy 284.893258 -15.593822)
			(xy 284.805374 -15.596108) (xy 284.785816 -15.605506) (xy 284.778704 -15.614142) (xy 284.760506 -15.635305)
			(xy 284.718965 -15.672581) (xy 284.672433 -15.703402) (xy 284.621905 -15.727111) (xy 284.56846 -15.743201)
			(xy 284.513241 -15.751328) (xy 284.485334 -15.75181) (xy 284.45808 -15.751345) (xy 284.404125 -15.743592)
			(xy 284.351824 -15.728239) (xy 284.30224 -15.705599) (xy 284.256382 -15.676132) (xy 284.215186 -15.640438)
			(xy 284.179489 -15.599245) (xy 284.150018 -15.55339) (xy 284.127373 -15.503808) (xy 284.112015 -15.451508)
			(xy 284.104257 -15.397554) (xy 278.938813 -15.397554) (xy 278.946239 -15.459774) (xy 278.953764 -15.586318)
			(xy 278.95423 -15.649702) (xy 278.95423 -15.649956) (xy 278.953724 -15.715692) (xy 278.945631 -15.846913)
			(xy 278.929474 -15.977388) (xy 278.905317 -16.106621) (xy 278.873249 -16.234121) (xy 278.833393 -16.359405)
			(xy 278.7859 -16.481999) (xy 278.730951 -16.601436) (xy 278.668752 -16.717263) (xy 278.599542 -16.829042)
			(xy 278.523581 -16.936349) (xy 278.496507 -16.969994) (xy 297.948103 -16.969994) (xy 297.952108 -16.882086)
			(xy 297.964091 -16.794906) (xy 297.983951 -16.709177) (xy 298.011526 -16.625609) (xy 298.046585 -16.544895)
			(xy 298.088838 -16.467703) (xy 298.137936 -16.394674) (xy 298.193472 -16.326412) (xy 298.254984 -16.263482)
			(xy 298.321965 -16.206408) (xy 298.393858 -16.15566) (xy 298.470067 -16.11166) (xy 298.549962 -16.074773)
			(xy 298.632881 -16.045304) (xy 298.718136 -16.023497) (xy 298.80502 -16.009533) (xy 298.892814 -16.003527)
			(xy 298.980791 -16.005531) (xy 299.068221 -16.015526) (xy 299.15438 -16.03343) (xy 299.238554 -16.059094)
			(xy 299.320045 -16.092307) (xy 299.398179 -16.132793) (xy 299.472307 -16.180215) (xy 299.541815 -16.234182)
			(xy 299.606129 -16.294247) (xy 299.664713 -16.359911) (xy 299.717084 -16.43063) (xy 299.762807 -16.505818)
			(xy 299.801504 -16.584853) (xy 299.832853 -16.667079) (xy 299.856595 -16.751815) (xy 299.872533 -16.838359)
			(xy 299.880535 -16.925994) (xy 299.881036 -16.969994) (xy 299.880535 -17.013994) (xy 299.872533 -17.101629)
			(xy 299.856595 -17.188173) (xy 299.832853 -17.272909) (xy 299.801504 -17.355135) (xy 299.762807 -17.43417)
			(xy 299.717084 -17.509358) (xy 299.664713 -17.580077) (xy 299.606129 -17.645741) (xy 299.541815 -17.705806)
			(xy 299.472307 -17.759773) (xy 299.398179 -17.807195) (xy 299.320045 -17.847681) (xy 299.238554 -17.880894)
			(xy 299.15438 -17.906558) (xy 299.068221 -17.924462) (xy 298.980791 -17.934457) (xy 298.892814 -17.936461)
			(xy 298.80502 -17.930455) (xy 298.718136 -17.916491) (xy 298.632881 -17.894684) (xy 298.549962 -17.865215)
			(xy 298.470067 -17.828328) (xy 298.393858 -17.784328) (xy 298.321965 -17.73358) (xy 298.254984 -17.676506)
			(xy 298.193472 -17.613576) (xy 298.137936 -17.545314) (xy 298.088838 -17.472285) (xy 298.046585 -17.395093)
			(xy 298.011526 -17.314379) (xy 297.983951 -17.230811) (xy 297.964091 -17.145082) (xy 297.952108 -17.057902)
			(xy 297.948103 -16.969994) (xy 278.496507 -16.969994) (xy 278.441159 -17.038775) (xy 278.352587 -17.135934)
			(xy 278.258202 -17.227455) (xy 278.158363 -17.312993) (xy 278.053446 -17.392222) (xy 278.012168 -17.419574)
			(xy 282.484066 -17.419574) (xy 282.488137 -17.363952) (xy 282.500263 -17.309515) (xy 282.520186 -17.257424)
			(xy 282.547482 -17.208789) (xy 282.581568 -17.164646) (xy 282.621717 -17.125937) (xy 282.667075 -17.093486)
			(xy 282.716675 -17.067985) (xy 282.769459 -17.049978) (xy 282.824302 -17.039848) (xy 282.880036 -17.037811)
			(xy 282.935473 -17.043911) (xy 282.98943 -17.058017) (xy 283.040759 -17.079829) (xy 283.088365 -17.108883)
			(xy 283.131233 -17.144558) (xy 283.16845 -17.186095) (xy 283.199223 -17.232608) (xy 283.222895 -17.283105)
			(xy 283.238963 -17.336512) (xy 283.247083 -17.391688) (xy 283.247592 -17.419574) (xy 283.247083 -17.44746)
			(xy 283.238963 -17.502636) (xy 283.222895 -17.556043) (xy 283.199223 -17.60654) (xy 283.16845 -17.653053)
			(xy 283.131233 -17.69459) (xy 283.088365 -17.730265) (xy 283.040759 -17.759319) (xy 282.98943 -17.781131)
			(xy 282.935473 -17.795237) (xy 282.880036 -17.801337) (xy 282.824302 -17.7993) (xy 282.769459 -17.78917)
			(xy 282.716675 -17.771163) (xy 282.667075 -17.745662) (xy 282.621717 -17.713211) (xy 282.581568 -17.674502)
			(xy 282.547482 -17.630359) (xy 282.520186 -17.581724) (xy 282.500263 -17.529633) (xy 282.488137 -17.475196)
			(xy 282.484066 -17.419574) (xy 278.012168 -17.419574) (xy 277.943852 -17.464842) (xy 277.829994 -17.530577)
			(xy 277.712306 -17.589179) (xy 277.591234 -17.640425) (xy 277.467236 -17.68412) (xy 277.340784 -17.720099)
			(xy 277.212356 -17.748225) (xy 277.082441 -17.768391) (xy 276.951531 -17.780522) (xy 276.820122 -17.784571)
			(xy 276.688713 -17.780522) (xy 276.557803 -17.768391) (xy 276.427888 -17.748225) (xy 276.29946 -17.720099)
			(xy 276.173008 -17.68412) (xy 276.04901 -17.640425) (xy 275.927938 -17.589179) (xy 275.81025 -17.530577)
			(xy 275.696392 -17.464842) (xy 275.586798 -17.392222) (xy 275.481881 -17.312993) (xy 275.382042 -17.227455)
			(xy 275.287657 -17.135934) (xy 275.199085 -17.038775) (xy 275.116663 -16.936349) (xy 275.040702 -16.829042)
			(xy 274.971492 -16.717263) (xy 274.909293 -16.601436) (xy 274.854344 -16.481999) (xy 274.806851 -16.359405)
			(xy 274.766995 -16.234121) (xy 274.734927 -16.106621) (xy 274.71077 -15.977388) (xy 274.694613 -15.846913)
			(xy 274.68652 -15.715692) (xy 274.686014 -15.649956) (xy 274.686014 -15.649702) (xy 274.686487 -15.585782)
			(xy 274.694146 -15.458171) (xy 274.70943 -15.331248) (xy 274.732285 -15.205467) (xy 274.762629 -15.08128)
			(xy 274.800353 -14.959132) (xy 274.845321 -14.839461) (xy 274.897372 -14.722697) (xy 274.95632 -14.609259)
			(xy 275.021953 -14.499553) (xy 275.057616 -14.446504) (xy 275.070316 -14.427708) (xy 275.071332 -14.426184)
			(xy 275.08073 -14.413484) (xy 275.08073 -14.412976) (xy 275.09978 -14.38656) (xy 275.100288 -14.386052)
			(xy 275.120354 -14.357604) (xy 275.156589 -14.310793) (xy 275.233518 -14.220805) (xy 275.315321 -14.135222)
			(xy 275.401744 -14.054309) (xy 275.492523 -13.978314) (xy 275.539708 -13.942568) (xy 275.57857 -13.91412)
			(xy 275.579332 -13.913612) (xy 275.57984 -13.913358) (xy 275.582126 -13.91158) (xy 275.58873 -13.904976)
			(xy 275.594963 -13.898101) (xy 275.602493 -13.881154) (xy 275.60355 -13.862641) (xy 275.601176 -13.853668)
			(xy 275.586698 -13.808202) (xy 275.586698 -13.807694) (xy 275.578062 -13.781024) (xy 275.578062 -13.780516)
			(xy 275.572728 -13.764514) (xy 275.569269 -13.753467) (xy 275.554219 -13.735909) (xy 275.532997 -13.726722)
			(xy 275.52142 -13.726668) (xy 274.904708 -13.726668) (xy 274.894697 -13.727154) (xy 274.876197 -13.734811)
			(xy 274.862034 -13.748963) (xy 274.854362 -13.767457) (xy 274.853908 -13.777468) (xy 274.853908 -13.895324)
			(xy 274.853429 -13.90529) (xy 274.845853 -13.923726) (xy 274.839176 -13.931138) (xy 274.66544 -14.104874)
			(xy 274.658039 -14.111714) (xy 274.639441 -14.11943) (xy 274.629372 -14.11986) (xy 267.165074 -14.11986)
			(xy 267.098426 -14.119382) (xy 266.96536 -14.111562) (xy 266.832983 -14.095945) (xy 266.70175 -14.072584)
			(xy 266.572115 -14.04156) (xy 266.444525 -14.002981) (xy 266.319419 -13.956978) (xy 266.197229 -13.903712)
			(xy 266.078377 -13.843364) (xy 265.963272 -13.776145) (xy 265.90752 -13.739622) (xy 265.901424 -13.735558)
			(xy 265.880088 -13.728954) (xy 265.87643 -13.727904) (xy 265.868906 -13.726764) (xy 265.865102 -13.726668)
			(xy 264.866882 -13.726668) (xy 264.856814 -13.726241) (xy 264.838217 -13.718518) (xy 264.830814 -13.711682)
			(xy 264.338054 -13.218922) (xy 264.331214 -13.211522) (xy 264.323499 -13.192923) (xy 264.323068 -13.182854)
			(xy 264.323068 -2.376932) (xy 264.322741 -2.368654) (xy 264.317419 -2.352976) (xy 264.312654 -2.346198)
			(xy 264.310622 -2.343912) (xy 264.308844 -2.342134) (xy 264.305542 -2.338324) (xy 263.664192 -1.696974)
			(xy 263.660461 -1.693453) (xy 263.651887 -1.687824) (xy 263.647174 -1.685798) (xy 263.638538 -1.682242)
			(xy 252.616462 -1.682242) (xy 252.608182 -1.682564) (xy 252.5925 -1.68788) (xy 252.585728 -1.692656)
			(xy 252.583442 -1.694688) (xy 252.581664 -1.696466) (xy 252.577854 -1.699768) (xy 251.85751 -2.420112)
			(xy 251.853987 -2.423841) (xy 251.848355 -2.432414) (xy 251.846334 -2.43713) (xy 251.842778 -2.445766)
			(xy 251.842778 -12.873482) (xy 251.842339 -12.883545) (xy 251.834602 -12.902126) (xy 251.827792 -12.90955)
			(xy 251.397008 -13.340334) (xy 251.386708 -13.351384) (xy 251.372506 -13.378026) (xy 251.366717 -13.407657)
			(xy 251.369848 -13.437685) (xy 251.381625 -13.465485) (xy 251.401019 -13.488623) (xy 251.426333 -13.505077)
			(xy 251.440696 -13.509752) (xy 251.503247 -13.528382) (xy 251.62627 -13.572006) (xy 251.746528 -13.622758)
			(xy 251.86361 -13.680462) (xy 251.977112 -13.744921) (xy 252.086647 -13.815914) (xy 252.191837 -13.893198)
			(xy 252.292323 -13.976507) (xy 252.387759 -14.065555) (xy 252.420879 -14.100302) (xy 257.442968 -14.100302)
			(xy 257.447039 -14.04468) (xy 257.459165 -13.990243) (xy 257.479088 -13.938152) (xy 257.506384 -13.889517)
			(xy 257.54047 -13.845374) (xy 257.580619 -13.806665) (xy 257.625977 -13.774214) (xy 257.675577 -13.748713)
			(xy 257.728361 -13.730706) (xy 257.783204 -13.720576) (xy 257.838938 -13.718539) (xy 257.894375 -13.724639)
			(xy 257.948332 -13.738745) (xy 257.999661 -13.760557) (xy 258.047267 -13.789611) (xy 258.090135 -13.825286)
			(xy 258.127352 -13.866823) (xy 258.158125 -13.913336) (xy 258.181797 -13.963833) (xy 258.197865 -14.01724)
			(xy 258.205985 -14.072416) (xy 258.206494 -14.100302) (xy 258.205985 -14.128188) (xy 258.197865 -14.183364)
			(xy 258.181797 -14.236771) (xy 258.158125 -14.287268) (xy 258.127352 -14.333781) (xy 258.090135 -14.375318)
			(xy 258.047267 -14.410993) (xy 257.999661 -14.440047) (xy 257.948332 -14.461859) (xy 257.894375 -14.475965)
			(xy 257.838938 -14.482065) (xy 257.783204 -14.480028) (xy 257.728361 -14.469898) (xy 257.675577 -14.451891)
			(xy 257.625977 -14.42639) (xy 257.580619 -14.393939) (xy 257.54047 -14.35523) (xy 257.506384 -14.311087)
			(xy 257.479088 -14.262452) (xy 257.459165 -14.210361) (xy 257.447039 -14.155924) (xy 257.442968 -14.100302)
			(xy 252.420879 -14.100302) (xy 252.477819 -14.160038) (xy 252.562194 -14.259631) (xy 252.640593 -14.363993)
			(xy 252.712749 -14.472765) (xy 252.778414 -14.585574) (xy 252.837362 -14.702034) (xy 252.889391 -14.821745)
			(xy 252.934323 -14.944297) (xy 252.972003 -15.069269) (xy 253.002304 -15.196232) (xy 253.025119 -15.324752)
			(xy 253.033685 -15.39755) (xy 258.10438 -15.39755) (xy 258.10438 -15.34305) (xy 258.112136 -15.289103)
			(xy 258.12749 -15.23681) (xy 258.15013 -15.187234) (xy 258.179595 -15.141384) (xy 258.215285 -15.100195)
			(xy 258.256473 -15.064503) (xy 258.302322 -15.035037) (xy 258.351897 -15.012395) (xy 258.40419 -14.997039)
			(xy 258.458136 -14.989281) (xy 258.485386 -14.988794) (xy 258.511621 -14.989263) (xy 258.563597 -14.996456)
			(xy 258.614095 -15.010709) (xy 258.662161 -15.031751) (xy 258.706889 -15.059186) (xy 258.747431 -15.092496)
			(xy 258.765548 -15.111476) (xy 258.765802 -15.11173) (xy 258.773518 -15.119132) (xy 258.793214 -15.127395)
			(xy 258.803902 -15.127732) (xy 258.891786 -15.125446) (xy 258.911344 -15.116048) (xy 258.918456 -15.107412)
			(xy 258.936664 -15.086259) (xy 258.978205 -15.048984) (xy 259.024735 -15.018163) (xy 259.075261 -14.994453)
			(xy 259.128703 -14.97836) (xy 259.18392 -14.970229) (xy 259.211826 -14.969744) (xy 259.239073 -14.970328)
			(xy 259.293011 -14.978086) (xy 259.345296 -14.993442) (xy 259.394863 -15.016082) (xy 259.440705 -15.045545)
			(xy 259.481887 -15.081232) (xy 259.517571 -15.122416) (xy 259.547031 -15.16826) (xy 259.569667 -15.217829)
			(xy 259.585019 -15.270115) (xy 259.592774 -15.324053) (xy 259.592774 -15.378547) (xy 259.585019 -15.432485)
			(xy 259.569667 -15.484771) (xy 259.547031 -15.53434) (xy 259.517571 -15.580184) (xy 259.481887 -15.621368)
			(xy 259.440705 -15.657055) (xy 259.394863 -15.686518) (xy 259.345296 -15.709158) (xy 259.293011 -15.724514)
			(xy 259.239073 -15.732272) (xy 259.211826 -15.73276) (xy 259.18559 -15.732298) (xy 259.133614 -15.725105)
			(xy 259.083115 -15.710852) (xy 259.035048 -15.689809) (xy 258.990321 -15.662372) (xy 258.94978 -15.62906)
			(xy 258.931664 -15.610078) (xy 258.93141 -15.609824) (xy 258.923695 -15.602421) (xy 258.903998 -15.59416)
			(xy 258.89331 -15.593822) (xy 258.805426 -15.596108) (xy 258.785868 -15.605506) (xy 258.778756 -15.614142)
			(xy 258.760531 -15.63528) (xy 258.718995 -15.672558) (xy 258.672469 -15.703382) (xy 258.621946 -15.727096)
			(xy 258.568506 -15.743191) (xy 258.513291 -15.751324) (xy 258.485386 -15.75181) (xy 258.458136 -15.751319)
			(xy 258.40419 -15.743561) (xy 258.351897 -15.728205) (xy 258.302322 -15.705563) (xy 258.256473 -15.676097)
			(xy 258.215285 -15.640405) (xy 258.179595 -15.599216) (xy 258.15013 -15.553366) (xy 258.12749 -15.50379)
			(xy 258.112136 -15.451497) (xy 258.10438 -15.39755) (xy 253.033685 -15.39755) (xy 253.040372 -15.454386)
			(xy 253.04801 -15.584692) (xy 253.048516 -15.649956) (xy 253.048008 -15.717282) (xy 253.039877 -15.851687)
			(xy 253.023647 -15.985357) (xy 252.999375 -16.117803) (xy 252.967151 -16.248542) (xy 252.927092 -16.377096)
			(xy 252.879344 -16.502997) (xy 252.824081 -16.625786) (xy 252.761506 -16.745014) (xy 252.691845 -16.860246)
			(xy 252.616092 -16.969994) (xy 271.948155 -16.969994) (xy 271.95216 -16.882086) (xy 271.964143 -16.794906)
			(xy 271.984003 -16.709177) (xy 272.011578 -16.625609) (xy 272.046637 -16.544895) (xy 272.08889 -16.467703)
			(xy 272.137988 -16.394674) (xy 272.193524 -16.326412) (xy 272.255036 -16.263482) (xy 272.322017 -16.206408)
			(xy 272.39391 -16.15566) (xy 272.470119 -16.11166) (xy 272.550014 -16.074773) (xy 272.632933 -16.045304)
			(xy 272.718188 -16.023497) (xy 272.805072 -16.009533) (xy 272.892866 -16.003527) (xy 272.980843 -16.005531)
			(xy 273.068273 -16.015526) (xy 273.154432 -16.03343) (xy 273.238606 -16.059094) (xy 273.320097 -16.092307)
			(xy 273.398231 -16.132793) (xy 273.472359 -16.180215) (xy 273.541867 -16.234182) (xy 273.606181 -16.294247)
			(xy 273.664765 -16.359911) (xy 273.717136 -16.43063) (xy 273.762859 -16.505818) (xy 273.801556 -16.584853)
			(xy 273.832905 -16.667079) (xy 273.856647 -16.751815) (xy 273.872585 -16.838359) (xy 273.880587 -16.925994)
			(xy 273.881088 -16.969994) (xy 273.880587 -17.013994) (xy 273.872585 -17.101629) (xy 273.856647 -17.188173)
			(xy 273.832905 -17.272909) (xy 273.801556 -17.355135) (xy 273.762859 -17.43417) (xy 273.717136 -17.509358)
			(xy 273.664765 -17.580077) (xy 273.606181 -17.645741) (xy 273.541867 -17.705806) (xy 273.472359 -17.759773)
			(xy 273.398231 -17.807195) (xy 273.320097 -17.847681) (xy 273.238606 -17.880894) (xy 273.154432 -17.906558)
			(xy 273.068273 -17.924462) (xy 272.980843 -17.934457) (xy 272.892866 -17.936461) (xy 272.805072 -17.930455)
			(xy 272.718188 -17.916491) (xy 272.632933 -17.894684) (xy 272.550014 -17.865215) (xy 272.470119 -17.828328)
			(xy 272.39391 -17.784328) (xy 272.322017 -17.73358) (xy 272.255036 -17.676506) (xy 272.193524 -17.613576)
			(xy 272.137988 -17.545314) (xy 272.08889 -17.472285) (xy 272.046637 -17.395093) (xy 272.011578 -17.314379)
			(xy 271.984003 -17.230811) (xy 271.964143 -17.145082) (xy 271.95216 -17.057902) (xy 271.948155 -16.969994)
			(xy 252.616092 -16.969994) (xy 252.615355 -16.971062) (xy 252.532313 -17.077057) (xy 252.443022 -17.177845)
			(xy 252.347809 -17.273058) (xy 252.247021 -17.362349) (xy 252.173979 -17.419574) (xy 256.484118 -17.419574)
			(xy 256.488189 -17.363952) (xy 256.500315 -17.309515) (xy 256.520238 -17.257424) (xy 256.547534 -17.208789)
			(xy 256.58162 -17.164646) (xy 256.621769 -17.125937) (xy 256.667127 -17.093486) (xy 256.716727 -17.067985)
			(xy 256.769511 -17.049978) (xy 256.824354 -17.039848) (xy 256.880088 -17.037811) (xy 256.935525 -17.043911)
			(xy 256.989482 -17.058017) (xy 257.040811 -17.079829) (xy 257.088417 -17.108883) (xy 257.131285 -17.144558)
			(xy 257.168502 -17.186095) (xy 257.199275 -17.232608) (xy 257.222947 -17.283105) (xy 257.239015 -17.336512)
			(xy 257.247135 -17.391688) (xy 257.247644 -17.419574) (xy 257.247135 -17.44746) (xy 257.239015 -17.502636)
			(xy 257.222947 -17.556043) (xy 257.199275 -17.60654) (xy 257.168502 -17.653053) (xy 257.131285 -17.69459)
			(xy 257.088417 -17.730265) (xy 257.040811 -17.759319) (xy 256.989482 -17.781131) (xy 256.935525 -17.795237)
			(xy 256.880088 -17.801337) (xy 256.824354 -17.7993) (xy 256.769511 -17.78917) (xy 256.716727 -17.771163)
			(xy 256.667127 -17.745662) (xy 256.621769 -17.713211) (xy 256.58162 -17.674502) (xy 256.547534 -17.630359)
			(xy 256.520238 -17.581724) (xy 256.500315 -17.529633) (xy 256.488189 -17.475196) (xy 256.484118 -17.419574)
			(xy 252.173979 -17.419574) (xy 252.141026 -17.445391) (xy 252.03021 -17.521881) (xy 251.914978 -17.591542)
			(xy 251.79575 -17.654117) (xy 251.672961 -17.70938) (xy 251.54706 -17.757128) (xy 251.418506 -17.797187)
			(xy 251.287767 -17.829411) (xy 251.155321 -17.853683) (xy 251.021651 -17.869913) (xy 250.887246 -17.878044)
			(xy 250.752594 -17.878044) (xy 250.618189 -17.869913) (xy 250.484519 -17.853683) (xy 250.352073 -17.829411)
			(xy 250.221334 -17.797187) (xy 250.09278 -17.757128) (xy 249.966879 -17.70938) (xy 249.84409 -17.654117)
			(xy 249.724862 -17.591542) (xy 249.60963 -17.521881) (xy 249.498814 -17.445391) (xy 249.392819 -17.362349)
			(xy 249.292031 -17.273058) (xy 249.196818 -17.177845) (xy 249.107527 -17.077057) (xy 249.024485 -16.971062)
			(xy 248.947995 -16.860246) (xy 248.878334 -16.745014) (xy 248.815759 -16.625786) (xy 248.760496 -16.502997)
			(xy 248.712748 -16.377096) (xy 248.672689 -16.248542) (xy 248.640465 -16.117803) (xy 248.616193 -15.985357)
			(xy 248.599963 -15.851687) (xy 248.591832 -15.717282) (xy 248.591324 -15.649956) (xy 248.59182 -15.583078)
			(xy 248.599844 -15.449564) (xy 248.615859 -15.316771) (xy 248.639809 -15.185178) (xy 248.671607 -15.055258)
			(xy 248.711138 -14.927478) (xy 248.758261 -14.802299) (xy 248.812806 -14.68017) (xy 248.874576 -14.561533)
			(xy 248.94335 -14.446813) (xy 249.018879 -14.336424) (xy 249.100891 -14.230762) (xy 249.189093 -14.130209)
			(xy 249.283165 -14.035126) (xy 249.38277 -13.945855) (xy 249.487549 -13.862718) (xy 249.542046 -13.82395)
			(xy 249.542808 -13.823442) (xy 249.551952 -13.816584) (xy 249.556786 -13.812217) (xy 249.564241 -13.801541)
			(xy 249.566684 -13.795502) (xy 249.567954 -13.791438) (xy 249.567954 -13.76426) (xy 249.56463 -13.754087)
			(xy 249.551158 -13.737489) (xy 249.532116 -13.727776) (xy 249.521472 -13.726668) (xy 248.916444 -13.726668)
			(xy 248.906415 -13.727079) (xy 248.887877 -13.73474) (xy 248.873683 -13.748913) (xy 248.865994 -13.767439)
			(xy 248.865644 -13.777468) (xy 248.865644 -13.91412) (xy 248.865167 -13.924087) (xy 248.857596 -13.942527)
			(xy 248.850912 -13.949934) (xy 248.695972 -14.104874) (xy 248.688573 -14.111719) (xy 248.669975 -14.119447)
			(xy 248.659904 -14.11986) (xy 241.164872 -14.11986) (xy 241.098224 -14.119382) (xy 240.965157 -14.111563)
			(xy 240.832779 -14.095946) (xy 240.701546 -14.072587) (xy 240.57191 -14.041566) (xy 240.444318 -14.002989)
			(xy 240.31921 -13.95699) (xy 240.197018 -13.903727) (xy 240.078162 -13.843384) (xy 239.963054 -13.776169)
			(xy 239.907318 -13.739622) (xy 239.901222 -13.735558) (xy 239.879886 -13.728954) (xy 239.87252 -13.726668)
			(xy 239.305084 -13.726668) (xy 239.295067 -13.726245) (xy 239.276561 -13.718571) (xy 239.262402 -13.704398)
			(xy 239.254745 -13.685885) (xy 239.254284 -13.675868) (xy 239.254284 -13.107416) (xy 239.253969 -13.099134)
			(xy 239.24866 -13.083445) (xy 239.24387 -13.076682) (xy 239.241838 -13.074396) (xy 239.24006 -13.072618)
			(xy 239.236758 -13.068808) (xy 238.635286 -12.467336) (xy 238.62844 -12.459938) (xy 238.620716 -12.441339)
			(xy 238.6203 -12.431268) (xy 238.6203 -0.998982) (xy 238.619873 -0.988913) (xy 238.612154 -0.970314)
			(xy 238.605314 -0.962914) (xy 238.393986 -0.751586) (xy 238.386591 -0.744732) (xy 238.367992 -0.73699)
			(xy 238.357918 -0.7366) (xy 213.685882 -0.7366) (xy 213.675813 -0.737027) (xy 213.657214 -0.744746)
			(xy 213.649814 -0.751586) (xy 213.419436 -0.981964) (xy 213.412596 -0.989364) (xy 213.404879 -1.007963)
			(xy 213.40445 -1.018032) (xy 213.40445 -13.206222) (xy 213.404021 -13.216289) (xy 213.396296 -13.234883)
			(xy 213.389464 -13.24229) (xy 213.215728 -13.416026) (xy 213.210867 -13.421318) (xy 213.204041 -13.433955)
			(xy 213.202266 -13.440918) (xy 213.201075 -13.446972) (xy 213.201328 -13.459304) (xy 213.202774 -13.465302)
			(xy 213.21649 -13.515086) (xy 213.21649 -13.515594) (xy 213.225126 -13.546836) (xy 213.226396 -13.549884)
			(xy 213.23427 -13.565886) (xy 213.242144 -13.574014) (xy 213.254844 -13.583666) (xy 213.264496 -13.586206)
			(xy 213.328872 -13.603732) (xy 213.455507 -13.645779) (xy 213.579269 -13.695656) (xy 213.699672 -13.753168)
			(xy 213.816247 -13.818089) (xy 213.928539 -13.890166) (xy 214.036109 -13.969117) (xy 214.138536 -14.054635)
			(xy 214.186759 -14.100302) (xy 219.342968 -14.100302) (xy 219.347039 -14.04468) (xy 219.359165 -13.990243)
			(xy 219.379088 -13.938152) (xy 219.406384 -13.889517) (xy 219.44047 -13.845374) (xy 219.480619 -13.806665)
			(xy 219.525977 -13.774214) (xy 219.575577 -13.748713) (xy 219.628361 -13.730706) (xy 219.683204 -13.720576)
			(xy 219.738938 -13.718539) (xy 219.794375 -13.724639) (xy 219.848332 -13.738745) (xy 219.899661 -13.760557)
			(xy 219.947267 -13.789611) (xy 219.990135 -13.825286) (xy 220.027352 -13.866823) (xy 220.058125 -13.913336)
			(xy 220.081797 -13.963833) (xy 220.097865 -14.01724) (xy 220.105985 -14.072416) (xy 220.106494 -14.100302)
			(xy 220.105985 -14.128188) (xy 220.097865 -14.183364) (xy 220.081797 -14.236771) (xy 220.058125 -14.287268)
			(xy 220.027352 -14.333781) (xy 219.990135 -14.375318) (xy 219.947267 -14.410993) (xy 219.899661 -14.440047)
			(xy 219.848332 -14.461859) (xy 219.794375 -14.475965) (xy 219.738938 -14.482065) (xy 219.683204 -14.480028)
			(xy 219.628361 -14.469898) (xy 219.575577 -14.451891) (xy 219.525977 -14.42639) (xy 219.480619 -14.393939)
			(xy 219.44047 -14.35523) (xy 219.406384 -14.311087) (xy 219.379088 -14.262452) (xy 219.359165 -14.210361)
			(xy 219.347039 -14.155924) (xy 219.342968 -14.100302) (xy 214.186759 -14.100302) (xy 214.23542 -14.146384)
			(xy 214.326383 -14.244007) (xy 214.41107 -14.347122) (xy 214.489149 -14.455327) (xy 214.560316 -14.568198)
			(xy 214.624293 -14.685294) (xy 214.680828 -14.806158) (xy 214.729703 -14.930319) (xy 214.770726 -15.05729)
			(xy 214.803736 -15.186576) (xy 214.828604 -15.317672) (xy 214.838638 -15.39755) (xy 220.00438 -15.39755)
			(xy 220.00438 -15.34305) (xy 220.012136 -15.289103) (xy 220.02749 -15.23681) (xy 220.05013 -15.187234)
			(xy 220.079595 -15.141384) (xy 220.115285 -15.100195) (xy 220.156473 -15.064503) (xy 220.202322 -15.035037)
			(xy 220.251897 -15.012395) (xy 220.30419 -14.997039) (xy 220.358136 -14.989281) (xy 220.385386 -14.988794)
			(xy 220.411621 -14.989263) (xy 220.463597 -14.996456) (xy 220.514095 -15.010709) (xy 220.562161 -15.031751)
			(xy 220.606889 -15.059186) (xy 220.647431 -15.092496) (xy 220.665548 -15.111476) (xy 220.665802 -15.11173)
			(xy 220.673518 -15.119132) (xy 220.693214 -15.127395) (xy 220.703902 -15.127732) (xy 220.791786 -15.125446)
			(xy 220.811344 -15.116048) (xy 220.818456 -15.107412) (xy 220.836664 -15.086259) (xy 220.878205 -15.048984)
			(xy 220.924735 -15.018163) (xy 220.975261 -14.994453) (xy 221.028703 -14.97836) (xy 221.08392 -14.970229)
			(xy 221.111826 -14.969744) (xy 221.139073 -14.970328) (xy 221.193011 -14.978086) (xy 221.245296 -14.993442)
			(xy 221.294863 -15.016082) (xy 221.340705 -15.045545) (xy 221.381887 -15.081232) (xy 221.417571 -15.122416)
			(xy 221.447031 -15.16826) (xy 221.469667 -15.217829) (xy 221.485019 -15.270115) (xy 221.492774 -15.324053)
			(xy 221.492774 -15.378547) (xy 221.485019 -15.432485) (xy 221.469667 -15.484771) (xy 221.447031 -15.53434)
			(xy 221.417571 -15.580184) (xy 221.381887 -15.621368) (xy 221.340705 -15.657055) (xy 221.294863 -15.686518)
			(xy 221.245296 -15.709158) (xy 221.193011 -15.724514) (xy 221.139073 -15.732272) (xy 221.111826 -15.73276)
			(xy 221.08559 -15.732298) (xy 221.033614 -15.725105) (xy 220.983115 -15.710852) (xy 220.935048 -15.689809)
			(xy 220.890321 -15.662372) (xy 220.84978 -15.62906) (xy 220.831664 -15.610078) (xy 220.83141 -15.609824)
			(xy 220.823695 -15.602421) (xy 220.803998 -15.59416) (xy 220.79331 -15.593822) (xy 220.705426 -15.596108)
			(xy 220.685868 -15.605506) (xy 220.678756 -15.614142) (xy 220.660531 -15.63528) (xy 220.618995 -15.672558)
			(xy 220.572469 -15.703382) (xy 220.521946 -15.727096) (xy 220.468506 -15.743191) (xy 220.413291 -15.751324)
			(xy 220.385386 -15.75181) (xy 220.358136 -15.751319) (xy 220.30419 -15.743561) (xy 220.251897 -15.728205)
			(xy 220.202322 -15.705563) (xy 220.156473 -15.676097) (xy 220.115285 -15.640405) (xy 220.079595 -15.599216)
			(xy 220.05013 -15.553366) (xy 220.02749 -15.50379) (xy 220.012136 -15.451497) (xy 220.00438 -15.39755)
			(xy 214.838638 -15.39755) (xy 214.845234 -15.450065) (xy 214.85356 -15.583239) (xy 214.854028 -15.649956)
			(xy 214.853552 -15.714429) (xy 214.845769 -15.843139) (xy 214.830229 -15.971144) (xy 214.806988 -16.097977)
			(xy 214.776132 -16.223176) (xy 214.737773 -16.346284) (xy 214.69205 -16.46685) (xy 214.639132 -16.584436)
			(xy 214.57921 -16.698613) (xy 214.512504 -16.808963) (xy 214.439256 -16.915084) (xy 214.396238 -16.969994)
			(xy 245.948207 -16.969994) (xy 245.952212 -16.882086) (xy 245.964195 -16.794906) (xy 245.984055 -16.709177)
			(xy 246.01163 -16.625609) (xy 246.046689 -16.544895) (xy 246.088942 -16.467703) (xy 246.13804 -16.394674)
			(xy 246.193576 -16.326412) (xy 246.255088 -16.263482) (xy 246.322069 -16.206408) (xy 246.393962 -16.15566)
			(xy 246.470171 -16.11166) (xy 246.550066 -16.074773) (xy 246.632985 -16.045304) (xy 246.71824 -16.023497)
			(xy 246.805124 -16.009533) (xy 246.892918 -16.003527) (xy 246.980895 -16.005531) (xy 247.068325 -16.015526)
			(xy 247.154484 -16.03343) (xy 247.238658 -16.059094) (xy 247.320149 -16.092307) (xy 247.398283 -16.132793)
			(xy 247.472411 -16.180215) (xy 247.541919 -16.234182) (xy 247.606233 -16.294247) (xy 247.664817 -16.359911)
			(xy 247.717188 -16.43063) (xy 247.762911 -16.505818) (xy 247.801608 -16.584853) (xy 247.832957 -16.667079)
			(xy 247.856699 -16.751815) (xy 247.872637 -16.838359) (xy 247.880639 -16.925994) (xy 247.88114 -16.969994)
			(xy 247.880639 -17.013994) (xy 247.872637 -17.101629) (xy 247.856699 -17.188173) (xy 247.832957 -17.272909)
			(xy 247.801608 -17.355135) (xy 247.762911 -17.43417) (xy 247.717188 -17.509358) (xy 247.664817 -17.580077)
			(xy 247.606233 -17.645741) (xy 247.541919 -17.705806) (xy 247.472411 -17.759773) (xy 247.398283 -17.807195)
			(xy 247.320149 -17.847681) (xy 247.238658 -17.880894) (xy 247.154484 -17.906558) (xy 247.068325 -17.924462)
			(xy 246.980895 -17.934457) (xy 246.892918 -17.936461) (xy 246.805124 -17.930455) (xy 246.71824 -17.916491)
			(xy 246.632985 -17.894684) (xy 246.550066 -17.865215) (xy 246.470171 -17.828328) (xy 246.393962 -17.784328)
			(xy 246.322069 -17.73358) (xy 246.255088 -17.676506) (xy 246.193576 -17.613576) (xy 246.13804 -17.545314)
			(xy 246.088942 -17.472285) (xy 246.046689 -17.395093) (xy 246.01163 -17.314379) (xy 245.984055 -17.230811)
			(xy 245.964195 -17.145082) (xy 245.952212 -17.057902) (xy 245.948207 -16.969994) (xy 214.396238 -16.969994)
			(xy 214.359735 -17.016588) (xy 214.27423 -17.113107) (xy 214.183053 -17.204286) (xy 214.086538 -17.289794)
			(xy 213.985035 -17.369318) (xy 213.912229 -17.419574) (xy 218.384118 -17.419574) (xy 218.388189 -17.363952)
			(xy 218.400315 -17.309515) (xy 218.420238 -17.257424) (xy 218.447534 -17.208789) (xy 218.48162 -17.164646)
			(xy 218.521769 -17.125937) (xy 218.567127 -17.093486) (xy 218.616727 -17.067985) (xy 218.669511 -17.049978)
			(xy 218.724354 -17.039848) (xy 218.780088 -17.037811) (xy 218.835525 -17.043911) (xy 218.889482 -17.058017)
			(xy 218.940811 -17.079829) (xy 218.988417 -17.108883) (xy 219.031285 -17.144558) (xy 219.068502 -17.186095)
			(xy 219.099275 -17.232608) (xy 219.122947 -17.283105) (xy 219.139015 -17.336512) (xy 219.147135 -17.391688)
			(xy 219.147644 -17.419574) (xy 219.147135 -17.44746) (xy 219.139015 -17.502636) (xy 219.122947 -17.556043)
			(xy 219.099275 -17.60654) (xy 219.068502 -17.653053) (xy 219.031285 -17.69459) (xy 218.988417 -17.730265)
			(xy 218.940811 -17.759319) (xy 218.889482 -17.781131) (xy 218.835525 -17.795237) (xy 218.780088 -17.801337)
			(xy 218.724354 -17.7993) (xy 218.669511 -17.78917) (xy 218.616727 -17.771163) (xy 218.567127 -17.745662)
			(xy 218.521769 -17.713211) (xy 218.48162 -17.674502) (xy 218.447534 -17.630359) (xy 218.420238 -17.581724)
			(xy 218.400315 -17.529633) (xy 218.388189 -17.475196) (xy 218.384118 -17.419574) (xy 213.912229 -17.419574)
			(xy 213.878916 -17.442569) (xy 213.768568 -17.509278) (xy 213.654394 -17.569204) (xy 213.536809 -17.622126)
			(xy 213.416244 -17.667852) (xy 213.293138 -17.706215) (xy 213.16794 -17.737075) (xy 213.041107 -17.760319)
			(xy 212.913102 -17.775863) (xy 212.784393 -17.78365) (xy 212.71992 -17.784064) (xy 212.655624 -17.783583)
			(xy 212.527264 -17.775841) (xy 212.399603 -17.760385) (xy 212.273105 -17.737269) (xy 212.148228 -17.706579)
			(xy 212.025426 -17.668424) (xy 211.905144 -17.622945) (xy 211.787819 -17.570306) (xy 211.673876 -17.510698)
			(xy 211.563729 -17.444337) (xy 211.457778 -17.371464) (xy 211.356407 -17.292344) (xy 211.259984 -17.207263)
			(xy 211.168859 -17.116531) (xy 211.083362 -17.020476) (xy 211.003805 -16.919448) (xy 210.930475 -16.813813)
			(xy 210.863639 -16.703953) (xy 210.803539 -16.590269) (xy 210.750393 -16.473172) (xy 210.704395 -16.353088)
			(xy 210.66571 -16.230452) (xy 210.634481 -16.105709) (xy 210.610819 -15.979311) (xy 210.594811 -15.851719)
			(xy 210.586515 -15.723394) (xy 210.585812 -15.6591) (xy 210.585812 -15.649702) (xy 210.586293 -15.585193)
			(xy 210.594092 -15.456412) (xy 210.609656 -15.328337) (xy 210.632927 -15.201435) (xy 210.66382 -15.076171)
			(xy 210.702224 -14.953002) (xy 210.747997 -14.832377) (xy 210.800973 -14.714738) (xy 210.860957 -14.600513)
			(xy 210.893914 -14.545056) (xy 210.895692 -14.542262) (xy 210.89874 -14.53515) (xy 210.900772 -14.531086)
			(xy 210.903566 -14.519656) (xy 210.904828 -14.512513) (xy 210.903661 -14.49806) (xy 210.90128 -14.491208)
			(xy 210.896708 -14.480032) (xy 210.889088 -14.472666) (xy 210.887818 -14.471396) (xy 210.886294 -14.469872)
			(xy 210.88325 -14.467085) (xy 210.878017 -14.460703) (xy 210.87588 -14.457172) (xy 210.852004 -14.414754)
			(xy 210.846924 -14.409928) (xy 210.84159 -14.404594) (xy 210.839558 -14.40307) (xy 210.838796 -14.402308)
			(xy 210.836002 -14.399768) (xy 210.82922 -14.395012) (xy 210.813544 -14.38969) (xy 210.805268 -14.389354)
			(xy 205.642464 -14.389354) (xy 205.632398 -14.388923) (xy 205.613807 -14.381194) (xy 205.606396 -14.374368)
			(xy 205.424786 -14.192758) (xy 205.421055 -14.189238) (xy 205.412479 -14.183611) (xy 205.407768 -14.181582)
			(xy 205.399132 -14.178026) (xy 201.944732 -14.178026) (xy 201.93468 -14.177523) (xy 201.916117 -14.169804)
			(xy 201.908664 -14.16304) (xy 200.74128 -12.995656) (xy 200.734432 -12.988259) (xy 200.726701 -12.96966)
			(xy 200.726294 -12.959588) (xy 200.726294 -2.436368) (xy 200.725971 -2.428089) (xy 200.720652 -2.412409)
			(xy 200.71588 -2.405634) (xy 200.713848 -2.403348) (xy 200.71207 -2.40157) (xy 200.708768 -2.39776)
			(xy 199.860662 -1.549654) (xy 199.856929 -1.546136) (xy 199.848353 -1.540513) (xy 199.843644 -1.538478)
			(xy 199.835008 -1.534922) (xy 188.56198 -1.534922) (xy 188.5537 -1.535243) (xy 188.538019 -1.540561)
			(xy 188.531246 -1.545336) (xy 188.52896 -1.547368) (xy 188.527182 -1.549146) (xy 188.523372 -1.552448)
			(xy 187.745624 -2.330196) (xy 187.742099 -2.333924) (xy 187.736463 -2.342496) (xy 187.734448 -2.347214)
			(xy 187.730892 -2.35585) (xy 187.730892 -13.488162) (xy 187.730457 -13.498227) (xy 187.722726 -13.516814)
			(xy 187.715906 -13.52423) (xy 187.657232 -13.582904) (xy 187.649255 -13.591866) (xy 187.641839 -13.614651)
			(xy 187.643008 -13.626592) (xy 187.643008 -13.626846) (xy 187.655454 -13.705078) (xy 187.660534 -13.71346)
			(xy 187.663328 -13.718286) (xy 187.676282 -13.736066) (xy 187.683648 -13.743686) (xy 187.687458 -13.746734)
			(xy 187.692792 -13.749528) (xy 187.750483 -13.779662) (xy 187.862486 -13.845993) (xy 187.970239 -13.919024)
			(xy 188.073345 -13.998483) (xy 188.171418 -14.084074) (xy 188.187872 -14.100302) (xy 193.34302 -14.100302)
			(xy 193.347091 -14.04468) (xy 193.359217 -13.990243) (xy 193.37914 -13.938152) (xy 193.406436 -13.889517)
			(xy 193.440522 -13.845374) (xy 193.480671 -13.806665) (xy 193.526029 -13.774214) (xy 193.575629 -13.748713)
			(xy 193.628413 -13.730706) (xy 193.683256 -13.720576) (xy 193.73899 -13.718539) (xy 193.794427 -13.724639)
			(xy 193.848384 -13.738745) (xy 193.899713 -13.760557) (xy 193.947319 -13.789611) (xy 193.990187 -13.825286)
			(xy 194.027404 -13.866823) (xy 194.058177 -13.913336) (xy 194.081849 -13.963833) (xy 194.097917 -14.01724)
			(xy 194.106037 -14.072416) (xy 194.106546 -14.100302) (xy 194.106037 -14.128188) (xy 194.097917 -14.183364)
			(xy 194.081849 -14.236771) (xy 194.058177 -14.287268) (xy 194.027404 -14.333781) (xy 193.990187 -14.375318)
			(xy 193.947319 -14.410993) (xy 193.899713 -14.440047) (xy 193.848384 -14.461859) (xy 193.794427 -14.475965)
			(xy 193.73899 -14.482065) (xy 193.683256 -14.480028) (xy 193.628413 -14.469898) (xy 193.575629 -14.451891)
			(xy 193.526029 -14.42639) (xy 193.480671 -14.393939) (xy 193.440522 -14.35523) (xy 193.406436 -14.311087)
			(xy 193.37914 -14.262452) (xy 193.359217 -14.210361) (xy 193.347091 -14.155924) (xy 193.34302 -14.100302)
			(xy 188.187872 -14.100302) (xy 188.264097 -14.175481) (xy 188.351035 -14.272362) (xy 188.431911 -14.37436)
			(xy 188.506424 -14.481094) (xy 188.574298 -14.592169) (xy 188.63528 -14.707171) (xy 188.689143 -14.825675)
			(xy 188.735689 -14.947239) (xy 188.774743 -15.071413) (xy 188.806161 -15.197735) (xy 188.829827 -15.325737)
			(xy 188.838623 -15.397554) (xy 194.004357 -15.397554) (xy 194.004357 -15.343046) (xy 194.012115 -15.289092)
			(xy 194.027473 -15.236791) (xy 194.050118 -15.187209) (xy 194.07959 -15.141354) (xy 194.115287 -15.10016)
			(xy 194.156484 -15.064467) (xy 194.202342 -15.035) (xy 194.251927 -15.01236) (xy 194.304229 -14.997007)
			(xy 194.358184 -14.989255) (xy 194.385438 -14.988794) (xy 194.411675 -14.989228) (xy 194.463652 -14.996429)
			(xy 194.51415 -15.010688) (xy 194.562217 -15.031737) (xy 194.606943 -15.059178) (xy 194.647484 -15.092493)
			(xy 194.6656 -15.111476) (xy 194.665854 -15.11173) (xy 194.673588 -15.11911) (xy 194.69327 -15.127385)
			(xy 194.703954 -15.127732) (xy 194.791838 -15.125446) (xy 194.811396 -15.116048) (xy 194.818508 -15.107412)
			(xy 194.836689 -15.086234) (xy 194.878235 -15.048961) (xy 194.924771 -15.018143) (xy 194.975302 -14.994437)
			(xy 195.028749 -14.97835) (xy 195.08397 -14.970225) (xy 195.111878 -14.969744) (xy 195.139128 -14.970302)
			(xy 195.193075 -14.978055) (xy 195.245369 -14.993407) (xy 195.294946 -15.016046) (xy 195.340796 -15.045509)
			(xy 195.381986 -15.081199) (xy 195.417677 -15.122387) (xy 195.447144 -15.168235) (xy 195.469785 -15.21781)
			(xy 195.48514 -15.270104) (xy 195.492897 -15.32405) (xy 195.492897 -15.37855) (xy 195.48514 -15.432497)
			(xy 195.469785 -15.48479) (xy 195.447144 -15.534365) (xy 195.417677 -15.580213) (xy 195.381986 -15.621401)
			(xy 195.340796 -15.657091) (xy 195.294946 -15.686554) (xy 195.245369 -15.709193) (xy 195.193075 -15.724545)
			(xy 195.139128 -15.732298) (xy 195.111878 -15.73276) (xy 195.085641 -15.73233) (xy 195.033663 -15.725131)
			(xy 194.983164 -15.710872) (xy 194.935097 -15.689822) (xy 194.890371 -15.662379) (xy 194.849831 -15.629062)
			(xy 194.831716 -15.610078) (xy 194.831462 -15.609824) (xy 194.823728 -15.602445) (xy 194.804046 -15.594171)
			(xy 194.793362 -15.593822) (xy 194.705478 -15.596108) (xy 194.68592 -15.605506) (xy 194.678808 -15.614142)
			(xy 194.660608 -15.635303) (xy 194.619067 -15.672579) (xy 194.572535 -15.703401) (xy 194.522008 -15.72711)
			(xy 194.468564 -15.7432) (xy 194.413345 -15.751328) (xy 194.385438 -15.75181) (xy 194.358184 -15.751345)
			(xy 194.304229 -15.743593) (xy 194.251927 -15.72824) (xy 194.202342 -15.7056) (xy 194.156484 -15.676133)
			(xy 194.115287 -15.64044) (xy 194.07959 -15.599246) (xy 194.050118 -15.553391) (xy 194.027473 -15.503809)
			(xy 194.012115 -15.451508) (xy 194.004357 -15.397554) (xy 188.838623 -15.397554) (xy 188.845651 -15.454942)
			(xy 188.853577 -15.584871) (xy 188.85408 -15.649956) (xy 188.853604 -15.714428) (xy 188.845821 -15.843137)
			(xy 188.830281 -15.971141) (xy 188.80704 -16.097974) (xy 188.776184 -16.223171) (xy 188.737824 -16.346278)
			(xy 188.692101 -16.466843) (xy 188.639183 -16.584428) (xy 188.57926 -16.698603) (xy 188.512554 -16.808951)
			(xy 188.439306 -16.915071) (xy 188.396277 -16.969994) (xy 207.848207 -16.969994) (xy 207.852212 -16.882086)
			(xy 207.864195 -16.794906) (xy 207.884055 -16.709177) (xy 207.91163 -16.625609) (xy 207.946689 -16.544895)
			(xy 207.988942 -16.467703) (xy 208.03804 -16.394674) (xy 208.093576 -16.326412) (xy 208.155088 -16.263482)
			(xy 208.222069 -16.206408) (xy 208.293962 -16.15566) (xy 208.370171 -16.11166) (xy 208.450066 -16.074773)
			(xy 208.532985 -16.045304) (xy 208.61824 -16.023497) (xy 208.705124 -16.009533) (xy 208.792918 -16.003527)
			(xy 208.880895 -16.005531) (xy 208.968325 -16.015526) (xy 209.054484 -16.03343) (xy 209.138658 -16.059094)
			(xy 209.220149 -16.092307) (xy 209.298283 -16.132793) (xy 209.372411 -16.180215) (xy 209.441919 -16.234182)
			(xy 209.506233 -16.294247) (xy 209.564817 -16.359911) (xy 209.617188 -16.43063) (xy 209.662911 -16.505818)
			(xy 209.701608 -16.584853) (xy 209.732957 -16.667079) (xy 209.756699 -16.751815) (xy 209.772637 -16.838359)
			(xy 209.780639 -16.925994) (xy 209.78114 -16.969994) (xy 209.780639 -17.013994) (xy 209.772637 -17.101629)
			(xy 209.756699 -17.188173) (xy 209.732957 -17.272909) (xy 209.701608 -17.355135) (xy 209.662911 -17.43417)
			(xy 209.617188 -17.509358) (xy 209.564817 -17.580077) (xy 209.506233 -17.645741) (xy 209.441919 -17.705806)
			(xy 209.372411 -17.759773) (xy 209.298283 -17.807195) (xy 209.220149 -17.847681) (xy 209.138658 -17.880894)
			(xy 209.054484 -17.906558) (xy 208.968325 -17.924462) (xy 208.880895 -17.934457) (xy 208.792918 -17.936461)
			(xy 208.705124 -17.930455) (xy 208.61824 -17.916491) (xy 208.532985 -17.894684) (xy 208.450066 -17.865215)
			(xy 208.370171 -17.828328) (xy 208.293962 -17.784328) (xy 208.222069 -17.73358) (xy 208.155088 -17.676506)
			(xy 208.093576 -17.613576) (xy 208.03804 -17.545314) (xy 207.988942 -17.472285) (xy 207.946689 -17.395093)
			(xy 207.91163 -17.314379) (xy 207.884055 -17.230811) (xy 207.864195 -17.145082) (xy 207.852212 -17.057902)
			(xy 207.848207 -16.969994) (xy 188.396277 -16.969994) (xy 188.359784 -17.016574) (xy 188.274279 -17.11309)
			(xy 188.183102 -17.204268) (xy 188.086586 -17.289774) (xy 187.985084 -17.369296) (xy 187.912244 -17.419574)
			(xy 192.38417 -17.419574) (xy 192.388241 -17.363952) (xy 192.400367 -17.309515) (xy 192.42029 -17.257424)
			(xy 192.447586 -17.208789) (xy 192.481672 -17.164646) (xy 192.521821 -17.125937) (xy 192.567179 -17.093486)
			(xy 192.616779 -17.067985) (xy 192.669563 -17.049978) (xy 192.724406 -17.039848) (xy 192.78014 -17.037811)
			(xy 192.835577 -17.043911) (xy 192.889534 -17.058017) (xy 192.940863 -17.079829) (xy 192.988469 -17.108883)
			(xy 193.031337 -17.144558) (xy 193.068554 -17.186095) (xy 193.099327 -17.232608) (xy 193.122999 -17.283105)
			(xy 193.139067 -17.336512) (xy 193.147187 -17.391688) (xy 193.147696 -17.419574) (xy 193.147187 -17.44746)
			(xy 193.139067 -17.502636) (xy 193.122999 -17.556043) (xy 193.099327 -17.60654) (xy 193.068554 -17.653053)
			(xy 193.031337 -17.69459) (xy 192.988469 -17.730265) (xy 192.940863 -17.759319) (xy 192.889534 -17.781131)
			(xy 192.835577 -17.795237) (xy 192.78014 -17.801337) (xy 192.724406 -17.7993) (xy 192.669563 -17.78917)
			(xy 192.616779 -17.771163) (xy 192.567179 -17.745662) (xy 192.521821 -17.713211) (xy 192.481672 -17.674502)
			(xy 192.447586 -17.630359) (xy 192.42029 -17.581724) (xy 192.400367 -17.529633) (xy 192.388241 -17.475196)
			(xy 192.38417 -17.419574) (xy 187.912244 -17.419574) (xy 187.878965 -17.442545) (xy 187.768617 -17.509253)
			(xy 187.654442 -17.569176) (xy 187.536858 -17.622095) (xy 187.416293 -17.667819) (xy 187.293187 -17.706179)
			(xy 187.167989 -17.737037) (xy 187.041157 -17.760278) (xy 186.913153 -17.77582) (xy 186.784444 -17.783603)
			(xy 186.719972 -17.784064) (xy 186.655677 -17.783582) (xy 186.527319 -17.775837) (xy 186.399661 -17.760378)
			(xy 186.273165 -17.73726) (xy 186.14829 -17.706568) (xy 186.02549 -17.668412) (xy 185.905211 -17.622932)
			(xy 185.787888 -17.570291) (xy 185.673948 -17.510682) (xy 185.563803 -17.44432) (xy 185.457855 -17.371447)
			(xy 185.356486 -17.292327) (xy 185.260066 -17.207246) (xy 185.168943 -17.116514) (xy 185.083449 -17.02046)
			(xy 185.003893 -16.919432) (xy 184.930565 -16.813798) (xy 184.863731 -16.70394) (xy 184.803632 -16.590257)
			(xy 184.750488 -16.473161) (xy 184.704491 -16.353078) (xy 184.665808 -16.230443) (xy 184.634579 -16.105702)
			(xy 184.610918 -15.979307) (xy 184.594911 -15.851716) (xy 184.586614 -15.723393) (xy 184.585864 -15.6591)
			(xy 184.585864 -15.649702) (xy 184.586345 -15.585193) (xy 184.594144 -15.456412) (xy 184.609707 -15.328336)
			(xy 184.632978 -15.201435) (xy 184.663871 -15.07617) (xy 184.702273 -14.953001) (xy 184.748046 -14.832376)
			(xy 184.80102 -14.714735) (xy 184.861004 -14.60051) (xy 184.893966 -14.545056) (xy 184.895744 -14.542262)
			(xy 184.898792 -14.53515) (xy 184.900824 -14.531086) (xy 184.903618 -14.519656) (xy 184.904879 -14.512513)
			(xy 184.903714 -14.49806) (xy 184.901332 -14.491208) (xy 184.89676 -14.480032) (xy 184.88914 -14.472666)
			(xy 184.88787 -14.471396) (xy 184.886346 -14.469872) (xy 184.883304 -14.467083) (xy 184.878076 -14.460699)
			(xy 184.875932 -14.457172) (xy 184.852056 -14.414754) (xy 184.846976 -14.409928) (xy 184.841642 -14.404594)
			(xy 184.83961 -14.40307) (xy 184.838848 -14.402308) (xy 184.836054 -14.399768) (xy 184.82927 -14.395019)
			(xy 184.813594 -14.389711) (xy 184.80532 -14.389354) (xy 176.165256 -14.389354) (xy 176.15519 -14.388921)
			(xy 176.136602 -14.381191) (xy 176.129188 -14.374368) (xy 174.645066 -12.890246) (xy 174.638221 -12.882848)
			(xy 174.630496 -12.864249) (xy 174.63008 -12.854178) (xy 174.63008 -1.143762) (xy 174.629649 -1.133695)
			(xy 174.621923 -1.115103) (xy 174.615094 -1.107694) (xy 174.309786 -0.802386) (xy 174.302391 -0.795532)
			(xy 174.283792 -0.78779) (xy 174.273718 -0.7874) (xy 161.869882 -0.7874) (xy 161.859813 -0.787827)
			(xy 161.841214 -0.795546) (xy 161.833814 -0.802386) (xy 161.79038 -0.84582) (xy 161.783528 -0.853216)
			(xy 161.775788 -0.871815) (xy 161.775394 -0.881888) (xy 161.775394 -12.60729) (xy 161.774972 -12.617361)
			(xy 161.76726 -12.635967) (xy 161.760408 -12.643358) (xy 161.028634 -13.375132) (xy 161.022571 -13.381749)
			(xy 161.015087 -13.398048) (xy 161.013634 -13.415924) (xy 161.01568 -13.424662) (xy 161.029904 -13.469112)
			(xy 161.029904 -13.46962) (xy 161.043874 -13.513816) (xy 161.04701 -13.521722) (xy 161.057618 -13.535003)
			(xy 161.071995 -13.544071) (xy 161.080196 -13.546328) (xy 161.083244 -13.546836) (xy 161.083498 -13.546836)
			(xy 161.147405 -13.558389) (xy 161.273805 -13.588269) (xy 161.398153 -13.62578) (xy 161.519991 -13.670782)
			(xy 161.638866 -13.723111) (xy 161.754339 -13.782571) (xy 161.865983 -13.848944) (xy 161.973384 -13.921982)
			(xy 162.076144 -14.001417) (xy 162.173884 -14.086953) (xy 162.266242 -14.178275) (xy 162.352876 -14.275044)
			(xy 162.433464 -14.376902) (xy 162.50771 -14.483472) (xy 162.575338 -14.59436) (xy 162.636097 -14.709155)
			(xy 162.647961 -14.735302) (xy 166.62476 -14.735302) (xy 166.628831 -14.67968) (xy 166.640957 -14.625243)
			(xy 166.66088 -14.573152) (xy 166.688176 -14.524517) (xy 166.722262 -14.480374) (xy 166.762411 -14.441665)
			(xy 166.807769 -14.409214) (xy 166.857369 -14.383713) (xy 166.910153 -14.365706) (xy 166.964996 -14.355576)
			(xy 167.02073 -14.353539) (xy 167.076167 -14.359639) (xy 167.130124 -14.373745) (xy 167.181453 -14.395557)
			(xy 167.229059 -14.424611) (xy 167.271927 -14.460286) (xy 167.309144 -14.501823) (xy 167.339917 -14.548336)
			(xy 167.363589 -14.598833) (xy 167.379657 -14.65224) (xy 167.387777 -14.707416) (xy 167.388286 -14.735302)
			(xy 167.387777 -14.763188) (xy 167.379657 -14.818364) (xy 167.363589 -14.871771) (xy 167.339917 -14.922268)
			(xy 167.309144 -14.968781) (xy 167.271927 -15.010318) (xy 167.229059 -15.045993) (xy 167.181453 -15.075047)
			(xy 167.130124 -15.096859) (xy 167.076167 -15.110965) (xy 167.02073 -15.117065) (xy 166.964996 -15.115028)
			(xy 166.910153 -15.104898) (xy 166.857369 -15.086891) (xy 166.807769 -15.06139) (xy 166.762411 -15.028939)
			(xy 166.722262 -14.99023) (xy 166.688176 -14.946087) (xy 166.66088 -14.897452) (xy 166.640957 -14.845361)
			(xy 166.628831 -14.790924) (xy 166.62476 -14.735302) (xy 162.647961 -14.735302) (xy 162.689763 -14.827432)
			(xy 162.736138 -14.948754) (xy 162.775049 -15.072671) (xy 162.806353 -15.198725) (xy 162.829933 -15.32645)
			(xy 162.83863 -15.397551) (xy 168.00448 -15.397551) (xy 168.00448 -15.343049) (xy 168.012236 -15.289103)
			(xy 168.02759 -15.236809) (xy 168.050231 -15.187233) (xy 168.079696 -15.141383) (xy 168.115386 -15.100193)
			(xy 168.156575 -15.064502) (xy 168.202424 -15.035036) (xy 168.252 -15.012394) (xy 168.304293 -14.997038)
			(xy 168.358239 -14.98928) (xy 168.38549 -14.988794) (xy 168.411726 -14.98926) (xy 168.463701 -14.996454)
			(xy 168.514199 -15.010707) (xy 168.562266 -15.03175) (xy 168.606993 -15.059186) (xy 168.647535 -15.092495)
			(xy 168.665652 -15.111476) (xy 168.665906 -15.11173) (xy 168.673621 -15.119134) (xy 168.693318 -15.127396)
			(xy 168.704006 -15.127732) (xy 168.79189 -15.125446) (xy 168.811448 -15.116048) (xy 168.81856 -15.107412)
			(xy 168.836766 -15.086257) (xy 168.878307 -15.048983) (xy 168.924838 -15.018161) (xy 168.975364 -14.994451)
			(xy 169.028806 -14.978359) (xy 169.084024 -14.970228) (xy 169.11193 -14.969744) (xy 169.139176 -14.970328)
			(xy 169.193114 -14.978087) (xy 169.245399 -14.993443) (xy 169.294966 -15.016083) (xy 169.340807 -15.045546)
			(xy 169.381988 -15.081233) (xy 169.417672 -15.122418) (xy 169.447131 -15.168261) (xy 169.469768 -15.21783)
			(xy 169.485119 -15.270115) (xy 169.492874 -15.324054) (xy 169.492874 -15.378546) (xy 169.485119 -15.432485)
			(xy 169.469768 -15.48477) (xy 169.447131 -15.534339) (xy 169.417672 -15.580182) (xy 169.381988 -15.621367)
			(xy 169.340807 -15.657054) (xy 169.294966 -15.686517) (xy 169.245399 -15.709157) (xy 169.193114 -15.724513)
			(xy 169.139176 -15.732272) (xy 169.11193 -15.73276) (xy 169.085692 -15.732362) (xy 169.033713 -15.725156)
			(xy 168.983213 -15.710891) (xy 168.935146 -15.689835) (xy 168.890421 -15.662387) (xy 168.849882 -15.629065)
			(xy 168.831768 -15.610078) (xy 168.831514 -15.609824) (xy 168.823798 -15.602423) (xy 168.804102 -15.594161)
			(xy 168.793414 -15.593822) (xy 168.70553 -15.596108) (xy 168.685972 -15.605506) (xy 168.67886 -15.614142)
			(xy 168.660632 -15.635278) (xy 168.619097 -15.672556) (xy 168.572571 -15.703381) (xy 168.522049 -15.727094)
			(xy 168.46861 -15.74319) (xy 168.413395 -15.751324) (xy 168.38549 -15.75181) (xy 168.358239 -15.75132)
			(xy 168.304293 -15.743562) (xy 168.252 -15.728206) (xy 168.202424 -15.705564) (xy 168.156575 -15.676098)
			(xy 168.115386 -15.640407) (xy 168.079696 -15.599217) (xy 168.050231 -15.553367) (xy 168.02759 -15.503791)
			(xy 168.012236 -15.451497) (xy 168.00448 -15.397551) (xy 162.83863 -15.397551) (xy 162.845703 -15.455372)
			(xy 162.853604 -15.585015) (xy 162.854132 -15.649956) (xy 162.853626 -15.715692) (xy 162.845533 -15.846913)
			(xy 162.829376 -15.977388) (xy 162.805219 -16.106621) (xy 162.773151 -16.234121) (xy 162.733295 -16.359405)
			(xy 162.685802 -16.481999) (xy 162.630853 -16.601436) (xy 162.568654 -16.717263) (xy 162.499444 -16.829042)
			(xy 162.423483 -16.936349) (xy 162.396409 -16.969994) (xy 181.848259 -16.969994) (xy 181.852264 -16.882086)
			(xy 181.864247 -16.794906) (xy 181.884107 -16.709177) (xy 181.911682 -16.625609) (xy 181.946741 -16.544895)
			(xy 181.988994 -16.467703) (xy 182.038092 -16.394674) (xy 182.093628 -16.326412) (xy 182.15514 -16.263482)
			(xy 182.222121 -16.206408) (xy 182.294014 -16.15566) (xy 182.370223 -16.11166) (xy 182.450118 -16.074773)
			(xy 182.533037 -16.045304) (xy 182.618292 -16.023497) (xy 182.705176 -16.009533) (xy 182.79297 -16.003527)
			(xy 182.880947 -16.005531) (xy 182.968377 -16.015526) (xy 183.054536 -16.03343) (xy 183.13871 -16.059094)
			(xy 183.220201 -16.092307) (xy 183.298335 -16.132793) (xy 183.372463 -16.180215) (xy 183.441971 -16.234182)
			(xy 183.506285 -16.294247) (xy 183.564869 -16.359911) (xy 183.61724 -16.43063) (xy 183.662963 -16.505818)
			(xy 183.70166 -16.584853) (xy 183.733009 -16.667079) (xy 183.756751 -16.751815) (xy 183.772689 -16.838359)
			(xy 183.780691 -16.925994) (xy 183.781192 -16.969994) (xy 183.780691 -17.013994) (xy 183.772689 -17.101629)
			(xy 183.756751 -17.188173) (xy 183.733009 -17.272909) (xy 183.70166 -17.355135) (xy 183.662963 -17.43417)
			(xy 183.61724 -17.509358) (xy 183.564869 -17.580077) (xy 183.506285 -17.645741) (xy 183.441971 -17.705806)
			(xy 183.372463 -17.759773) (xy 183.298335 -17.807195) (xy 183.220201 -17.847681) (xy 183.13871 -17.880894)
			(xy 183.054536 -17.906558) (xy 182.968377 -17.924462) (xy 182.880947 -17.934457) (xy 182.79297 -17.936461)
			(xy 182.705176 -17.930455) (xy 182.618292 -17.916491) (xy 182.533037 -17.894684) (xy 182.450118 -17.865215)
			(xy 182.370223 -17.828328) (xy 182.294014 -17.784328) (xy 182.222121 -17.73358) (xy 182.15514 -17.676506)
			(xy 182.093628 -17.613576) (xy 182.038092 -17.545314) (xy 181.988994 -17.472285) (xy 181.946741 -17.395093)
			(xy 181.911682 -17.314379) (xy 181.884107 -17.230811) (xy 181.864247 -17.145082) (xy 181.852264 -17.057902)
			(xy 181.848259 -16.969994) (xy 162.396409 -16.969994) (xy 162.341061 -17.038775) (xy 162.252489 -17.135934)
			(xy 162.158104 -17.227455) (xy 162.058265 -17.312993) (xy 161.953348 -17.392222) (xy 161.91207 -17.419574)
			(xy 166.384222 -17.419574) (xy 166.388293 -17.363952) (xy 166.400419 -17.309515) (xy 166.420342 -17.257424)
			(xy 166.447638 -17.208789) (xy 166.481724 -17.164646) (xy 166.521873 -17.125937) (xy 166.567231 -17.093486)
			(xy 166.616831 -17.067985) (xy 166.669615 -17.049978) (xy 166.724458 -17.039848) (xy 166.780192 -17.037811)
			(xy 166.835629 -17.043911) (xy 166.889586 -17.058017) (xy 166.940915 -17.079829) (xy 166.988521 -17.108883)
			(xy 167.031389 -17.144558) (xy 167.068606 -17.186095) (xy 167.099379 -17.232608) (xy 167.123051 -17.283105)
			(xy 167.139119 -17.336512) (xy 167.147239 -17.391688) (xy 167.147748 -17.419574) (xy 167.147239 -17.44746)
			(xy 167.139119 -17.502636) (xy 167.123051 -17.556043) (xy 167.099379 -17.60654) (xy 167.068606 -17.653053)
			(xy 167.031389 -17.69459) (xy 166.988521 -17.730265) (xy 166.940915 -17.759319) (xy 166.889586 -17.781131)
			(xy 166.835629 -17.795237) (xy 166.780192 -17.801337) (xy 166.724458 -17.7993) (xy 166.669615 -17.78917)
			(xy 166.616831 -17.771163) (xy 166.567231 -17.745662) (xy 166.521873 -17.713211) (xy 166.481724 -17.674502)
			(xy 166.447638 -17.630359) (xy 166.420342 -17.581724) (xy 166.400419 -17.529633) (xy 166.388293 -17.475196)
			(xy 166.384222 -17.419574) (xy 161.91207 -17.419574) (xy 161.843754 -17.464842) (xy 161.729896 -17.530577)
			(xy 161.612208 -17.589179) (xy 161.491136 -17.640425) (xy 161.367138 -17.68412) (xy 161.240686 -17.720099)
			(xy 161.112258 -17.748225) (xy 160.982343 -17.768391) (xy 160.851433 -17.780522) (xy 160.720024 -17.784571)
			(xy 160.588615 -17.780522) (xy 160.457705 -17.768391) (xy 160.32779 -17.748225) (xy 160.199362 -17.720099)
			(xy 160.07291 -17.68412) (xy 159.948912 -17.640425) (xy 159.82784 -17.589179) (xy 159.710152 -17.530577)
			(xy 159.596294 -17.464842) (xy 159.4867 -17.392222) (xy 159.381783 -17.312993) (xy 159.281944 -17.227455)
			(xy 159.187559 -17.135934) (xy 159.098987 -17.038775) (xy 159.016565 -16.936349) (xy 158.940604 -16.829042)
			(xy 158.871394 -16.717263) (xy 158.809195 -16.601436) (xy 158.754246 -16.481999) (xy 158.706753 -16.359405)
			(xy 158.666897 -16.234121) (xy 158.634829 -16.106621) (xy 158.610672 -15.977388) (xy 158.594515 -15.846913)
			(xy 158.586422 -15.715692) (xy 158.585916 -15.649956) (xy 158.585916 -15.627604) (xy 158.587123 -15.560184)
			(xy 158.596995 -15.425688) (xy 158.61534 -15.292084) (xy 158.642086 -15.159906) (xy 158.677126 -15.02968)
			(xy 158.720319 -14.901927) (xy 158.771495 -14.777156) (xy 158.830447 -14.655867) (xy 158.896941 -14.538542)
			(xy 158.933388 -14.48181) (xy 158.938214 -14.474444) (xy 158.939992 -14.468094) (xy 158.94177 -14.454886)
			(xy 158.94177 -14.42847) (xy 158.939738 -14.423136) (xy 158.895542 -14.341602) (xy 158.888666 -14.332254)
			(xy 158.868697 -14.320474) (xy 158.857188 -14.318996) (xy 158.85668 -14.318996) (xy 158.85287 -14.318742)
			(xy 149.646386 -14.318742) (xy 149.636318 -14.318315) (xy 149.617723 -14.31059) (xy 149.610318 -14.303756)
			(xy 148.795232 -13.48867) (xy 148.788387 -13.481271) (xy 148.780658 -13.462673) (xy 148.780246 -13.452602)
			(xy 148.780246 -2.454402) (xy 148.77993 -2.44612) (xy 148.774623 -2.43043) (xy 148.769832 -2.423668)
			(xy 148.7678 -2.421382) (xy 148.766022 -2.419604) (xy 148.76272 -2.415794) (xy 148.002498 -1.655572)
			(xy 147.998768 -1.65205) (xy 147.990194 -1.646421) (xy 147.98548 -1.644396) (xy 147.976844 -1.64084)
			(xy 136.069832 -1.64084) (xy 136.061554 -1.641167) (xy 136.045877 -1.64649) (xy 136.039098 -1.651254)
			(xy 136.036812 -1.653286) (xy 136.035034 -1.655064) (xy 136.031224 -1.658366) (xy 135.78205 -1.90754)
			(xy 135.778532 -1.911273) (xy 135.77291 -1.91985) (xy 135.770874 -1.924558) (xy 135.767318 -1.933194)
			(xy 135.767318 -12.994894) (xy 135.766897 -13.004965) (xy 135.759186 -13.023573) (xy 135.752332 -13.030962)
			(xy 135.353298 -13.429996) (xy 135.342884 -13.438124) (xy 135.330692 -13.445236) (xy 135.328152 -13.44676)
			(xy 135.321802 -13.461492) (xy 135.318793 -13.469189) (xy 135.317381 -13.485646) (xy 135.319008 -13.49375)
			(xy 135.331708 -13.546328) (xy 135.331708 -13.546836) (xy 135.338566 -13.575538) (xy 135.340348 -13.582288)
			(xy 135.347049 -13.594529) (xy 135.351774 -13.599668) (xy 135.359394 -13.607288) (xy 135.361172 -13.608812)
			(xy 135.364474 -13.61186) (xy 135.369808 -13.61567) (xy 135.373872 -13.61821) (xy 135.434653 -13.638272)
			(xy 135.553934 -13.684729) (xy 135.670216 -13.738252) (xy 135.78308 -13.798648) (xy 135.892122 -13.865701)
			(xy 135.996949 -13.939168) (xy 136.097184 -14.018787) (xy 136.188044 -14.100302) (xy 141.343124 -14.100302)
			(xy 141.347195 -14.04468) (xy 141.359321 -13.990243) (xy 141.379244 -13.938152) (xy 141.40654 -13.889517)
			(xy 141.440626 -13.845374) (xy 141.480775 -13.806665) (xy 141.526133 -13.774214) (xy 141.575733 -13.748713)
			(xy 141.628517 -13.730706) (xy 141.68336 -13.720576) (xy 141.739094 -13.718539) (xy 141.794531 -13.724639)
			(xy 141.848488 -13.738745) (xy 141.899817 -13.760557) (xy 141.947423 -13.789611) (xy 141.990291 -13.825286)
			(xy 142.027508 -13.866823) (xy 142.058281 -13.913336) (xy 142.081953 -13.963833) (xy 142.098021 -14.01724)
			(xy 142.106141 -14.072416) (xy 142.10665 -14.100302) (xy 142.106141 -14.128188) (xy 142.098021 -14.183364)
			(xy 142.081953 -14.236771) (xy 142.058281 -14.287268) (xy 142.027508 -14.333781) (xy 141.990291 -14.375318)
			(xy 141.947423 -14.410993) (xy 141.899817 -14.440047) (xy 141.848488 -14.461859) (xy 141.794531 -14.475965)
			(xy 141.739094 -14.482065) (xy 141.68336 -14.480028) (xy 141.628517 -14.469898) (xy 141.575733 -14.451891)
			(xy 141.526133 -14.42639) (xy 141.480775 -14.393939) (xy 141.440626 -14.35523) (xy 141.40654 -14.311087)
			(xy 141.379244 -14.262452) (xy 141.359321 -14.210361) (xy 141.347195 -14.155924) (xy 141.343124 -14.100302)
			(xy 136.188044 -14.100302) (xy 136.192467 -14.10427) (xy 136.282455 -14.195311) (xy 136.366824 -14.291581)
			(xy 136.445271 -14.392736) (xy 136.517515 -14.49841) (xy 136.583294 -14.608225) (xy 136.642373 -14.721785)
			(xy 136.69454 -14.838682) (xy 136.739606 -14.958495) (xy 136.77741 -15.080794) (xy 136.807816 -15.205139)
			(xy 136.830714 -15.331083) (xy 136.838721 -15.397555) (xy 142.004457 -15.397555) (xy 142.004457 -15.343045)
			(xy 142.012215 -15.289091) (xy 142.027574 -15.23679) (xy 142.050219 -15.187207) (xy 142.079691 -15.141353)
			(xy 142.115389 -15.100159) (xy 142.156586 -15.064466) (xy 142.202444 -15.034999) (xy 142.25203 -15.012359)
			(xy 142.304332 -14.997007) (xy 142.358287 -14.989254) (xy 142.385542 -14.988794) (xy 142.411779 -14.989226)
			(xy 142.463756 -14.996426) (xy 142.514254 -15.010686) (xy 142.562321 -15.031736) (xy 142.607047 -15.059178)
			(xy 142.647588 -15.092493) (xy 142.665704 -15.111476) (xy 142.665958 -15.11173) (xy 142.673691 -15.119112)
			(xy 142.693374 -15.127386) (xy 142.704058 -15.127732) (xy 142.791942 -15.125446) (xy 142.8115 -15.116048)
			(xy 142.818612 -15.107412) (xy 142.83679 -15.086232) (xy 142.878337 -15.048959) (xy 142.924874 -15.018141)
			(xy 142.975405 -14.994435) (xy 143.028853 -14.978349) (xy 143.084074 -14.970225) (xy 143.111982 -14.969744)
			(xy 143.139232 -14.970302) (xy 143.193178 -14.978056) (xy 143.245472 -14.993408) (xy 143.295048 -15.016047)
			(xy 143.340898 -15.045511) (xy 143.382087 -15.0812) (xy 143.417778 -15.122388) (xy 143.447244 -15.168236)
			(xy 143.469885 -15.217811) (xy 143.48524 -15.270104) (xy 143.492997 -15.32405) (xy 143.492997 -15.37855)
			(xy 143.48524 -15.432496) (xy 143.469885 -15.484789) (xy 143.447244 -15.534364) (xy 143.417778 -15.580212)
			(xy 143.382087 -15.6214) (xy 143.340898 -15.657089) (xy 143.295048 -15.686553) (xy 143.245472 -15.709192)
			(xy 143.193178 -15.724544) (xy 143.139232 -15.732298) (xy 143.111982 -15.73276) (xy 143.085745 -15.732327)
			(xy 143.033768 -15.725129) (xy 142.983268 -15.71087) (xy 142.935202 -15.689821) (xy 142.890475 -15.662379)
			(xy 142.849935 -15.629062) (xy 142.83182 -15.610078) (xy 142.831566 -15.609824) (xy 142.82383 -15.602446)
			(xy 142.804149 -15.594171) (xy 142.793466 -15.593822) (xy 142.705582 -15.596108) (xy 142.686024 -15.605506)
			(xy 142.678912 -15.614142) (xy 142.66071 -15.635301) (xy 142.619169 -15.672577) (xy 142.572638 -15.703399)
			(xy 142.522111 -15.727109) (xy 142.468667 -15.7432) (xy 142.413449 -15.751328) (xy 142.385542 -15.75181)
			(xy 142.358287 -15.751346) (xy 142.304332 -15.743593) (xy 142.25203 -15.728241) (xy 142.202444 -15.705601)
			(xy 142.156586 -15.676134) (xy 142.115389 -15.640441) (xy 142.079691 -15.599247) (xy 142.050219 -15.553393)
			(xy 142.027574 -15.50381) (xy 142.012215 -15.451509) (xy 142.004457 -15.397555) (xy 136.838721 -15.397555)
			(xy 136.846022 -15.458173) (xy 136.853685 -15.585952) (xy 136.854184 -15.649956) (xy 136.853708 -15.714428)
			(xy 136.845925 -15.843137) (xy 136.830385 -15.971142) (xy 136.807144 -16.097974) (xy 136.776288 -16.223172)
			(xy 136.737928 -16.346278) (xy 136.692206 -16.466844) (xy 136.639287 -16.584428) (xy 136.579365 -16.698604)
			(xy 136.512658 -16.808952) (xy 136.43941 -16.915072) (xy 136.396382 -16.969994) (xy 155.848311 -16.969994)
			(xy 155.852316 -16.882086) (xy 155.864299 -16.794906) (xy 155.884159 -16.709177) (xy 155.911734 -16.625609)
			(xy 155.946793 -16.544895) (xy 155.989046 -16.467703) (xy 156.038144 -16.394674) (xy 156.09368 -16.326412)
			(xy 156.155192 -16.263482) (xy 156.222173 -16.206408) (xy 156.294066 -16.15566) (xy 156.370275 -16.11166)
			(xy 156.45017 -16.074773) (xy 156.533089 -16.045304) (xy 156.618344 -16.023497) (xy 156.705228 -16.009533)
			(xy 156.793022 -16.003527) (xy 156.880999 -16.005531) (xy 156.968429 -16.015526) (xy 157.054588 -16.03343)
			(xy 157.138762 -16.059094) (xy 157.220253 -16.092307) (xy 157.298387 -16.132793) (xy 157.372515 -16.180215)
			(xy 157.442023 -16.234182) (xy 157.506337 -16.294247) (xy 157.564921 -16.359911) (xy 157.617292 -16.43063)
			(xy 157.663015 -16.505818) (xy 157.701712 -16.584853) (xy 157.733061 -16.667079) (xy 157.756803 -16.751815)
			(xy 157.772741 -16.838359) (xy 157.780743 -16.925994) (xy 157.781244 -16.969994) (xy 157.780743 -17.013994)
			(xy 157.772741 -17.101629) (xy 157.756803 -17.188173) (xy 157.733061 -17.272909) (xy 157.701712 -17.355135)
			(xy 157.663015 -17.43417) (xy 157.617292 -17.509358) (xy 157.564921 -17.580077) (xy 157.506337 -17.645741)
			(xy 157.442023 -17.705806) (xy 157.372515 -17.759773) (xy 157.298387 -17.807195) (xy 157.220253 -17.847681)
			(xy 157.138762 -17.880894) (xy 157.054588 -17.906558) (xy 156.968429 -17.924462) (xy 156.880999 -17.934457)
			(xy 156.793022 -17.936461) (xy 156.705228 -17.930455) (xy 156.618344 -17.916491) (xy 156.533089 -17.894684)
			(xy 156.45017 -17.865215) (xy 156.370275 -17.828328) (xy 156.294066 -17.784328) (xy 156.222173 -17.73358)
			(xy 156.155192 -17.676506) (xy 156.09368 -17.613576) (xy 156.038144 -17.545314) (xy 155.989046 -17.472285)
			(xy 155.946793 -17.395093) (xy 155.911734 -17.314379) (xy 155.884159 -17.230811) (xy 155.864299 -17.145082)
			(xy 155.852316 -17.057902) (xy 155.848311 -16.969994) (xy 136.396382 -16.969994) (xy 136.359888 -17.016575)
			(xy 136.274383 -17.113092) (xy 136.183206 -17.20427) (xy 136.086691 -17.289776) (xy 135.985188 -17.369298)
			(xy 135.912351 -17.419574) (xy 140.384274 -17.419574) (xy 140.388345 -17.363952) (xy 140.400471 -17.309515)
			(xy 140.420394 -17.257424) (xy 140.44769 -17.208789) (xy 140.481776 -17.164646) (xy 140.521925 -17.125937)
			(xy 140.567283 -17.093486) (xy 140.616883 -17.067985) (xy 140.669667 -17.049978) (xy 140.72451 -17.039848)
			(xy 140.780244 -17.037811) (xy 140.835681 -17.043911) (xy 140.889638 -17.058017) (xy 140.940967 -17.079829)
			(xy 140.988573 -17.108883) (xy 141.031441 -17.144558) (xy 141.068658 -17.186095) (xy 141.099431 -17.232608)
			(xy 141.123103 -17.283105) (xy 141.139171 -17.336512) (xy 141.147291 -17.391688) (xy 141.1478 -17.419574)
			(xy 141.147291 -17.44746) (xy 141.139171 -17.502636) (xy 141.123103 -17.556043) (xy 141.099431 -17.60654)
			(xy 141.068658 -17.653053) (xy 141.031441 -17.69459) (xy 140.988573 -17.730265) (xy 140.940967 -17.759319)
			(xy 140.889638 -17.781131) (xy 140.835681 -17.795237) (xy 140.780244 -17.801337) (xy 140.72451 -17.7993)
			(xy 140.669667 -17.78917) (xy 140.616883 -17.771163) (xy 140.567283 -17.745662) (xy 140.521925 -17.713211)
			(xy 140.481776 -17.674502) (xy 140.44769 -17.630359) (xy 140.420394 -17.581724) (xy 140.400471 -17.529633)
			(xy 140.388345 -17.475196) (xy 140.384274 -17.419574) (xy 135.912351 -17.419574) (xy 135.879069 -17.442547)
			(xy 135.768721 -17.509255) (xy 135.654546 -17.569178) (xy 135.536962 -17.622098) (xy 135.416397 -17.667822)
			(xy 135.293291 -17.706182) (xy 135.168094 -17.73704) (xy 135.041261 -17.760282) (xy 134.913257 -17.775823)
			(xy 134.784548 -17.783607) (xy 134.720076 -17.784064) (xy 134.655655 -17.783578) (xy 134.527046 -17.775803)
			(xy 134.399142 -17.760283) (xy 134.272406 -17.737074) (xy 134.147302 -17.706261) (xy 134.024285 -17.667957)
			(xy 133.903803 -17.6223) (xy 133.786295 -17.569457) (xy 133.672189 -17.509621) (xy 133.561901 -17.44301)
			(xy 133.455833 -17.369865) (xy 133.354371 -17.290455) (xy 133.257885 -17.205068) (xy 133.166727 -17.114015)
			(xy 133.081228 -17.017628) (xy 133.0017 -16.916258) (xy 132.928433 -16.810275) (xy 132.861694 -16.700064)
			(xy 132.801726 -16.586028) (xy 132.748747 -16.468581) (xy 132.702951 -16.348152) (xy 132.664504 -16.225179)
			(xy 132.633546 -16.100111) (xy 132.61019 -15.973402) (xy 132.594522 -15.845516) (xy 132.586598 -15.716917)
			(xy 132.585968 -15.652496) (xy 132.585968 -15.649702) (xy 132.586476 -15.584199) (xy 132.594527 -15.45344)
			(xy 132.610581 -15.323422) (xy 132.634578 -15.194632) (xy 132.666428 -15.067556) (xy 132.706009 -14.942673)
			(xy 132.753174 -14.820451) (xy 132.780024 -14.760702) (xy 132.789168 -14.740636) (xy 132.789168 -14.734286)
			(xy 132.78993 -14.730984) (xy 132.791063 -14.721808) (xy 132.787413 -14.703701) (xy 132.782818 -14.695678)
			(xy 132.782564 -14.69517) (xy 132.748782 -14.64183) (xy 132.73659 -14.62278) (xy 132.734042 -14.619215)
			(xy 132.727906 -14.612961) (xy 132.724398 -14.610334) (xy 132.718039 -14.606128) (xy 132.703564 -14.601358)
			(xy 132.69595 -14.600936) (xy 124.113798 -14.600936) (xy 124.103729 -14.600511) (xy 124.085131 -14.592789)
			(xy 124.07773 -14.58595) (xy 122.5931 -13.10132) (xy 122.586266 -13.093917) (xy 122.578561 -13.075319)
			(xy 122.578114 -13.065252) (xy 122.578114 -2.08407) (xy 122.577792 -2.07579) (xy 122.572475 -2.060108)
			(xy 122.5677 -2.053336) (xy 122.565668 -2.05105) (xy 122.56389 -2.049272) (xy 122.560588 -2.045462)
			(xy 122.099832 -1.584706) (xy 122.096104 -1.58118) (xy 122.087534 -1.575542) (xy 122.082814 -1.57353)
			(xy 122.074178 -1.569974) (xy 98.933 -1.569974) (xy 98.924718 -1.570291) (xy 98.90903 -1.5756) (xy 98.902266 -1.580388)
			(xy 98.89998 -1.58242) (xy 98.898202 -1.584198) (xy 98.894392 -1.5875) (xy 97.87001 -2.611882) (xy 97.866485 -2.61561)
			(xy 97.860848 -2.624181) (xy 97.858834 -2.6289) (xy 97.855278 -2.637536) (xy 97.855278 -5.747258)
			(xy 103.958388 -5.747258) (xy 103.962459 -5.691636) (xy 103.974585 -5.637199) (xy 103.994508 -5.585108)
			(xy 104.021804 -5.536473) (xy 104.05589 -5.49233) (xy 104.096039 -5.453621) (xy 104.141397 -5.42117)
			(xy 104.190997 -5.395669) (xy 104.243781 -5.377662) (xy 104.298624 -5.367532) (xy 104.354358 -5.365495)
			(xy 104.409795 -5.371595) (xy 104.463752 -5.385701) (xy 104.515081 -5.407513) (xy 104.562687 -5.436567)
			(xy 104.605555 -5.472242) (xy 104.642772 -5.513779) (xy 104.673545 -5.560292) (xy 104.697217 -5.610789)
			(xy 104.713285 -5.664196) (xy 104.721405 -5.719372) (xy 104.721914 -5.747258) (xy 106.926124 -5.747258)
			(xy 106.930195 -5.691636) (xy 106.942321 -5.637199) (xy 106.962244 -5.585108) (xy 106.98954 -5.536473)
			(xy 107.023626 -5.49233) (xy 107.063775 -5.453621) (xy 107.109133 -5.42117) (xy 107.158733 -5.395669)
			(xy 107.211517 -5.377662) (xy 107.26636 -5.367532) (xy 107.322094 -5.365495) (xy 107.377531 -5.371595)
			(xy 107.431488 -5.385701) (xy 107.482817 -5.407513) (xy 107.530423 -5.436567) (xy 107.573291 -5.472242)
			(xy 107.610508 -5.513779) (xy 107.641281 -5.560292) (xy 107.664953 -5.610789) (xy 107.681021 -5.664196)
			(xy 107.689141 -5.719372) (xy 107.68965 -5.747258) (xy 107.689141 -5.775144) (xy 107.681021 -5.83032)
			(xy 107.664953 -5.883727) (xy 107.641281 -5.934224) (xy 107.610508 -5.980737) (xy 107.573291 -6.022274)
			(xy 107.530423 -6.057949) (xy 107.482817 -6.087003) (xy 107.431488 -6.108815) (xy 107.377531 -6.122921)
			(xy 107.322094 -6.129021) (xy 107.26636 -6.126984) (xy 107.211517 -6.116854) (xy 107.158733 -6.098847)
			(xy 107.109133 -6.073346) (xy 107.063775 -6.040895) (xy 107.023626 -6.002186) (xy 106.98954 -5.958043)
			(xy 106.962244 -5.909408) (xy 106.942321 -5.857317) (xy 106.930195 -5.80288) (xy 106.926124 -5.747258)
			(xy 104.721914 -5.747258) (xy 104.721405 -5.775144) (xy 104.713285 -5.83032) (xy 104.697217 -5.883727)
			(xy 104.673545 -5.934224) (xy 104.642772 -5.980737) (xy 104.605555 -6.022274) (xy 104.562687 -6.057949)
			(xy 104.515081 -6.087003) (xy 104.463752 -6.108815) (xy 104.409795 -6.122921) (xy 104.354358 -6.129021)
			(xy 104.298624 -6.126984) (xy 104.243781 -6.116854) (xy 104.190997 -6.098847) (xy 104.141397 -6.073346)
			(xy 104.096039 -6.040895) (xy 104.05589 -6.002186) (xy 104.021804 -5.958043) (xy 103.994508 -5.909408)
			(xy 103.974585 -5.857317) (xy 103.962459 -5.80288) (xy 103.958388 -5.747258) (xy 97.855278 -5.747258)
			(xy 97.855278 -6.931152) (xy 98.156774 -6.931152) (xy 98.160845 -6.87553) (xy 98.172971 -6.821093)
			(xy 98.192894 -6.769002) (xy 98.22019 -6.720367) (xy 98.254276 -6.676224) (xy 98.294425 -6.637515)
			(xy 98.339783 -6.605064) (xy 98.389383 -6.579563) (xy 98.442167 -6.561556) (xy 98.49701 -6.551426)
			(xy 98.552744 -6.549389) (xy 98.608181 -6.555489) (xy 98.662138 -6.569595) (xy 98.713467 -6.591407)
			(xy 98.761073 -6.620461) (xy 98.803941 -6.656136) (xy 98.841158 -6.697673) (xy 98.871931 -6.744186)
			(xy 98.895603 -6.794683) (xy 98.911671 -6.84809) (xy 98.919791 -6.903266) (xy 98.9203 -6.931152)
			(xy 98.919791 -6.959038) (xy 98.916494 -6.981444) (xy 104.810812 -6.981444) (xy 104.814883 -6.925822)
			(xy 104.827009 -6.871385) (xy 104.846932 -6.819294) (xy 104.874228 -6.770659) (xy 104.908314 -6.726516)
			(xy 104.948463 -6.687807) (xy 104.993821 -6.655356) (xy 105.043421 -6.629855) (xy 105.096205 -6.611848)
			(xy 105.151048 -6.601718) (xy 105.206782 -6.599681) (xy 105.262219 -6.605781) (xy 105.316176 -6.619887)
			(xy 105.367505 -6.641699) (xy 105.415111 -6.670753) (xy 105.457979 -6.706428) (xy 105.487733 -6.739636)
			(xy 106.901994 -6.739636) (xy 106.906065 -6.684014) (xy 106.918191 -6.629577) (xy 106.938114 -6.577486)
			(xy 106.96541 -6.528851) (xy 106.999496 -6.484708) (xy 107.039645 -6.445999) (xy 107.085003 -6.413548)
			(xy 107.134603 -6.388047) (xy 107.187387 -6.37004) (xy 107.24223 -6.35991) (xy 107.297964 -6.357873)
			(xy 107.353401 -6.363973) (xy 107.407358 -6.378079) (xy 107.458687 -6.399891) (xy 107.506293 -6.428945)
			(xy 107.549161 -6.46462) (xy 107.586378 -6.506157) (xy 107.617151 -6.55267) (xy 107.640823 -6.603167)
			(xy 107.656891 -6.656574) (xy 107.665011 -6.71175) (xy 107.66552 -6.739636) (xy 107.665011 -6.767522)
			(xy 107.656891 -6.822698) (xy 107.640823 -6.876105) (xy 107.617151 -6.926602) (xy 107.586378 -6.973115)
			(xy 107.549161 -7.014652) (xy 107.506293 -7.050327) (xy 107.458687 -7.079381) (xy 107.407358 -7.101193)
			(xy 107.353401 -7.115299) (xy 107.297964 -7.121399) (xy 107.24223 -7.119362) (xy 107.187387 -7.109232)
			(xy 107.134603 -7.091225) (xy 107.085003 -7.065724) (xy 107.039645 -7.033273) (xy 106.999496 -6.994564)
			(xy 106.96541 -6.950421) (xy 106.938114 -6.901786) (xy 106.918191 -6.849695) (xy 106.906065 -6.795258)
			(xy 106.901994 -6.739636) (xy 105.487733 -6.739636) (xy 105.495196 -6.747965) (xy 105.525969 -6.794478)
			(xy 105.549641 -6.844975) (xy 105.565709 -6.898382) (xy 105.573829 -6.953558) (xy 105.574338 -6.981444)
			(xy 105.573829 -7.00933) (xy 105.565709 -7.064506) (xy 105.549641 -7.117913) (xy 105.525969 -7.16841)
			(xy 105.495196 -7.214923) (xy 105.457979 -7.25646) (xy 105.415111 -7.292135) (xy 105.367505 -7.321189)
			(xy 105.316176 -7.343001) (xy 105.262219 -7.357107) (xy 105.206782 -7.363207) (xy 105.151048 -7.36117)
			(xy 105.096205 -7.35104) (xy 105.043421 -7.333033) (xy 104.993821 -7.307532) (xy 104.948463 -7.275081)
			(xy 104.908314 -7.236372) (xy 104.874228 -7.192229) (xy 104.846932 -7.143594) (xy 104.827009 -7.091503)
			(xy 104.814883 -7.037066) (xy 104.810812 -6.981444) (xy 98.916494 -6.981444) (xy 98.911671 -7.014214)
			(xy 98.895603 -7.067621) (xy 98.871931 -7.118118) (xy 98.841158 -7.164631) (xy 98.803941 -7.206168)
			(xy 98.761073 -7.241843) (xy 98.713467 -7.270897) (xy 98.662138 -7.292709) (xy 98.608181 -7.306815)
			(xy 98.552744 -7.312915) (xy 98.49701 -7.310878) (xy 98.442167 -7.300748) (xy 98.389383 -7.282741)
			(xy 98.339783 -7.25724) (xy 98.294425 -7.224789) (xy 98.254276 -7.18608) (xy 98.22019 -7.141937)
			(xy 98.192894 -7.093302) (xy 98.172971 -7.041211) (xy 98.160845 -6.986774) (xy 98.156774 -6.931152)
			(xy 97.855278 -6.931152) (xy 97.855278 -7.916672) (xy 98.32543 -7.916672) (xy 98.329501 -7.86105)
			(xy 98.341627 -7.806613) (xy 98.36155 -7.754522) (xy 98.388846 -7.705887) (xy 98.422932 -7.661744)
			(xy 98.463081 -7.623035) (xy 98.508439 -7.590584) (xy 98.558039 -7.565083) (xy 98.610823 -7.547076)
			(xy 98.665666 -7.536946) (xy 98.7214 -7.534909) (xy 98.776837 -7.541009) (xy 98.830794 -7.555115)
			(xy 98.882123 -7.576927) (xy 98.929729 -7.605981) (xy 98.972597 -7.641656) (xy 99.009814 -7.683193)
			(xy 99.040587 -7.729706) (xy 99.04667 -7.742682) (xy 106.920282 -7.742682) (xy 106.924353 -7.68706)
			(xy 106.936479 -7.632623) (xy 106.956402 -7.580532) (xy 106.983698 -7.531897) (xy 107.017784 -7.487754)
			(xy 107.057933 -7.449045) (xy 107.103291 -7.416594) (xy 107.152891 -7.391093) (xy 107.205675 -7.373086)
			(xy 107.260518 -7.362956) (xy 107.316252 -7.360919) (xy 107.371689 -7.367019) (xy 107.425646 -7.381125)
			(xy 107.476975 -7.402937) (xy 107.524581 -7.431991) (xy 107.567449 -7.467666) (xy 107.604666 -7.509203)
			(xy 107.635439 -7.555716) (xy 107.659111 -7.606213) (xy 107.675179 -7.65962) (xy 107.683299 -7.714796)
			(xy 107.683808 -7.742682) (xy 107.683299 -7.770568) (xy 107.675179 -7.825744) (xy 107.659111 -7.879151)
			(xy 107.635439 -7.929648) (xy 107.604666 -7.976161) (xy 107.567449 -8.017698) (xy 107.524581 -8.053373)
			(xy 107.476975 -8.082427) (xy 107.425646 -8.104239) (xy 107.371689 -8.118345) (xy 107.316252 -8.124445)
			(xy 107.260518 -8.122408) (xy 107.205675 -8.112278) (xy 107.152891 -8.094271) (xy 107.103291 -8.06877)
			(xy 107.057933 -8.036319) (xy 107.017784 -7.99761) (xy 106.983698 -7.953467) (xy 106.956402 -7.904832)
			(xy 106.936479 -7.852741) (xy 106.924353 -7.798304) (xy 106.920282 -7.742682) (xy 99.04667 -7.742682)
			(xy 99.064259 -7.780203) (xy 99.080327 -7.83361) (xy 99.088447 -7.888786) (xy 99.088956 -7.916672)
			(xy 99.088447 -7.944558) (xy 99.080327 -7.999734) (xy 99.064259 -8.053141) (xy 99.040587 -8.103638)
			(xy 99.009814 -8.150151) (xy 98.972597 -8.191688) (xy 98.929729 -8.227363) (xy 98.882123 -8.256417)
			(xy 98.830794 -8.278229) (xy 98.776837 -8.292335) (xy 98.7214 -8.298435) (xy 98.665666 -8.296398)
			(xy 98.610823 -8.286268) (xy 98.558039 -8.268261) (xy 98.508439 -8.24276) (xy 98.463081 -8.210309)
			(xy 98.422932 -8.1716) (xy 98.388846 -8.127457) (xy 98.36155 -8.078822) (xy 98.341627 -8.026731)
			(xy 98.329501 -7.972294) (xy 98.32543 -7.916672) (xy 97.855278 -7.916672) (xy 97.855278 -8.299752)
			(xy 104.750581 -8.299752) (xy 104.750581 -8.245248) (xy 104.758338 -8.1913) (xy 104.773694 -8.139004)
			(xy 104.796336 -8.089426) (xy 104.825804 -8.043575) (xy 104.861497 -8.002385) (xy 104.902688 -7.966694)
			(xy 104.94854 -7.937228) (xy 104.998119 -7.914588) (xy 105.050415 -7.899235) (xy 105.104364 -7.89148)
			(xy 105.131616 -7.891018) (xy 105.16089 -7.891548) (xy 105.218749 -7.900509) (xy 105.27456 -7.918202)
			(xy 105.327014 -7.944212) (xy 105.374879 -7.977929) (xy 105.417033 -8.018562) (xy 105.452485 -8.065157)
			(xy 105.480405 -8.11662) (xy 105.490772 -8.144002) (xy 105.495899 -8.156931) (xy 105.512004 -8.179593)
			(xy 105.53362 -8.197078) (xy 105.559148 -8.208091) (xy 105.586699 -8.211819) (xy 105.614236 -8.207984)
			(xy 105.63972 -8.196871) (xy 105.650792 -8.188452) (xy 105.671338 -8.172191) (xy 105.71604 -8.144855)
			(xy 105.76406 -8.123891) (xy 105.814497 -8.109692) (xy 105.866401 -8.102525) (xy 105.8926 -8.102092)
			(xy 105.919851 -8.102578) (xy 105.973799 -8.110334) (xy 106.026094 -8.125689) (xy 106.075671 -8.148331)
			(xy 106.121521 -8.177797) (xy 106.162712 -8.213488) (xy 106.198403 -8.254679) (xy 106.227869 -8.300529)
			(xy 106.250511 -8.350106) (xy 106.265866 -8.402401) (xy 106.273622 -8.456349) (xy 106.273622 -8.510851)
			(xy 106.265866 -8.564799) (xy 106.250511 -8.617094) (xy 106.227869 -8.666671) (xy 106.198403 -8.712521)
			(xy 106.162712 -8.753712) (xy 106.121521 -8.789403) (xy 106.075671 -8.818869) (xy 106.026094 -8.841511)
			(xy 105.973799 -8.856866) (xy 105.919851 -8.864622) (xy 105.8926 -8.865108) (xy 105.863327 -8.864547)
			(xy 105.805471 -8.85559) (xy 105.749661 -8.8379) (xy 105.697208 -8.811894) (xy 105.649343 -8.778181)
			(xy 105.607189 -8.737553) (xy 105.571735 -8.690963) (xy 105.543813 -8.639504) (xy 105.533444 -8.612124)
			(xy 105.528286 -8.599208) (xy 105.512189 -8.576544) (xy 105.490579 -8.559057) (xy 105.465056 -8.548042)
			(xy 105.437509 -8.544312) (xy 105.409976 -8.548145) (xy 105.384494 -8.559256) (xy 105.373424 -8.567674)
			(xy 105.352864 -8.583917) (xy 105.308167 -8.611257) (xy 105.260151 -8.632227) (xy 105.209717 -8.64643)
			(xy 105.157814 -8.6536) (xy 105.131616 -8.654034) (xy 105.104364 -8.65352) (xy 105.050415 -8.645765)
			(xy 104.998119 -8.630412) (xy 104.94854 -8.607772) (xy 104.902688 -8.578306) (xy 104.861497 -8.542615)
			(xy 104.825804 -8.501425) (xy 104.796336 -8.455574) (xy 104.773694 -8.405996) (xy 104.758338 -8.3537)
			(xy 104.750581 -8.299752) (xy 97.855278 -8.299752) (xy 97.855278 -9.535922) (xy 100.374702 -9.535922)
			(xy 100.378773 -9.4803) (xy 100.390899 -9.425863) (xy 100.410822 -9.373772) (xy 100.438118 -9.325137)
			(xy 100.472204 -9.280994) (xy 100.512353 -9.242285) (xy 100.557711 -9.209834) (xy 100.607311 -9.184333)
			(xy 100.660095 -9.166326) (xy 100.714938 -9.156196) (xy 100.770672 -9.154159) (xy 100.826109 -9.160259)
			(xy 100.880066 -9.174365) (xy 100.931395 -9.196177) (xy 100.979001 -9.225231) (xy 101.021869 -9.260906)
			(xy 101.059086 -9.302443) (xy 101.089859 -9.348956) (xy 101.113531 -9.399453) (xy 101.129599 -9.45286)
			(xy 101.137719 -9.508036) (xy 101.138168 -9.53262) (xy 103.422702 -9.53262) (xy 103.426773 -9.476998)
			(xy 103.438899 -9.422561) (xy 103.458822 -9.37047) (xy 103.486118 -9.321835) (xy 103.520204 -9.277692)
			(xy 103.560353 -9.238983) (xy 103.605711 -9.206532) (xy 103.655311 -9.181031) (xy 103.708095 -9.163024)
			(xy 103.762938 -9.152894) (xy 103.818672 -9.150857) (xy 103.874109 -9.156957) (xy 103.928066 -9.171063)
			(xy 103.979395 -9.192875) (xy 104.027001 -9.221929) (xy 104.069869 -9.257604) (xy 104.107086 -9.299141)
			(xy 104.137859 -9.345654) (xy 104.161531 -9.396151) (xy 104.177599 -9.449558) (xy 104.185719 -9.504734)
			(xy 104.186228 -9.53262) (xy 104.185719 -9.560506) (xy 104.177599 -9.615682) (xy 104.161531 -9.669089)
			(xy 104.137859 -9.719586) (xy 104.107086 -9.766099) (xy 104.069869 -9.807636) (xy 104.027001 -9.843311)
			(xy 103.979395 -9.872365) (xy 103.928066 -9.894177) (xy 103.874109 -9.908283) (xy 103.818672 -9.914383)
			(xy 103.762938 -9.912346) (xy 103.708095 -9.902216) (xy 103.655311 -9.884209) (xy 103.605711 -9.858708)
			(xy 103.560353 -9.826257) (xy 103.520204 -9.787548) (xy 103.486118 -9.743405) (xy 103.458822 -9.69477)
			(xy 103.438899 -9.642679) (xy 103.426773 -9.588242) (xy 103.422702 -9.53262) (xy 101.138168 -9.53262)
			(xy 101.138228 -9.535922) (xy 101.137719 -9.563808) (xy 101.129599 -9.618984) (xy 101.113531 -9.672391)
			(xy 101.089859 -9.722888) (xy 101.059086 -9.769401) (xy 101.021869 -9.810938) (xy 100.979001 -9.846613)
			(xy 100.931395 -9.875667) (xy 100.880066 -9.897479) (xy 100.826109 -9.911585) (xy 100.770672 -9.917685)
			(xy 100.714938 -9.915648) (xy 100.660095 -9.905518) (xy 100.607311 -9.887511) (xy 100.557711 -9.86201)
			(xy 100.512353 -9.829559) (xy 100.472204 -9.79085) (xy 100.438118 -9.746707) (xy 100.410822 -9.698072)
			(xy 100.390899 -9.645981) (xy 100.378773 -9.591544) (xy 100.374702 -9.535922) (xy 97.855278 -9.535922)
			(xy 97.855278 -11.543792) (xy 101.399338 -11.543792) (xy 101.403409 -11.48817) (xy 101.415535 -11.433733)
			(xy 101.435458 -11.381642) (xy 101.462754 -11.333007) (xy 101.49684 -11.288864) (xy 101.536989 -11.250155)
			(xy 101.582347 -11.217704) (xy 101.631947 -11.192203) (xy 101.684731 -11.174196) (xy 101.739574 -11.164066)
			(xy 101.795308 -11.162029) (xy 101.850745 -11.168129) (xy 101.904702 -11.182235) (xy 101.956031 -11.204047)
			(xy 102.003637 -11.233101) (xy 102.046505 -11.268776) (xy 102.083722 -11.310313) (xy 102.114495 -11.356826)
			(xy 102.138167 -11.407323) (xy 102.154235 -11.46073) (xy 102.162355 -11.515906) (xy 102.162864 -11.543792)
			(xy 102.408226 -11.543792) (xy 102.412297 -11.48817) (xy 102.424423 -11.433733) (xy 102.444346 -11.381642)
			(xy 102.471642 -11.333007) (xy 102.505728 -11.288864) (xy 102.545877 -11.250155) (xy 102.591235 -11.217704)
			(xy 102.640835 -11.192203) (xy 102.693619 -11.174196) (xy 102.748462 -11.164066) (xy 102.804196 -11.162029)
			(xy 102.859633 -11.168129) (xy 102.91359 -11.182235) (xy 102.964919 -11.204047) (xy 103.012525 -11.233101)
			(xy 103.055393 -11.268776) (xy 103.09261 -11.310313) (xy 103.123383 -11.356826) (xy 103.147055 -11.407323)
			(xy 103.163123 -11.46073) (xy 103.171243 -11.515906) (xy 103.171752 -11.543792) (xy 103.171243 -11.571678)
			(xy 103.163123 -11.626854) (xy 103.147055 -11.680261) (xy 103.123383 -11.730758) (xy 103.09261 -11.777271)
			(xy 103.055393 -11.818808) (xy 103.012525 -11.854483) (xy 102.964919 -11.883537) (xy 102.91359 -11.905349)
			(xy 102.859633 -11.919455) (xy 102.804196 -11.925555) (xy 102.748462 -11.923518) (xy 102.693619 -11.913388)
			(xy 102.640835 -11.895381) (xy 102.591235 -11.86988) (xy 102.545877 -11.837429) (xy 102.505728 -11.79872)
			(xy 102.471642 -11.754577) (xy 102.444346 -11.705942) (xy 102.424423 -11.653851) (xy 102.412297 -11.599414)
			(xy 102.408226 -11.543792) (xy 102.162864 -11.543792) (xy 102.162355 -11.571678) (xy 102.154235 -11.626854)
			(xy 102.138167 -11.680261) (xy 102.114495 -11.730758) (xy 102.083722 -11.777271) (xy 102.046505 -11.818808)
			(xy 102.003637 -11.854483) (xy 101.956031 -11.883537) (xy 101.904702 -11.905349) (xy 101.850745 -11.919455)
			(xy 101.795308 -11.925555) (xy 101.739574 -11.923518) (xy 101.684731 -11.913388) (xy 101.631947 -11.895381)
			(xy 101.582347 -11.86988) (xy 101.536989 -11.837429) (xy 101.49684 -11.79872) (xy 101.462754 -11.754577)
			(xy 101.435458 -11.705942) (xy 101.415535 -11.653851) (xy 101.403409 -11.599414) (xy 101.399338 -11.543792)
			(xy 97.855278 -11.543792) (xy 97.855278 -12.466574) (xy 97.854841 -12.476638) (xy 97.847105 -12.495221)
			(xy 97.840292 -12.502642) (xy 96.96196 -13.380974) (xy 96.957326 -13.385957) (xy 96.950645 -13.397805)
			(xy 96.948752 -13.404342) (xy 96.948752 -13.422884) (xy 96.95053 -13.433806) (xy 96.952054 -13.440918)
			(xy 96.969072 -13.495528) (xy 96.969072 -13.496036) (xy 96.975676 -13.517626) (xy 96.977059 -13.521771)
			(xy 96.981018 -13.529559) (xy 96.98355 -13.53312) (xy 96.990662 -13.540994) (xy 96.995742 -13.545312)
			(xy 97.008188 -13.551408) (xy 97.015046 -13.552678) (xy 97.078092 -13.565039) (xy 97.202703 -13.596373)
			(xy 97.325203 -13.635147) (xy 97.445147 -13.681221) (xy 97.562103 -13.734428) (xy 97.675645 -13.794576)
			(xy 97.785362 -13.861447) (xy 97.890858 -13.934798) (xy 97.991748 -14.014363) (xy 98.087669 -14.099854)
			(xy 98.178273 -14.190962) (xy 98.26323 -14.287356) (xy 98.342234 -14.388688) (xy 98.414997 -14.494589)
			(xy 98.481258 -14.604676) (xy 98.540774 -14.71855) (xy 98.593331 -14.835799) (xy 98.638739 -14.955998)
			(xy 98.676832 -15.078711) (xy 98.707472 -15.203494) (xy 98.73055 -15.329894) (xy 98.74598 -15.457454)
			(xy 98.753708 -15.585711) (xy 98.754184 -15.649956) (xy 98.753708 -15.714428) (xy 98.745925 -15.843137)
			(xy 98.730385 -15.971142) (xy 98.707144 -16.097974) (xy 98.676288 -16.223172) (xy 98.637928 -16.346278)
			(xy 98.592206 -16.466844) (xy 98.539287 -16.584428) (xy 98.479365 -16.698604) (xy 98.412658 -16.808952)
			(xy 98.33941 -16.915072) (xy 98.296382 -16.969994) (xy 129.848363 -16.969994) (xy 129.852368 -16.882086)
			(xy 129.864351 -16.794906) (xy 129.884211 -16.709177) (xy 129.911786 -16.625609) (xy 129.946845 -16.544895)
			(xy 129.989098 -16.467703) (xy 130.038196 -16.394674) (xy 130.093732 -16.326412) (xy 130.155244 -16.263482)
			(xy 130.222225 -16.206408) (xy 130.294118 -16.15566) (xy 130.370327 -16.11166) (xy 130.450222 -16.074773)
			(xy 130.533141 -16.045304) (xy 130.618396 -16.023497) (xy 130.70528 -16.009533) (xy 130.793074 -16.003527)
			(xy 130.881051 -16.005531) (xy 130.968481 -16.015526) (xy 131.05464 -16.03343) (xy 131.138814 -16.059094)
			(xy 131.220305 -16.092307) (xy 131.298439 -16.132793) (xy 131.372567 -16.180215) (xy 131.442075 -16.234182)
			(xy 131.506389 -16.294247) (xy 131.564973 -16.359911) (xy 131.617344 -16.43063) (xy 131.663067 -16.505818)
			(xy 131.701764 -16.584853) (xy 131.733113 -16.667079) (xy 131.756855 -16.751815) (xy 131.772793 -16.838359)
			(xy 131.780795 -16.925994) (xy 131.781296 -16.969994) (xy 131.780795 -17.013994) (xy 131.772793 -17.101629)
			(xy 131.756855 -17.188173) (xy 131.733113 -17.272909) (xy 131.701764 -17.355135) (xy 131.663067 -17.43417)
			(xy 131.617344 -17.509358) (xy 131.564973 -17.580077) (xy 131.506389 -17.645741) (xy 131.442075 -17.705806)
			(xy 131.372567 -17.759773) (xy 131.298439 -17.807195) (xy 131.220305 -17.847681) (xy 131.138814 -17.880894)
			(xy 131.05464 -17.906558) (xy 130.968481 -17.924462) (xy 130.881051 -17.934457) (xy 130.793074 -17.936461)
			(xy 130.70528 -17.930455) (xy 130.618396 -17.916491) (xy 130.533141 -17.894684) (xy 130.450222 -17.865215)
			(xy 130.370327 -17.828328) (xy 130.294118 -17.784328) (xy 130.222225 -17.73358) (xy 130.155244 -17.676506)
			(xy 130.093732 -17.613576) (xy 130.038196 -17.545314) (xy 129.989098 -17.472285) (xy 129.946845 -17.395093)
			(xy 129.911786 -17.314379) (xy 129.884211 -17.230811) (xy 129.864351 -17.145082) (xy 129.852368 -17.057902)
			(xy 129.848363 -16.969994) (xy 98.296382 -16.969994) (xy 98.259888 -17.016575) (xy 98.174383 -17.113092)
			(xy 98.083206 -17.20427) (xy 97.986691 -17.289776) (xy 97.885188 -17.369298) (xy 97.779069 -17.442547)
			(xy 97.668721 -17.509255) (xy 97.554546 -17.569178) (xy 97.436962 -17.622098) (xy 97.316397 -17.667822)
			(xy 97.193291 -17.706182) (xy 97.068094 -17.73704) (xy 96.941261 -17.760282) (xy 96.813257 -17.775823)
			(xy 96.684548 -17.783607) (xy 96.620076 -17.784064) (xy 96.555824 -17.783583) (xy 96.427554 -17.775849)
			(xy 96.299981 -17.760412) (xy 96.173569 -17.737325) (xy 96.048775 -17.706675) (xy 95.926051 -17.668571)
			(xy 95.805842 -17.623151) (xy 95.688584 -17.57058) (xy 95.574702 -17.51105) (xy 95.464608 -17.444774)
			(xy 95.358702 -17.371994) (xy 95.257366 -17.292974) (xy 95.160969 -17.207999) (xy 95.06986 -17.117378)
			(xy 94.984369 -17.021439) (xy 94.904805 -16.920529) (xy 94.831458 -16.815015) (xy 94.764592 -16.705279)
			(xy 94.70445 -16.591718) (xy 94.651251 -16.474744) (xy 94.605186 -16.354781) (xy 94.566423 -16.232263)
			(xy 94.535103 -16.107636) (xy 94.511338 -15.981349) (xy 94.495215 -15.853861) (xy 94.486793 -15.725634)
			(xy 94.485968 -15.661386) (xy 94.485968 -15.649194) (xy 94.486427 -15.586991) (xy 94.493699 -15.462798)
			(xy 94.508196 -15.33924) (xy 94.529868 -15.216736) (xy 94.558642 -15.095704) (xy 94.594419 -14.976553)
			(xy 94.637078 -14.85969) (xy 94.686475 -14.745512) (xy 94.74244 -14.634405) (xy 94.773242 -14.580362)
			(xy 94.77375 -14.5796) (xy 94.774004 -14.579092) (xy 94.77629 -14.574266) (xy 94.777814 -14.570964)
			(xy 94.779675 -14.566096) (xy 94.781594 -14.555855) (xy 94.781624 -14.550644) (xy 94.78137 -14.54531)
			(xy 94.780831 -14.541573) (xy 94.778788 -14.534305) (xy 94.777306 -14.530832) (xy 94.76105 -14.50213)
			(xy 94.731586 -14.450314) (xy 94.726861 -14.442692) (xy 94.713185 -14.431109) (xy 94.696352 -14.424959)
			(xy 94.68739 -14.42466) (xy 89.353644 -14.42466) (xy 89.343579 -14.424225) (xy 89.324993 -14.416492)
			(xy 89.317576 -14.409674) (xy 89.135966 -14.228064) (xy 89.132234 -14.224545) (xy 89.123658 -14.218921)
			(xy 89.118948 -14.216888) (xy 89.110312 -14.213332) (xy 85.127592 -14.213332) (xy 85.117522 -14.212908)
			(xy 85.098916 -14.205195) (xy 85.091524 -14.198346) (xy 84.487512 -13.594334) (xy 84.480675 -13.586932)
			(xy 84.472963 -13.568334) (xy 84.472526 -13.558266) (xy 84.472526 -7.423404) (xy 84.472272 -7.418578)
			(xy 84.471158 -7.410354) (xy 84.464425 -7.395195) (xy 84.459064 -7.38886) (xy 84.455508 -7.385304)
			(xy 84.455 -7.38505) (xy 84.448396 -7.380224) (xy 84.4423 -7.377176) (xy 84.40039 -7.35838) (xy 84.399882 -7.35838)
			(xy 84.385658 -7.351776) (xy 84.380978 -7.349928) (xy 84.371129 -7.347874) (xy 84.3661 -7.347712)
			(xy 84.322666 -7.347712) (xy 84.309458 -7.34949) (xy 84.297012 -7.353554) (xy 84.289392 -7.35965)
			(xy 84.268956 -7.375577) (xy 84.224597 -7.40235) (xy 84.177023 -7.422875) (xy 84.12711 -7.436775)
			(xy 84.075776 -7.443794) (xy 84.04987 -7.444232) (xy 84.022618 -7.443744) (xy 83.968671 -7.435984)
			(xy 83.916376 -7.420625) (xy 83.8668 -7.397981) (xy 83.82095 -7.368512) (xy 83.779761 -7.332818)
			(xy 83.74407 -7.291626) (xy 83.714605 -7.245774) (xy 83.691965 -7.196196) (xy 83.67661 -7.1439) (xy 83.668854 -7.089952)
			(xy 83.668854 -7.035448) (xy 83.67661 -6.9815) (xy 83.691965 -6.929204) (xy 83.714605 -6.879626)
			(xy 83.74407 -6.833774) (xy 83.779761 -6.792582) (xy 83.82095 -6.756888) (xy 83.8668 -6.727419) (xy 83.916376 -6.704775)
			(xy 83.968671 -6.689416) (xy 84.022618 -6.681656) (xy 84.04987 -6.681216) (xy 84.076934 -6.681686)
			(xy 84.13052 -6.689331) (xy 84.182488 -6.704472) (xy 84.231795 -6.726804) (xy 84.27745 -6.755881)
			(xy 84.298282 -6.773164) (xy 84.30387 -6.77799) (xy 84.318856 -6.784848) (xy 84.32227 -6.786308)
			(xy 84.32941 -6.788346) (xy 84.33308 -6.788912) (xy 84.338414 -6.789166) (xy 84.347558 -6.788404)
			(xy 84.358734 -6.785864) (xy 84.399882 -6.767068) (xy 84.40039 -6.767068) (xy 84.442554 -6.748272)
			(xy 84.443824 -6.74751) (xy 84.449158 -6.745224) (xy 84.46008 -6.735826) (xy 84.464144 -6.72973)
			(xy 84.468 -6.723398) (xy 84.472243 -6.709199) (xy 84.472526 -6.70179) (xy 84.472526 -5.391404) (xy 84.472272 -5.386578)
			(xy 84.471158 -5.378354) (xy 84.464425 -5.363195) (xy 84.459064 -5.35686) (xy 84.455508 -5.353304)
			(xy 84.455 -5.35305) (xy 84.448396 -5.348224) (xy 84.4423 -5.345176) (xy 84.40039 -5.32638) (xy 84.399882 -5.32638)
			(xy 84.385658 -5.319776) (xy 84.380978 -5.317928) (xy 84.371129 -5.315874) (xy 84.3661 -5.315712)
			(xy 84.322666 -5.315712) (xy 84.309458 -5.31749) (xy 84.297012 -5.321554) (xy 84.289392 -5.32765)
			(xy 84.268956 -5.343577) (xy 84.224597 -5.37035) (xy 84.177023 -5.390875) (xy 84.12711 -5.404775)
			(xy 84.075776 -5.411794) (xy 84.04987 -5.412232) (xy 84.022618 -5.411744) (xy 83.968671 -5.403984)
			(xy 83.916376 -5.388625) (xy 83.8668 -5.365981) (xy 83.82095 -5.336512) (xy 83.779761 -5.300818)
			(xy 83.74407 -5.259626) (xy 83.714605 -5.213774) (xy 83.691965 -5.164196) (xy 83.67661 -5.1119) (xy 83.668854 -5.057952)
			(xy 83.668854 -5.003448) (xy 83.67661 -4.9495) (xy 83.691965 -4.897204) (xy 83.714605 -4.847626)
			(xy 83.74407 -4.801774) (xy 83.779761 -4.760582) (xy 83.82095 -4.724888) (xy 83.8668 -4.695419) (xy 83.916376 -4.672775)
			(xy 83.968671 -4.657416) (xy 84.022618 -4.649656) (xy 84.04987 -4.649216) (xy 84.076934 -4.649686)
			(xy 84.13052 -4.657331) (xy 84.182488 -4.672472) (xy 84.231795 -4.694804) (xy 84.27745 -4.723881)
			(xy 84.298282 -4.741164) (xy 84.30387 -4.74599) (xy 84.318856 -4.752848) (xy 84.32227 -4.754308)
			(xy 84.32941 -4.756346) (xy 84.33308 -4.756912) (xy 84.338414 -4.757166) (xy 84.347558 -4.756404)
			(xy 84.358734 -4.753864) (xy 84.399882 -4.735068) (xy 84.40039 -4.735068) (xy 84.442554 -4.716272)
			(xy 84.443824 -4.71551) (xy 84.449158 -4.713224) (xy 84.46008 -4.703826) (xy 84.464144 -4.69773)
			(xy 84.468 -4.691398) (xy 84.472243 -4.677199) (xy 84.472526 -4.66979) (xy 84.472526 -4.375404) (xy 84.472272 -4.370578)
			(xy 84.471158 -4.362354) (xy 84.464425 -4.347195) (xy 84.459064 -4.34086) (xy 84.455508 -4.337304)
			(xy 84.455 -4.33705) (xy 84.448396 -4.332224) (xy 84.4423 -4.329176) (xy 84.40039 -4.31038) (xy 84.399882 -4.31038)
			(xy 84.385658 -4.303776) (xy 84.380978 -4.301928) (xy 84.371129 -4.299874) (xy 84.3661 -4.299712)
			(xy 84.322666 -4.299712) (xy 84.309458 -4.30149) (xy 84.297012 -4.305554) (xy 84.289392 -4.31165)
			(xy 84.268956 -4.327577) (xy 84.224597 -4.35435) (xy 84.177023 -4.374875) (xy 84.12711 -4.388775)
			(xy 84.075776 -4.395794) (xy 84.04987 -4.396232) (xy 84.022618 -4.395744) (xy 83.968671 -4.387984)
			(xy 83.916376 -4.372625) (xy 83.8668 -4.349981) (xy 83.82095 -4.320512) (xy 83.779761 -4.284818)
			(xy 83.74407 -4.243626) (xy 83.714605 -4.197774) (xy 83.691965 -4.148196) (xy 83.67661 -4.0959) (xy 83.668854 -4.041952)
			(xy 83.668854 -3.987448) (xy 83.67661 -3.9335) (xy 83.691965 -3.881204) (xy 83.714605 -3.831626)
			(xy 83.74407 -3.785774) (xy 83.779761 -3.744582) (xy 83.82095 -3.708888) (xy 83.8668 -3.679419) (xy 83.916376 -3.656775)
			(xy 83.968671 -3.641416) (xy 84.022618 -3.633656) (xy 84.04987 -3.633216) (xy 84.076934 -3.633686)
			(xy 84.13052 -3.641331) (xy 84.182488 -3.656472) (xy 84.231795 -3.678804) (xy 84.27745 -3.707881)
			(xy 84.298282 -3.725164) (xy 84.30387 -3.72999) (xy 84.318856 -3.736848) (xy 84.32227 -3.738308)
			(xy 84.32941 -3.740346) (xy 84.33308 -3.740912) (xy 84.338414 -3.741166) (xy 84.347558 -3.740404)
			(xy 84.358734 -3.737864) (xy 84.399882 -3.719068) (xy 84.40039 -3.719068) (xy 84.442554 -3.700272)
			(xy 84.443824 -3.69951) (xy 84.449158 -3.697224) (xy 84.46008 -3.687826) (xy 84.464144 -3.68173)
			(xy 84.468 -3.675398) (xy 84.472243 -3.661199) (xy 84.472526 -3.65379) (xy 84.472526 -2.049018) (xy 84.472212 -2.040735)
			(xy 84.466907 -2.025044) (xy 84.462112 -2.018284) (xy 84.46008 -2.015998) (xy 84.458302 -2.01422)
			(xy 84.455 -2.01041) (xy 83.88858 -1.44399) (xy 83.88485 -1.440469) (xy 83.876275 -1.43484) (xy 83.871562 -1.432814)
			(xy 83.862926 -1.429258) (xy 72.343772 -1.429258) (xy 72.335492 -1.429579) (xy 72.319808 -1.434894)
			(xy 72.313038 -1.439672) (xy 72.310752 -1.441704) (xy 72.308974 -1.443482) (xy 72.305164 -1.446784)
			(xy 71.49211 -2.259838) (xy 71.488589 -2.263568) (xy 71.48296 -2.272143) (xy 71.480934 -2.276856)
			(xy 71.477378 -2.285492) (xy 71.477378 -3.659632) (xy 81.365342 -3.659632) (xy 81.369413 -3.60401)
			(xy 81.381539 -3.549573) (xy 81.401462 -3.497482) (xy 81.428758 -3.448847) (xy 81.462844 -3.404704)
			(xy 81.502993 -3.365995) (xy 81.548351 -3.333544) (xy 81.597951 -3.308043) (xy 81.650735 -3.290036)
			(xy 81.705578 -3.279906) (xy 81.761312 -3.277869) (xy 81.816749 -3.283969) (xy 81.870706 -3.298075)
			(xy 81.922035 -3.319887) (xy 81.969641 -3.348941) (xy 82.012509 -3.384616) (xy 82.049726 -3.426153)
			(xy 82.080499 -3.472666) (xy 82.104171 -3.523163) (xy 82.120239 -3.57657) (xy 82.128359 -3.631746)
			(xy 82.128868 -3.659632) (xy 82.128359 -3.687518) (xy 82.120239 -3.742694) (xy 82.104171 -3.796101)
			(xy 82.080499 -3.846598) (xy 82.049726 -3.893111) (xy 82.012509 -3.934648) (xy 81.969641 -3.970323)
			(xy 81.922035 -3.999377) (xy 81.870706 -4.021189) (xy 81.816749 -4.035295) (xy 81.761312 -4.041395)
			(xy 81.705578 -4.039358) (xy 81.650735 -4.029228) (xy 81.597951 -4.011221) (xy 81.548351 -3.98572)
			(xy 81.502993 -3.953269) (xy 81.462844 -3.91456) (xy 81.428758 -3.870417) (xy 81.401462 -3.821782)
			(xy 81.381539 -3.769691) (xy 81.369413 -3.715254) (xy 81.365342 -3.659632) (xy 71.477378 -3.659632)
			(xy 71.477378 -4.557776) (xy 71.477721 -4.566468) (xy 71.483563 -4.582841) (xy 71.488808 -4.58978)
			(xy 71.494396 -4.596384) (xy 71.509382 -4.605528) (xy 71.518272 -4.607306) (xy 71.543968 -4.612805)
			(xy 71.59365 -4.629921) (xy 71.640513 -4.653695) (xy 71.683669 -4.683677) (xy 71.7223 -4.719298)
			(xy 71.755677 -4.759885) (xy 71.783167 -4.80467) (xy 71.804249 -4.852803) (xy 71.818525 -4.903375)
			(xy 71.825724 -4.955428) (xy 71.82612 -4.981702) (xy 71.825646 -5.009102) (xy 71.822519 -5.030724)
			(xy 81.62112 -5.030724) (xy 81.625191 -4.975102) (xy 81.637317 -4.920665) (xy 81.65724 -4.868574)
			(xy 81.684536 -4.819939) (xy 81.718622 -4.775796) (xy 81.758771 -4.737087) (xy 81.804129 -4.704636)
			(xy 81.853729 -4.679135) (xy 81.906513 -4.661128) (xy 81.961356 -4.650998) (xy 82.01709 -4.648961)
			(xy 82.072527 -4.655061) (xy 82.126484 -4.669167) (xy 82.177813 -4.690979) (xy 82.225419 -4.720033)
			(xy 82.268287 -4.755708) (xy 82.305504 -4.797245) (xy 82.336277 -4.843758) (xy 82.359949 -4.894255)
			(xy 82.376017 -4.947662) (xy 82.384137 -5.002838) (xy 82.384646 -5.030724) (xy 82.384137 -5.05861)
			(xy 82.376017 -5.113786) (xy 82.359949 -5.167193) (xy 82.336277 -5.21769) (xy 82.305504 -5.264203)
			(xy 82.268287 -5.30574) (xy 82.225419 -5.341415) (xy 82.177813 -5.370469) (xy 82.126484 -5.392281)
			(xy 82.072527 -5.406387) (xy 82.01709 -5.412487) (xy 81.961356 -5.41045) (xy 81.906513 -5.40032)
			(xy 81.853729 -5.382313) (xy 81.804129 -5.356812) (xy 81.758771 -5.324361) (xy 81.718622 -5.285652)
			(xy 81.684536 -5.241509) (xy 81.65724 -5.192874) (xy 81.637317 -5.140783) (xy 81.625191 -5.086346)
			(xy 81.62112 -5.030724) (xy 71.822519 -5.030724) (xy 71.817803 -5.063337) (xy 71.802279 -5.115892)
			(xy 71.779394 -5.165685) (xy 71.749619 -5.21169) (xy 71.713566 -5.252959) (xy 71.671978 -5.288645)
			(xy 71.625711 -5.318012) (xy 71.575718 -5.340455) (xy 71.549514 -5.348478) (xy 71.54926 -5.348478)
			(xy 71.54545 -5.349494) (xy 71.536769 -5.353267) (xy 71.522702 -5.365906) (xy 71.518018 -5.374132)
			(xy 71.518018 -5.37464) (xy 71.515495 -5.379953) (xy 71.512679 -5.391369) (xy 71.51243 -5.397246)
			(xy 71.51243 -5.889752) (xy 73.306684 -5.889752) (xy 73.310755 -5.83413) (xy 73.322881 -5.779693)
			(xy 73.342804 -5.727602) (xy 73.3701 -5.678967) (xy 73.404186 -5.634824) (xy 73.444335 -5.596115)
			(xy 73.489693 -5.563664) (xy 73.539293 -5.538163) (xy 73.592077 -5.520156) (xy 73.64692 -5.510026)
			(xy 73.702654 -5.507989) (xy 73.758091 -5.514089) (xy 73.812048 -5.528195) (xy 73.863377 -5.550007)
			(xy 73.910983 -5.579061) (xy 73.953851 -5.614736) (xy 73.991068 -5.656273) (xy 74.021841 -5.702786)
			(xy 74.045513 -5.753283) (xy 74.061581 -5.80669) (xy 74.069701 -5.861866) (xy 74.07021 -5.889752)
			(xy 74.069701 -5.917638) (xy 74.061581 -5.972814) (xy 74.045513 -6.026221) (xy 74.021841 -6.076718)
			(xy 73.991068 -6.123231) (xy 73.953851 -6.164768) (xy 73.910983 -6.200443) (xy 73.863377 -6.229497)
			(xy 73.812048 -6.251309) (xy 73.758091 -6.265415) (xy 73.702654 -6.271515) (xy 73.64692 -6.269478)
			(xy 73.592077 -6.259348) (xy 73.539293 -6.241341) (xy 73.489693 -6.21584) (xy 73.444335 -6.183389)
			(xy 73.404186 -6.14468) (xy 73.3701 -6.100537) (xy 73.342804 -6.051902) (xy 73.322881 -5.999811)
			(xy 73.310755 -5.945374) (xy 73.306684 -5.889752) (xy 71.51243 -5.889752) (xy 71.51243 -6.651498)
			(xy 81.434684 -6.651498) (xy 81.438755 -6.595876) (xy 81.450881 -6.541439) (xy 81.470804 -6.489348)
			(xy 81.4981 -6.440713) (xy 81.532186 -6.39657) (xy 81.572335 -6.357861) (xy 81.617693 -6.32541) (xy 81.667293 -6.299909)
			(xy 81.720077 -6.281902) (xy 81.77492 -6.271772) (xy 81.830654 -6.269735) (xy 81.886091 -6.275835)
			(xy 81.940048 -6.289941) (xy 81.991377 -6.311753) (xy 82.038983 -6.340807) (xy 82.081851 -6.376482)
			(xy 82.119068 -6.418019) (xy 82.149841 -6.464532) (xy 82.173513 -6.515029) (xy 82.189581 -6.568436)
			(xy 82.197701 -6.623612) (xy 82.19821 -6.651498) (xy 82.197701 -6.679384) (xy 82.189581 -6.73456)
			(xy 82.173513 -6.787967) (xy 82.149841 -6.838464) (xy 82.119068 -6.884977) (xy 82.081851 -6.926514)
			(xy 82.038983 -6.962189) (xy 81.991377 -6.991243) (xy 81.940048 -7.013055) (xy 81.886091 -7.027161)
			(xy 81.830654 -7.033261) (xy 81.77492 -7.031224) (xy 81.720077 -7.021094) (xy 81.667293 -7.003087)
			(xy 81.617693 -6.977586) (xy 81.572335 -6.945135) (xy 81.532186 -6.906426) (xy 81.4981 -6.862283)
			(xy 81.470804 -6.813648) (xy 81.450881 -6.761557) (xy 81.438755 -6.70712) (xy 81.434684 -6.651498)
			(xy 71.51243 -6.651498) (xy 71.51243 -7.183374) (xy 73.184256 -7.183374) (xy 73.188327 -7.127752)
			(xy 73.200453 -7.073315) (xy 73.220376 -7.021224) (xy 73.247672 -6.972589) (xy 73.281758 -6.928446)
			(xy 73.321907 -6.889737) (xy 73.367265 -6.857286) (xy 73.416865 -6.831785) (xy 73.469649 -6.813778)
			(xy 73.524492 -6.803648) (xy 73.580226 -6.801611) (xy 73.635663 -6.807711) (xy 73.68962 -6.821817)
			(xy 73.740949 -6.843629) (xy 73.788555 -6.872683) (xy 73.831423 -6.908358) (xy 73.86864 -6.949895)
			(xy 73.899413 -6.996408) (xy 73.923085 -7.046905) (xy 73.939153 -7.100312) (xy 73.947273 -7.155488)
			(xy 73.947782 -7.183374) (xy 73.947273 -7.21126) (xy 73.939153 -7.266436) (xy 73.923085 -7.319843)
			(xy 73.899413 -7.37034) (xy 73.86864 -7.416853) (xy 73.831423 -7.45839) (xy 73.788555 -7.494065)
			(xy 73.740949 -7.523119) (xy 73.68962 -7.544931) (xy 73.635663 -7.559037) (xy 73.580226 -7.565137)
			(xy 73.524492 -7.5631) (xy 73.469649 -7.55297) (xy 73.416865 -7.534963) (xy 73.367265 -7.509462)
			(xy 73.321907 -7.477011) (xy 73.281758 -7.438302) (xy 73.247672 -7.394159) (xy 73.220376 -7.345524)
			(xy 73.200453 -7.293433) (xy 73.188327 -7.238996) (xy 73.184256 -7.183374) (xy 71.51243 -7.183374)
			(xy 71.51243 -8.653272) (xy 71.923146 -8.653272) (xy 71.927217 -8.59765) (xy 71.939343 -8.543213)
			(xy 71.959266 -8.491122) (xy 71.986562 -8.442487) (xy 72.020648 -8.398344) (xy 72.060797 -8.359635)
			(xy 72.106155 -8.327184) (xy 72.155755 -8.301683) (xy 72.208539 -8.283676) (xy 72.263382 -8.273546)
			(xy 72.319116 -8.271509) (xy 72.374553 -8.277609) (xy 72.42851 -8.291715) (xy 72.479839 -8.313527)
			(xy 72.527445 -8.342581) (xy 72.570313 -8.378256) (xy 72.60753 -8.419793) (xy 72.638303 -8.466306)
			(xy 72.661975 -8.516803) (xy 72.678043 -8.57021) (xy 72.686163 -8.625386) (xy 72.686672 -8.653272)
			(xy 72.686163 -8.681158) (xy 72.678043 -8.736334) (xy 72.661975 -8.789741) (xy 72.638303 -8.840238)
			(xy 72.60753 -8.886751) (xy 72.570313 -8.928288) (xy 72.527445 -8.963963) (xy 72.479839 -8.993017)
			(xy 72.42851 -9.014829) (xy 72.374553 -9.028935) (xy 72.319116 -9.035035) (xy 72.263382 -9.032998)
			(xy 72.208539 -9.022868) (xy 72.155755 -9.004861) (xy 72.106155 -8.97936) (xy 72.060797 -8.946909)
			(xy 72.020648 -8.9082) (xy 71.986562 -8.864057) (xy 71.959266 -8.815422) (xy 71.939343 -8.763331)
			(xy 71.927217 -8.708894) (xy 71.923146 -8.653272) (xy 71.51243 -8.653272) (xy 71.51243 -9.33069)
			(xy 73.22642 -9.33069) (xy 73.230491 -9.275068) (xy 73.242617 -9.220631) (xy 73.26254 -9.16854) (xy 73.289836 -9.119905)
			(xy 73.323922 -9.075762) (xy 73.364071 -9.037053) (xy 73.409429 -9.004602) (xy 73.459029 -8.979101)
			(xy 73.511813 -8.961094) (xy 73.566656 -8.950964) (xy 73.62239 -8.948927) (xy 73.677827 -8.955027)
			(xy 73.731784 -8.969133) (xy 73.783113 -8.990945) (xy 73.830719 -9.019999) (xy 73.873587 -9.055674)
			(xy 73.910804 -9.097211) (xy 73.941577 -9.143724) (xy 73.965249 -9.194221) (xy 73.981317 -9.247628)
			(xy 73.989437 -9.302804) (xy 73.989946 -9.33069) (xy 73.989437 -9.358576) (xy 73.981317 -9.413752)
			(xy 73.965249 -9.467159) (xy 73.941577 -9.517656) (xy 73.929492 -9.535922) (xy 78.931006 -9.535922)
			(xy 78.935077 -9.4803) (xy 78.947203 -9.425863) (xy 78.967126 -9.373772) (xy 78.994422 -9.325137)
			(xy 79.028508 -9.280994) (xy 79.068657 -9.242285) (xy 79.114015 -9.209834) (xy 79.163615 -9.184333)
			(xy 79.216399 -9.166326) (xy 79.271242 -9.156196) (xy 79.326976 -9.154159) (xy 79.382413 -9.160259)
			(xy 79.43637 -9.174365) (xy 79.487699 -9.196177) (xy 79.535305 -9.225231) (xy 79.578173 -9.260906)
			(xy 79.61539 -9.302443) (xy 79.646163 -9.348956) (xy 79.669835 -9.399453) (xy 79.685903 -9.45286)
			(xy 79.694023 -9.508036) (xy 79.694532 -9.535922) (xy 79.694023 -9.563808) (xy 79.685903 -9.618984)
			(xy 79.669835 -9.672391) (xy 79.646163 -9.722888) (xy 79.61539 -9.769401) (xy 79.578173 -9.810938)
			(xy 79.535305 -9.846613) (xy 79.487699 -9.875667) (xy 79.43637 -9.897479) (xy 79.382413 -9.911585)
			(xy 79.326976 -9.917685) (xy 79.271242 -9.915648) (xy 79.216399 -9.905518) (xy 79.163615 -9.887511)
			(xy 79.114015 -9.86201) (xy 79.068657 -9.829559) (xy 79.028508 -9.79085) (xy 78.994422 -9.746707)
			(xy 78.967126 -9.698072) (xy 78.947203 -9.645981) (xy 78.935077 -9.591544) (xy 78.931006 -9.535922)
			(xy 73.929492 -9.535922) (xy 73.910804 -9.564169) (xy 73.873587 -9.605706) (xy 73.830719 -9.641381)
			(xy 73.783113 -9.670435) (xy 73.731784 -9.692247) (xy 73.677827 -9.706353) (xy 73.62239 -9.712453)
			(xy 73.566656 -9.710416) (xy 73.511813 -9.700286) (xy 73.459029 -9.682279) (xy 73.409429 -9.656778)
			(xy 73.364071 -9.624327) (xy 73.323922 -9.585618) (xy 73.289836 -9.541475) (xy 73.26254 -9.49284)
			(xy 73.242617 -9.440749) (xy 73.230491 -9.386312) (xy 73.22642 -9.33069) (xy 71.51243 -9.33069) (xy 71.51243 -12.713208)
			(xy 71.512006 -12.723278) (xy 71.504293 -12.741883) (xy 71.497444 -12.749276) (xy 70.891908 -13.354812)
			(xy 70.888385 -13.358542) (xy 70.882753 -13.367115) (xy 70.880732 -13.37183) (xy 70.877176 -13.380466)
			(xy 70.877176 -13.439902) (xy 70.879208 -13.452348) (xy 70.880986 -13.460222) (xy 70.888606 -13.48359)
			(xy 70.888606 -13.484098) (xy 70.895464 -13.504418) (xy 70.899724 -13.515501) (xy 70.916416 -13.532341)
			(xy 70.927468 -13.536676) (xy 70.935596 -13.539216) (xy 70.939914 -13.539978) (xy 71.004996 -13.550349)
			(xy 71.133843 -13.578105) (xy 71.260731 -13.613761) (xy 71.385176 -13.657179) (xy 71.506705 -13.708194)
			(xy 71.624854 -13.766613) (xy 71.739172 -13.832211) (xy 71.849224 -13.90474) (xy 71.95459 -13.983923)
			(xy 72.054869 -14.069457) (xy 72.086808 -14.100302) (xy 77.242922 -14.100302) (xy 77.246993 -14.04468)
			(xy 77.259119 -13.990243) (xy 77.279042 -13.938152) (xy 77.306338 -13.889517) (xy 77.340424 -13.845374)
			(xy 77.380573 -13.806665) (xy 77.425931 -13.774214) (xy 77.475531 -13.748713) (xy 77.528315 -13.730706)
			(xy 77.583158 -13.720576) (xy 77.638892 -13.718539) (xy 77.694329 -13.724639) (xy 77.748286 -13.738745)
			(xy 77.799615 -13.760557) (xy 77.847221 -13.789611) (xy 77.890089 -13.825286) (xy 77.927306 -13.866823)
			(xy 77.958079 -13.913336) (xy 77.981751 -13.963833) (xy 77.997819 -14.01724) (xy 78.005939 -14.072416)
			(xy 78.006448 -14.100302) (xy 78.005939 -14.128188) (xy 77.997819 -14.183364) (xy 77.981751 -14.236771)
			(xy 77.958079 -14.287268) (xy 77.927306 -14.333781) (xy 77.890089 -14.375318) (xy 77.847221 -14.410993)
			(xy 77.799615 -14.440047) (xy 77.748286 -14.461859) (xy 77.694329 -14.475965) (xy 77.638892 -14.482065)
			(xy 77.583158 -14.480028) (xy 77.528315 -14.469898) (xy 77.475531 -14.451891) (xy 77.425931 -14.42639)
			(xy 77.380573 -14.393939) (xy 77.340424 -14.35523) (xy 77.306338 -14.311087) (xy 77.279042 -14.262452)
			(xy 77.259119 -14.210361) (xy 77.246993 -14.155924) (xy 77.242922 -14.100302) (xy 72.086808 -14.100302)
			(xy 72.149677 -14.161017) (xy 72.238655 -14.258253) (xy 72.321461 -14.360795) (xy 72.397782 -14.468253)
			(xy 72.467325 -14.580215) (xy 72.529825 -14.696256) (xy 72.585046 -14.815933) (xy 72.632775 -14.93879)
			(xy 72.672831 -15.064358) (xy 72.705061 -15.192159) (xy 72.729342 -15.321706) (xy 72.739268 -15.401652)
			(xy 77.829644 -15.401652) (xy 77.829644 -15.347148) (xy 77.8374 -15.293199) (xy 77.852755 -15.240902)
			(xy 77.875395 -15.191323) (xy 77.904861 -15.14547) (xy 77.940552 -15.104277) (xy 77.981741 -15.068582)
			(xy 78.027591 -15.039113) (xy 78.077168 -15.016467) (xy 78.129463 -15.001108) (xy 78.183412 -14.993346)
			(xy 78.210664 -14.992858) (xy 78.236798 -14.993271) (xy 78.288576 -15.00042) (xy 78.338895 -15.014563)
			(xy 78.386816 -15.035434) (xy 78.431443 -15.062645) (xy 78.471943 -15.095687) (xy 78.490064 -15.114524)
			(xy 78.497684 -15.122906) (xy 78.518258 -15.131288) (xy 78.618588 -15.126462) (xy 78.638146 -15.116302)
			(xy 78.645004 -15.107412) (xy 78.663187 -15.084652) (xy 78.705279 -15.044382) (xy 78.753006 -15.010982)
			(xy 78.805256 -14.985228) (xy 78.860816 -14.96772) (xy 78.918392 -14.958864) (xy 78.947518 -14.958314)
			(xy 78.97477 -14.958757) (xy 79.028719 -14.966516) (xy 79.081014 -14.981874) (xy 79.130592 -15.004517)
			(xy 79.176443 -15.033986) (xy 79.217634 -15.069679) (xy 79.253325 -15.110871) (xy 79.282791 -15.156724)
			(xy 79.305433 -15.206302) (xy 79.320788 -15.258599) (xy 79.328544 -15.312548) (xy 79.328544 -15.367052)
			(xy 79.320788 -15.421001) (xy 79.305433 -15.473298) (xy 79.282791 -15.522876) (xy 79.253325 -15.568729)
			(xy 79.217634 -15.609921) (xy 79.176443 -15.645614) (xy 79.130592 -15.675083) (xy 79.081014 -15.697726)
			(xy 79.028719 -15.713084) (xy 78.97477 -15.720843) (xy 78.947518 -15.72133) (xy 78.921385 -15.720867)
			(xy 78.86961 -15.713728) (xy 78.819292 -15.699596) (xy 78.771371 -15.678734) (xy 78.726742 -15.651531)
			(xy 78.68624 -15.618497) (xy 78.668118 -15.599664) (xy 78.660498 -15.591282) (xy 78.639924 -15.5829)
			(xy 78.539594 -15.587726) (xy 78.520036 -15.597886) (xy 78.513178 -15.606776) (xy 78.495002 -15.629542)
			(xy 78.452909 -15.669812) (xy 78.405181 -15.703212) (xy 78.352929 -15.728965) (xy 78.297368 -15.746472)
			(xy 78.239791 -15.755326) (xy 78.210664 -15.755874) (xy 78.183412 -15.755454) (xy 78.129463 -15.747692)
			(xy 78.077168 -15.732333) (xy 78.027591 -15.709687) (xy 77.981741 -15.680218) (xy 77.940552 -15.644523)
			(xy 77.904861 -15.60333) (xy 77.875395 -15.557477) (xy 77.852755 -15.507898) (xy 77.8374 -15.455601)
			(xy 77.829644 -15.401652) (xy 72.739268 -15.401652) (xy 72.745582 -15.452504) (xy 72.753719 -15.584055)
			(xy 72.754236 -15.649956) (xy 72.753759 -15.714428) (xy 72.745974 -15.843135) (xy 72.730431 -15.971139)
			(xy 72.707189 -16.09797) (xy 72.676331 -16.223166) (xy 72.63797 -16.346271) (xy 72.592247 -16.466835)
			(xy 72.539327 -16.584418) (xy 72.479404 -16.698592) (xy 72.412697 -16.808939) (xy 72.339449 -16.915057)
			(xy 72.296408 -16.969994) (xy 91.748109 -16.969994) (xy 91.752114 -16.882086) (xy 91.764097 -16.794906)
			(xy 91.783957 -16.709177) (xy 91.811532 -16.625609) (xy 91.846591 -16.544895) (xy 91.888844 -16.467703)
			(xy 91.937942 -16.394674) (xy 91.993478 -16.326412) (xy 92.05499 -16.263482) (xy 92.121971 -16.206408)
			(xy 92.193864 -16.15566) (xy 92.270073 -16.11166) (xy 92.349968 -16.074773) (xy 92.432887 -16.045304)
			(xy 92.518142 -16.023497) (xy 92.605026 -16.009533) (xy 92.69282 -16.003527) (xy 92.780797 -16.005531)
			(xy 92.868227 -16.015526) (xy 92.954386 -16.03343) (xy 93.03856 -16.059094) (xy 93.120051 -16.092307)
			(xy 93.198185 -16.132793) (xy 93.272313 -16.180215) (xy 93.341821 -16.234182) (xy 93.406135 -16.294247)
			(xy 93.464719 -16.359911) (xy 93.51709 -16.43063) (xy 93.562813 -16.505818) (xy 93.60151 -16.584853)
			(xy 93.632859 -16.667079) (xy 93.656601 -16.751815) (xy 93.672539 -16.838359) (xy 93.680541 -16.925994)
			(xy 93.681042 -16.969994) (xy 93.680541 -17.013994) (xy 93.672539 -17.101629) (xy 93.656601 -17.188173)
			(xy 93.632859 -17.272909) (xy 93.60151 -17.355135) (xy 93.562813 -17.43417) (xy 93.51709 -17.509358)
			(xy 93.464719 -17.580077) (xy 93.406135 -17.645741) (xy 93.341821 -17.705806) (xy 93.272313 -17.759773)
			(xy 93.198185 -17.807195) (xy 93.120051 -17.847681) (xy 93.03856 -17.880894) (xy 92.954386 -17.906558)
			(xy 92.868227 -17.924462) (xy 92.780797 -17.934457) (xy 92.69282 -17.936461) (xy 92.605026 -17.930455)
			(xy 92.518142 -17.916491) (xy 92.432887 -17.894684) (xy 92.349968 -17.865215) (xy 92.270073 -17.828328)
			(xy 92.193864 -17.784328) (xy 92.121971 -17.73358) (xy 92.05499 -17.676506) (xy 91.993478 -17.613576)
			(xy 91.937942 -17.545314) (xy 91.888844 -17.472285) (xy 91.846591 -17.395093) (xy 91.811532 -17.314379)
			(xy 91.783957 -17.230811) (xy 91.764097 -17.145082) (xy 91.752114 -17.057902) (xy 91.748109 -16.969994)
			(xy 72.296408 -16.969994) (xy 72.259927 -17.016559) (xy 72.174422 -17.113074) (xy 72.083246 -17.204251)
			(xy 71.98673 -17.289756) (xy 71.885229 -17.369278) (xy 71.812362 -17.419574) (xy 76.284072 -17.419574)
			(xy 76.288143 -17.363952) (xy 76.300269 -17.309515) (xy 76.320192 -17.257424) (xy 76.347488 -17.208789)
			(xy 76.381574 -17.164646) (xy 76.421723 -17.125937) (xy 76.467081 -17.093486) (xy 76.516681 -17.067985)
			(xy 76.569465 -17.049978) (xy 76.624308 -17.039848) (xy 76.680042 -17.037811) (xy 76.735479 -17.043911)
			(xy 76.789436 -17.058017) (xy 76.840765 -17.079829) (xy 76.888371 -17.108883) (xy 76.931239 -17.144558)
			(xy 76.968456 -17.186095) (xy 76.999229 -17.232608) (xy 77.022901 -17.283105) (xy 77.038969 -17.336512)
			(xy 77.047089 -17.391688) (xy 77.047598 -17.419574) (xy 77.047089 -17.44746) (xy 77.038969 -17.502636)
			(xy 77.022901 -17.556043) (xy 76.999229 -17.60654) (xy 76.968456 -17.653053) (xy 76.931239 -17.69459)
			(xy 76.888371 -17.730265) (xy 76.840765 -17.759319) (xy 76.789436 -17.781131) (xy 76.735479 -17.795237)
			(xy 76.680042 -17.801337) (xy 76.624308 -17.7993) (xy 76.569465 -17.78917) (xy 76.516681 -17.771163)
			(xy 76.467081 -17.745662) (xy 76.421723 -17.713211) (xy 76.381574 -17.674502) (xy 76.347488 -17.630359)
			(xy 76.320192 -17.581724) (xy 76.300269 -17.529633) (xy 76.288143 -17.475196) (xy 76.284072 -17.419574)
			(xy 71.812362 -17.419574) (xy 71.77911 -17.442526) (xy 71.668763 -17.509233) (xy 71.55459 -17.569156)
			(xy 71.437007 -17.622076) (xy 71.316443 -17.6678) (xy 71.193338 -17.706161) (xy 71.068142 -17.737019)
			(xy 70.94131 -17.760261) (xy 70.813307 -17.775803) (xy 70.6846 -17.783589) (xy 70.620128 -17.784064)
			(xy 70.619874 -17.784064) (xy 70.555403 -17.783586) (xy 70.426698 -17.775799) (xy 70.298697 -17.760255)
			(xy 70.171868 -17.737011) (xy 70.046674 -17.706152) (xy 69.923572 -17.66779) (xy 69.803011 -17.622065)
			(xy 69.68543 -17.569144) (xy 69.57126 -17.509221) (xy 69.460915 -17.442513) (xy 69.3548 -17.369264)
			(xy 69.253301 -17.289742) (xy 69.156788 -17.204237) (xy 69.065615 -17.113061) (xy 68.980113 -17.016545)
			(xy 68.900594 -16.915044) (xy 68.827349 -16.808926) (xy 68.760645 -16.698579) (xy 68.700725 -16.584407)
			(xy 68.647808 -16.466824) (xy 68.602087 -16.346262) (xy 68.563729 -16.223158) (xy 68.532874 -16.097963)
			(xy 68.509634 -15.971134) (xy 68.494095 -15.843133) (xy 68.486312 -15.714427) (xy 68.485766 -15.649956)
			(xy 68.485766 -15.649702) (xy 68.486231 -15.586655) (xy 68.49368 -15.460782) (xy 68.508546 -15.335568)
			(xy 68.530777 -15.21145) (xy 68.560296 -15.088861) (xy 68.597 -14.968228) (xy 68.640761 -14.849972)
			(xy 68.691426 -14.734505) (xy 68.7197 -14.678152) (xy 68.720462 -14.676882) (xy 68.720462 -14.676628)
			(xy 68.722881 -14.671036) (xy 68.725308 -14.659099) (xy 68.725288 -14.653006) (xy 68.72478 -14.640052)
			(xy 68.672456 -14.554708) (xy 68.667884 -14.548358) (xy 68.6608 -14.540711) (xy 68.642184 -14.531377)
			(xy 68.631816 -14.530324) (xy 60.26404 -14.530324) (xy 60.253974 -14.529891) (xy 60.235383 -14.522164)
			(xy 60.227972 -14.515338) (xy 58.426604 -12.71397) (xy 58.419762 -12.70657) (xy 58.412038 -12.687972)
			(xy 58.411618 -12.677902) (xy 58.411618 -1.73228) (xy 58.411298 -1.724) (xy 58.405983 -1.708316)
			(xy 58.401204 -1.701546) (xy 58.399172 -1.69926) (xy 58.397394 -1.697482) (xy 58.394092 -1.693672)
			(xy 58.250074 -1.549654) (xy 58.246342 -1.546135) (xy 58.237766 -1.540511) (xy 58.233056 -1.538478)
			(xy 58.22442 -1.534922) (xy 46.38802 -1.534922) (xy 46.379738 -1.535237) (xy 46.364049 -1.540545)
			(xy 46.357286 -1.545336) (xy 46.355 -1.547368) (xy 46.353222 -1.549146) (xy 46.349412 -1.552448)
			(xy 45.712634 -2.189226) (xy 45.709111 -2.192955) (xy 45.703478 -2.201528) (xy 45.701458 -2.206244)
			(xy 45.697902 -2.21488) (xy 45.697902 -12.853924) (xy 45.697474 -12.863992) (xy 45.689754 -12.882591)
			(xy 45.682916 -12.889992) (xy 45.148246 -13.424662) (xy 45.141228 -13.432467) (xy 45.13363 -13.452011)
			(xy 45.133514 -13.462508) (xy 45.133514 -13.468096) (xy 45.153326 -13.543026) (xy 45.155358 -13.551408)
			(xy 45.163486 -13.5636) (xy 45.168566 -13.569696) (xy 45.18406 -13.58519) (xy 45.19422 -13.593064)
			(xy 45.199554 -13.596112) (xy 45.205904 -13.59789) (xy 45.268927 -13.616412) (xy 45.392793 -13.660187)
			(xy 45.513731 -13.7115) (xy 45.631284 -13.770154) (xy 45.745006 -13.835929) (xy 45.854467 -13.908575)
			(xy 45.959252 -13.987816) (xy 46.058963 -14.073353) (xy 46.086722 -14.100302) (xy 51.242974 -14.100302)
			(xy 51.247045 -14.04468) (xy 51.259171 -13.990243) (xy 51.279094 -13.938152) (xy 51.30639 -13.889517)
			(xy 51.340476 -13.845374) (xy 51.380625 -13.806665) (xy 51.425983 -13.774214) (xy 51.475583 -13.748713)
			(xy 51.528367 -13.730706) (xy 51.58321 -13.720576) (xy 51.638944 -13.718539) (xy 51.694381 -13.724639)
			(xy 51.748338 -13.738745) (xy 51.799667 -13.760557) (xy 51.847273 -13.789611) (xy 51.890141 -13.825286)
			(xy 51.927358 -13.866823) (xy 51.958131 -13.913336) (xy 51.981803 -13.963833) (xy 51.997871 -14.01724)
			(xy 52.005991 -14.072416) (xy 52.0065 -14.100302) (xy 52.005991 -14.128188) (xy 51.997871 -14.183364)
			(xy 51.981803 -14.236771) (xy 51.958131 -14.287268) (xy 51.927358 -14.333781) (xy 51.890141 -14.375318)
			(xy 51.847273 -14.410993) (xy 51.799667 -14.440047) (xy 51.748338 -14.461859) (xy 51.694381 -14.475965)
			(xy 51.638944 -14.482065) (xy 51.58321 -14.480028) (xy 51.528367 -14.469898) (xy 51.475583 -14.451891)
			(xy 51.425983 -14.42639) (xy 51.380625 -14.393939) (xy 51.340476 -14.35523) (xy 51.30639 -14.311087)
			(xy 51.279094 -14.262452) (xy 51.259171 -14.210361) (xy 51.247045 -14.155924) (xy 51.242974 -14.100302)
			(xy 46.086722 -14.100302) (xy 46.153224 -14.164862) (xy 46.241678 -14.261996) (xy 46.323989 -14.364387)
			(xy 46.399845 -14.471648) (xy 46.46896 -14.583372) (xy 46.531071 -14.699135) (xy 46.585943 -14.8185)
			(xy 46.633369 -14.941015) (xy 46.673169 -15.066215) (xy 46.705192 -15.193626) (xy 46.729316 -15.322766)
			(xy 46.738571 -15.397551) (xy 51.90438 -15.397551) (xy 51.90438 -15.343049) (xy 51.912136 -15.289103)
			(xy 51.927491 -15.236809) (xy 51.950131 -15.187232) (xy 51.979596 -15.141382) (xy 52.015287 -15.100193)
			(xy 52.056476 -15.064501) (xy 52.102325 -15.035035) (xy 52.151901 -15.012393) (xy 52.204195 -14.997038)
			(xy 52.258141 -14.98928) (xy 52.285392 -14.988794) (xy 52.31501 -14.989396) (xy 52.373535 -14.998549)
			(xy 52.429941 -15.016637) (xy 52.482876 -15.043224) (xy 52.531065 -15.077673) (xy 52.5526 -15.098014)
			(xy 52.560524 -15.105065) (xy 52.580347 -15.112546) (xy 52.590954 -15.112492) (xy 52.676298 -15.10792)
			(xy 52.695094 -15.098522) (xy 52.701952 -15.090394) (xy 52.720189 -15.069186) (xy 52.761774 -15.031783)
			(xy 52.808373 -15.000848) (xy 52.858987 -14.977046) (xy 52.912533 -14.960886) (xy 52.967864 -14.952713)
			(xy 52.99583 -14.952218) (xy 53.023082 -14.952654) (xy 53.07703 -14.960414) (xy 53.129325 -14.975773)
			(xy 53.178901 -14.998418) (xy 53.224751 -15.027887) (xy 53.265941 -15.063581) (xy 53.301631 -15.104773)
			(xy 53.331097 -15.150625) (xy 53.353737 -15.200204) (xy 53.369092 -15.252499) (xy 53.376848 -15.306448)
			(xy 53.376848 -15.360952) (xy 53.369092 -15.414901) (xy 53.353737 -15.467196) (xy 53.331097 -15.516775)
			(xy 53.301631 -15.562627) (xy 53.265941 -15.603819) (xy 53.224751 -15.639513) (xy 53.178901 -15.668982)
			(xy 53.129325 -15.691627) (xy 53.07703 -15.706986) (xy 53.023082 -15.714746) (xy 52.99583 -15.715234)
			(xy 52.966209 -15.714701) (xy 52.90768 -15.705534) (xy 52.851272 -15.687431) (xy 52.798339 -15.660828)
			(xy 52.750154 -15.626363) (xy 52.728622 -15.606014) (xy 52.720697 -15.598964) (xy 52.700875 -15.591485)
			(xy 52.690268 -15.591536) (xy 52.604924 -15.596108) (xy 52.586128 -15.605506) (xy 52.57927 -15.613634)
			(xy 52.561081 -15.634885) (xy 52.519485 -15.672284) (xy 52.472876 -15.703212) (xy 52.422253 -15.727007)
			(xy 52.368699 -15.743158) (xy 52.31336 -15.751321) (xy 52.285392 -15.75181) (xy 52.258141 -15.75132)
			(xy 52.204195 -15.743562) (xy 52.151901 -15.728207) (xy 52.102325 -15.705565) (xy 52.056476 -15.676099)
			(xy 52.015287 -15.640407) (xy 51.979596 -15.599218) (xy 51.950131 -15.553368) (xy 51.927491 -15.503791)
			(xy 51.912136 -15.451497) (xy 51.90438 -15.397551) (xy 46.738571 -15.397551) (xy 46.745451 -15.453145)
			(xy 46.753535 -15.584269) (xy 46.754034 -15.649956) (xy 46.753557 -15.714428) (xy 46.745772 -15.843135)
			(xy 46.730229 -15.971138) (xy 46.706987 -16.097969) (xy 46.676129 -16.223166) (xy 46.637768 -16.34627)
			(xy 46.592044 -16.466834) (xy 46.539125 -16.584418) (xy 46.479202 -16.698591) (xy 46.412495 -16.808938)
			(xy 46.339247 -16.915056) (xy 46.296206 -16.969994) (xy 65.748161 -16.969994) (xy 65.752166 -16.882086)
			(xy 65.764149 -16.794906) (xy 65.784009 -16.709177) (xy 65.811584 -16.625609) (xy 65.846643 -16.544895)
			(xy 65.888896 -16.467703) (xy 65.937994 -16.394674) (xy 65.99353 -16.326412) (xy 66.055042 -16.263482)
			(xy 66.122023 -16.206408) (xy 66.193916 -16.15566) (xy 66.270125 -16.11166) (xy 66.35002 -16.074773)
			(xy 66.432939 -16.045304) (xy 66.518194 -16.023497) (xy 66.605078 -16.009533) (xy 66.692872 -16.003527)
			(xy 66.780849 -16.005531) (xy 66.868279 -16.015526) (xy 66.954438 -16.03343) (xy 67.038612 -16.059094)
			(xy 67.120103 -16.092307) (xy 67.198237 -16.132793) (xy 67.272365 -16.180215) (xy 67.341873 -16.234182)
			(xy 67.406187 -16.294247) (xy 67.464771 -16.359911) (xy 67.517142 -16.43063) (xy 67.562865 -16.505818)
			(xy 67.601562 -16.584853) (xy 67.632911 -16.667079) (xy 67.656653 -16.751815) (xy 67.672591 -16.838359)
			(xy 67.680593 -16.925994) (xy 67.681094 -16.969994) (xy 67.680593 -17.013994) (xy 67.672591 -17.101629)
			(xy 67.656653 -17.188173) (xy 67.632911 -17.272909) (xy 67.601562 -17.355135) (xy 67.562865 -17.43417)
			(xy 67.517142 -17.509358) (xy 67.464771 -17.580077) (xy 67.406187 -17.645741) (xy 67.341873 -17.705806)
			(xy 67.272365 -17.759773) (xy 67.198237 -17.807195) (xy 67.120103 -17.847681) (xy 67.038612 -17.880894)
			(xy 66.954438 -17.906558) (xy 66.868279 -17.924462) (xy 66.780849 -17.934457) (xy 66.692872 -17.936461)
			(xy 66.605078 -17.930455) (xy 66.518194 -17.916491) (xy 66.432939 -17.894684) (xy 66.35002 -17.865215)
			(xy 66.270125 -17.828328) (xy 66.193916 -17.784328) (xy 66.122023 -17.73358) (xy 66.055042 -17.676506)
			(xy 65.99353 -17.613576) (xy 65.937994 -17.545314) (xy 65.888896 -17.472285) (xy 65.846643 -17.395093)
			(xy 65.811584 -17.314379) (xy 65.784009 -17.230811) (xy 65.764149 -17.145082) (xy 65.752166 -17.057902)
			(xy 65.748161 -16.969994) (xy 46.296206 -16.969994) (xy 46.259725 -17.016558) (xy 46.17422 -17.113074)
			(xy 46.083044 -17.20425) (xy 45.986528 -17.289755) (xy 45.885026 -17.369277) (xy 45.812158 -17.419574)
			(xy 50.284124 -17.419574) (xy 50.288195 -17.363952) (xy 50.300321 -17.309515) (xy 50.320244 -17.257424)
			(xy 50.34754 -17.208789) (xy 50.381626 -17.164646) (xy 50.421775 -17.125937) (xy 50.467133 -17.093486)
			(xy 50.516733 -17.067985) (xy 50.569517 -17.049978) (xy 50.62436 -17.039848) (xy 50.680094 -17.037811)
			(xy 50.735531 -17.043911) (xy 50.789488 -17.058017) (xy 50.840817 -17.079829) (xy 50.888423 -17.108883)
			(xy 50.931291 -17.144558) (xy 50.968508 -17.186095) (xy 50.999281 -17.232608) (xy 51.022953 -17.283105)
			(xy 51.039021 -17.336512) (xy 51.047141 -17.391688) (xy 51.04765 -17.419574) (xy 51.047141 -17.44746)
			(xy 51.039021 -17.502636) (xy 51.022953 -17.556043) (xy 50.999281 -17.60654) (xy 50.968508 -17.653053)
			(xy 50.931291 -17.69459) (xy 50.888423 -17.730265) (xy 50.840817 -17.759319) (xy 50.789488 -17.781131)
			(xy 50.735531 -17.795237) (xy 50.680094 -17.801337) (xy 50.62436 -17.7993) (xy 50.569517 -17.78917)
			(xy 50.516733 -17.771163) (xy 50.467133 -17.745662) (xy 50.421775 -17.713211) (xy 50.381626 -17.674502)
			(xy 50.34754 -17.630359) (xy 50.320244 -17.581724) (xy 50.300321 -17.529633) (xy 50.288195 -17.475196)
			(xy 50.284124 -17.419574) (xy 45.812158 -17.419574) (xy 45.778908 -17.442525) (xy 45.668561 -17.509232)
			(xy 45.554388 -17.569155) (xy 45.436804 -17.622074) (xy 45.31624 -17.667798) (xy 45.193136 -17.706159)
			(xy 45.067939 -17.737017) (xy 44.941108 -17.760259) (xy 44.813105 -17.775802) (xy 44.684398 -17.783587)
			(xy 44.619926 -17.784064) (xy 44.569126 -17.783556) (xy 44.503349 -17.781492) (xy 44.372214 -17.770258)
			(xy 44.24202 -17.750963) (xy 44.113264 -17.723681) (xy 43.986433 -17.688515) (xy 43.862011 -17.6456)
			(xy 43.74047 -17.595099) (xy 43.622272 -17.537203) (xy 43.507868 -17.472132) (xy 43.397691 -17.400135)
			(xy 43.29216 -17.321484) (xy 43.191678 -17.236479) (xy 43.096625 -17.145443) (xy 43.007363 -17.048722)
			(xy 42.924232 -16.946683) (xy 42.847548 -16.839716) (xy 42.777602 -16.728225) (xy 42.714659 -16.612636)
			(xy 42.65896 -16.493387) (xy 42.610717 -16.370933) (xy 42.570111 -16.245738) (xy 42.537299 -16.118278)
			(xy 42.512404 -15.989038) (xy 42.495522 -15.85851) (xy 42.486716 -15.72719) (xy 42.485818 -15.661386)
			(xy 42.485818 -15.649194) (xy 42.486277 -15.586991) (xy 42.493549 -15.462798) (xy 42.508046 -15.33924)
			(xy 42.529718 -15.216736) (xy 42.55849 -15.095703) (xy 42.594267 -14.976552) (xy 42.636925 -14.859689)
			(xy 42.686321 -14.745509) (xy 42.742285 -14.634402) (xy 42.773092 -14.580362) (xy 42.7736 -14.5796)
			(xy 42.773854 -14.579092) (xy 42.77614 -14.574266) (xy 42.777664 -14.570964) (xy 42.779527 -14.566097)
			(xy 42.781447 -14.555855) (xy 42.781474 -14.550644) (xy 42.78122 -14.54531) (xy 42.780682 -14.541573)
			(xy 42.778641 -14.534304) (xy 42.777156 -14.530832) (xy 42.7609 -14.50213) (xy 42.731436 -14.450314)
			(xy 42.726708 -14.442698) (xy 42.71303 -14.431128) (xy 42.696198 -14.424994) (xy 42.68724 -14.42466)
			(xy 32.8295 -14.42466) (xy 32.819431 -14.424236) (xy 32.80083 -14.416517) (xy 32.793432 -14.409674)
			(xy 32.119062 -13.735304) (xy 32.112208 -13.727909) (xy 32.104462 -13.70931) (xy 32.104076 -13.699236)
			(xy 32.104076 -2.22504) (xy 32.103749 -2.216762) (xy 32.098421 -2.201089) (xy 32.093662 -2.194306)
			(xy 32.09163 -2.19202) (xy 32.089852 -2.190242) (xy 32.08655 -2.186432) (xy 31.484824 -1.584706)
			(xy 31.481096 -1.581181) (xy 31.472525 -1.575543) (xy 31.467806 -1.57353) (xy 31.45917 -1.569974)
			(xy 20.256754 -1.569974) (xy 20.248475 -1.570298) (xy 20.232796 -1.575618) (xy 20.22602 -1.580388)
			(xy 20.223734 -1.58242) (xy 20.221956 -1.584198) (xy 20.218146 -1.5875) (xy 19.863054 -1.942592)
			(xy 19.859532 -1.946322) (xy 19.853903 -1.954896) (xy 19.851878 -1.95961) (xy 19.848322 -1.968246)
			(xy 19.848322 -12.60729) (xy 19.847901 -12.617362) (xy 19.840192 -12.635971) (xy 19.833336 -12.643358)
			(xy 19.072098 -13.404596) (xy 19.066197 -13.411056) (xy 19.058777 -13.426886) (xy 19.05711 -13.444289)
			(xy 19.05889 -13.452856) (xy 19.05889 -13.453364) (xy 19.08175 -13.535914) (xy 19.083218 -13.539881)
			(xy 19.087307 -13.547286) (xy 19.089878 -13.550646) (xy 19.092418 -13.55344) (xy 19.093434 -13.554456)
			(xy 19.09572 -13.556996) (xy 19.10715 -13.565124) (xy 19.11858 -13.570712) (xy 19.124168 -13.571982)
			(xy 19.186984 -13.587743) (xy 19.310763 -13.625889) (xy 19.432006 -13.671457) (xy 19.550269 -13.72428)
			(xy 19.665117 -13.784165) (xy 19.776131 -13.850891) (xy 19.882901 -13.924214) (xy 19.985038 -14.003866)
			(xy 20.082167 -14.089554) (xy 20.17393 -14.180964) (xy 20.259993 -14.27776) (xy 20.340039 -14.379588)
			(xy 20.413774 -14.486075) (xy 20.480929 -14.596829) (xy 20.541257 -14.711446) (xy 20.594537 -14.829503)
			(xy 20.640573 -14.950569) (xy 20.679197 -15.0742) (xy 20.710267 -15.199942) (xy 20.733669 -15.327333)
			(xy 20.749317 -15.455908) (xy 20.757154 -15.585194) (xy 20.757642 -15.649956) (xy 20.757135 -15.715801)
			(xy 20.749028 -15.847242) (xy 20.732845 -15.977934) (xy 20.708647 -16.107382) (xy 20.676526 -16.235094)
			(xy 20.636603 -16.360587) (xy 20.589031 -16.483385) (xy 20.53399 -16.603021) (xy 20.471688 -16.719042)
			(xy 20.402362 -16.831007) (xy 20.326275 -16.938492) (xy 20.300926 -16.969994) (xy 39.748213 -16.969994)
			(xy 39.752218 -16.882086) (xy 39.764201 -16.794906) (xy 39.784061 -16.709177) (xy 39.811636 -16.625609)
			(xy 39.846695 -16.544895) (xy 39.888948 -16.467703) (xy 39.938046 -16.394674) (xy 39.993582 -16.326412)
			(xy 40.055094 -16.263482) (xy 40.122075 -16.206408) (xy 40.193968 -16.15566) (xy 40.270177 -16.11166)
			(xy 40.350072 -16.074773) (xy 40.432991 -16.045304) (xy 40.518246 -16.023497) (xy 40.60513 -16.009533)
			(xy 40.692924 -16.003527) (xy 40.780901 -16.005531) (xy 40.868331 -16.015526) (xy 40.95449 -16.03343)
			(xy 41.038664 -16.059094) (xy 41.120155 -16.092307) (xy 41.198289 -16.132793) (xy 41.272417 -16.180215)
			(xy 41.341925 -16.234182) (xy 41.406239 -16.294247) (xy 41.464823 -16.359911) (xy 41.517194 -16.43063)
			(xy 41.562917 -16.505818) (xy 41.601614 -16.584853) (xy 41.632963 -16.667079) (xy 41.656705 -16.751815)
			(xy 41.672643 -16.838359) (xy 41.680645 -16.925994) (xy 41.681146 -16.969994) (xy 41.680645 -17.013994)
			(xy 41.672643 -17.101629) (xy 41.656705 -17.188173) (xy 41.632963 -17.272909) (xy 41.601614 -17.355135)
			(xy 41.562917 -17.43417) (xy 41.517194 -17.509358) (xy 41.464823 -17.580077) (xy 41.406239 -17.645741)
			(xy 41.341925 -17.705806) (xy 41.272417 -17.759773) (xy 41.198289 -17.807195) (xy 41.120155 -17.847681)
			(xy 41.038664 -17.880894) (xy 40.95449 -17.906558) (xy 40.868331 -17.924462) (xy 40.780901 -17.934457)
			(xy 40.692924 -17.936461) (xy 40.60513 -17.930455) (xy 40.518246 -17.916491) (xy 40.432991 -17.894684)
			(xy 40.350072 -17.865215) (xy 40.270177 -17.828328) (xy 40.193968 -17.784328) (xy 40.122075 -17.73358)
			(xy 40.055094 -17.676506) (xy 39.993582 -17.613576) (xy 39.938046 -17.545314) (xy 39.888948 -17.472285)
			(xy 39.846695 -17.395093) (xy 39.811636 -17.314379) (xy 39.784061 -17.230811) (xy 39.764201 -17.145082)
			(xy 39.752218 -17.057902) (xy 39.748213 -16.969994) (xy 20.300926 -16.969994) (xy 20.243716 -17.041089)
			(xy 20.154996 -17.138409) (xy 20.060454 -17.230083) (xy 19.960448 -17.315763) (xy 19.855357 -17.395125)
			(xy 19.74558 -17.467866) (xy 19.631533 -17.533711) (xy 19.513649 -17.59241) (xy 19.392374 -17.643741)
			(xy 19.26817 -17.687509) (xy 19.141507 -17.723548) (xy 19.012866 -17.751721) (xy 18.882734 -17.771921)
			(xy 18.751606 -17.784072) (xy 18.619978 -17.788127) (xy 18.48835 -17.784072) (xy 18.357222 -17.771921)
			(xy 18.22709 -17.751721) (xy 18.098449 -17.723548) (xy 17.971786 -17.687509) (xy 17.847582 -17.643741)
			(xy 17.726307 -17.59241) (xy 17.608423 -17.533711) (xy 17.494376 -17.467866) (xy 17.384599 -17.395125)
			(xy 17.279508 -17.315763) (xy 17.179502 -17.230083) (xy 17.08496 -17.138409) (xy 16.99624 -17.041089)
			(xy 16.913681 -16.938492) (xy 16.837594 -16.831007) (xy 16.768268 -16.719042) (xy 16.705966 -16.603021)
			(xy 16.650925 -16.483385) (xy 16.603353 -16.360587) (xy 16.56343 -16.235094) (xy 16.531309 -16.107382)
			(xy 16.507111 -15.977934) (xy 16.490928 -15.847242) (xy 16.482821 -15.715801) (xy 16.482314 -15.649956)
			(xy 16.482816 -15.583886) (xy 16.490975 -15.451998) (xy 16.507265 -15.320866) (xy 16.531623 -15.190991)
			(xy 16.563958 -15.062868) (xy 16.604145 -14.936987) (xy 16.652031 -14.813829) (xy 16.707434 -14.693864)
			(xy 16.77014 -14.577551) (xy 16.839912 -14.465333) (xy 16.877792 -14.411198) (xy 16.88084 -14.40688)
			(xy 16.881602 -14.405864) (xy 16.888206 -14.38783) (xy 16.889984 -14.375638) (xy 16.88973 -14.369288)
			(xy 16.889244 -14.365294) (xy 16.8872 -14.357513) (xy 16.885666 -14.353794) (xy 16.884904 -14.352524)
			(xy 16.884904 -14.35227) (xy 16.844772 -14.273784) (xy 16.839993 -14.26629) (xy 16.826389 -14.254874)
			(xy 16.809709 -14.248778) (xy 16.80083 -14.248384) (xy 8.036052 -14.248384) (xy 8.025986 -14.247952)
			(xy 8.007396 -14.240223) (xy 7.999984 -14.233398) (xy 7.779258 -14.012672) (xy 7.775448 -14.00937)
			(xy 7.768324 -14.003695) (xy 7.751274 -13.997326) (xy 7.742174 -13.996924) (xy 7.732268 -13.996924)
			(xy 7.696962 -14.01064) (xy 7.696454 -14.01064) (xy 7.634478 -14.035024) (xy 7.6327 -14.035786) (xy 7.625588 -14.040358)
			(xy 7.619746 -14.050518) (xy 7.605776 -14.074648) (xy 7.60476 -14.085316) (xy 7.60476 -14.086332)
			(xy 7.602072 -14.114314) (xy 7.58952 -14.169108) (xy 7.569067 -14.221468) (xy 7.541156 -14.270262)
			(xy 7.506389 -14.314434) (xy 7.465519 -14.353028) (xy 7.41943 -14.385211) (xy 7.369119 -14.410285)
			(xy 7.315675 -14.427709) (xy 7.260253 -14.437105) (xy 7.204052 -14.438271) (xy 7.148288 -14.43118)
			(xy 7.094167 -14.415987) (xy 7.04286 -14.39302) (xy 6.995477 -14.362775) (xy 6.953042 -14.325908)
			(xy 6.916474 -14.283215) (xy 6.886563 -14.23562) (xy 6.863957 -14.184153) (xy 6.849145 -14.129927)
			(xy 6.8453 -14.10208) (xy 6.843776 -14.087348) (xy 6.842016 -14.059705) (xy 6.845539 -14.004429)
			(xy 6.857018 -13.950243) (xy 6.876213 -13.898287) (xy 6.90272 -13.849653) (xy 6.935982 -13.805364)
			(xy 6.975298 -13.76635) (xy 7.019844 -13.733432) (xy 7.068681 -13.707302) (xy 7.120784 -13.688509)
			(xy 7.175057 -13.677449) (xy 7.202678 -13.67536) (xy 7.210552 -13.674852) (xy 7.22376 -13.670026)
			(xy 7.229856 -13.665708) (xy 7.235391 -13.661375) (xy 7.24403 -13.650292) (xy 7.246874 -13.643864)
			(xy 7.271258 -13.579856) (xy 7.271766 -13.578586) (xy 7.272528 -13.576554) (xy 7.272528 -13.5763)
			(xy 7.276846 -13.567664) (xy 7.2771 -13.567156) (xy 7.279386 -13.562838) (xy 7.281624 -13.557723)
			(xy 7.284054 -13.546829) (xy 7.284212 -13.541248) (xy 7.284212 -13.527278) (xy 7.276592 -13.512546)
			(xy 7.273036 -13.506958) (xy 7.268972 -13.502386) (xy 6.480556 -12.71397) (xy 6.473708 -12.706572)
			(xy 6.465976 -12.687974) (xy 6.46557 -12.677902) (xy 6.46557 -2.647696) (xy 6.465253 -2.639414) (xy 6.459947 -2.623724)
			(xy 6.455156 -2.616962) (xy 6.453124 -2.614676) (xy 6.451346 -2.612898) (xy 6.448044 -2.609088) (xy 5.670296 -1.83134)
			(xy 5.666568 -1.827815) (xy 5.657997 -1.822178) (xy 5.653278 -1.820164) (xy 5.644642 -1.816608) (xy 2.084324 -1.816608)
			(xy 2.076041 -1.816922) (xy 2.060351 -1.822228) (xy 2.05359 -1.827022) (xy 2.051304 -1.829054) (xy 2.049526 -1.830832)
			(xy 2.045716 -1.834134) (xy 1.514602 -2.365248) (xy 1.511082 -2.368979) (xy 1.505456 -2.377555) (xy 1.503426 -2.382266)
			(xy 1.49987 -2.390902) (xy 1.49987 -15.128748) (xy 7.834882 -15.128748) (xy 7.838953 -15.073126)
			(xy 7.851079 -15.018689) (xy 7.871002 -14.966598) (xy 7.898298 -14.917963) (xy 7.932384 -14.87382)
			(xy 7.972533 -14.835111) (xy 8.017891 -14.80266) (xy 8.067491 -14.777159) (xy 8.120275 -14.759152)
			(xy 8.175118 -14.749022) (xy 8.230852 -14.746985) (xy 8.286289 -14.753085) (xy 8.340246 -14.767191)
			(xy 8.391575 -14.789003) (xy 8.439181 -14.818057) (xy 8.482049 -14.853732) (xy 8.519266 -14.895269)
			(xy 8.550039 -14.941782) (xy 8.573711 -14.992279) (xy 8.589779 -15.045686) (xy 8.597899 -15.100862)
			(xy 8.598408 -15.128748) (xy 8.597899 -15.156634) (xy 8.589779 -15.21181) (xy 8.573711 -15.265217)
			(xy 8.550039 -15.315714) (xy 8.519266 -15.362227) (xy 8.482049 -15.403764) (xy 8.439181 -15.439439)
			(xy 8.391575 -15.468493) (xy 8.340246 -15.490305) (xy 8.286289 -15.504411) (xy 8.230852 -15.510511)
			(xy 8.175118 -15.508474) (xy 8.120275 -15.498344) (xy 8.067491 -15.480337) (xy 8.017891 -15.454836)
			(xy 7.972533 -15.422385) (xy 7.932384 -15.383676) (xy 7.898298 -15.339533) (xy 7.871002 -15.290898)
			(xy 7.851079 -15.238807) (xy 7.838953 -15.18437) (xy 7.834882 -15.128748) (xy 1.49987 -15.128748)
			(xy 1.49987 -16.144748) (xy 7.834882 -16.144748) (xy 7.838953 -16.089126) (xy 7.851079 -16.034689)
			(xy 7.871002 -15.982598) (xy 7.898298 -15.933963) (xy 7.932384 -15.88982) (xy 7.972533 -15.851111)
			(xy 8.017891 -15.81866) (xy 8.067491 -15.793159) (xy 8.120275 -15.775152) (xy 8.175118 -15.765022)
			(xy 8.230852 -15.762985) (xy 8.286289 -15.769085) (xy 8.340246 -15.783191) (xy 8.391575 -15.805003)
			(xy 8.439181 -15.834057) (xy 8.482049 -15.869732) (xy 8.519266 -15.911269) (xy 8.550039 -15.957782)
			(xy 8.573711 -16.008279) (xy 8.589779 -16.061686) (xy 8.597899 -16.116862) (xy 8.598408 -16.144748)
			(xy 8.597899 -16.172634) (xy 8.589779 -16.22781) (xy 8.573711 -16.281217) (xy 8.550039 -16.331714)
			(xy 8.519266 -16.378227) (xy 8.482049 -16.419764) (xy 8.439181 -16.455439) (xy 8.391575 -16.484493)
			(xy 8.340246 -16.506305) (xy 8.286289 -16.520411) (xy 8.230852 -16.526511) (xy 8.175118 -16.524474)
			(xy 8.120275 -16.514344) (xy 8.067491 -16.496337) (xy 8.017891 -16.470836) (xy 7.972533 -16.438385)
			(xy 7.932384 -16.399676) (xy 7.898298 -16.355533) (xy 7.871002 -16.306898) (xy 7.851079 -16.254807)
			(xy 7.838953 -16.20037) (xy 7.834882 -16.144748) (xy 1.49987 -16.144748) (xy 1.49987 -17.160748)
			(xy 7.834882 -17.160748) (xy 7.838953 -17.105126) (xy 7.851079 -17.050689) (xy 7.871002 -16.998598)
			(xy 7.898298 -16.949963) (xy 7.932384 -16.90582) (xy 7.972533 -16.867111) (xy 8.017891 -16.83466)
			(xy 8.067491 -16.809159) (xy 8.120275 -16.791152) (xy 8.175118 -16.781022) (xy 8.230852 -16.778985)
			(xy 8.286289 -16.785085) (xy 8.340246 -16.799191) (xy 8.391575 -16.821003) (xy 8.439181 -16.850057)
			(xy 8.482049 -16.885732) (xy 8.519266 -16.927269) (xy 8.547533 -16.969994) (xy 13.748265 -16.969994)
			(xy 13.75227 -16.882086) (xy 13.764253 -16.794906) (xy 13.784113 -16.709177) (xy 13.811688 -16.625609)
			(xy 13.846747 -16.544895) (xy 13.889 -16.467703) (xy 13.938098 -16.394674) (xy 13.993634 -16.326412)
			(xy 14.055146 -16.263482) (xy 14.122127 -16.206408) (xy 14.19402 -16.15566) (xy 14.270229 -16.11166)
			(xy 14.350124 -16.074773) (xy 14.433043 -16.045304) (xy 14.518298 -16.023497) (xy 14.605182 -16.009533)
			(xy 14.692976 -16.003527) (xy 14.780953 -16.005531) (xy 14.868383 -16.015526) (xy 14.954542 -16.03343)
			(xy 15.038716 -16.059094) (xy 15.120207 -16.092307) (xy 15.198341 -16.132793) (xy 15.272469 -16.180215)
			(xy 15.341977 -16.234182) (xy 15.406291 -16.294247) (xy 15.464875 -16.359911) (xy 15.517246 -16.43063)
			(xy 15.562969 -16.505818) (xy 15.601666 -16.584853) (xy 15.633015 -16.667079) (xy 15.656757 -16.751815)
			(xy 15.672695 -16.838359) (xy 15.680697 -16.925994) (xy 15.681198 -16.969994) (xy 15.680697 -17.013994)
			(xy 15.672695 -17.101629) (xy 15.656757 -17.188173) (xy 15.633015 -17.272909) (xy 15.601666 -17.355135)
			(xy 15.562969 -17.43417) (xy 15.517246 -17.509358) (xy 15.464875 -17.580077) (xy 15.406291 -17.645741)
			(xy 15.341977 -17.705806) (xy 15.272469 -17.759773) (xy 15.198341 -17.807195) (xy 15.120207 -17.847681)
			(xy 15.038716 -17.880894) (xy 14.954542 -17.906558) (xy 14.868383 -17.924462) (xy 14.780953 -17.934457)
			(xy 14.692976 -17.936461) (xy 14.605182 -17.930455) (xy 14.518298 -17.916491) (xy 14.433043 -17.894684)
			(xy 14.350124 -17.865215) (xy 14.270229 -17.828328) (xy 14.19402 -17.784328) (xy 14.122127 -17.73358)
			(xy 14.055146 -17.676506) (xy 13.993634 -17.613576) (xy 13.938098 -17.545314) (xy 13.889 -17.472285)
			(xy 13.846747 -17.395093) (xy 13.811688 -17.314379) (xy 13.784113 -17.230811) (xy 13.764253 -17.145082)
			(xy 13.75227 -17.057902) (xy 13.748265 -16.969994) (xy 8.547533 -16.969994) (xy 8.550039 -16.973782)
			(xy 8.573711 -17.024279) (xy 8.589779 -17.077686) (xy 8.597899 -17.132862) (xy 8.598408 -17.160748)
			(xy 8.597899 -17.188634) (xy 8.589779 -17.24381) (xy 8.573711 -17.297217) (xy 8.550039 -17.347714)
			(xy 8.519266 -17.394227) (xy 8.482049 -17.435764) (xy 8.439181 -17.471439) (xy 8.391575 -17.500493)
			(xy 8.340246 -17.522305) (xy 8.286289 -17.536411) (xy 8.230852 -17.542511) (xy 8.175118 -17.540474)
			(xy 8.120275 -17.530344) (xy 8.067491 -17.512337) (xy 8.017891 -17.486836) (xy 7.972533 -17.454385)
			(xy 7.932384 -17.415676) (xy 7.898298 -17.371533) (xy 7.871002 -17.322898) (xy 7.851079 -17.270807)
			(xy 7.838953 -17.21637) (xy 7.834882 -17.160748) (xy 1.49987 -17.160748) (xy 1.49987 -17.610836)
			(xy 1.499923 -17.614908) (xy 1.501199 -17.62295) (xy 1.50241 -17.626838) (xy 1.503172 -17.629124)
			(xy 1.506459 -17.637792) (xy 1.518183 -17.652131) (xy 1.526032 -17.657064) (xy 1.567942 -17.681448)
			(xy 1.56845 -17.681448) (xy 1.603248 -17.70126) (xy 1.60866 -17.703911) (xy 1.62034 -17.706867) (xy 1.626362 -17.707102)
			(xy 1.641094 -17.707102) (xy 1.652778 -17.700244) (xy 1.653032 -17.700244) (xy 1.65862 -17.697196)
			(xy 1.680167 -17.685433) (xy 1.725635 -17.666923) (xy 1.773101 -17.654394) (xy 1.821781 -17.648053)
			(xy 1.846326 -17.647666) (xy 1.850898 -17.647666) (xy 1.879676 -17.648497) (xy 1.936499 -17.657752)
			(xy 1.991286 -17.67544) (xy 2.042793 -17.70116) (xy 2.089851 -17.734326) (xy 2.131391 -17.774187)
			(xy 2.16647 -17.819837) (xy 2.194292 -17.870239) (xy 2.214224 -17.92425) (xy 2.225815 -17.980642)
			(xy 2.227834 -18.009362) (xy 2.227834 -18.010124) (xy 2.228088 -18.013934) (xy 2.228088 -18.015966)
			(xy 2.228342 -18.02892) (xy 2.228342 -18.035016) (xy 2.227474 -18.061868) (xy 2.219126 -18.114939)
			(xy 2.203416 -18.166314) (xy 2.180653 -18.214976) (xy 2.151287 -18.259964) (xy 2.1159 -18.300387)
			(xy 2.075193 -18.335445) (xy 2.029969 -18.364445) (xy 1.981123 -18.386814) (xy 1.929623 -18.402108)
			(xy 1.876486 -18.410026) (xy 1.849628 -18.410682) (xy 1.846072 -18.410682) (xy 1.821456 -18.410277)
			(xy 1.772637 -18.403906) (xy 1.725043 -18.391312) (xy 1.679462 -18.372705) (xy 1.657858 -18.360898)
			(xy 1.652016 -18.357596) (xy 1.6383 -18.35404) (xy 1.628637 -18.35191) (xy 1.609025 -18.354392) (xy 1.6002 -18.358866)
			(xy 1.563878 -18.37944) (xy 1.56337 -18.37944) (xy 1.525778 -18.40103) (xy 1.515618 -18.40865) (xy 1.51384 -18.410428)
			(xy 1.507459 -18.41775) (xy 1.500278 -18.435776) (xy 1.499923 -18.44421) (xy 48.276254 -18.44421)
			(xy 48.280325 -18.388588) (xy 48.292451 -18.334151) (xy 48.312374 -18.28206) (xy 48.33967 -18.233425)
			(xy 48.373756 -18.189282) (xy 48.413905 -18.150573) (xy 48.459263 -18.118122) (xy 48.508863 -18.092621)
			(xy 48.561647 -18.074614) (xy 48.61649 -18.064484) (xy 48.672224 -18.062447) (xy 48.727661 -18.068547)
			(xy 48.781618 -18.082653) (xy 48.832947 -18.104465) (xy 48.880553 -18.133519) (xy 48.923421 -18.169194)
			(xy 48.960638 -18.210731) (xy 48.991411 -18.257244) (xy 49.015083 -18.307741) (xy 49.031151 -18.361148)
			(xy 49.039271 -18.416324) (xy 49.03978 -18.44421) (xy 74.276202 -18.44421) (xy 74.280273 -18.388588)
			(xy 74.292399 -18.334151) (xy 74.312322 -18.28206) (xy 74.339618 -18.233425) (xy 74.373704 -18.189282)
			(xy 74.413853 -18.150573) (xy 74.459211 -18.118122) (xy 74.508811 -18.092621) (xy 74.561595 -18.074614)
			(xy 74.616438 -18.064484) (xy 74.672172 -18.062447) (xy 74.727609 -18.068547) (xy 74.781566 -18.082653)
			(xy 74.832895 -18.104465) (xy 74.880501 -18.133519) (xy 74.923369 -18.169194) (xy 74.960586 -18.210731)
			(xy 74.991359 -18.257244) (xy 75.015031 -18.307741) (xy 75.031099 -18.361148) (xy 75.039219 -18.416324)
			(xy 75.039728 -18.44421) (xy 138.376404 -18.44421) (xy 138.380475 -18.388588) (xy 138.392601 -18.334151)
			(xy 138.412524 -18.28206) (xy 138.43982 -18.233425) (xy 138.473906 -18.189282) (xy 138.514055 -18.150573)
			(xy 138.559413 -18.118122) (xy 138.609013 -18.092621) (xy 138.661797 -18.074614) (xy 138.71664 -18.064484)
			(xy 138.772374 -18.062447) (xy 138.827811 -18.068547) (xy 138.881768 -18.082653) (xy 138.933097 -18.104465)
			(xy 138.980703 -18.133519) (xy 139.023571 -18.169194) (xy 139.060788 -18.210731) (xy 139.091561 -18.257244)
			(xy 139.115233 -18.307741) (xy 139.131301 -18.361148) (xy 139.139421 -18.416324) (xy 139.13993 -18.44421)
			(xy 164.376352 -18.44421) (xy 164.380423 -18.388588) (xy 164.392549 -18.334151) (xy 164.412472 -18.28206)
			(xy 164.439768 -18.233425) (xy 164.473854 -18.189282) (xy 164.514003 -18.150573) (xy 164.559361 -18.118122)
			(xy 164.608961 -18.092621) (xy 164.661745 -18.074614) (xy 164.716588 -18.064484) (xy 164.772322 -18.062447)
			(xy 164.827759 -18.068547) (xy 164.881716 -18.082653) (xy 164.933045 -18.104465) (xy 164.980651 -18.133519)
			(xy 165.023519 -18.169194) (xy 165.060736 -18.210731) (xy 165.091509 -18.257244) (xy 165.115181 -18.307741)
			(xy 165.131249 -18.361148) (xy 165.139369 -18.416324) (xy 165.139878 -18.44421) (xy 190.3763 -18.44421)
			(xy 190.380371 -18.388588) (xy 190.392497 -18.334151) (xy 190.41242 -18.28206) (xy 190.439716 -18.233425)
			(xy 190.473802 -18.189282) (xy 190.513951 -18.150573) (xy 190.559309 -18.118122) (xy 190.608909 -18.092621)
			(xy 190.661693 -18.074614) (xy 190.716536 -18.064484) (xy 190.77227 -18.062447) (xy 190.827707 -18.068547)
			(xy 190.881664 -18.082653) (xy 190.932993 -18.104465) (xy 190.980599 -18.133519) (xy 191.023467 -18.169194)
			(xy 191.060684 -18.210731) (xy 191.091457 -18.257244) (xy 191.115129 -18.307741) (xy 191.131197 -18.361148)
			(xy 191.139317 -18.416324) (xy 191.139826 -18.44421) (xy 216.376248 -18.44421) (xy 216.380319 -18.388588)
			(xy 216.392445 -18.334151) (xy 216.412368 -18.28206) (xy 216.439664 -18.233425) (xy 216.47375 -18.189282)
			(xy 216.513899 -18.150573) (xy 216.559257 -18.118122) (xy 216.608857 -18.092621) (xy 216.661641 -18.074614)
			(xy 216.716484 -18.064484) (xy 216.772218 -18.062447) (xy 216.827655 -18.068547) (xy 216.881612 -18.082653)
			(xy 216.932941 -18.104465) (xy 216.980547 -18.133519) (xy 217.023415 -18.169194) (xy 217.060632 -18.210731)
			(xy 217.091405 -18.257244) (xy 217.115077 -18.307741) (xy 217.131145 -18.361148) (xy 217.139265 -18.416324)
			(xy 217.139774 -18.44421) (xy 254.476248 -18.44421) (xy 254.480319 -18.388588) (xy 254.492445 -18.334151)
			(xy 254.512368 -18.28206) (xy 254.539664 -18.233425) (xy 254.57375 -18.189282) (xy 254.613899 -18.150573)
			(xy 254.659257 -18.118122) (xy 254.708857 -18.092621) (xy 254.761641 -18.074614) (xy 254.816484 -18.064484)
			(xy 254.872218 -18.062447) (xy 254.927655 -18.068547) (xy 254.981612 -18.082653) (xy 255.032941 -18.104465)
			(xy 255.080547 -18.133519) (xy 255.123415 -18.169194) (xy 255.160632 -18.210731) (xy 255.191405 -18.257244)
			(xy 255.215077 -18.307741) (xy 255.231145 -18.361148) (xy 255.239265 -18.416324) (xy 255.239774 -18.44421)
			(xy 280.476196 -18.44421) (xy 280.480267 -18.388588) (xy 280.492393 -18.334151) (xy 280.512316 -18.28206)
			(xy 280.539612 -18.233425) (xy 280.573698 -18.189282) (xy 280.613847 -18.150573) (xy 280.659205 -18.118122)
			(xy 280.708805 -18.092621) (xy 280.761589 -18.074614) (xy 280.816432 -18.064484) (xy 280.872166 -18.062447)
			(xy 280.927603 -18.068547) (xy 280.98156 -18.082653) (xy 281.032889 -18.104465) (xy 281.080495 -18.133519)
			(xy 281.123363 -18.169194) (xy 281.16058 -18.210731) (xy 281.191353 -18.257244) (xy 281.215025 -18.307741)
			(xy 281.231093 -18.361148) (xy 281.239213 -18.416324) (xy 281.239722 -18.44421) (xy 306.476144 -18.44421)
			(xy 306.480215 -18.388588) (xy 306.492341 -18.334151) (xy 306.512264 -18.28206) (xy 306.53956 -18.233425)
			(xy 306.573646 -18.189282) (xy 306.613795 -18.150573) (xy 306.659153 -18.118122) (xy 306.708753 -18.092621)
			(xy 306.761537 -18.074614) (xy 306.81638 -18.064484) (xy 306.872114 -18.062447) (xy 306.927551 -18.068547)
			(xy 306.981508 -18.082653) (xy 307.032837 -18.104465) (xy 307.080443 -18.133519) (xy 307.123311 -18.169194)
			(xy 307.160528 -18.210731) (xy 307.191301 -18.257244) (xy 307.214973 -18.307741) (xy 307.231041 -18.361148)
			(xy 307.239161 -18.416324) (xy 307.23967 -18.44421) (xy 370.576346 -18.44421) (xy 370.580417 -18.388588)
			(xy 370.592543 -18.334151) (xy 370.612466 -18.28206) (xy 370.639762 -18.233425) (xy 370.673848 -18.189282)
			(xy 370.713997 -18.150573) (xy 370.759355 -18.118122) (xy 370.808955 -18.092621) (xy 370.861739 -18.074614)
			(xy 370.916582 -18.064484) (xy 370.972316 -18.062447) (xy 371.027753 -18.068547) (xy 371.08171 -18.082653)
			(xy 371.133039 -18.104465) (xy 371.180645 -18.133519) (xy 371.223513 -18.169194) (xy 371.26073 -18.210731)
			(xy 371.291503 -18.257244) (xy 371.315175 -18.307741) (xy 371.331243 -18.361148) (xy 371.339363 -18.416324)
			(xy 371.339872 -18.44421) (xy 396.576294 -18.44421) (xy 396.580365 -18.388588) (xy 396.592491 -18.334151)
			(xy 396.612414 -18.28206) (xy 396.63971 -18.233425) (xy 396.673796 -18.189282) (xy 396.713945 -18.150573)
			(xy 396.759303 -18.118122) (xy 396.808903 -18.092621) (xy 396.861687 -18.074614) (xy 396.91653 -18.064484)
			(xy 396.972264 -18.062447) (xy 397.027701 -18.068547) (xy 397.081658 -18.082653) (xy 397.132987 -18.104465)
			(xy 397.180593 -18.133519) (xy 397.223461 -18.169194) (xy 397.260678 -18.210731) (xy 397.291451 -18.257244)
			(xy 397.315123 -18.307741) (xy 397.331191 -18.361148) (xy 397.339311 -18.416324) (xy 397.33982 -18.44421)
			(xy 422.576242 -18.44421) (xy 422.580313 -18.388588) (xy 422.592439 -18.334151) (xy 422.612362 -18.28206)
			(xy 422.639658 -18.233425) (xy 422.673744 -18.189282) (xy 422.713893 -18.150573) (xy 422.759251 -18.118122)
			(xy 422.808851 -18.092621) (xy 422.861635 -18.074614) (xy 422.916478 -18.064484) (xy 422.972212 -18.062447)
			(xy 423.027649 -18.068547) (xy 423.081606 -18.082653) (xy 423.132935 -18.104465) (xy 423.180541 -18.133519)
			(xy 423.223409 -18.169194) (xy 423.260626 -18.210731) (xy 423.291399 -18.257244) (xy 423.315071 -18.307741)
			(xy 423.331139 -18.361148) (xy 423.339259 -18.416324) (xy 423.339768 -18.44421) (xy 448.57619 -18.44421)
			(xy 448.580261 -18.388588) (xy 448.592387 -18.334151) (xy 448.61231 -18.28206) (xy 448.639606 -18.233425)
			(xy 448.673692 -18.189282) (xy 448.713841 -18.150573) (xy 448.759199 -18.118122) (xy 448.808799 -18.092621)
			(xy 448.861583 -18.074614) (xy 448.916426 -18.064484) (xy 448.97216 -18.062447) (xy 449.027597 -18.068547)
			(xy 449.081554 -18.082653) (xy 449.132883 -18.104465) (xy 449.180489 -18.133519) (xy 449.223357 -18.169194)
			(xy 449.260574 -18.210731) (xy 449.291347 -18.257244) (xy 449.29481 -18.264632) (xy 454.446638 -18.264632)
			(xy 454.450709 -18.20901) (xy 454.462835 -18.154573) (xy 454.482758 -18.102482) (xy 454.510054 -18.053847)
			(xy 454.54414 -18.009704) (xy 454.584289 -17.970995) (xy 454.629647 -17.938544) (xy 454.679247 -17.913043)
			(xy 454.732031 -17.895036) (xy 454.786874 -17.884906) (xy 454.842608 -17.882869) (xy 454.898045 -17.888969)
			(xy 454.952002 -17.903075) (xy 455.003331 -17.924887) (xy 455.050937 -17.953941) (xy 455.093805 -17.989616)
			(xy 455.131022 -18.031153) (xy 455.161795 -18.077666) (xy 455.185467 -18.128163) (xy 455.201535 -18.18157)
			(xy 455.209655 -18.236746) (xy 455.210164 -18.264632) (xy 455.209655 -18.292518) (xy 455.201535 -18.347694)
			(xy 455.185467 -18.401101) (xy 455.161795 -18.451598) (xy 455.131022 -18.498111) (xy 455.093805 -18.539648)
			(xy 455.050937 -18.575323) (xy 455.003331 -18.604377) (xy 454.952002 -18.626189) (xy 454.898045 -18.640295)
			(xy 454.842608 -18.646395) (xy 454.786874 -18.644358) (xy 454.732031 -18.634228) (xy 454.679247 -18.616221)
			(xy 454.629647 -18.59072) (xy 454.584289 -18.558269) (xy 454.54414 -18.51956) (xy 454.510054 -18.475417)
			(xy 454.482758 -18.426782) (xy 454.462835 -18.374691) (xy 454.450709 -18.320254) (xy 454.446638 -18.264632)
			(xy 449.29481 -18.264632) (xy 449.315019 -18.307741) (xy 449.331087 -18.361148) (xy 449.339207 -18.416324)
			(xy 449.339716 -18.44421) (xy 449.339207 -18.472096) (xy 449.331087 -18.527272) (xy 449.315019 -18.580679)
			(xy 449.291347 -18.631176) (xy 449.260574 -18.677689) (xy 449.223357 -18.719226) (xy 449.180489 -18.754901)
			(xy 449.132883 -18.783955) (xy 449.081554 -18.805767) (xy 449.027597 -18.819873) (xy 448.97216 -18.825973)
			(xy 448.916426 -18.823936) (xy 448.861583 -18.813806) (xy 448.808799 -18.795799) (xy 448.759199 -18.770298)
			(xy 448.713841 -18.737847) (xy 448.673692 -18.699138) (xy 448.639606 -18.654995) (xy 448.61231 -18.60636)
			(xy 448.592387 -18.554269) (xy 448.580261 -18.499832) (xy 448.57619 -18.44421) (xy 423.339768 -18.44421)
			(xy 423.339259 -18.472096) (xy 423.331139 -18.527272) (xy 423.315071 -18.580679) (xy 423.291399 -18.631176)
			(xy 423.260626 -18.677689) (xy 423.223409 -18.719226) (xy 423.180541 -18.754901) (xy 423.132935 -18.783955)
			(xy 423.081606 -18.805767) (xy 423.027649 -18.819873) (xy 422.972212 -18.825973) (xy 422.916478 -18.823936)
			(xy 422.861635 -18.813806) (xy 422.808851 -18.795799) (xy 422.759251 -18.770298) (xy 422.713893 -18.737847)
			(xy 422.673744 -18.699138) (xy 422.639658 -18.654995) (xy 422.612362 -18.60636) (xy 422.592439 -18.554269)
			(xy 422.580313 -18.499832) (xy 422.576242 -18.44421) (xy 397.33982 -18.44421) (xy 397.339311 -18.472096)
			(xy 397.331191 -18.527272) (xy 397.315123 -18.580679) (xy 397.291451 -18.631176) (xy 397.260678 -18.677689)
			(xy 397.223461 -18.719226) (xy 397.180593 -18.754901) (xy 397.132987 -18.783955) (xy 397.081658 -18.805767)
			(xy 397.027701 -18.819873) (xy 396.972264 -18.825973) (xy 396.91653 -18.823936) (xy 396.861687 -18.813806)
			(xy 396.808903 -18.795799) (xy 396.759303 -18.770298) (xy 396.713945 -18.737847) (xy 396.673796 -18.699138)
			(xy 396.63971 -18.654995) (xy 396.612414 -18.60636) (xy 396.592491 -18.554269) (xy 396.580365 -18.499832)
			(xy 396.576294 -18.44421) (xy 371.339872 -18.44421) (xy 371.339363 -18.472096) (xy 371.331243 -18.527272)
			(xy 371.315175 -18.580679) (xy 371.291503 -18.631176) (xy 371.26073 -18.677689) (xy 371.223513 -18.719226)
			(xy 371.180645 -18.754901) (xy 371.133039 -18.783955) (xy 371.08171 -18.805767) (xy 371.027753 -18.819873)
			(xy 370.972316 -18.825973) (xy 370.916582 -18.823936) (xy 370.861739 -18.813806) (xy 370.808955 -18.795799)
			(xy 370.759355 -18.770298) (xy 370.713997 -18.737847) (xy 370.673848 -18.699138) (xy 370.639762 -18.654995)
			(xy 370.612466 -18.60636) (xy 370.592543 -18.554269) (xy 370.580417 -18.499832) (xy 370.576346 -18.44421)
			(xy 307.23967 -18.44421) (xy 307.239161 -18.472096) (xy 307.231041 -18.527272) (xy 307.214973 -18.580679)
			(xy 307.191301 -18.631176) (xy 307.160528 -18.677689) (xy 307.123311 -18.719226) (xy 307.080443 -18.754901)
			(xy 307.032837 -18.783955) (xy 306.981508 -18.805767) (xy 306.927551 -18.819873) (xy 306.872114 -18.825973)
			(xy 306.81638 -18.823936) (xy 306.761537 -18.813806) (xy 306.708753 -18.795799) (xy 306.659153 -18.770298)
			(xy 306.613795 -18.737847) (xy 306.573646 -18.699138) (xy 306.53956 -18.654995) (xy 306.512264 -18.60636)
			(xy 306.492341 -18.554269) (xy 306.480215 -18.499832) (xy 306.476144 -18.44421) (xy 281.239722 -18.44421)
			(xy 281.239213 -18.472096) (xy 281.231093 -18.527272) (xy 281.215025 -18.580679) (xy 281.191353 -18.631176)
			(xy 281.16058 -18.677689) (xy 281.123363 -18.719226) (xy 281.080495 -18.754901) (xy 281.032889 -18.783955)
			(xy 280.98156 -18.805767) (xy 280.927603 -18.819873) (xy 280.872166 -18.825973) (xy 280.816432 -18.823936)
			(xy 280.761589 -18.813806) (xy 280.708805 -18.795799) (xy 280.659205 -18.770298) (xy 280.613847 -18.737847)
			(xy 280.573698 -18.699138) (xy 280.539612 -18.654995) (xy 280.512316 -18.60636) (xy 280.492393 -18.554269)
			(xy 280.480267 -18.499832) (xy 280.476196 -18.44421) (xy 255.239774 -18.44421) (xy 255.239265 -18.472096)
			(xy 255.231145 -18.527272) (xy 255.215077 -18.580679) (xy 255.191405 -18.631176) (xy 255.160632 -18.677689)
			(xy 255.123415 -18.719226) (xy 255.080547 -18.754901) (xy 255.032941 -18.783955) (xy 254.981612 -18.805767)
			(xy 254.927655 -18.819873) (xy 254.872218 -18.825973) (xy 254.816484 -18.823936) (xy 254.761641 -18.813806)
			(xy 254.708857 -18.795799) (xy 254.659257 -18.770298) (xy 254.613899 -18.737847) (xy 254.57375 -18.699138)
			(xy 254.539664 -18.654995) (xy 254.512368 -18.60636) (xy 254.492445 -18.554269) (xy 254.480319 -18.499832)
			(xy 254.476248 -18.44421) (xy 217.139774 -18.44421) (xy 217.139265 -18.472096) (xy 217.131145 -18.527272)
			(xy 217.115077 -18.580679) (xy 217.091405 -18.631176) (xy 217.060632 -18.677689) (xy 217.023415 -18.719226)
			(xy 216.980547 -18.754901) (xy 216.932941 -18.783955) (xy 216.881612 -18.805767) (xy 216.827655 -18.819873)
			(xy 216.772218 -18.825973) (xy 216.716484 -18.823936) (xy 216.661641 -18.813806) (xy 216.608857 -18.795799)
			(xy 216.559257 -18.770298) (xy 216.513899 -18.737847) (xy 216.47375 -18.699138) (xy 216.439664 -18.654995)
			(xy 216.412368 -18.60636) (xy 216.392445 -18.554269) (xy 216.380319 -18.499832) (xy 216.376248 -18.44421)
			(xy 191.139826 -18.44421) (xy 191.139317 -18.472096) (xy 191.131197 -18.527272) (xy 191.115129 -18.580679)
			(xy 191.091457 -18.631176) (xy 191.060684 -18.677689) (xy 191.023467 -18.719226) (xy 190.980599 -18.754901)
			(xy 190.932993 -18.783955) (xy 190.881664 -18.805767) (xy 190.827707 -18.819873) (xy 190.77227 -18.825973)
			(xy 190.716536 -18.823936) (xy 190.661693 -18.813806) (xy 190.608909 -18.795799) (xy 190.559309 -18.770298)
			(xy 190.513951 -18.737847) (xy 190.473802 -18.699138) (xy 190.439716 -18.654995) (xy 190.41242 -18.60636)
			(xy 190.392497 -18.554269) (xy 190.380371 -18.499832) (xy 190.3763 -18.44421) (xy 165.139878 -18.44421)
			(xy 165.139369 -18.472096) (xy 165.131249 -18.527272) (xy 165.115181 -18.580679) (xy 165.091509 -18.631176)
			(xy 165.060736 -18.677689) (xy 165.023519 -18.719226) (xy 164.980651 -18.754901) (xy 164.933045 -18.783955)
			(xy 164.881716 -18.805767) (xy 164.827759 -18.819873) (xy 164.772322 -18.825973) (xy 164.716588 -18.823936)
			(xy 164.661745 -18.813806) (xy 164.608961 -18.795799) (xy 164.559361 -18.770298) (xy 164.514003 -18.737847)
			(xy 164.473854 -18.699138) (xy 164.439768 -18.654995) (xy 164.412472 -18.60636) (xy 164.392549 -18.554269)
			(xy 164.380423 -18.499832) (xy 164.376352 -18.44421) (xy 139.13993 -18.44421) (xy 139.139421 -18.472096)
			(xy 139.131301 -18.527272) (xy 139.115233 -18.580679) (xy 139.091561 -18.631176) (xy 139.060788 -18.677689)
			(xy 139.023571 -18.719226) (xy 138.980703 -18.754901) (xy 138.933097 -18.783955) (xy 138.881768 -18.805767)
			(xy 138.827811 -18.819873) (xy 138.772374 -18.825973) (xy 138.71664 -18.823936) (xy 138.661797 -18.813806)
			(xy 138.609013 -18.795799) (xy 138.559413 -18.770298) (xy 138.514055 -18.737847) (xy 138.473906 -18.699138)
			(xy 138.43982 -18.654995) (xy 138.412524 -18.60636) (xy 138.392601 -18.554269) (xy 138.380475 -18.499832)
			(xy 138.376404 -18.44421) (xy 75.039728 -18.44421) (xy 75.039219 -18.472096) (xy 75.031099 -18.527272)
			(xy 75.015031 -18.580679) (xy 74.991359 -18.631176) (xy 74.960586 -18.677689) (xy 74.923369 -18.719226)
			(xy 74.880501 -18.754901) (xy 74.832895 -18.783955) (xy 74.781566 -18.805767) (xy 74.727609 -18.819873)
			(xy 74.672172 -18.825973) (xy 74.616438 -18.823936) (xy 74.561595 -18.813806) (xy 74.508811 -18.795799)
			(xy 74.459211 -18.770298) (xy 74.413853 -18.737847) (xy 74.373704 -18.699138) (xy 74.339618 -18.654995)
			(xy 74.312322 -18.60636) (xy 74.292399 -18.554269) (xy 74.280273 -18.499832) (xy 74.276202 -18.44421)
			(xy 49.03978 -18.44421) (xy 49.039271 -18.472096) (xy 49.031151 -18.527272) (xy 49.015083 -18.580679)
			(xy 48.991411 -18.631176) (xy 48.960638 -18.677689) (xy 48.923421 -18.719226) (xy 48.880553 -18.754901)
			(xy 48.832947 -18.783955) (xy 48.781618 -18.805767) (xy 48.727661 -18.819873) (xy 48.672224 -18.825973)
			(xy 48.61649 -18.823936) (xy 48.561647 -18.813806) (xy 48.508863 -18.795799) (xy 48.459263 -18.770298)
			(xy 48.413905 -18.737847) (xy 48.373756 -18.699138) (xy 48.33967 -18.654995) (xy 48.312374 -18.60636)
			(xy 48.292451 -18.554269) (xy 48.280325 -18.499832) (xy 48.276254 -18.44421) (xy 1.499923 -18.44421)
			(xy 1.49987 -18.44548) (xy 1.49987 -20.24888) (xy 2.414776 -20.24888) (xy 2.418847 -20.193258) (xy 2.430973 -20.138821)
			(xy 2.450896 -20.08673) (xy 2.478192 -20.038095) (xy 2.512278 -19.993952) (xy 2.552427 -19.955243)
			(xy 2.597785 -19.922792) (xy 2.647385 -19.897291) (xy 2.700169 -19.879284) (xy 2.755012 -19.869154)
			(xy 2.810746 -19.867117) (xy 2.866183 -19.873217) (xy 2.92014 -19.887323) (xy 2.971469 -19.909135)
			(xy 3.019075 -19.938189) (xy 3.061943 -19.973864) (xy 3.09916 -20.015401) (xy 3.129933 -20.061914)
			(xy 3.153605 -20.112411) (xy 3.169673 -20.165818) (xy 3.177793 -20.220994) (xy 3.178302 -20.24888)
			(xy 3.177793 -20.276766) (xy 3.169673 -20.331942) (xy 3.153605 -20.385349) (xy 3.129933 -20.435846)
			(xy 3.09916 -20.482359) (xy 3.061943 -20.523896) (xy 3.019075 -20.559571) (xy 2.971469 -20.588625)
			(xy 2.92014 -20.610437) (xy 2.866183 -20.624543) (xy 2.810746 -20.630643) (xy 2.755012 -20.628606)
			(xy 2.700169 -20.618476) (xy 2.647385 -20.600469) (xy 2.597785 -20.574968) (xy 2.552427 -20.542517)
			(xy 2.512278 -20.503808) (xy 2.478192 -20.459665) (xy 2.450896 -20.41103) (xy 2.430973 -20.358939)
			(xy 2.418847 -20.304502) (xy 2.414776 -20.24888) (xy 1.49987 -20.24888) (xy 1.49987 -20.72005) (xy 5.185422 -20.72005)
			(xy 5.189392 -20.589916) (xy 5.201288 -20.460266) (xy 5.221067 -20.331583) (xy 5.248653 -20.204344)
			(xy 5.283946 -20.079025) (xy 5.326812 -19.956089) (xy 5.377094 -19.835996) (xy 5.434603 -19.719192)
			(xy 5.499127 -19.60611) (xy 5.570424 -19.497173) (xy 5.648229 -19.392785) (xy 5.732254 -19.293334)
			(xy 5.822186 -19.199191) (xy 5.91769 -19.110706) (xy 6.01841 -19.028207) (xy 6.123972 -18.952002)
			(xy 6.233984 -18.882375) (xy 6.348036 -18.819584) (xy 6.465704 -18.763862) (xy 6.58655 -18.715418)
			(xy 6.710125 -18.674431) (xy 6.835968 -18.641054) (xy 6.963613 -18.615411) (xy 7.092583 -18.597597)
			(xy 7.222399 -18.587679) (xy 7.352578 -18.585694) (xy 7.482637 -18.591648) (xy 7.61209 -18.605521)
			(xy 7.740457 -18.627259) (xy 7.86726 -18.656783) (xy 7.992027 -18.693982) (xy 8.114294 -18.738718)
			(xy 8.233607 -18.790826) (xy 8.34952 -18.850109) (xy 8.461605 -18.91635) (xy 8.569442 -18.9893) (xy 8.672631 -19.068688)
			(xy 8.770789 -19.15422) (xy 8.86355 -19.245577) (xy 8.950569 -19.342419) (xy 9.031522 -19.444386)
			(xy 9.106108 -19.551098) (xy 9.174049 -19.662159) (xy 9.235094 -19.777155) (xy 9.289015 -19.895659)
			(xy 9.33561 -20.01723) (xy 9.374708 -20.141415) (xy 9.406162 -20.267753) (xy 9.429856 -20.395774)
			(xy 9.4457 -20.525) (xy 9.453638 -20.654953) (xy 9.454134 -20.72005) (xy 9.453638 -20.785147) (xy 9.4457 -20.9151)
			(xy 9.429856 -21.044326) (xy 9.406162 -21.172347) (xy 9.374708 -21.298685) (xy 9.33561 -21.42287)
			(xy 9.289015 -21.544441) (xy 9.245979 -21.639022) (xy 16.073882 -21.639022) (xy 16.074424 -21.610284)
			(xy 16.083043 -21.553458) (xy 16.100089 -21.498567) (xy 16.125176 -21.446855) (xy 16.157737 -21.399492)
			(xy 16.177006 -21.378164) (xy 16.18361 -21.371306) (xy 16.190722 -21.353272) (xy 16.190722 -21.264372)
			(xy 16.18361 -21.246338) (xy 16.177006 -21.23948) (xy 16.157758 -21.218134) (xy 16.125193 -21.170774)
			(xy 16.100102 -21.119065) (xy 16.083051 -21.064178) (xy 16.074427 -21.007354) (xy 16.074424 -20.949879)
			(xy 16.083044 -20.893053) (xy 16.10009 -20.838164) (xy 16.125177 -20.786454) (xy 16.157738 -20.739091)
			(xy 16.177006 -20.717764) (xy 16.18361 -20.710906) (xy 16.190722 -20.692872) (xy 16.190722 -20.603972)
			(xy 16.18361 -20.585938) (xy 16.177006 -20.57908) (xy 16.157758 -20.557734) (xy 16.125193 -20.510374)
			(xy 16.100102 -20.458665) (xy 16.083051 -20.403778) (xy 16.074427 -20.346954) (xy 16.074424 -20.289479)
			(xy 16.083044 -20.232653) (xy 16.10009 -20.177764) (xy 16.125177 -20.126054) (xy 16.157738 -20.078691)
			(xy 16.177006 -20.057364) (xy 16.18361 -20.050506) (xy 16.190722 -20.032472) (xy 16.190722 -19.943572)
			(xy 16.18361 -19.925538) (xy 16.177006 -19.91868) (xy 16.157758 -19.897334) (xy 16.125193 -19.849974)
			(xy 16.100102 -19.798265) (xy 16.083051 -19.743378) (xy 16.074427 -19.686554) (xy 16.074424 -19.629079)
			(xy 16.083044 -19.572253) (xy 16.10009 -19.517364) (xy 16.125177 -19.465654) (xy 16.157738 -19.418291)
			(xy 16.177006 -19.396964) (xy 16.18361 -19.390106) (xy 16.190722 -19.372072) (xy 16.190722 -19.283172)
			(xy 16.18361 -19.265138) (xy 16.177006 -19.25828) (xy 16.157757 -19.236934) (xy 16.125186 -19.189578)
			(xy 16.100088 -19.137872) (xy 16.083032 -19.082985) (xy 16.074405 -19.02616) (xy 16.073882 -18.997422)
			(xy 16.074368 -18.970171) (xy 16.082124 -18.916223) (xy 16.097479 -18.863928) (xy 16.120121 -18.814351)
			(xy 16.149587 -18.768501) (xy 16.185278 -18.72731) (xy 16.226469 -18.691619) (xy 16.272319 -18.662153)
			(xy 16.321896 -18.639511) (xy 16.374191 -18.624156) (xy 16.428139 -18.6164) (xy 16.482641 -18.6164)
			(xy 16.536589 -18.624156) (xy 16.588884 -18.639511) (xy 16.638461 -18.662153) (xy 16.684311 -18.691619)
			(xy 16.725502 -18.72731) (xy 16.761193 -18.768501) (xy 16.790659 -18.814351) (xy 16.813301 -18.863928)
			(xy 16.828656 -18.916223) (xy 16.836412 -18.970171) (xy 16.836898 -18.997422) (xy 16.836388 -19.026161)
			(xy 16.827762 -19.082989) (xy 16.810709 -19.13788) (xy 16.785614 -19.189592) (xy 16.753046 -19.236954)
			(xy 16.733774 -19.25828) (xy 16.72717 -19.265138) (xy 16.720058 -19.283172) (xy 16.720058 -19.372072)
			(xy 16.72717 -19.390106) (xy 16.733774 -19.396964) (xy 16.753067 -19.418272) (xy 16.785631 -19.465637)
			(xy 16.810722 -19.517352) (xy 16.82777 -19.572246) (xy 16.836391 -19.629076) (xy 16.836389 -19.686556)
			(xy 16.827763 -19.743385) (xy 16.81071 -19.798278) (xy 16.785615 -19.84999) (xy 16.753047 -19.897353)
			(xy 16.733774 -19.91868) (xy 16.72717 -19.925538) (xy 16.720058 -19.943572) (xy 16.720058 -20.032472)
			(xy 16.72717 -20.050506) (xy 16.733774 -20.057364) (xy 16.753067 -20.078672) (xy 16.785631 -20.126037)
			(xy 16.810722 -20.177752) (xy 16.82777 -20.232646) (xy 16.836391 -20.289476) (xy 16.836389 -20.346956)
			(xy 16.827763 -20.403785) (xy 16.81071 -20.458678) (xy 16.785615 -20.51039) (xy 16.753047 -20.557753)
			(xy 16.733774 -20.57908) (xy 16.72717 -20.585938) (xy 16.720058 -20.603972) (xy 16.720058 -20.692872)
			(xy 16.72717 -20.710906) (xy 16.733774 -20.717764) (xy 16.735844 -20.72005) (xy 31.18537 -20.72005)
			(xy 31.18934 -20.589916) (xy 31.201236 -20.460266) (xy 31.221015 -20.331583) (xy 31.248601 -20.204344)
			(xy 31.283894 -20.079025) (xy 31.32676 -19.956089) (xy 31.377042 -19.835996) (xy 31.434551 -19.719192)
			(xy 31.499075 -19.60611) (xy 31.570372 -19.497173) (xy 31.648177 -19.392785) (xy 31.732202 -19.293334)
			(xy 31.822134 -19.199191) (xy 31.917638 -19.110706) (xy 32.018358 -19.028207) (xy 32.12392 -18.952002)
			(xy 32.233932 -18.882375) (xy 32.347984 -18.819584) (xy 32.465652 -18.763862) (xy 32.586498 -18.715418)
			(xy 32.710073 -18.674431) (xy 32.835916 -18.641054) (xy 32.963561 -18.615411) (xy 33.092531 -18.597597)
			(xy 33.222347 -18.587679) (xy 33.352526 -18.585694) (xy 33.482585 -18.591648) (xy 33.612038 -18.605521)
			(xy 33.740405 -18.627259) (xy 33.867208 -18.656783) (xy 33.991975 -18.693982) (xy 34.114242 -18.738718)
			(xy 34.233555 -18.790826) (xy 34.349468 -18.850109) (xy 34.461553 -18.91635) (xy 34.56939 -18.9893)
			(xy 34.672579 -19.068688) (xy 34.770737 -19.15422) (xy 34.863498 -19.245577) (xy 34.950517 -19.342419)
			(xy 35.03147 -19.444386) (xy 35.106056 -19.551098) (xy 35.173997 -19.662159) (xy 35.235042 -19.777155)
			(xy 35.288963 -19.895659) (xy 35.335558 -20.01723) (xy 35.374656 -20.141415) (xy 35.40611 -20.267753)
			(xy 35.429804 -20.395774) (xy 35.445648 -20.525) (xy 35.453586 -20.654953) (xy 35.454082 -20.72005)
			(xy 35.453586 -20.785147) (xy 35.445648 -20.9151) (xy 35.429804 -21.044326) (xy 35.40611 -21.172347)
			(xy 35.374656 -21.298685) (xy 35.335558 -21.42287) (xy 35.288963 -21.544441) (xy 35.245927 -21.639022)
			(xy 42.07383 -21.639022) (xy 42.074386 -21.610285) (xy 42.083003 -21.553459) (xy 42.100047 -21.49857)
			(xy 42.125131 -21.446858) (xy 42.157688 -21.399493) (xy 42.176954 -21.378164) (xy 42.183558 -21.371306)
			(xy 42.19067 -21.353272) (xy 42.19067 -21.264372) (xy 42.183558 -21.246338) (xy 42.176954 -21.23948)
			(xy 42.157704 -21.218135) (xy 42.125135 -21.170777) (xy 42.10004 -21.119068) (xy 42.082987 -21.06418)
			(xy 42.074362 -21.007354) (xy 42.07436 -20.949878) (xy 42.08298 -20.893052) (xy 42.100029 -20.838162)
			(xy 42.125119 -20.786451) (xy 42.157683 -20.73909) (xy 42.176954 -20.717764) (xy 42.183558 -20.710906)
			(xy 42.19067 -20.692872) (xy 42.19067 -20.603972) (xy 42.183558 -20.585938) (xy 42.176954 -20.57908)
			(xy 42.157704 -20.557735) (xy 42.125135 -20.510377) (xy 42.10004 -20.458668) (xy 42.082987 -20.40378)
			(xy 42.074362 -20.346954) (xy 42.07436 -20.289478) (xy 42.08298 -20.232652) (xy 42.100029 -20.177762)
			(xy 42.125119 -20.126051) (xy 42.157683 -20.07869) (xy 42.176954 -20.057364) (xy 42.183558 -20.050506)
			(xy 42.19067 -20.032472) (xy 42.19067 -19.943572) (xy 42.183558 -19.925538) (xy 42.176954 -19.91868)
			(xy 42.157704 -19.897335) (xy 42.125135 -19.849977) (xy 42.10004 -19.798268) (xy 42.082987 -19.74338)
			(xy 42.074362 -19.686554) (xy 42.07436 -19.629078) (xy 42.08298 -19.572252) (xy 42.100029 -19.517362)
			(xy 42.125119 -19.465651) (xy 42.157683 -19.41829) (xy 42.176954 -19.396964) (xy 42.183558 -19.390106)
			(xy 42.19067 -19.372072) (xy 42.19067 -19.283172) (xy 42.183558 -19.265138) (xy 42.176954 -19.25828)
			(xy 42.157696 -19.236942) (xy 42.125128 -19.189583) (xy 42.100032 -19.137874) (xy 42.082979 -19.082986)
			(xy 42.074353 -19.02616) (xy 42.07383 -18.997422) (xy 42.074316 -18.970171) (xy 42.082072 -18.916223)
			(xy 42.097427 -18.863928) (xy 42.120069 -18.814351) (xy 42.149535 -18.768501) (xy 42.185226 -18.72731)
			(xy 42.226417 -18.691619) (xy 42.272267 -18.662153) (xy 42.321844 -18.639511) (xy 42.374139 -18.624156)
			(xy 42.428087 -18.6164) (xy 42.482589 -18.6164) (xy 42.536537 -18.624156) (xy 42.588832 -18.639511)
			(xy 42.638409 -18.662153) (xy 42.684259 -18.691619) (xy 42.72545 -18.72731) (xy 42.761141 -18.768501)
			(xy 42.790607 -18.814351) (xy 42.813249 -18.863928) (xy 42.828604 -18.916223) (xy 42.83636 -18.970171)
			(xy 42.836846 -18.997422) (xy 42.836323 -19.026161) (xy 42.827699 -19.082988) (xy 42.810648 -19.137878)
			(xy 42.785556 -19.18959) (xy 42.752992 -19.236953) (xy 42.733722 -19.25828) (xy 42.727118 -19.265138)
			(xy 42.720006 -19.283172) (xy 42.720006 -19.372072) (xy 42.727118 -19.390106) (xy 42.733722 -19.396964)
			(xy 42.753013 -19.418273) (xy 42.776952 -19.453098) (xy 48.276254 -19.453098) (xy 48.280325 -19.397476)
			(xy 48.292451 -19.343039) (xy 48.312374 -19.290948) (xy 48.33967 -19.242313) (xy 48.373756 -19.19817)
			(xy 48.413905 -19.159461) (xy 48.459263 -19.12701) (xy 48.508863 -19.101509) (xy 48.561647 -19.083502)
			(xy 48.61649 -19.073372) (xy 48.672224 -19.071335) (xy 48.727661 -19.077435) (xy 48.781618 -19.091541)
			(xy 48.832947 -19.113353) (xy 48.880553 -19.142407) (xy 48.923421 -19.178082) (xy 48.960638 -19.219619)
			(xy 48.991411 -19.266132) (xy 49.015083 -19.316629) (xy 49.031151 -19.370036) (xy 49.039271 -19.425212)
			(xy 49.03978 -19.453098) (xy 49.039271 -19.480984) (xy 49.031151 -19.53616) (xy 49.015083 -19.589567)
			(xy 48.991411 -19.640064) (xy 48.960638 -19.686577) (xy 48.923421 -19.728114) (xy 48.880553 -19.763789)
			(xy 48.832947 -19.792843) (xy 48.781618 -19.814655) (xy 48.727661 -19.828761) (xy 48.672224 -19.834861)
			(xy 48.61649 -19.832824) (xy 48.561647 -19.822694) (xy 48.508863 -19.804687) (xy 48.459263 -19.779186)
			(xy 48.413905 -19.746735) (xy 48.373756 -19.708026) (xy 48.33967 -19.663883) (xy 48.312374 -19.615248)
			(xy 48.292451 -19.563157) (xy 48.280325 -19.50872) (xy 48.276254 -19.453098) (xy 42.776952 -19.453098)
			(xy 42.785573 -19.46564) (xy 42.810661 -19.517355) (xy 42.827707 -19.572248) (xy 42.836326 -19.629077)
			(xy 42.836324 -19.686555) (xy 42.8277 -19.743384) (xy 42.810649 -19.798275) (xy 42.785557 -19.849988)
			(xy 42.752992 -19.897352) (xy 42.733722 -19.91868) (xy 42.727118 -19.925538) (xy 42.720006 -19.943572)
			(xy 42.720006 -20.032472) (xy 42.727118 -20.050506) (xy 42.733722 -20.057364) (xy 42.753013 -20.078673)
			(xy 42.785573 -20.12604) (xy 42.810661 -20.177755) (xy 42.827707 -20.232648) (xy 42.836326 -20.289477)
			(xy 42.836324 -20.346955) (xy 42.8277 -20.403784) (xy 42.810649 -20.458675) (xy 42.806331 -20.467574)
			(xy 50.287426 -20.467574) (xy 50.291497 -20.411952) (xy 50.303623 -20.357515) (xy 50.323546 -20.305424)
			(xy 50.350842 -20.256789) (xy 50.384928 -20.212646) (xy 50.425077 -20.173937) (xy 50.470435 -20.141486)
			(xy 50.520035 -20.115985) (xy 50.572819 -20.097978) (xy 50.627662 -20.087848) (xy 50.683396 -20.085811)
			(xy 50.738833 -20.091911) (xy 50.79279 -20.106017) (xy 50.844119 -20.127829) (xy 50.891725 -20.156883)
			(xy 50.934593 -20.192558) (xy 50.97181 -20.234095) (xy 51.002583 -20.280608) (xy 51.026255 -20.331105)
			(xy 51.042323 -20.384512) (xy 51.050443 -20.439688) (xy 51.050952 -20.467574) (xy 51.050443 -20.49546)
			(xy 51.042323 -20.550636) (xy 51.026255 -20.604043) (xy 51.002583 -20.65454) (xy 50.97181 -20.701053)
			(xy 50.954789 -20.72005) (xy 57.185318 -20.72005) (xy 57.189288 -20.589916) (xy 57.201184 -20.460266)
			(xy 57.220963 -20.331583) (xy 57.248549 -20.204344) (xy 57.283842 -20.079025) (xy 57.326708 -19.956089)
			(xy 57.37699 -19.835996) (xy 57.434499 -19.719192) (xy 57.499023 -19.60611) (xy 57.57032 -19.497173)
			(xy 57.648125 -19.392785) (xy 57.73215 -19.293334) (xy 57.822082 -19.199191) (xy 57.917586 -19.110706)
			(xy 58.018306 -19.028207) (xy 58.123868 -18.952002) (xy 58.23388 -18.882375) (xy 58.347932 -18.819584)
			(xy 58.4656 -18.763862) (xy 58.586446 -18.715418) (xy 58.710021 -18.674431) (xy 58.835864 -18.641054)
			(xy 58.963509 -18.615411) (xy 59.092479 -18.597597) (xy 59.222295 -18.587679) (xy 59.352474 -18.585694)
			(xy 59.482533 -18.591648) (xy 59.611986 -18.605521) (xy 59.740353 -18.627259) (xy 59.867156 -18.656783)
			(xy 59.991923 -18.693982) (xy 60.11419 -18.738718) (xy 60.233503 -18.790826) (xy 60.349416 -18.850109)
			(xy 60.461501 -18.91635) (xy 60.569338 -18.9893) (xy 60.672527 -19.068688) (xy 60.770685 -19.15422)
			(xy 60.863446 -19.245577) (xy 60.950465 -19.342419) (xy 61.031418 -19.444386) (xy 61.106004 -19.551098)
			(xy 61.173945 -19.662159) (xy 61.23499 -19.777155) (xy 61.288911 -19.895659) (xy 61.335506 -20.01723)
			(xy 61.374604 -20.141415) (xy 61.406058 -20.267753) (xy 61.429752 -20.395774) (xy 61.445596 -20.525)
			(xy 61.453534 -20.654953) (xy 61.45403 -20.72005) (xy 61.453534 -20.785147) (xy 61.445596 -20.9151)
			(xy 61.429752 -21.044326) (xy 61.406058 -21.172347) (xy 61.374604 -21.298685) (xy 61.335506 -21.42287)
			(xy 61.288911 -21.544441) (xy 61.245875 -21.639022) (xy 68.073778 -21.639022) (xy 68.074321 -21.610284)
			(xy 68.08294 -21.553458) (xy 68.099986 -21.498567) (xy 68.125073 -21.446855) (xy 68.157633 -21.399492)
			(xy 68.176902 -21.378164) (xy 68.183506 -21.371306) (xy 68.190618 -21.353272) (xy 68.190618 -21.264372)
			(xy 68.183506 -21.246338) (xy 68.176902 -21.23948) (xy 68.157654 -21.218134) (xy 68.12509 -21.170774)
			(xy 68.099999 -21.119065) (xy 68.082948 -21.064178) (xy 68.074324 -21.007354) (xy 68.074321 -20.949879)
			(xy 68.082941 -20.893054) (xy 68.099987 -20.838165) (xy 68.125074 -20.786454) (xy 68.157634 -20.739091)
			(xy 68.176902 -20.717764) (xy 68.183506 -20.710906) (xy 68.190618 -20.692872) (xy 68.190618 -20.603972)
			(xy 68.183506 -20.585938) (xy 68.176902 -20.57908) (xy 68.157654 -20.557734) (xy 68.12509 -20.510374)
			(xy 68.099999 -20.458665) (xy 68.082948 -20.403778) (xy 68.074324 -20.346954) (xy 68.074321 -20.289479)
			(xy 68.082941 -20.232654) (xy 68.099987 -20.177765) (xy 68.125074 -20.126054) (xy 68.157634 -20.078691)
			(xy 68.176902 -20.057364) (xy 68.183506 -20.050506) (xy 68.190618 -20.032472) (xy 68.190618 -19.943572)
			(xy 68.183506 -19.925538) (xy 68.176902 -19.91868) (xy 68.157654 -19.897334) (xy 68.12509 -19.849974)
			(xy 68.099999 -19.798265) (xy 68.082948 -19.743378) (xy 68.074324 -19.686554) (xy 68.074321 -19.629079)
			(xy 68.082941 -19.572254) (xy 68.099987 -19.517365) (xy 68.125074 -19.465654) (xy 68.157634 -19.418291)
			(xy 68.176902 -19.396964) (xy 68.183506 -19.390106) (xy 68.190618 -19.372072) (xy 68.190618 -19.283172)
			(xy 68.183506 -19.265138) (xy 68.176902 -19.25828) (xy 68.157653 -19.236934) (xy 68.125081 -19.189578)
			(xy 68.099984 -19.137872) (xy 68.082928 -19.082985) (xy 68.074301 -19.02616) (xy 68.073778 -18.997422)
			(xy 68.074264 -18.970171) (xy 68.08202 -18.916223) (xy 68.097375 -18.863928) (xy 68.120017 -18.814351)
			(xy 68.149483 -18.768501) (xy 68.185174 -18.72731) (xy 68.226365 -18.691619) (xy 68.272215 -18.662153)
			(xy 68.321792 -18.639511) (xy 68.374087 -18.624156) (xy 68.428035 -18.6164) (xy 68.482537 -18.6164)
			(xy 68.536485 -18.624156) (xy 68.58878 -18.639511) (xy 68.638357 -18.662153) (xy 68.684207 -18.691619)
			(xy 68.725398 -18.72731) (xy 68.761089 -18.768501) (xy 68.790555 -18.814351) (xy 68.813197 -18.863928)
			(xy 68.828552 -18.916223) (xy 68.836308 -18.970171) (xy 68.836794 -18.997422) (xy 68.836285 -19.026161)
			(xy 68.827659 -19.08299) (xy 68.810606 -19.137881) (xy 68.785511 -19.189592) (xy 68.752942 -19.236954)
			(xy 68.73367 -19.25828) (xy 68.727066 -19.265138) (xy 68.719954 -19.283172) (xy 68.719954 -19.372072)
			(xy 68.727066 -19.390106) (xy 68.73367 -19.396964) (xy 68.752963 -19.418272) (xy 68.776907 -19.453098)
			(xy 74.276202 -19.453098) (xy 74.280273 -19.397476) (xy 74.292399 -19.343039) (xy 74.312322 -19.290948)
			(xy 74.339618 -19.242313) (xy 74.373704 -19.19817) (xy 74.413853 -19.159461) (xy 74.459211 -19.12701)
			(xy 74.508811 -19.101509) (xy 74.561595 -19.083502) (xy 74.616438 -19.073372) (xy 74.672172 -19.071335)
			(xy 74.727609 -19.077435) (xy 74.781566 -19.091541) (xy 74.832895 -19.113353) (xy 74.880501 -19.142407)
			(xy 74.923369 -19.178082) (xy 74.960586 -19.219619) (xy 74.991359 -19.266132) (xy 75.015031 -19.316629)
			(xy 75.031099 -19.370036) (xy 75.039219 -19.425212) (xy 75.039728 -19.453098) (xy 75.039219 -19.480984)
			(xy 75.031099 -19.53616) (xy 75.015031 -19.589567) (xy 74.991359 -19.640064) (xy 74.960586 -19.686577)
			(xy 74.923369 -19.728114) (xy 74.880501 -19.763789) (xy 74.832895 -19.792843) (xy 74.781566 -19.814655)
			(xy 74.727609 -19.828761) (xy 74.672172 -19.834861) (xy 74.616438 -19.832824) (xy 74.561595 -19.822694)
			(xy 74.508811 -19.804687) (xy 74.459211 -19.779186) (xy 74.413853 -19.746735) (xy 74.373704 -19.708026)
			(xy 74.339618 -19.663883) (xy 74.312322 -19.615248) (xy 74.292399 -19.563157) (xy 74.280273 -19.50872)
			(xy 74.276202 -19.453098) (xy 68.776907 -19.453098) (xy 68.785528 -19.465637) (xy 68.810619 -19.517352)
			(xy 68.827667 -19.572246) (xy 68.836288 -19.629076) (xy 68.836286 -19.686556) (xy 68.82766 -19.743386)
			(xy 68.810607 -19.798278) (xy 68.785512 -19.849991) (xy 68.752943 -19.897353) (xy 68.73367 -19.91868)
			(xy 68.727066 -19.925538) (xy 68.719954 -19.943572) (xy 68.719954 -20.032472) (xy 68.727066 -20.050506)
			(xy 68.73367 -20.057364) (xy 68.752963 -20.078672) (xy 68.785528 -20.126037) (xy 68.810619 -20.177752)
			(xy 68.827667 -20.232646) (xy 68.836288 -20.289476) (xy 68.836286 -20.346956) (xy 68.82766 -20.403786)
			(xy 68.810607 -20.458678) (xy 68.80629 -20.467574) (xy 76.287374 -20.467574) (xy 76.291445 -20.411952)
			(xy 76.303571 -20.357515) (xy 76.323494 -20.305424) (xy 76.35079 -20.256789) (xy 76.384876 -20.212646)
			(xy 76.425025 -20.173937) (xy 76.470383 -20.141486) (xy 76.519983 -20.115985) (xy 76.572767 -20.097978)
			(xy 76.62761 -20.087848) (xy 76.683344 -20.085811) (xy 76.738781 -20.091911) (xy 76.792738 -20.106017)
			(xy 76.844067 -20.127829) (xy 76.891673 -20.156883) (xy 76.934541 -20.192558) (xy 76.971758 -20.234095)
			(xy 77.002531 -20.280608) (xy 77.026203 -20.331105) (xy 77.042271 -20.384512) (xy 77.050391 -20.439688)
			(xy 77.0509 -20.467574) (xy 77.050391 -20.49546) (xy 77.042271 -20.550636) (xy 77.026203 -20.604043)
			(xy 77.002531 -20.65454) (xy 76.971758 -20.701053) (xy 76.954737 -20.72005) (xy 83.18552 -20.72005)
			(xy 83.18949 -20.589916) (xy 83.201386 -20.460266) (xy 83.221165 -20.331583) (xy 83.248751 -20.204344)
			(xy 83.284044 -20.079025) (xy 83.32691 -19.956089) (xy 83.377192 -19.835996) (xy 83.434701 -19.719192)
			(xy 83.499225 -19.60611) (xy 83.570522 -19.497173) (xy 83.648327 -19.392785) (xy 83.732352 -19.293334)
			(xy 83.822284 -19.199191) (xy 83.917788 -19.110706) (xy 84.018508 -19.028207) (xy 84.12407 -18.952002)
			(xy 84.234082 -18.882375) (xy 84.348134 -18.819584) (xy 84.465802 -18.763862) (xy 84.586648 -18.715418)
			(xy 84.710223 -18.674431) (xy 84.836066 -18.641054) (xy 84.963711 -18.615411) (xy 85.092681 -18.597597)
			(xy 85.222497 -18.587679) (xy 85.352676 -18.585694) (xy 85.482735 -18.591648) (xy 85.612188 -18.605521)
			(xy 85.740555 -18.627259) (xy 85.867358 -18.656783) (xy 85.992125 -18.693982) (xy 86.114392 -18.738718)
			(xy 86.233705 -18.790826) (xy 86.349618 -18.850109) (xy 86.461703 -18.91635) (xy 86.56954 -18.9893)
			(xy 86.672729 -19.068688) (xy 86.770887 -19.15422) (xy 86.863648 -19.245577) (xy 86.950667 -19.342419)
			(xy 87.03162 -19.444386) (xy 87.106206 -19.551098) (xy 87.174147 -19.662159) (xy 87.235192 -19.777155)
			(xy 87.289113 -19.895659) (xy 87.335708 -20.01723) (xy 87.374806 -20.141415) (xy 87.40626 -20.267753)
			(xy 87.429954 -20.395774) (xy 87.445798 -20.525) (xy 87.453736 -20.654953) (xy 87.454232 -20.72005)
			(xy 87.453736 -20.785147) (xy 87.445798 -20.9151) (xy 87.429954 -21.044326) (xy 87.40626 -21.172347)
			(xy 87.374806 -21.298685) (xy 87.335708 -21.42287) (xy 87.289113 -21.544441) (xy 87.246077 -21.639022)
			(xy 94.073726 -21.639022) (xy 94.074283 -21.610285) (xy 94.0829 -21.55346) (xy 94.099944 -21.49857)
			(xy 94.125027 -21.446858) (xy 94.157584 -21.399493) (xy 94.17685 -21.378164) (xy 94.183454 -21.371306)
			(xy 94.190566 -21.353272) (xy 94.190566 -21.264372) (xy 94.183454 -21.246338) (xy 94.17685 -21.23948)
			(xy 94.1576 -21.218135) (xy 94.125032 -21.170776) (xy 94.099937 -21.119068) (xy 94.082884 -21.064179)
			(xy 94.074259 -21.007354) (xy 94.074257 -20.949878) (xy 94.082877 -20.893052) (xy 94.099925 -20.838162)
			(xy 94.125016 -20.786451) (xy 94.15758 -20.73909) (xy 94.17685 -20.717764) (xy 94.183454 -20.710906)
			(xy 94.190566 -20.692872) (xy 94.190566 -20.603972) (xy 94.183454 -20.585938) (xy 94.17685 -20.57908)
			(xy 94.1576 -20.557735) (xy 94.125032 -20.510376) (xy 94.099937 -20.458668) (xy 94.082884 -20.403779)
			(xy 94.074259 -20.346954) (xy 94.074257 -20.289478) (xy 94.082877 -20.232652) (xy 94.099925 -20.177762)
			(xy 94.125016 -20.126051) (xy 94.15758 -20.07869) (xy 94.17685 -20.057364) (xy 94.183454 -20.050506)
			(xy 94.190566 -20.032472) (xy 94.190566 -19.943572) (xy 94.183454 -19.925538) (xy 94.17685 -19.91868)
			(xy 94.1576 -19.897335) (xy 94.125032 -19.849976) (xy 94.099937 -19.798268) (xy 94.082884 -19.743379)
			(xy 94.074259 -19.686554) (xy 94.074257 -19.629078) (xy 94.082877 -19.572252) (xy 94.099925 -19.517362)
			(xy 94.125016 -19.465651) (xy 94.15758 -19.41829) (xy 94.17685 -19.396964) (xy 94.183454 -19.390106)
			(xy 94.190566 -19.372072) (xy 94.190566 -19.283172) (xy 94.183454 -19.265138) (xy 94.17685 -19.25828)
			(xy 94.157592 -19.236942) (xy 94.125023 -19.189583) (xy 94.099928 -19.137874) (xy 94.082875 -19.082986)
			(xy 94.074249 -19.02616) (xy 94.073726 -18.997422) (xy 94.074212 -18.970171) (xy 94.081968 -18.916223)
			(xy 94.097323 -18.863928) (xy 94.119965 -18.814351) (xy 94.149431 -18.768501) (xy 94.185122 -18.72731)
			(xy 94.226313 -18.691619) (xy 94.272163 -18.662153) (xy 94.32174 -18.639511) (xy 94.374035 -18.624156)
			(xy 94.427983 -18.6164) (xy 94.482485 -18.6164) (xy 94.536433 -18.624156) (xy 94.588728 -18.639511)
			(xy 94.638305 -18.662153) (xy 94.684155 -18.691619) (xy 94.725346 -18.72731) (xy 94.761037 -18.768501)
			(xy 94.790503 -18.814351) (xy 94.813145 -18.863928) (xy 94.8285 -18.916223) (xy 94.836256 -18.970171)
			(xy 94.836742 -18.997422) (xy 94.83622 -19.026161) (xy 94.827596 -19.082988) (xy 94.810544 -19.137878)
			(xy 94.785453 -19.18959) (xy 94.752888 -19.236953) (xy 94.733618 -19.25828) (xy 94.727014 -19.265138)
			(xy 94.719902 -19.283172) (xy 94.719902 -19.372072) (xy 94.727014 -19.390106) (xy 94.733618 -19.396964)
			(xy 94.752909 -19.418273) (xy 94.78547 -19.46564) (xy 94.810557 -19.517355) (xy 94.827604 -19.572248)
			(xy 94.836223 -19.629077) (xy 94.836221 -19.686555) (xy 94.827597 -19.743384) (xy 94.810545 -19.798275)
			(xy 94.785454 -19.849988) (xy 94.752889 -19.897352) (xy 94.733618 -19.91868) (xy 94.727014 -19.925538)
			(xy 94.719902 -19.943572) (xy 94.719902 -20.032472) (xy 94.727014 -20.050506) (xy 94.733618 -20.057364)
			(xy 94.752909 -20.078673) (xy 94.78547 -20.12604) (xy 94.810557 -20.177755) (xy 94.827604 -20.232648)
			(xy 94.836223 -20.289477) (xy 94.836221 -20.346955) (xy 94.827597 -20.403784) (xy 94.810545 -20.458675)
			(xy 94.785454 -20.510388) (xy 94.752889 -20.557752) (xy 94.733618 -20.57908) (xy 94.727014 -20.585938)
			(xy 94.719902 -20.603972) (xy 94.719902 -20.692872) (xy 94.727014 -20.710906) (xy 94.733618 -20.717764)
			(xy 94.740286 -20.72513) (xy 121.28044 -20.72513) (xy 121.28441 -20.594996) (xy 121.296306 -20.465346)
			(xy 121.316085 -20.336663) (xy 121.343671 -20.209424) (xy 121.378964 -20.084105) (xy 121.42183 -19.961169)
			(xy 121.472112 -19.841076) (xy 121.529621 -19.724272) (xy 121.594145 -19.61119) (xy 121.665442 -19.502253)
			(xy 121.743247 -19.397865) (xy 121.827272 -19.298414) (xy 121.917204 -19.204271) (xy 122.012708 -19.115786)
			(xy 122.113428 -19.033287) (xy 122.21899 -18.957082) (xy 122.329002 -18.887455) (xy 122.443054 -18.824664)
			(xy 122.560722 -18.768942) (xy 122.681568 -18.720498) (xy 122.805143 -18.679511) (xy 122.930986 -18.646134)
			(xy 123.058631 -18.620491) (xy 123.187601 -18.602677) (xy 123.317417 -18.592759) (xy 123.447596 -18.590774)
			(xy 123.577655 -18.596728) (xy 123.707108 -18.610601) (xy 123.835475 -18.632339) (xy 123.962278 -18.661863)
			(xy 124.087045 -18.699062) (xy 124.209312 -18.743798) (xy 124.328625 -18.795906) (xy 124.444538 -18.855189)
			(xy 124.556623 -18.92143) (xy 124.66446 -18.99438) (xy 124.767649 -19.073768) (xy 124.865807 -19.1593)
			(xy 124.958568 -19.250657) (xy 125.045587 -19.347499) (xy 125.12654 -19.449466) (xy 125.201126 -19.556178)
			(xy 125.269067 -19.667239) (xy 125.330112 -19.782235) (xy 125.384033 -19.900739) (xy 125.430628 -20.02231)
			(xy 125.469726 -20.146495) (xy 125.50118 -20.272833) (xy 125.524874 -20.400854) (xy 125.540718 -20.53008)
			(xy 125.548656 -20.660033) (xy 125.549152 -20.72513) (xy 125.548656 -20.790227) (xy 125.540718 -20.92018)
			(xy 125.524874 -21.049406) (xy 125.50118 -21.177427) (xy 125.469726 -21.303765) (xy 125.430628 -21.42795)
			(xy 125.384033 -21.549521) (xy 125.343309 -21.639022) (xy 132.17398 -21.639022) (xy 132.174522 -21.610284)
			(xy 132.183141 -21.553458) (xy 132.200187 -21.498567) (xy 132.225275 -21.446855) (xy 132.257835 -21.399492)
			(xy 132.277104 -21.378164) (xy 132.283708 -21.371306) (xy 132.29082 -21.353272) (xy 132.29082 -21.264372)
			(xy 132.283708 -21.246338) (xy 132.277104 -21.23948) (xy 132.257856 -21.218134) (xy 132.225292 -21.170774)
			(xy 132.2002 -21.119065) (xy 132.183149 -21.064178) (xy 132.174525 -21.007354) (xy 132.174523 -20.949879)
			(xy 132.183142 -20.893054) (xy 132.200188 -20.838165) (xy 132.225275 -20.786454) (xy 132.257836 -20.739091)
			(xy 132.277104 -20.717764) (xy 132.283708 -20.710906) (xy 132.29082 -20.692872) (xy 132.29082 -20.603972)
			(xy 132.283708 -20.585938) (xy 132.277104 -20.57908) (xy 132.257856 -20.557734) (xy 132.225292 -20.510374)
			(xy 132.2002 -20.458665) (xy 132.183149 -20.403778) (xy 132.174525 -20.346954) (xy 132.174523 -20.289479)
			(xy 132.183142 -20.232654) (xy 132.200188 -20.177765) (xy 132.225275 -20.126054) (xy 132.257836 -20.078691)
			(xy 132.277104 -20.057364) (xy 132.283708 -20.050506) (xy 132.29082 -20.032472) (xy 132.29082 -19.943572)
			(xy 132.283708 -19.925538) (xy 132.277104 -19.91868) (xy 132.257856 -19.897334) (xy 132.225292 -19.849974)
			(xy 132.2002 -19.798265) (xy 132.183149 -19.743378) (xy 132.174525 -19.686554) (xy 132.174523 -19.629079)
			(xy 132.183142 -19.572254) (xy 132.200188 -19.517365) (xy 132.225275 -19.465654) (xy 132.257836 -19.418291)
			(xy 132.277104 -19.396964) (xy 132.283708 -19.390106) (xy 132.29082 -19.372072) (xy 132.29082 -19.283172)
			(xy 132.283708 -19.265138) (xy 132.277104 -19.25828) (xy 132.257855 -19.236934) (xy 132.225283 -19.189578)
			(xy 132.200186 -19.137872) (xy 132.18313 -19.082985) (xy 132.174503 -19.02616) (xy 132.17398 -18.997422)
			(xy 132.174466 -18.970171) (xy 132.182222 -18.916223) (xy 132.197577 -18.863928) (xy 132.220219 -18.814351)
			(xy 132.249685 -18.768501) (xy 132.285376 -18.72731) (xy 132.326567 -18.691619) (xy 132.372417 -18.662153)
			(xy 132.421994 -18.639511) (xy 132.474289 -18.624156) (xy 132.528237 -18.6164) (xy 132.582739 -18.6164)
			(xy 132.636687 -18.624156) (xy 132.688982 -18.639511) (xy 132.738559 -18.662153) (xy 132.784409 -18.691619)
			(xy 132.8256 -18.72731) (xy 132.861291 -18.768501) (xy 132.890757 -18.814351) (xy 132.913399 -18.863928)
			(xy 132.928754 -18.916223) (xy 132.93651 -18.970171) (xy 132.936996 -18.997422) (xy 132.936487 -19.026161)
			(xy 132.927861 -19.082989) (xy 132.910807 -19.13788) (xy 132.885713 -19.189592) (xy 132.853144 -19.236954)
			(xy 132.833872 -19.25828) (xy 132.827268 -19.265138) (xy 132.820156 -19.283172) (xy 132.820156 -19.372072)
			(xy 132.827268 -19.390106) (xy 132.833872 -19.396964) (xy 132.853165 -19.418272) (xy 132.877109 -19.453098)
			(xy 138.376404 -19.453098) (xy 138.380475 -19.397476) (xy 138.392601 -19.343039) (xy 138.412524 -19.290948)
			(xy 138.43982 -19.242313) (xy 138.473906 -19.19817) (xy 138.514055 -19.159461) (xy 138.559413 -19.12701)
			(xy 138.609013 -19.101509) (xy 138.661797 -19.083502) (xy 138.71664 -19.073372) (xy 138.772374 -19.071335)
			(xy 138.827811 -19.077435) (xy 138.881768 -19.091541) (xy 138.933097 -19.113353) (xy 138.980703 -19.142407)
			(xy 139.023571 -19.178082) (xy 139.060788 -19.219619) (xy 139.091561 -19.266132) (xy 139.115233 -19.316629)
			(xy 139.131301 -19.370036) (xy 139.139421 -19.425212) (xy 139.13993 -19.453098) (xy 139.139421 -19.480984)
			(xy 139.131301 -19.53616) (xy 139.115233 -19.589567) (xy 139.091561 -19.640064) (xy 139.060788 -19.686577)
			(xy 139.023571 -19.728114) (xy 138.980703 -19.763789) (xy 138.933097 -19.792843) (xy 138.881768 -19.814655)
			(xy 138.827811 -19.828761) (xy 138.772374 -19.834861) (xy 138.71664 -19.832824) (xy 138.661797 -19.822694)
			(xy 138.609013 -19.804687) (xy 138.559413 -19.779186) (xy 138.514055 -19.746735) (xy 138.473906 -19.708026)
			(xy 138.43982 -19.663883) (xy 138.412524 -19.615248) (xy 138.392601 -19.563157) (xy 138.380475 -19.50872)
			(xy 138.376404 -19.453098) (xy 132.877109 -19.453098) (xy 132.88573 -19.465637) (xy 132.91082 -19.517352)
			(xy 132.927869 -19.572246) (xy 132.93649 -19.629076) (xy 132.936487 -19.686556) (xy 132.927862 -19.743385)
			(xy 132.910808 -19.798278) (xy 132.885713 -19.84999) (xy 132.853145 -19.897353) (xy 132.833872 -19.91868)
			(xy 132.827268 -19.925538) (xy 132.820156 -19.943572) (xy 132.820156 -20.032472) (xy 132.827268 -20.050506)
			(xy 132.833872 -20.057364) (xy 132.853165 -20.078672) (xy 132.88573 -20.126037) (xy 132.91082 -20.177752)
			(xy 132.927869 -20.232646) (xy 132.93649 -20.289476) (xy 132.936487 -20.346956) (xy 132.927862 -20.403785)
			(xy 132.910808 -20.458678) (xy 132.906491 -20.467574) (xy 140.387576 -20.467574) (xy 140.391647 -20.411952)
			(xy 140.403773 -20.357515) (xy 140.423696 -20.305424) (xy 140.450992 -20.256789) (xy 140.485078 -20.212646)
			(xy 140.525227 -20.173937) (xy 140.570585 -20.141486) (xy 140.620185 -20.115985) (xy 140.672969 -20.097978)
			(xy 140.727812 -20.087848) (xy 140.783546 -20.085811) (xy 140.838983 -20.091911) (xy 140.89294 -20.106017)
			(xy 140.944269 -20.127829) (xy 140.991875 -20.156883) (xy 141.034743 -20.192558) (xy 141.07196 -20.234095)
			(xy 141.102733 -20.280608) (xy 141.126405 -20.331105) (xy 141.142473 -20.384512) (xy 141.150593 -20.439688)
			(xy 141.151102 -20.467574) (xy 141.150593 -20.49546) (xy 141.142473 -20.550636) (xy 141.126405 -20.604043)
			(xy 141.102733 -20.65454) (xy 141.07196 -20.701053) (xy 141.050615 -20.724876) (xy 147.280388 -20.724876)
			(xy 147.284358 -20.594742) (xy 147.296254 -20.465092) (xy 147.316033 -20.336409) (xy 147.343619 -20.20917)
			(xy 147.378912 -20.083851) (xy 147.421778 -19.960915) (xy 147.47206 -19.840822) (xy 147.529569 -19.724018)
			(xy 147.594093 -19.610936) (xy 147.66539 -19.501999) (xy 147.743195 -19.397611) (xy 147.82722 -19.29816)
			(xy 147.917152 -19.204017) (xy 148.012656 -19.115532) (xy 148.113376 -19.033033) (xy 148.218938 -18.956828)
			(xy 148.32895 -18.887201) (xy 148.443002 -18.82441) (xy 148.56067 -18.768688) (xy 148.681516 -18.720244)
			(xy 148.805091 -18.679257) (xy 148.930934 -18.64588) (xy 149.058579 -18.620237) (xy 149.187549 -18.602423)
			(xy 149.317365 -18.592505) (xy 149.447544 -18.59052) (xy 149.577603 -18.596474) (xy 149.707056 -18.610347)
			(xy 149.835423 -18.632085) (xy 149.962226 -18.661609) (xy 150.086993 -18.698808) (xy 150.20926 -18.743544)
			(xy 150.328573 -18.795652) (xy 150.444486 -18.854935) (xy 150.556571 -18.921176) (xy 150.664408 -18.994126)
			(xy 150.767597 -19.073514) (xy 150.865755 -19.159046) (xy 150.958516 -19.250403) (xy 151.045535 -19.347245)
			(xy 151.126488 -19.449212) (xy 151.201074 -19.555924) (xy 151.269015 -19.666985) (xy 151.33006 -19.781981)
			(xy 151.383981 -19.900485) (xy 151.430576 -20.022056) (xy 151.469674 -20.146241) (xy 151.501128 -20.272579)
			(xy 151.524822 -20.4006) (xy 151.540666 -20.529826) (xy 151.548604 -20.659779) (xy 151.5491 -20.724876)
			(xy 151.548604 -20.789973) (xy 151.540666 -20.919926) (xy 151.524822 -21.049152) (xy 151.501128 -21.177173)
			(xy 151.469674 -21.303511) (xy 151.430576 -21.427696) (xy 151.383981 -21.549267) (xy 151.343141 -21.639022)
			(xy 158.173928 -21.639022) (xy 158.174484 -21.610285) (xy 158.183102 -21.55346) (xy 158.200145 -21.49857)
			(xy 158.225229 -21.446858) (xy 158.257786 -21.399493) (xy 158.277052 -21.378164) (xy 158.283656 -21.371306)
			(xy 158.290768 -21.353272) (xy 158.290768 -21.264372) (xy 158.283656 -21.246338) (xy 158.277052 -21.23948)
			(xy 158.257802 -21.218135) (xy 158.225233 -21.170776) (xy 158.200139 -21.119068) (xy 158.183086 -21.06418)
			(xy 158.17446 -21.007354) (xy 158.174458 -20.949878) (xy 158.183079 -20.893052) (xy 158.200127 -20.838162)
			(xy 158.225217 -20.786451) (xy 158.257782 -20.73909) (xy 158.277052 -20.717764) (xy 158.283656 -20.710906)
			(xy 158.290768 -20.692872) (xy 158.290768 -20.603972) (xy 158.283656 -20.585938) (xy 158.277052 -20.57908)
			(xy 158.257802 -20.557735) (xy 158.225233 -20.510376) (xy 158.200139 -20.458668) (xy 158.183086 -20.40378)
			(xy 158.17446 -20.346954) (xy 158.174458 -20.289478) (xy 158.183079 -20.232652) (xy 158.200127 -20.177762)
			(xy 158.225217 -20.126051) (xy 158.257782 -20.07869) (xy 158.277052 -20.057364) (xy 158.283656 -20.050506)
			(xy 158.290768 -20.032472) (xy 158.290768 -19.943572) (xy 158.283656 -19.925538) (xy 158.277052 -19.91868)
			(xy 158.257802 -19.897335) (xy 158.225233 -19.849976) (xy 158.200139 -19.798268) (xy 158.183086 -19.74338)
			(xy 158.17446 -19.686554) (xy 158.174458 -19.629078) (xy 158.183079 -19.572252) (xy 158.200127 -19.517362)
			(xy 158.225217 -19.465651) (xy 158.257782 -19.41829) (xy 158.277052 -19.396964) (xy 158.283656 -19.390106)
			(xy 158.290768 -19.372072) (xy 158.290768 -19.283172) (xy 158.283656 -19.265138) (xy 158.277052 -19.25828)
			(xy 158.257794 -19.236942) (xy 158.225225 -19.189583) (xy 158.20013 -19.137874) (xy 158.183077 -19.082986)
			(xy 158.174451 -19.02616) (xy 158.173928 -18.997422) (xy 158.174414 -18.970171) (xy 158.18217 -18.916223)
			(xy 158.197525 -18.863928) (xy 158.220167 -18.814351) (xy 158.249633 -18.768501) (xy 158.285324 -18.72731)
			(xy 158.326515 -18.691619) (xy 158.372365 -18.662153) (xy 158.421942 -18.639511) (xy 158.474237 -18.624156)
			(xy 158.528185 -18.6164) (xy 158.582687 -18.6164) (xy 158.636635 -18.624156) (xy 158.68893 -18.639511)
			(xy 158.738507 -18.662153) (xy 158.784357 -18.691619) (xy 158.825548 -18.72731) (xy 158.861239 -18.768501)
			(xy 158.890705 -18.814351) (xy 158.913347 -18.863928) (xy 158.928702 -18.916223) (xy 158.936458 -18.970171)
			(xy 158.936944 -18.997422) (xy 158.936422 -19.026161) (xy 158.927797 -19.082988) (xy 158.910746 -19.137878)
			(xy 158.885654 -19.18959) (xy 158.85309 -19.236953) (xy 158.83382 -19.25828) (xy 158.827216 -19.265138)
			(xy 158.820104 -19.283172) (xy 158.820104 -19.372072) (xy 158.827216 -19.390106) (xy 158.83382 -19.396964)
			(xy 158.853111 -19.418273) (xy 158.87705 -19.453098) (xy 164.376352 -19.453098) (xy 164.380423 -19.397476)
			(xy 164.392549 -19.343039) (xy 164.412472 -19.290948) (xy 164.439768 -19.242313) (xy 164.473854 -19.19817)
			(xy 164.514003 -19.159461) (xy 164.559361 -19.12701) (xy 164.608961 -19.101509) (xy 164.661745 -19.083502)
			(xy 164.716588 -19.073372) (xy 164.772322 -19.071335) (xy 164.827759 -19.077435) (xy 164.881716 -19.091541)
			(xy 164.933045 -19.113353) (xy 164.980651 -19.142407) (xy 165.023519 -19.178082) (xy 165.060736 -19.219619)
			(xy 165.091509 -19.266132) (xy 165.115181 -19.316629) (xy 165.131249 -19.370036) (xy 165.139369 -19.425212)
			(xy 165.139878 -19.453098) (xy 165.139369 -19.480984) (xy 165.131249 -19.53616) (xy 165.115181 -19.589567)
			(xy 165.091509 -19.640064) (xy 165.060736 -19.686577) (xy 165.023519 -19.728114) (xy 164.980651 -19.763789)
			(xy 164.933045 -19.792843) (xy 164.881716 -19.814655) (xy 164.827759 -19.828761) (xy 164.772322 -19.834861)
			(xy 164.716588 -19.832824) (xy 164.661745 -19.822694) (xy 164.608961 -19.804687) (xy 164.559361 -19.779186)
			(xy 164.514003 -19.746735) (xy 164.473854 -19.708026) (xy 164.439768 -19.663883) (xy 164.412472 -19.615248)
			(xy 164.392549 -19.563157) (xy 164.380423 -19.50872) (xy 164.376352 -19.453098) (xy 158.87705 -19.453098)
			(xy 158.885671 -19.46564) (xy 158.910759 -19.517355) (xy 158.927805 -19.572248) (xy 158.936425 -19.629077)
			(xy 158.936422 -19.686555) (xy 158.927798 -19.743384) (xy 158.910747 -19.798275) (xy 158.885655 -19.849988)
			(xy 158.85309 -19.897352) (xy 158.83382 -19.91868) (xy 158.827216 -19.925538) (xy 158.820104 -19.943572)
			(xy 158.820104 -20.032472) (xy 158.827216 -20.050506) (xy 158.83382 -20.057364) (xy 158.853111 -20.078673)
			(xy 158.885671 -20.12604) (xy 158.910759 -20.177755) (xy 158.927805 -20.232648) (xy 158.936425 -20.289477)
			(xy 158.936422 -20.346955) (xy 158.927798 -20.403784) (xy 158.910747 -20.458675) (xy 158.906429 -20.467574)
			(xy 166.387524 -20.467574) (xy 166.391595 -20.411952) (xy 166.403721 -20.357515) (xy 166.423644 -20.305424)
			(xy 166.45094 -20.256789) (xy 166.485026 -20.212646) (xy 166.525175 -20.173937) (xy 166.570533 -20.141486)
			(xy 166.620133 -20.115985) (xy 166.672917 -20.097978) (xy 166.72776 -20.087848) (xy 166.783494 -20.085811)
			(xy 166.838931 -20.091911) (xy 166.892888 -20.106017) (xy 166.944217 -20.127829) (xy 166.991823 -20.156883)
			(xy 167.034691 -20.192558) (xy 167.071908 -20.234095) (xy 167.102681 -20.280608) (xy 167.126353 -20.331105)
			(xy 167.142421 -20.384512) (xy 167.150541 -20.439688) (xy 167.15105 -20.467574) (xy 167.150541 -20.49546)
			(xy 167.142421 -20.550636) (xy 167.126353 -20.604043) (xy 167.102681 -20.65454) (xy 167.071908 -20.701053)
			(xy 167.050335 -20.72513) (xy 173.28059 -20.72513) (xy 173.28456 -20.594996) (xy 173.296456 -20.465346)
			(xy 173.316235 -20.336663) (xy 173.343821 -20.209424) (xy 173.379114 -20.084105) (xy 173.42198 -19.961169)
			(xy 173.472262 -19.841076) (xy 173.529771 -19.724272) (xy 173.594295 -19.61119) (xy 173.665592 -19.502253)
			(xy 173.743397 -19.397865) (xy 173.827422 -19.298414) (xy 173.917354 -19.204271) (xy 174.012858 -19.115786)
			(xy 174.113578 -19.033287) (xy 174.21914 -18.957082) (xy 174.329152 -18.887455) (xy 174.443204 -18.824664)
			(xy 174.560872 -18.768942) (xy 174.681718 -18.720498) (xy 174.805293 -18.679511) (xy 174.931136 -18.646134)
			(xy 175.058781 -18.620491) (xy 175.187751 -18.602677) (xy 175.317567 -18.592759) (xy 175.447746 -18.590774)
			(xy 175.577805 -18.596728) (xy 175.707258 -18.610601) (xy 175.835625 -18.632339) (xy 175.962428 -18.661863)
			(xy 176.087195 -18.699062) (xy 176.209462 -18.743798) (xy 176.328775 -18.795906) (xy 176.444688 -18.855189)
			(xy 176.556773 -18.92143) (xy 176.66461 -18.99438) (xy 176.767799 -19.073768) (xy 176.865957 -19.1593)
			(xy 176.958718 -19.250657) (xy 177.045737 -19.347499) (xy 177.12669 -19.449466) (xy 177.201276 -19.556178)
			(xy 177.269217 -19.667239) (xy 177.330262 -19.782235) (xy 177.384183 -19.900739) (xy 177.430778 -20.02231)
			(xy 177.469876 -20.146495) (xy 177.50133 -20.272833) (xy 177.525024 -20.400854) (xy 177.540868 -20.53008)
			(xy 177.548806 -20.660033) (xy 177.549302 -20.72513) (xy 177.548806 -20.790227) (xy 177.540868 -20.92018)
			(xy 177.525024 -21.049406) (xy 177.50133 -21.177427) (xy 177.469876 -21.303765) (xy 177.430778 -21.42795)
			(xy 177.384183 -21.549521) (xy 177.343459 -21.639022) (xy 184.173876 -21.639022) (xy 184.17442 -21.610284)
			(xy 184.183038 -21.553458) (xy 184.200084 -21.498567) (xy 184.225171 -21.446855) (xy 184.257732 -21.399492)
			(xy 184.277 -21.378164) (xy 184.283604 -21.371306) (xy 184.290716 -21.353272) (xy 184.290716 -21.264372)
			(xy 184.283604 -21.246338) (xy 184.277 -21.23948) (xy 184.257752 -21.218134) (xy 184.225188 -21.170774)
			(xy 184.200097 -21.119065) (xy 184.183046 -21.064178) (xy 184.174422 -21.007353) (xy 184.17442 -20.949879)
			(xy 184.183039 -20.893054) (xy 184.200085 -20.838165) (xy 184.225172 -20.786454) (xy 184.257732 -20.739091)
			(xy 184.277 -20.717764) (xy 184.283604 -20.710906) (xy 184.290716 -20.692872) (xy 184.290716 -20.603972)
			(xy 184.283604 -20.585938) (xy 184.277 -20.57908) (xy 184.257752 -20.557734) (xy 184.225188 -20.510374)
			(xy 184.200097 -20.458665) (xy 184.183046 -20.403778) (xy 184.174422 -20.346953) (xy 184.17442 -20.289479)
			(xy 184.183039 -20.232654) (xy 184.200085 -20.177765) (xy 184.225172 -20.126054) (xy 184.257732 -20.078691)
			(xy 184.277 -20.057364) (xy 184.283604 -20.050506) (xy 184.290716 -20.032472) (xy 184.290716 -19.943572)
			(xy 184.283604 -19.925538) (xy 184.277 -19.91868) (xy 184.257752 -19.897334) (xy 184.225188 -19.849974)
			(xy 184.200097 -19.798265) (xy 184.183046 -19.743378) (xy 184.174422 -19.686553) (xy 184.17442 -19.629079)
			(xy 184.183039 -19.572254) (xy 184.200085 -19.517365) (xy 184.225172 -19.465654) (xy 184.257732 -19.418291)
			(xy 184.277 -19.396964) (xy 184.283604 -19.390106) (xy 184.290716 -19.372072) (xy 184.290716 -19.283172)
			(xy 184.283604 -19.265138) (xy 184.277 -19.25828) (xy 184.25775 -19.236935) (xy 184.225179 -19.189579)
			(xy 184.200081 -19.137872) (xy 184.183026 -19.082985) (xy 184.174399 -19.02616) (xy 184.173876 -18.997422)
			(xy 184.174362 -18.970171) (xy 184.182118 -18.916223) (xy 184.197473 -18.863928) (xy 184.220115 -18.814351)
			(xy 184.249581 -18.768501) (xy 184.285272 -18.72731) (xy 184.326463 -18.691619) (xy 184.372313 -18.662153)
			(xy 184.42189 -18.639511) (xy 184.474185 -18.624156) (xy 184.528133 -18.6164) (xy 184.582635 -18.6164)
			(xy 184.636583 -18.624156) (xy 184.688878 -18.639511) (xy 184.738455 -18.662153) (xy 184.784305 -18.691619)
			(xy 184.825496 -18.72731) (xy 184.861187 -18.768501) (xy 184.890653 -18.814351) (xy 184.913295 -18.863928)
			(xy 184.92865 -18.916223) (xy 184.936406 -18.970171) (xy 184.936892 -18.997422) (xy 184.936384 -19.026162)
			(xy 184.927758 -19.08299) (xy 184.910704 -19.137881) (xy 184.885609 -19.189592) (xy 184.85304 -19.236954)
			(xy 184.833768 -19.25828) (xy 184.827164 -19.265138) (xy 184.820052 -19.283172) (xy 184.820052 -19.372072)
			(xy 184.827164 -19.390106) (xy 184.833768 -19.396964) (xy 184.853061 -19.418272) (xy 184.877005 -19.453098)
			(xy 190.3763 -19.453098) (xy 190.380371 -19.397476) (xy 190.392497 -19.343039) (xy 190.41242 -19.290948)
			(xy 190.439716 -19.242313) (xy 190.473802 -19.19817) (xy 190.513951 -19.159461) (xy 190.559309 -19.12701)
			(xy 190.608909 -19.101509) (xy 190.661693 -19.083502) (xy 190.716536 -19.073372) (xy 190.77227 -19.071335)
			(xy 190.827707 -19.077435) (xy 190.881664 -19.091541) (xy 190.932993 -19.113353) (xy 190.980599 -19.142407)
			(xy 191.023467 -19.178082) (xy 191.060684 -19.219619) (xy 191.091457 -19.266132) (xy 191.115129 -19.316629)
			(xy 191.131197 -19.370036) (xy 191.139317 -19.425212) (xy 191.139826 -19.453098) (xy 191.139317 -19.480984)
			(xy 191.131197 -19.53616) (xy 191.115129 -19.589567) (xy 191.091457 -19.640064) (xy 191.060684 -19.686577)
			(xy 191.023467 -19.728114) (xy 190.980599 -19.763789) (xy 190.932993 -19.792843) (xy 190.881664 -19.814655)
			(xy 190.827707 -19.828761) (xy 190.77227 -19.834861) (xy 190.716536 -19.832824) (xy 190.661693 -19.822694)
			(xy 190.608909 -19.804687) (xy 190.559309 -19.779186) (xy 190.513951 -19.746735) (xy 190.473802 -19.708026)
			(xy 190.439716 -19.663883) (xy 190.41242 -19.615248) (xy 190.392497 -19.563157) (xy 190.380371 -19.50872)
			(xy 190.3763 -19.453098) (xy 184.877005 -19.453098) (xy 184.885626 -19.465637) (xy 184.910717 -19.517352)
			(xy 184.927766 -19.572246) (xy 184.936387 -19.629076) (xy 184.936384 -19.686556) (xy 184.927759 -19.743386)
			(xy 184.910705 -19.798278) (xy 184.88561 -19.849991) (xy 184.853041 -19.897353) (xy 184.833768 -19.91868)
			(xy 184.827164 -19.925538) (xy 184.820052 -19.943572) (xy 184.820052 -20.032472) (xy 184.827164 -20.050506)
			(xy 184.833768 -20.057364) (xy 184.853061 -20.078672) (xy 184.885626 -20.126037) (xy 184.910717 -20.177752)
			(xy 184.927766 -20.232646) (xy 184.936387 -20.289476) (xy 184.936384 -20.346956) (xy 184.927759 -20.403786)
			(xy 184.910705 -20.458678) (xy 184.906388 -20.467574) (xy 192.387472 -20.467574) (xy 192.391543 -20.411952)
			(xy 192.403669 -20.357515) (xy 192.423592 -20.305424) (xy 192.450888 -20.256789) (xy 192.484974 -20.212646)
			(xy 192.525123 -20.173937) (xy 192.570481 -20.141486) (xy 192.620081 -20.115985) (xy 192.672865 -20.097978)
			(xy 192.727708 -20.087848) (xy 192.783442 -20.085811) (xy 192.838879 -20.091911) (xy 192.892836 -20.106017)
			(xy 192.944165 -20.127829) (xy 192.991771 -20.156883) (xy 193.034639 -20.192558) (xy 193.071856 -20.234095)
			(xy 193.102629 -20.280608) (xy 193.126301 -20.331105) (xy 193.142369 -20.384512) (xy 193.150489 -20.439688)
			(xy 193.150998 -20.467574) (xy 193.150489 -20.49546) (xy 193.142369 -20.550636) (xy 193.126301 -20.604043)
			(xy 193.102629 -20.65454) (xy 193.071856 -20.701053) (xy 193.050283 -20.72513) (xy 199.280538 -20.72513)
			(xy 199.284508 -20.594996) (xy 199.296404 -20.465346) (xy 199.316183 -20.336663) (xy 199.343769 -20.209424)
			(xy 199.379062 -20.084105) (xy 199.421928 -19.961169) (xy 199.47221 -19.841076) (xy 199.529719 -19.724272)
			(xy 199.594243 -19.61119) (xy 199.66554 -19.502253) (xy 199.743345 -19.397865) (xy 199.82737 -19.298414)
			(xy 199.917302 -19.204271) (xy 200.012806 -19.115786) (xy 200.113526 -19.033287) (xy 200.219088 -18.957082)
			(xy 200.3291 -18.887455) (xy 200.443152 -18.824664) (xy 200.56082 -18.768942) (xy 200.681666 -18.720498)
			(xy 200.805241 -18.679511) (xy 200.931084 -18.646134) (xy 201.058729 -18.620491) (xy 201.187699 -18.602677)
			(xy 201.317515 -18.592759) (xy 201.447694 -18.590774) (xy 201.577753 -18.596728) (xy 201.707206 -18.610601)
			(xy 201.835573 -18.632339) (xy 201.962376 -18.661863) (xy 202.087143 -18.699062) (xy 202.20941 -18.743798)
			(xy 202.328723 -18.795906) (xy 202.444636 -18.855189) (xy 202.556721 -18.92143) (xy 202.664558 -18.99438)
			(xy 202.767747 -19.073768) (xy 202.865905 -19.1593) (xy 202.958666 -19.250657) (xy 203.045685 -19.347499)
			(xy 203.126638 -19.449466) (xy 203.201224 -19.556178) (xy 203.269165 -19.667239) (xy 203.33021 -19.782235)
			(xy 203.384131 -19.900739) (xy 203.430726 -20.02231) (xy 203.469824 -20.146495) (xy 203.501278 -20.272833)
			(xy 203.524972 -20.400854) (xy 203.540816 -20.53008) (xy 203.548754 -20.660033) (xy 203.54925 -20.72513)
			(xy 203.548754 -20.790227) (xy 203.540816 -20.92018) (xy 203.524972 -21.049406) (xy 203.501278 -21.177427)
			(xy 203.469824 -21.303765) (xy 203.430726 -21.42795) (xy 203.384131 -21.549521) (xy 203.343407 -21.639022)
			(xy 210.173824 -21.639022) (xy 210.174381 -21.610285) (xy 210.182999 -21.55346) (xy 210.200042 -21.49857)
			(xy 210.225126 -21.446858) (xy 210.257682 -21.399493) (xy 210.276948 -21.378164) (xy 210.283552 -21.371306)
			(xy 210.290664 -21.353272) (xy 210.290664 -21.264372) (xy 210.283552 -21.246338) (xy 210.276948 -21.23948)
			(xy 210.257698 -21.218135) (xy 210.22513 -21.170776) (xy 210.200036 -21.119068) (xy 210.182983 -21.064179)
			(xy 210.174358 -21.007354) (xy 210.174355 -20.949878) (xy 210.182976 -20.893052) (xy 210.200024 -20.838162)
			(xy 210.225114 -20.786452) (xy 210.257678 -20.73909) (xy 210.276948 -20.717764) (xy 210.283552 -20.710906)
			(xy 210.290664 -20.692872) (xy 210.290664 -20.603972) (xy 210.283552 -20.585938) (xy 210.276948 -20.57908)
			(xy 210.257698 -20.557735) (xy 210.22513 -20.510376) (xy 210.200036 -20.458668) (xy 210.182983 -20.403779)
			(xy 210.174358 -20.346954) (xy 210.174355 -20.289478) (xy 210.182976 -20.232652) (xy 210.200024 -20.177762)
			(xy 210.225114 -20.126052) (xy 210.257678 -20.07869) (xy 210.276948 -20.057364) (xy 210.283552 -20.050506)
			(xy 210.290664 -20.032472) (xy 210.290664 -19.943572) (xy 210.283552 -19.925538) (xy 210.276948 -19.91868)
			(xy 210.257698 -19.897335) (xy 210.22513 -19.849976) (xy 210.200036 -19.798268) (xy 210.182983 -19.743379)
			(xy 210.174358 -19.686554) (xy 210.174355 -19.629078) (xy 210.182976 -19.572252) (xy 210.200024 -19.517362)
			(xy 210.225114 -19.465652) (xy 210.257678 -19.41829) (xy 210.276948 -19.396964) (xy 210.283552 -19.390106)
			(xy 210.290664 -19.372072) (xy 210.290664 -19.283172) (xy 210.283552 -19.265138) (xy 210.276948 -19.25828)
			(xy 210.257689 -19.236942) (xy 210.225121 -19.189584) (xy 210.200026 -19.137875) (xy 210.182973 -19.082986)
			(xy 210.174347 -19.02616) (xy 210.173824 -18.997422) (xy 210.17431 -18.970171) (xy 210.182066 -18.916223)
			(xy 210.197421 -18.863928) (xy 210.220063 -18.814351) (xy 210.249529 -18.768501) (xy 210.28522 -18.72731)
			(xy 210.326411 -18.691619) (xy 210.372261 -18.662153) (xy 210.421838 -18.639511) (xy 210.474133 -18.624156)
			(xy 210.528081 -18.6164) (xy 210.582583 -18.6164) (xy 210.636531 -18.624156) (xy 210.688826 -18.639511)
			(xy 210.738403 -18.662153) (xy 210.784253 -18.691619) (xy 210.825444 -18.72731) (xy 210.861135 -18.768501)
			(xy 210.890601 -18.814351) (xy 210.913243 -18.863928) (xy 210.928598 -18.916223) (xy 210.936354 -18.970171)
			(xy 210.93684 -18.997422) (xy 210.936319 -19.026161) (xy 210.927694 -19.082988) (xy 210.910643 -19.137878)
			(xy 210.885551 -19.18959) (xy 210.852986 -19.236953) (xy 210.833716 -19.25828) (xy 210.827112 -19.265138)
			(xy 210.82 -19.283172) (xy 210.82 -19.372072) (xy 210.827112 -19.390106) (xy 210.833716 -19.396964)
			(xy 210.853007 -19.418273) (xy 210.876947 -19.453098) (xy 216.376248 -19.453098) (xy 216.380319 -19.397476)
			(xy 216.392445 -19.343039) (xy 216.412368 -19.290948) (xy 216.439664 -19.242313) (xy 216.47375 -19.19817)
			(xy 216.513899 -19.159461) (xy 216.559257 -19.12701) (xy 216.608857 -19.101509) (xy 216.661641 -19.083502)
			(xy 216.716484 -19.073372) (xy 216.772218 -19.071335) (xy 216.827655 -19.077435) (xy 216.881612 -19.091541)
			(xy 216.932941 -19.113353) (xy 216.980547 -19.142407) (xy 217.023415 -19.178082) (xy 217.060632 -19.219619)
			(xy 217.091405 -19.266132) (xy 217.115077 -19.316629) (xy 217.131145 -19.370036) (xy 217.139265 -19.425212)
			(xy 217.139774 -19.453098) (xy 217.139265 -19.480984) (xy 217.131145 -19.53616) (xy 217.115077 -19.589567)
			(xy 217.091405 -19.640064) (xy 217.060632 -19.686577) (xy 217.023415 -19.728114) (xy 216.980547 -19.763789)
			(xy 216.932941 -19.792843) (xy 216.881612 -19.814655) (xy 216.827655 -19.828761) (xy 216.772218 -19.834861)
			(xy 216.716484 -19.832824) (xy 216.661641 -19.822694) (xy 216.608857 -19.804687) (xy 216.559257 -19.779186)
			(xy 216.513899 -19.746735) (xy 216.47375 -19.708026) (xy 216.439664 -19.663883) (xy 216.412368 -19.615248)
			(xy 216.392445 -19.563157) (xy 216.380319 -19.50872) (xy 216.376248 -19.453098) (xy 210.876947 -19.453098)
			(xy 210.885568 -19.465639) (xy 210.910656 -19.517354) (xy 210.927702 -19.572248) (xy 210.936322 -19.629077)
			(xy 210.936319 -19.686556) (xy 210.927695 -19.743384) (xy 210.910644 -19.798275) (xy 210.885552 -19.849988)
			(xy 210.852987 -19.897352) (xy 210.833716 -19.91868) (xy 210.827112 -19.925538) (xy 210.82 -19.943572)
			(xy 210.82 -20.032472) (xy 210.827112 -20.050506) (xy 210.833716 -20.057364) (xy 210.853007 -20.078673)
			(xy 210.885568 -20.126039) (xy 210.910656 -20.177754) (xy 210.927702 -20.232648) (xy 210.936322 -20.289477)
			(xy 210.936319 -20.346956) (xy 210.927695 -20.403784) (xy 210.910644 -20.458675) (xy 210.906326 -20.467574)
			(xy 218.38742 -20.467574) (xy 218.391491 -20.411952) (xy 218.403617 -20.357515) (xy 218.42354 -20.305424)
			(xy 218.450836 -20.256789) (xy 218.484922 -20.212646) (xy 218.525071 -20.173937) (xy 218.570429 -20.141486)
			(xy 218.620029 -20.115985) (xy 218.672813 -20.097978) (xy 218.727656 -20.087848) (xy 218.78339 -20.085811)
			(xy 218.838827 -20.091911) (xy 218.892784 -20.106017) (xy 218.944113 -20.127829) (xy 218.991719 -20.156883)
			(xy 219.034587 -20.192558) (xy 219.071804 -20.234095) (xy 219.102577 -20.280608) (xy 219.126249 -20.331105)
			(xy 219.142317 -20.384512) (xy 219.150437 -20.439688) (xy 219.150946 -20.467574) (xy 219.150437 -20.49546)
			(xy 219.142317 -20.550636) (xy 219.126249 -20.604043) (xy 219.102577 -20.65454) (xy 219.071804 -20.701053)
			(xy 219.050231 -20.72513) (xy 237.380538 -20.72513) (xy 237.384508 -20.594996) (xy 237.396404 -20.465346)
			(xy 237.416183 -20.336663) (xy 237.443769 -20.209424) (xy 237.479062 -20.084105) (xy 237.521928 -19.961169)
			(xy 237.57221 -19.841076) (xy 237.629719 -19.724272) (xy 237.694243 -19.61119) (xy 237.76554 -19.502253)
			(xy 237.843345 -19.397865) (xy 237.92737 -19.298414) (xy 238.017302 -19.204271) (xy 238.112806 -19.115786)
			(xy 238.213526 -19.033287) (xy 238.319088 -18.957082) (xy 238.4291 -18.887455) (xy 238.543152 -18.824664)
			(xy 238.66082 -18.768942) (xy 238.781666 -18.720498) (xy 238.905241 -18.679511) (xy 239.031084 -18.646134)
			(xy 239.158729 -18.620491) (xy 239.287699 -18.602677) (xy 239.417515 -18.592759) (xy 239.547694 -18.590774)
			(xy 239.677753 -18.596728) (xy 239.807206 -18.610601) (xy 239.935573 -18.632339) (xy 240.062376 -18.661863)
			(xy 240.187143 -18.699062) (xy 240.30941 -18.743798) (xy 240.428723 -18.795906) (xy 240.544636 -18.855189)
			(xy 240.656721 -18.92143) (xy 240.764558 -18.99438) (xy 240.867747 -19.073768) (xy 240.965905 -19.1593)
			(xy 241.058666 -19.250657) (xy 241.145685 -19.347499) (xy 241.226638 -19.449466) (xy 241.301224 -19.556178)
			(xy 241.369165 -19.667239) (xy 241.43021 -19.782235) (xy 241.484131 -19.900739) (xy 241.530726 -20.02231)
			(xy 241.569824 -20.146495) (xy 241.601278 -20.272833) (xy 241.624972 -20.400854) (xy 241.640816 -20.53008)
			(xy 241.648754 -20.660033) (xy 241.64925 -20.72513) (xy 241.648754 -20.790227) (xy 241.640816 -20.92018)
			(xy 241.624972 -21.049406) (xy 241.601278 -21.177427) (xy 241.569824 -21.303765) (xy 241.530726 -21.42795)
			(xy 241.484131 -21.549521) (xy 241.443407 -21.639022) (xy 248.273824 -21.639022) (xy 248.274381 -21.610285)
			(xy 248.282999 -21.55346) (xy 248.300042 -21.49857) (xy 248.325126 -21.446858) (xy 248.357682 -21.399493)
			(xy 248.376948 -21.378164) (xy 248.383552 -21.371306) (xy 248.390664 -21.353272) (xy 248.390664 -21.264372)
			(xy 248.383552 -21.246338) (xy 248.376948 -21.23948) (xy 248.357698 -21.218135) (xy 248.32513 -21.170776)
			(xy 248.300036 -21.119068) (xy 248.282983 -21.064179) (xy 248.274358 -21.007354) (xy 248.274355 -20.949878)
			(xy 248.282976 -20.893052) (xy 248.300024 -20.838162) (xy 248.325114 -20.786452) (xy 248.357678 -20.73909)
			(xy 248.376948 -20.717764) (xy 248.383552 -20.710906) (xy 248.390664 -20.692872) (xy 248.390664 -20.603972)
			(xy 248.383552 -20.585938) (xy 248.376948 -20.57908) (xy 248.357698 -20.557735) (xy 248.32513 -20.510376)
			(xy 248.300036 -20.458668) (xy 248.282983 -20.403779) (xy 248.274358 -20.346954) (xy 248.274355 -20.289478)
			(xy 248.282976 -20.232652) (xy 248.300024 -20.177762) (xy 248.325114 -20.126052) (xy 248.357678 -20.07869)
			(xy 248.376948 -20.057364) (xy 248.383552 -20.050506) (xy 248.390664 -20.032472) (xy 248.390664 -19.943572)
			(xy 248.383552 -19.925538) (xy 248.376948 -19.91868) (xy 248.357698 -19.897335) (xy 248.32513 -19.849976)
			(xy 248.300036 -19.798268) (xy 248.282983 -19.743379) (xy 248.274358 -19.686554) (xy 248.274355 -19.629078)
			(xy 248.282976 -19.572252) (xy 248.300024 -19.517362) (xy 248.325114 -19.465652) (xy 248.357678 -19.41829)
			(xy 248.376948 -19.396964) (xy 248.383552 -19.390106) (xy 248.390664 -19.372072) (xy 248.390664 -19.283172)
			(xy 248.383552 -19.265138) (xy 248.376948 -19.25828) (xy 248.357689 -19.236942) (xy 248.325121 -19.189584)
			(xy 248.300026 -19.137875) (xy 248.282973 -19.082986) (xy 248.274347 -19.02616) (xy 248.273824 -18.997422)
			(xy 248.27431 -18.970171) (xy 248.282066 -18.916223) (xy 248.297421 -18.863928) (xy 248.320063 -18.814351)
			(xy 248.349529 -18.768501) (xy 248.38522 -18.72731) (xy 248.426411 -18.691619) (xy 248.472261 -18.662153)
			(xy 248.521838 -18.639511) (xy 248.574133 -18.624156) (xy 248.628081 -18.6164) (xy 248.682583 -18.6164)
			(xy 248.736531 -18.624156) (xy 248.788826 -18.639511) (xy 248.838403 -18.662153) (xy 248.884253 -18.691619)
			(xy 248.925444 -18.72731) (xy 248.961135 -18.768501) (xy 248.990601 -18.814351) (xy 249.013243 -18.863928)
			(xy 249.028598 -18.916223) (xy 249.036354 -18.970171) (xy 249.03684 -18.997422) (xy 249.036319 -19.026161)
			(xy 249.027694 -19.082988) (xy 249.010643 -19.137878) (xy 248.985551 -19.18959) (xy 248.952986 -19.236953)
			(xy 248.933716 -19.25828) (xy 248.927112 -19.265138) (xy 248.92 -19.283172) (xy 248.92 -19.372072)
			(xy 248.927112 -19.390106) (xy 248.933716 -19.396964) (xy 248.953007 -19.418273) (xy 248.976947 -19.453098)
			(xy 254.476248 -19.453098) (xy 254.480319 -19.397476) (xy 254.492445 -19.343039) (xy 254.512368 -19.290948)
			(xy 254.539664 -19.242313) (xy 254.57375 -19.19817) (xy 254.613899 -19.159461) (xy 254.659257 -19.12701)
			(xy 254.708857 -19.101509) (xy 254.761641 -19.083502) (xy 254.816484 -19.073372) (xy 254.872218 -19.071335)
			(xy 254.927655 -19.077435) (xy 254.981612 -19.091541) (xy 255.032941 -19.113353) (xy 255.080547 -19.142407)
			(xy 255.123415 -19.178082) (xy 255.160632 -19.219619) (xy 255.191405 -19.266132) (xy 255.215077 -19.316629)
			(xy 255.231145 -19.370036) (xy 255.239265 -19.425212) (xy 255.239774 -19.453098) (xy 255.239265 -19.480984)
			(xy 255.231145 -19.53616) (xy 255.215077 -19.589567) (xy 255.191405 -19.640064) (xy 255.160632 -19.686577)
			(xy 255.123415 -19.728114) (xy 255.080547 -19.763789) (xy 255.032941 -19.792843) (xy 254.981612 -19.814655)
			(xy 254.927655 -19.828761) (xy 254.872218 -19.834861) (xy 254.816484 -19.832824) (xy 254.761641 -19.822694)
			(xy 254.708857 -19.804687) (xy 254.659257 -19.779186) (xy 254.613899 -19.746735) (xy 254.57375 -19.708026)
			(xy 254.539664 -19.663883) (xy 254.512368 -19.615248) (xy 254.492445 -19.563157) (xy 254.480319 -19.50872)
			(xy 254.476248 -19.453098) (xy 248.976947 -19.453098) (xy 248.985568 -19.465639) (xy 249.010656 -19.517354)
			(xy 249.027702 -19.572248) (xy 249.036322 -19.629077) (xy 249.036319 -19.686556) (xy 249.027695 -19.743384)
			(xy 249.010644 -19.798275) (xy 248.985552 -19.849988) (xy 248.952987 -19.897352) (xy 248.933716 -19.91868)
			(xy 248.927112 -19.925538) (xy 248.92 -19.943572) (xy 248.92 -20.032472) (xy 248.927112 -20.050506)
			(xy 248.933716 -20.057364) (xy 248.953007 -20.078673) (xy 248.985568 -20.126039) (xy 249.010656 -20.177754)
			(xy 249.027702 -20.232648) (xy 249.036322 -20.289477) (xy 249.036319 -20.346956) (xy 249.027695 -20.403784)
			(xy 249.010644 -20.458675) (xy 249.006326 -20.467574) (xy 256.48742 -20.467574) (xy 256.491491 -20.411952)
			(xy 256.503617 -20.357515) (xy 256.52354 -20.305424) (xy 256.550836 -20.256789) (xy 256.584922 -20.212646)
			(xy 256.625071 -20.173937) (xy 256.670429 -20.141486) (xy 256.720029 -20.115985) (xy 256.772813 -20.097978)
			(xy 256.827656 -20.087848) (xy 256.88339 -20.085811) (xy 256.938827 -20.091911) (xy 256.992784 -20.106017)
			(xy 257.044113 -20.127829) (xy 257.091719 -20.156883) (xy 257.134587 -20.192558) (xy 257.171804 -20.234095)
			(xy 257.202577 -20.280608) (xy 257.226249 -20.331105) (xy 257.242317 -20.384512) (xy 257.250437 -20.439688)
			(xy 257.250946 -20.467574) (xy 257.250437 -20.49546) (xy 257.242317 -20.550636) (xy 257.226249 -20.604043)
			(xy 257.202577 -20.65454) (xy 257.171804 -20.701053) (xy 257.150231 -20.72513) (xy 263.380486 -20.72513)
			(xy 263.384456 -20.594996) (xy 263.396352 -20.465346) (xy 263.416131 -20.336663) (xy 263.443717 -20.209424)
			(xy 263.47901 -20.084105) (xy 263.521876 -19.961169) (xy 263.572158 -19.841076) (xy 263.629667 -19.724272)
			(xy 263.694191 -19.61119) (xy 263.765488 -19.502253) (xy 263.843293 -19.397865) (xy 263.927318 -19.298414)
			(xy 264.01725 -19.204271) (xy 264.112754 -19.115786) (xy 264.213474 -19.033287) (xy 264.319036 -18.957082)
			(xy 264.429048 -18.887455) (xy 264.5431 -18.824664) (xy 264.660768 -18.768942) (xy 264.781614 -18.720498)
			(xy 264.905189 -18.679511) (xy 265.031032 -18.646134) (xy 265.158677 -18.620491) (xy 265.287647 -18.602677)
			(xy 265.417463 -18.592759) (xy 265.547642 -18.590774) (xy 265.677701 -18.596728) (xy 265.807154 -18.610601)
			(xy 265.935521 -18.632339) (xy 266.062324 -18.661863) (xy 266.187091 -18.699062) (xy 266.309358 -18.743798)
			(xy 266.428671 -18.795906) (xy 266.544584 -18.855189) (xy 266.656669 -18.92143) (xy 266.764506 -18.99438)
			(xy 266.867695 -19.073768) (xy 266.965853 -19.1593) (xy 267.058614 -19.250657) (xy 267.145633 -19.347499)
			(xy 267.226586 -19.449466) (xy 267.301172 -19.556178) (xy 267.369113 -19.667239) (xy 267.430158 -19.782235)
			(xy 267.484079 -19.900739) (xy 267.530674 -20.02231) (xy 267.569772 -20.146495) (xy 267.601226 -20.272833)
			(xy 267.62492 -20.400854) (xy 267.640764 -20.53008) (xy 267.648702 -20.660033) (xy 267.649198 -20.72513)
			(xy 267.648702 -20.790227) (xy 267.640764 -20.92018) (xy 267.62492 -21.049406) (xy 267.601226 -21.177427)
			(xy 267.569772 -21.303765) (xy 267.530674 -21.42795) (xy 267.484079 -21.549521) (xy 267.443355 -21.639022)
			(xy 274.273772 -21.639022) (xy 274.274317 -21.610284) (xy 274.282935 -21.553458) (xy 274.299981 -21.498568)
			(xy 274.325068 -21.446856) (xy 274.357628 -21.399492) (xy 274.376896 -21.378164) (xy 274.3835 -21.371306)
			(xy 274.390612 -21.353272) (xy 274.390612 -21.264372) (xy 274.3835 -21.246338) (xy 274.376896 -21.23948)
			(xy 274.357648 -21.218134) (xy 274.325085 -21.170774) (xy 274.299994 -21.119065) (xy 274.282943 -21.064178)
			(xy 274.274319 -21.007353) (xy 274.274317 -20.949879) (xy 274.282936 -20.893054) (xy 274.299982 -20.838165)
			(xy 274.325068 -20.786454) (xy 274.357628 -20.739091) (xy 274.376896 -20.717764) (xy 274.3835 -20.710906)
			(xy 274.390612 -20.692872) (xy 274.390612 -20.603972) (xy 274.3835 -20.585938) (xy 274.376896 -20.57908)
			(xy 274.357648 -20.557734) (xy 274.325085 -20.510374) (xy 274.299994 -20.458665) (xy 274.282943 -20.403778)
			(xy 274.274319 -20.346953) (xy 274.274317 -20.289479) (xy 274.282936 -20.232654) (xy 274.299982 -20.177765)
			(xy 274.325068 -20.126054) (xy 274.357628 -20.078691) (xy 274.376896 -20.057364) (xy 274.3835 -20.050506)
			(xy 274.390612 -20.032472) (xy 274.390612 -19.943572) (xy 274.3835 -19.925538) (xy 274.376896 -19.91868)
			(xy 274.357648 -19.897334) (xy 274.325085 -19.849974) (xy 274.299994 -19.798265) (xy 274.282943 -19.743378)
			(xy 274.274319 -19.686553) (xy 274.274317 -19.629079) (xy 274.282936 -19.572254) (xy 274.299982 -19.517365)
			(xy 274.325068 -19.465654) (xy 274.357628 -19.418291) (xy 274.376896 -19.396964) (xy 274.3835 -19.390106)
			(xy 274.390612 -19.372072) (xy 274.390612 -19.283172) (xy 274.3835 -19.265138) (xy 274.376896 -19.25828)
			(xy 274.357646 -19.236935) (xy 274.325075 -19.189579) (xy 274.299977 -19.137872) (xy 274.282922 -19.082985)
			(xy 274.274295 -19.02616) (xy 274.273772 -18.997422) (xy 274.274258 -18.970171) (xy 274.282014 -18.916223)
			(xy 274.297369 -18.863928) (xy 274.320011 -18.814351) (xy 274.349477 -18.768501) (xy 274.385168 -18.72731)
			(xy 274.426359 -18.691619) (xy 274.472209 -18.662153) (xy 274.521786 -18.639511) (xy 274.574081 -18.624156)
			(xy 274.628029 -18.6164) (xy 274.682531 -18.6164) (xy 274.736479 -18.624156) (xy 274.788774 -18.639511)
			(xy 274.838351 -18.662153) (xy 274.884201 -18.691619) (xy 274.925392 -18.72731) (xy 274.961083 -18.768501)
			(xy 274.990549 -18.814351) (xy 275.013191 -18.863928) (xy 275.028546 -18.916223) (xy 275.036302 -18.970171)
			(xy 275.036788 -18.997422) (xy 275.036281 -19.026162) (xy 275.027655 -19.08299) (xy 275.010601 -19.137881)
			(xy 274.985506 -19.189592) (xy 274.952937 -19.236954) (xy 274.933664 -19.25828) (xy 274.92706 -19.265138)
			(xy 274.919948 -19.283172) (xy 274.919948 -19.372072) (xy 274.92706 -19.390106) (xy 274.933664 -19.396964)
			(xy 274.952957 -19.418272) (xy 274.976902 -19.453098) (xy 280.476196 -19.453098) (xy 280.480267 -19.397476)
			(xy 280.492393 -19.343039) (xy 280.512316 -19.290948) (xy 280.539612 -19.242313) (xy 280.573698 -19.19817)
			(xy 280.613847 -19.159461) (xy 280.659205 -19.12701) (xy 280.708805 -19.101509) (xy 280.761589 -19.083502)
			(xy 280.816432 -19.073372) (xy 280.872166 -19.071335) (xy 280.927603 -19.077435) (xy 280.98156 -19.091541)
			(xy 281.032889 -19.113353) (xy 281.080495 -19.142407) (xy 281.123363 -19.178082) (xy 281.16058 -19.219619)
			(xy 281.191353 -19.266132) (xy 281.215025 -19.316629) (xy 281.231093 -19.370036) (xy 281.239213 -19.425212)
			(xy 281.239722 -19.453098) (xy 281.239213 -19.480984) (xy 281.231093 -19.53616) (xy 281.215025 -19.589567)
			(xy 281.191353 -19.640064) (xy 281.16058 -19.686577) (xy 281.123363 -19.728114) (xy 281.080495 -19.763789)
			(xy 281.032889 -19.792843) (xy 280.98156 -19.814655) (xy 280.927603 -19.828761) (xy 280.872166 -19.834861)
			(xy 280.816432 -19.832824) (xy 280.761589 -19.822694) (xy 280.708805 -19.804687) (xy 280.659205 -19.779186)
			(xy 280.613847 -19.746735) (xy 280.573698 -19.708026) (xy 280.539612 -19.663883) (xy 280.512316 -19.615248)
			(xy 280.492393 -19.563157) (xy 280.480267 -19.50872) (xy 280.476196 -19.453098) (xy 274.976902 -19.453098)
			(xy 274.985523 -19.465637) (xy 275.010614 -19.517352) (xy 275.027663 -19.572246) (xy 275.036284 -19.629076)
			(xy 275.036281 -19.686556) (xy 275.027656 -19.743386) (xy 275.010602 -19.798278) (xy 274.985506 -19.849991)
			(xy 274.952937 -19.897353) (xy 274.933664 -19.91868) (xy 274.92706 -19.925538) (xy 274.919948 -19.943572)
			(xy 274.919948 -20.032472) (xy 274.92706 -20.050506) (xy 274.933664 -20.057364) (xy 274.952957 -20.078672)
			(xy 274.985523 -20.126037) (xy 275.010614 -20.177752) (xy 275.027663 -20.232646) (xy 275.036284 -20.289476)
			(xy 275.036281 -20.346956) (xy 275.027656 -20.403786) (xy 275.010602 -20.458678) (xy 275.006285 -20.467574)
			(xy 282.487368 -20.467574) (xy 282.491439 -20.411952) (xy 282.503565 -20.357515) (xy 282.523488 -20.305424)
			(xy 282.550784 -20.256789) (xy 282.58487 -20.212646) (xy 282.625019 -20.173937) (xy 282.670377 -20.141486)
			(xy 282.719977 -20.115985) (xy 282.772761 -20.097978) (xy 282.827604 -20.087848) (xy 282.883338 -20.085811)
			(xy 282.938775 -20.091911) (xy 282.992732 -20.106017) (xy 283.044061 -20.127829) (xy 283.091667 -20.156883)
			(xy 283.134535 -20.192558) (xy 283.171752 -20.234095) (xy 283.202525 -20.280608) (xy 283.226197 -20.331105)
			(xy 283.242265 -20.384512) (xy 283.250385 -20.439688) (xy 283.250894 -20.467574) (xy 283.250385 -20.49546)
			(xy 283.242265 -20.550636) (xy 283.226197 -20.604043) (xy 283.202525 -20.65454) (xy 283.171752 -20.701053)
			(xy 283.150179 -20.72513) (xy 289.380434 -20.72513) (xy 289.384404 -20.594996) (xy 289.3963 -20.465346)
			(xy 289.416079 -20.336663) (xy 289.443665 -20.209424) (xy 289.478958 -20.084105) (xy 289.521824 -19.961169)
			(xy 289.572106 -19.841076) (xy 289.629615 -19.724272) (xy 289.694139 -19.61119) (xy 289.765436 -19.502253)
			(xy 289.843241 -19.397865) (xy 289.927266 -19.298414) (xy 290.017198 -19.204271) (xy 290.112702 -19.115786)
			(xy 290.213422 -19.033287) (xy 290.318984 -18.957082) (xy 290.428996 -18.887455) (xy 290.543048 -18.824664)
			(xy 290.660716 -18.768942) (xy 290.781562 -18.720498) (xy 290.905137 -18.679511) (xy 291.03098 -18.646134)
			(xy 291.158625 -18.620491) (xy 291.287595 -18.602677) (xy 291.417411 -18.592759) (xy 291.54759 -18.590774)
			(xy 291.677649 -18.596728) (xy 291.807102 -18.610601) (xy 291.935469 -18.632339) (xy 292.062272 -18.661863)
			(xy 292.187039 -18.699062) (xy 292.309306 -18.743798) (xy 292.428619 -18.795906) (xy 292.544532 -18.855189)
			(xy 292.656617 -18.92143) (xy 292.764454 -18.99438) (xy 292.867643 -19.073768) (xy 292.965801 -19.1593)
			(xy 293.058562 -19.250657) (xy 293.145581 -19.347499) (xy 293.226534 -19.449466) (xy 293.30112 -19.556178)
			(xy 293.369061 -19.667239) (xy 293.430106 -19.782235) (xy 293.484027 -19.900739) (xy 293.530622 -20.02231)
			(xy 293.56972 -20.146495) (xy 293.601174 -20.272833) (xy 293.624868 -20.400854) (xy 293.640712 -20.53008)
			(xy 293.64865 -20.660033) (xy 293.649146 -20.72513) (xy 293.64865 -20.790227) (xy 293.640712 -20.92018)
			(xy 293.624868 -21.049406) (xy 293.601174 -21.177427) (xy 293.56972 -21.303765) (xy 293.530622 -21.42795)
			(xy 293.484027 -21.549521) (xy 293.443303 -21.639022) (xy 300.27372 -21.639022) (xy 300.274279 -21.610285)
			(xy 300.282896 -21.55346) (xy 300.299939 -21.49857) (xy 300.325022 -21.446858) (xy 300.357578 -21.399493)
			(xy 300.376844 -21.378164) (xy 300.383448 -21.371306) (xy 300.39056 -21.353272) (xy 300.39056 -21.264372)
			(xy 300.383448 -21.246338) (xy 300.376844 -21.23948) (xy 300.357594 -21.218135) (xy 300.325026 -21.170776)
			(xy 300.299932 -21.119067) (xy 300.28288 -21.064179) (xy 300.274255 -21.007354) (xy 300.274252 -20.949878)
			(xy 300.282873 -20.893052) (xy 300.299921 -20.838162) (xy 300.32501 -20.786452) (xy 300.357574 -20.73909)
			(xy 300.376844 -20.717764) (xy 300.383448 -20.710906) (xy 300.39056 -20.692872) (xy 300.39056 -20.603972)
			(xy 300.383448 -20.585938) (xy 300.376844 -20.57908) (xy 300.357594 -20.557735) (xy 300.325026 -20.510376)
			(xy 300.299932 -20.458667) (xy 300.28288 -20.403779) (xy 300.274255 -20.346954) (xy 300.274252 -20.289478)
			(xy 300.282873 -20.232652) (xy 300.299921 -20.177762) (xy 300.32501 -20.126052) (xy 300.357574 -20.07869)
			(xy 300.376844 -20.057364) (xy 300.383448 -20.050506) (xy 300.39056 -20.032472) (xy 300.39056 -19.943572)
			(xy 300.383448 -19.925538) (xy 300.376844 -19.91868) (xy 300.357594 -19.897335) (xy 300.325026 -19.849976)
			(xy 300.299932 -19.798267) (xy 300.28288 -19.743379) (xy 300.274255 -19.686554) (xy 300.274252 -19.629078)
			(xy 300.282873 -19.572252) (xy 300.299921 -19.517362) (xy 300.32501 -19.465652) (xy 300.357574 -19.41829)
			(xy 300.376844 -19.396964) (xy 300.383448 -19.390106) (xy 300.39056 -19.372072) (xy 300.39056 -19.283172)
			(xy 300.383448 -19.265138) (xy 300.376844 -19.25828) (xy 300.357585 -19.236943) (xy 300.325017 -19.189584)
			(xy 300.299922 -19.137875) (xy 300.282869 -19.082986) (xy 300.274243 -19.02616) (xy 300.27372 -18.997422)
			(xy 300.274206 -18.970171) (xy 300.281962 -18.916223) (xy 300.297317 -18.863928) (xy 300.319959 -18.814351)
			(xy 300.349425 -18.768501) (xy 300.385116 -18.72731) (xy 300.426307 -18.691619) (xy 300.472157 -18.662153)
			(xy 300.521734 -18.639511) (xy 300.574029 -18.624156) (xy 300.627977 -18.6164) (xy 300.682479 -18.6164)
			(xy 300.736427 -18.624156) (xy 300.788722 -18.639511) (xy 300.838299 -18.662153) (xy 300.884149 -18.691619)
			(xy 300.92534 -18.72731) (xy 300.961031 -18.768501) (xy 300.990497 -18.814351) (xy 301.013139 -18.863928)
			(xy 301.028494 -18.916223) (xy 301.03625 -18.970171) (xy 301.036736 -18.997422) (xy 301.036216 -19.026161)
			(xy 301.027591 -19.082988) (xy 301.01054 -19.137878) (xy 300.985447 -19.18959) (xy 300.952882 -19.236953)
			(xy 300.933612 -19.25828) (xy 300.927008 -19.265138) (xy 300.919896 -19.283172) (xy 300.919896 -19.372072)
			(xy 300.927008 -19.390106) (xy 300.933612 -19.396964) (xy 300.952903 -19.418273) (xy 300.976844 -19.453098)
			(xy 306.476144 -19.453098) (xy 306.480215 -19.397476) (xy 306.492341 -19.343039) (xy 306.512264 -19.290948)
			(xy 306.53956 -19.242313) (xy 306.573646 -19.19817) (xy 306.613795 -19.159461) (xy 306.659153 -19.12701)
			(xy 306.708753 -19.101509) (xy 306.761537 -19.083502) (xy 306.81638 -19.073372) (xy 306.872114 -19.071335)
			(xy 306.927551 -19.077435) (xy 306.981508 -19.091541) (xy 307.032837 -19.113353) (xy 307.080443 -19.142407)
			(xy 307.123311 -19.178082) (xy 307.160528 -19.219619) (xy 307.191301 -19.266132) (xy 307.214973 -19.316629)
			(xy 307.231041 -19.370036) (xy 307.239161 -19.425212) (xy 307.23967 -19.453098) (xy 307.239161 -19.480984)
			(xy 307.231041 -19.53616) (xy 307.214973 -19.589567) (xy 307.191301 -19.640064) (xy 307.160528 -19.686577)
			(xy 307.123311 -19.728114) (xy 307.080443 -19.763789) (xy 307.032837 -19.792843) (xy 306.981508 -19.814655)
			(xy 306.927551 -19.828761) (xy 306.872114 -19.834861) (xy 306.81638 -19.832824) (xy 306.761537 -19.822694)
			(xy 306.708753 -19.804687) (xy 306.659153 -19.779186) (xy 306.613795 -19.746735) (xy 306.573646 -19.708026)
			(xy 306.53956 -19.663883) (xy 306.512264 -19.615248) (xy 306.492341 -19.563157) (xy 306.480215 -19.50872)
			(xy 306.476144 -19.453098) (xy 300.976844 -19.453098) (xy 300.985465 -19.465639) (xy 301.010552 -19.517354)
			(xy 301.027599 -19.572247) (xy 301.036219 -19.629076) (xy 301.036216 -19.686556) (xy 301.027592 -19.743384)
			(xy 301.010541 -19.798276) (xy 300.985448 -19.849989) (xy 300.952883 -19.897352) (xy 300.933612 -19.91868)
			(xy 300.927008 -19.925538) (xy 300.919896 -19.943572) (xy 300.919896 -20.032472) (xy 300.927008 -20.050506)
			(xy 300.933612 -20.057364) (xy 300.952903 -20.078673) (xy 300.985465 -20.126039) (xy 301.010552 -20.177754)
			(xy 301.027599 -20.232647) (xy 301.036219 -20.289476) (xy 301.036216 -20.346956) (xy 301.027592 -20.403784)
			(xy 301.010541 -20.458676) (xy 301.006223 -20.467574) (xy 308.487316 -20.467574) (xy 308.491387 -20.411952)
			(xy 308.503513 -20.357515) (xy 308.523436 -20.305424) (xy 308.550732 -20.256789) (xy 308.584818 -20.212646)
			(xy 308.624967 -20.173937) (xy 308.670325 -20.141486) (xy 308.719925 -20.115985) (xy 308.772709 -20.097978)
			(xy 308.827552 -20.087848) (xy 308.883286 -20.085811) (xy 308.938723 -20.091911) (xy 308.99268 -20.106017)
			(xy 309.044009 -20.127829) (xy 309.091615 -20.156883) (xy 309.134483 -20.192558) (xy 309.1717 -20.234095)
			(xy 309.202473 -20.280608) (xy 309.226145 -20.331105) (xy 309.242213 -20.384512) (xy 309.250333 -20.439688)
			(xy 309.250842 -20.467574) (xy 309.250333 -20.49546) (xy 309.242213 -20.550636) (xy 309.226145 -20.604043)
			(xy 309.202473 -20.65454) (xy 309.1717 -20.701053) (xy 309.150127 -20.72513) (xy 315.380636 -20.72513)
			(xy 315.384606 -20.594996) (xy 315.396502 -20.465346) (xy 315.416281 -20.336663) (xy 315.443867 -20.209424)
			(xy 315.47916 -20.084105) (xy 315.522026 -19.961169) (xy 315.572308 -19.841076) (xy 315.629817 -19.724272)
			(xy 315.694341 -19.61119) (xy 315.765638 -19.502253) (xy 315.843443 -19.397865) (xy 315.927468 -19.298414)
			(xy 316.0174 -19.204271) (xy 316.112904 -19.115786) (xy 316.213624 -19.033287) (xy 316.319186 -18.957082)
			(xy 316.429198 -18.887455) (xy 316.54325 -18.824664) (xy 316.660918 -18.768942) (xy 316.781764 -18.720498)
			(xy 316.905339 -18.679511) (xy 317.031182 -18.646134) (xy 317.158827 -18.620491) (xy 317.287797 -18.602677)
			(xy 317.417613 -18.592759) (xy 317.547792 -18.590774) (xy 317.677851 -18.596728) (xy 317.807304 -18.610601)
			(xy 317.935671 -18.632339) (xy 318.062474 -18.661863) (xy 318.187241 -18.699062) (xy 318.309508 -18.743798)
			(xy 318.428821 -18.795906) (xy 318.544734 -18.855189) (xy 318.656819 -18.92143) (xy 318.764656 -18.99438)
			(xy 318.867845 -19.073768) (xy 318.966003 -19.1593) (xy 319.058764 -19.250657) (xy 319.145783 -19.347499)
			(xy 319.226736 -19.449466) (xy 319.301322 -19.556178) (xy 319.369263 -19.667239) (xy 319.430308 -19.782235)
			(xy 319.484229 -19.900739) (xy 319.530824 -20.02231) (xy 319.569922 -20.146495) (xy 319.601376 -20.272833)
			(xy 319.62507 -20.400854) (xy 319.640914 -20.53008) (xy 319.648852 -20.660033) (xy 319.649348 -20.72513)
			(xy 319.648852 -20.790227) (xy 319.640914 -20.92018) (xy 319.62507 -21.049406) (xy 319.601376 -21.177427)
			(xy 319.569922 -21.303765) (xy 319.530824 -21.42795) (xy 319.484229 -21.549521) (xy 319.430308 -21.668025)
			(xy 319.399051 -21.726906) (xy 326.273668 -21.726906) (xy 326.274204 -21.698168) (xy 326.282825 -21.641341)
			(xy 326.299873 -21.586451) (xy 326.324961 -21.534739) (xy 326.357523 -21.487376) (xy 326.376792 -21.466048)
			(xy 326.383396 -21.45919) (xy 326.390508 -21.441156) (xy 326.390508 -21.352256) (xy 326.383396 -21.334222)
			(xy 326.376792 -21.327364) (xy 326.357529 -21.306031) (xy 326.324966 -21.258669) (xy 326.299876 -21.206958)
			(xy 326.282827 -21.152068) (xy 326.274205 -21.095243) (xy 326.274204 -21.037766) (xy 326.282825 -20.98094)
			(xy 326.299873 -20.92605) (xy 326.324961 -20.874339) (xy 326.357523 -20.826975) (xy 326.376792 -20.805648)
			(xy 326.383396 -20.79879) (xy 326.390508 -20.780756) (xy 326.390508 -20.691856) (xy 326.383396 -20.673822)
			(xy 326.376792 -20.666964) (xy 326.357529 -20.645631) (xy 326.324966 -20.598269) (xy 326.299876 -20.546558)
			(xy 326.282827 -20.491668) (xy 326.274205 -20.434843) (xy 326.274204 -20.377366) (xy 326.282825 -20.32054)
			(xy 326.299873 -20.26565) (xy 326.324961 -20.213939) (xy 326.357523 -20.166575) (xy 326.376792 -20.145248)
			(xy 326.383396 -20.13839) (xy 326.390508 -20.120356) (xy 326.390508 -20.031456) (xy 326.383396 -20.013422)
			(xy 326.376792 -20.006564) (xy 326.357529 -19.985231) (xy 326.324966 -19.937869) (xy 326.299876 -19.886158)
			(xy 326.282827 -19.831268) (xy 326.274205 -19.774443) (xy 326.274204 -19.716966) (xy 326.282825 -19.66014)
			(xy 326.299873 -19.60525) (xy 326.324961 -19.553539) (xy 326.357523 -19.506175) (xy 326.376792 -19.484848)
			(xy 326.383396 -19.47799) (xy 326.390508 -19.459956) (xy 326.390508 -19.371056) (xy 326.383396 -19.353022)
			(xy 326.376792 -19.346164) (xy 326.357533 -19.324826) (xy 326.324964 -19.277468) (xy 326.299868 -19.225759)
			(xy 326.282815 -19.170871) (xy 326.27419 -19.114044) (xy 326.273668 -19.085306) (xy 326.274154 -19.058055)
			(xy 326.28191 -19.004107) (xy 326.297265 -18.951812) (xy 326.319907 -18.902235) (xy 326.349373 -18.856385)
			(xy 326.385064 -18.815194) (xy 326.426255 -18.779503) (xy 326.472105 -18.750037) (xy 326.521682 -18.727395)
			(xy 326.573977 -18.71204) (xy 326.627925 -18.704284) (xy 326.682427 -18.704284) (xy 326.736375 -18.71204)
			(xy 326.78867 -18.727395) (xy 326.838247 -18.750037) (xy 326.884097 -18.779503) (xy 326.925288 -18.815194)
			(xy 326.960979 -18.856385) (xy 326.990445 -18.902235) (xy 327.013087 -18.951812) (xy 327.028442 -19.004107)
			(xy 327.036198 -19.058055) (xy 327.036684 -19.085306) (xy 327.036141 -19.114044) (xy 327.02752 -19.170869)
			(xy 327.010473 -19.225759) (xy 326.985386 -19.277471) (xy 326.952827 -19.324835) (xy 326.93356 -19.346164)
			(xy 326.926956 -19.353022) (xy 326.919844 -19.371056) (xy 326.919844 -19.459956) (xy 326.926956 -19.47799)
			(xy 326.93356 -19.484848) (xy 326.952837 -19.506169) (xy 326.985404 -19.553532) (xy 327.010496 -19.605245)
			(xy 327.027547 -19.660137) (xy 327.036169 -19.716965) (xy 327.036168 -19.774444) (xy 327.027545 -19.831272)
			(xy 327.010493 -19.886163) (xy 326.985399 -19.937875) (xy 326.952832 -19.985238) (xy 326.93356 -20.006564)
			(xy 326.926956 -20.013422) (xy 326.919844 -20.031456) (xy 326.919844 -20.120356) (xy 326.926956 -20.13839)
			(xy 326.93356 -20.145248) (xy 326.952837 -20.166569) (xy 326.985404 -20.213932) (xy 327.010496 -20.265645)
			(xy 327.027547 -20.320537) (xy 327.036169 -20.377365) (xy 327.036168 -20.434844) (xy 327.027545 -20.491672)
			(xy 327.010493 -20.546563) (xy 326.985399 -20.598275) (xy 326.952832 -20.645638) (xy 326.93356 -20.666964)
			(xy 326.926956 -20.673822) (xy 326.919844 -20.691856) (xy 326.919844 -20.72513) (xy 353.480636 -20.72513)
			(xy 353.484606 -20.594996) (xy 353.496502 -20.465346) (xy 353.516281 -20.336663) (xy 353.543867 -20.209424)
			(xy 353.57916 -20.084105) (xy 353.622026 -19.961169) (xy 353.672308 -19.841076) (xy 353.729817 -19.724272)
			(xy 353.794341 -19.61119) (xy 353.865638 -19.502253) (xy 353.943443 -19.397865) (xy 354.027468 -19.298414)
			(xy 354.1174 -19.204271) (xy 354.212904 -19.115786) (xy 354.313624 -19.033287) (xy 354.419186 -18.957082)
			(xy 354.529198 -18.887455) (xy 354.64325 -18.824664) (xy 354.760918 -18.768942) (xy 354.881764 -18.720498)
			(xy 355.005339 -18.679511) (xy 355.131182 -18.646134) (xy 355.258827 -18.620491) (xy 355.387797 -18.602677)
			(xy 355.517613 -18.592759) (xy 355.647792 -18.590774) (xy 355.777851 -18.596728) (xy 355.907304 -18.610601)
			(xy 356.035671 -18.632339) (xy 356.162474 -18.661863) (xy 356.287241 -18.699062) (xy 356.409508 -18.743798)
			(xy 356.528821 -18.795906) (xy 356.644734 -18.855189) (xy 356.756819 -18.92143) (xy 356.864656 -18.99438)
			(xy 356.967845 -19.073768) (xy 357.066003 -19.1593) (xy 357.158764 -19.250657) (xy 357.245783 -19.347499)
			(xy 357.326736 -19.449466) (xy 357.401322 -19.556178) (xy 357.469263 -19.667239) (xy 357.530308 -19.782235)
			(xy 357.584229 -19.900739) (xy 357.630824 -20.02231) (xy 357.669922 -20.146495) (xy 357.701376 -20.272833)
			(xy 357.72507 -20.400854) (xy 357.740914 -20.53008) (xy 357.748852 -20.660033) (xy 357.749348 -20.72513)
			(xy 357.748852 -20.790227) (xy 357.740914 -20.92018) (xy 357.72507 -21.049406) (xy 357.701376 -21.177427)
			(xy 357.669922 -21.303765) (xy 357.630824 -21.42795) (xy 357.584229 -21.549521) (xy 357.543505 -21.639022)
			(xy 364.373922 -21.639022) (xy 364.37448 -21.610285) (xy 364.383097 -21.55346) (xy 364.400141 -21.49857)
			(xy 364.425224 -21.446858) (xy 364.45778 -21.399493) (xy 364.477046 -21.378164) (xy 364.48365 -21.371306)
			(xy 364.490762 -21.353272) (xy 364.490762 -21.264372) (xy 364.48365 -21.246338) (xy 364.477046 -21.23948)
			(xy 364.457796 -21.218135) (xy 364.425228 -21.170776) (xy 364.400134 -21.119068) (xy 364.383081 -21.064179)
			(xy 364.374456 -21.007354) (xy 364.374454 -20.949878) (xy 364.383074 -20.893052) (xy 364.400122 -20.838162)
			(xy 364.425212 -20.786452) (xy 364.457776 -20.73909) (xy 364.477046 -20.717764) (xy 364.48365 -20.710906)
			(xy 364.490762 -20.692872) (xy 364.490762 -20.603972) (xy 364.48365 -20.585938) (xy 364.477046 -20.57908)
			(xy 364.457796 -20.557735) (xy 364.425228 -20.510376) (xy 364.400134 -20.458668) (xy 364.383081 -20.403779)
			(xy 364.374456 -20.346954) (xy 364.374454 -20.289478) (xy 364.383074 -20.232652) (xy 364.400122 -20.177762)
			(xy 364.425212 -20.126052) (xy 364.457776 -20.07869) (xy 364.477046 -20.057364) (xy 364.48365 -20.050506)
			(xy 364.490762 -20.032472) (xy 364.490762 -19.943572) (xy 364.48365 -19.925538) (xy 364.477046 -19.91868)
			(xy 364.457796 -19.897335) (xy 364.425228 -19.849976) (xy 364.400134 -19.798268) (xy 364.383081 -19.743379)
			(xy 364.374456 -19.686554) (xy 364.374454 -19.629078) (xy 364.383074 -19.572252) (xy 364.400122 -19.517362)
			(xy 364.425212 -19.465652) (xy 364.457776 -19.41829) (xy 364.477046 -19.396964) (xy 364.48365 -19.390106)
			(xy 364.490762 -19.372072) (xy 364.490762 -19.283172) (xy 364.48365 -19.265138) (xy 364.477046 -19.25828)
			(xy 364.457787 -19.236943) (xy 364.425219 -19.189584) (xy 364.400124 -19.137875) (xy 364.383071 -19.082986)
			(xy 364.374445 -19.02616) (xy 364.373922 -18.997422) (xy 364.374408 -18.970171) (xy 364.382164 -18.916223)
			(xy 364.397519 -18.863928) (xy 364.420161 -18.814351) (xy 364.449627 -18.768501) (xy 364.485318 -18.72731)
			(xy 364.526509 -18.691619) (xy 364.572359 -18.662153) (xy 364.621936 -18.639511) (xy 364.674231 -18.624156)
			(xy 364.728179 -18.6164) (xy 364.782681 -18.6164) (xy 364.836629 -18.624156) (xy 364.888924 -18.639511)
			(xy 364.938501 -18.662153) (xy 364.984351 -18.691619) (xy 365.025542 -18.72731) (xy 365.061233 -18.768501)
			(xy 365.090699 -18.814351) (xy 365.113341 -18.863928) (xy 365.128696 -18.916223) (xy 365.136452 -18.970171)
			(xy 365.136938 -18.997422) (xy 365.136417 -19.026161) (xy 365.127793 -19.082988) (xy 365.110741 -19.137878)
			(xy 365.085649 -19.18959) (xy 365.053084 -19.236953) (xy 365.033814 -19.25828) (xy 365.02721 -19.265138)
			(xy 365.020098 -19.283172) (xy 365.020098 -19.372072) (xy 365.02721 -19.390106) (xy 365.033814 -19.396964)
			(xy 365.053105 -19.418273) (xy 365.077045 -19.453098) (xy 370.576346 -19.453098) (xy 370.580417 -19.397476)
			(xy 370.592543 -19.343039) (xy 370.612466 -19.290948) (xy 370.639762 -19.242313) (xy 370.673848 -19.19817)
			(xy 370.713997 -19.159461) (xy 370.759355 -19.12701) (xy 370.808955 -19.101509) (xy 370.861739 -19.083502)
			(xy 370.916582 -19.073372) (xy 370.972316 -19.071335) (xy 371.027753 -19.077435) (xy 371.08171 -19.091541)
			(xy 371.133039 -19.113353) (xy 371.180645 -19.142407) (xy 371.223513 -19.178082) (xy 371.26073 -19.219619)
			(xy 371.291503 -19.266132) (xy 371.315175 -19.316629) (xy 371.331243 -19.370036) (xy 371.339363 -19.425212)
			(xy 371.339872 -19.453098) (xy 371.339363 -19.480984) (xy 371.331243 -19.53616) (xy 371.315175 -19.589567)
			(xy 371.291503 -19.640064) (xy 371.26073 -19.686577) (xy 371.223513 -19.728114) (xy 371.180645 -19.763789)
			(xy 371.133039 -19.792843) (xy 371.08171 -19.814655) (xy 371.027753 -19.828761) (xy 370.972316 -19.834861)
			(xy 370.916582 -19.832824) (xy 370.861739 -19.822694) (xy 370.808955 -19.804687) (xy 370.759355 -19.779186)
			(xy 370.713997 -19.746735) (xy 370.673848 -19.708026) (xy 370.639762 -19.663883) (xy 370.612466 -19.615248)
			(xy 370.592543 -19.563157) (xy 370.580417 -19.50872) (xy 370.576346 -19.453098) (xy 365.077045 -19.453098)
			(xy 365.085666 -19.465639) (xy 365.110754 -19.517354) (xy 365.127801 -19.572247) (xy 365.13642 -19.629077)
			(xy 365.136418 -19.686556) (xy 365.127793 -19.743384) (xy 365.110742 -19.798276) (xy 365.08565 -19.849988)
			(xy 365.053085 -19.897352) (xy 365.033814 -19.91868) (xy 365.02721 -19.925538) (xy 365.020098 -19.943572)
			(xy 365.020098 -20.032472) (xy 365.02721 -20.050506) (xy 365.033814 -20.057364) (xy 365.053105 -20.078673)
			(xy 365.085666 -20.126039) (xy 365.110754 -20.177754) (xy 365.127801 -20.232647) (xy 365.13642 -20.289477)
			(xy 365.136418 -20.346956) (xy 365.127793 -20.403784) (xy 365.110742 -20.458676) (xy 365.106424 -20.467574)
			(xy 372.587518 -20.467574) (xy 372.591589 -20.411952) (xy 372.603715 -20.357515) (xy 372.623638 -20.305424)
			(xy 372.650934 -20.256789) (xy 372.68502 -20.212646) (xy 372.725169 -20.173937) (xy 372.770527 -20.141486)
			(xy 372.820127 -20.115985) (xy 372.872911 -20.097978) (xy 372.927754 -20.087848) (xy 372.983488 -20.085811)
			(xy 373.038925 -20.091911) (xy 373.092882 -20.106017) (xy 373.144211 -20.127829) (xy 373.191817 -20.156883)
			(xy 373.234685 -20.192558) (xy 373.271902 -20.234095) (xy 373.302675 -20.280608) (xy 373.326347 -20.331105)
			(xy 373.342415 -20.384512) (xy 373.350535 -20.439688) (xy 373.351044 -20.467574) (xy 373.350535 -20.49546)
			(xy 373.342415 -20.550636) (xy 373.326347 -20.604043) (xy 373.302675 -20.65454) (xy 373.271902 -20.701053)
			(xy 373.254881 -20.72005) (xy 379.48541 -20.72005) (xy 379.48938 -20.589916) (xy 379.501276 -20.460266)
			(xy 379.521055 -20.331583) (xy 379.548641 -20.204344) (xy 379.583934 -20.079025) (xy 379.6268 -19.956089)
			(xy 379.677082 -19.835996) (xy 379.734591 -19.719192) (xy 379.799115 -19.60611) (xy 379.870412 -19.497173)
			(xy 379.948217 -19.392785) (xy 380.032242 -19.293334) (xy 380.122174 -19.199191) (xy 380.217678 -19.110706)
			(xy 380.318398 -19.028207) (xy 380.42396 -18.952002) (xy 380.533972 -18.882375) (xy 380.648024 -18.819584)
			(xy 380.765692 -18.763862) (xy 380.886538 -18.715418) (xy 381.010113 -18.674431) (xy 381.135956 -18.641054)
			(xy 381.263601 -18.615411) (xy 381.392571 -18.597597) (xy 381.522387 -18.587679) (xy 381.652566 -18.585694)
			(xy 381.782625 -18.591648) (xy 381.912078 -18.605521) (xy 382.040445 -18.627259) (xy 382.167248 -18.656783)
			(xy 382.292015 -18.693982) (xy 382.414282 -18.738718) (xy 382.533595 -18.790826) (xy 382.649508 -18.850109)
			(xy 382.761593 -18.91635) (xy 382.86943 -18.9893) (xy 382.972619 -19.068688) (xy 383.070777 -19.15422)
			(xy 383.163538 -19.245577) (xy 383.250557 -19.342419) (xy 383.33151 -19.444386) (xy 383.406096 -19.551098)
			(xy 383.474037 -19.662159) (xy 383.535082 -19.777155) (xy 383.589003 -19.895659) (xy 383.635598 -20.01723)
			(xy 383.674696 -20.141415) (xy 383.70615 -20.267753) (xy 383.729844 -20.395774) (xy 383.745688 -20.525)
			(xy 383.753626 -20.654953) (xy 383.754122 -20.72005) (xy 383.753626 -20.785147) (xy 383.745688 -20.9151)
			(xy 383.729844 -21.044326) (xy 383.70615 -21.172347) (xy 383.674696 -21.298685) (xy 383.635598 -21.42287)
			(xy 383.589003 -21.544441) (xy 383.535082 -21.662945) (xy 383.501129 -21.726906) (xy 390.37387 -21.726906)
			(xy 390.374405 -21.698168) (xy 390.383026 -21.641341) (xy 390.400074 -21.586451) (xy 390.425163 -21.534739)
			(xy 390.457725 -21.487376) (xy 390.476994 -21.466048) (xy 390.483598 -21.45919) (xy 390.49071 -21.441156)
			(xy 390.49071 -21.352256) (xy 390.483598 -21.334222) (xy 390.476994 -21.327364) (xy 390.45773 -21.306031)
			(xy 390.425168 -21.258669) (xy 390.400078 -21.206958) (xy 390.383029 -21.152068) (xy 390.374406 -21.095243)
			(xy 390.374406 -21.037766) (xy 390.383027 -20.98094) (xy 390.400074 -20.92605) (xy 390.425163 -20.874339)
			(xy 390.457725 -20.826975) (xy 390.476994 -20.805648) (xy 390.483598 -20.79879) (xy 390.49071 -20.780756)
			(xy 390.49071 -20.691856) (xy 390.483598 -20.673822) (xy 390.476994 -20.666964) (xy 390.45773 -20.645631)
			(xy 390.425168 -20.598269) (xy 390.400078 -20.546558) (xy 390.383029 -20.491668) (xy 390.374406 -20.434843)
			(xy 390.374406 -20.377366) (xy 390.383027 -20.32054) (xy 390.400074 -20.26565) (xy 390.425163 -20.213939)
			(xy 390.457725 -20.166575) (xy 390.476994 -20.145248) (xy 390.483598 -20.13839) (xy 390.49071 -20.120356)
			(xy 390.49071 -20.031456) (xy 390.483598 -20.013422) (xy 390.476994 -20.006564) (xy 390.45773 -19.985231)
			(xy 390.425168 -19.937869) (xy 390.400078 -19.886158) (xy 390.383029 -19.831268) (xy 390.374406 -19.774443)
			(xy 390.374406 -19.716966) (xy 390.383027 -19.66014) (xy 390.400074 -19.60525) (xy 390.425163 -19.553539)
			(xy 390.457725 -19.506175) (xy 390.476994 -19.484848) (xy 390.483598 -19.47799) (xy 390.49071 -19.459956)
			(xy 390.49071 -19.371056) (xy 390.483598 -19.353022) (xy 390.476994 -19.346164) (xy 390.457736 -19.324826)
			(xy 390.425166 -19.277468) (xy 390.40007 -19.225759) (xy 390.383017 -19.17087) (xy 390.374392 -19.114044)
			(xy 390.37387 -19.085306) (xy 390.374356 -19.058055) (xy 390.382112 -19.004107) (xy 390.397467 -18.951812)
			(xy 390.420109 -18.902235) (xy 390.449575 -18.856385) (xy 390.485266 -18.815194) (xy 390.526457 -18.779503)
			(xy 390.572307 -18.750037) (xy 390.621884 -18.727395) (xy 390.674179 -18.71204) (xy 390.728127 -18.704284)
			(xy 390.782629 -18.704284) (xy 390.836577 -18.71204) (xy 390.888872 -18.727395) (xy 390.938449 -18.750037)
			(xy 390.984299 -18.779503) (xy 391.02549 -18.815194) (xy 391.061181 -18.856385) (xy 391.090647 -18.902235)
			(xy 391.113289 -18.951812) (xy 391.128644 -19.004107) (xy 391.1364 -19.058055) (xy 391.136886 -19.085306)
			(xy 391.136343 -19.114044) (xy 391.127722 -19.170869) (xy 391.110675 -19.225759) (xy 391.085588 -19.277471)
			(xy 391.053029 -19.324835) (xy 391.033762 -19.346164) (xy 391.027158 -19.353022) (xy 391.020046 -19.371056)
			(xy 391.020046 -19.453098) (xy 396.576294 -19.453098) (xy 396.580365 -19.397476) (xy 396.592491 -19.343039)
			(xy 396.612414 -19.290948) (xy 396.63971 -19.242313) (xy 396.673796 -19.19817) (xy 396.713945 -19.159461)
			(xy 396.759303 -19.12701) (xy 396.808903 -19.101509) (xy 396.861687 -19.083502) (xy 396.91653 -19.073372)
			(xy 396.972264 -19.071335) (xy 397.027701 -19.077435) (xy 397.081658 -19.091541) (xy 397.132987 -19.113353)
			(xy 397.180593 -19.142407) (xy 397.223461 -19.178082) (xy 397.260678 -19.219619) (xy 397.291451 -19.266132)
			(xy 397.315123 -19.316629) (xy 397.331191 -19.370036) (xy 397.339311 -19.425212) (xy 397.33982 -19.453098)
			(xy 397.339311 -19.480984) (xy 397.331191 -19.53616) (xy 397.315123 -19.589567) (xy 397.291451 -19.640064)
			(xy 397.260678 -19.686577) (xy 397.223461 -19.728114) (xy 397.180593 -19.763789) (xy 397.132987 -19.792843)
			(xy 397.081658 -19.814655) (xy 397.027701 -19.828761) (xy 396.972264 -19.834861) (xy 396.91653 -19.832824)
			(xy 396.861687 -19.822694) (xy 396.808903 -19.804687) (xy 396.759303 -19.779186) (xy 396.713945 -19.746735)
			(xy 396.673796 -19.708026) (xy 396.63971 -19.663883) (xy 396.612414 -19.615248) (xy 396.592491 -19.563157)
			(xy 396.580365 -19.50872) (xy 396.576294 -19.453098) (xy 391.020046 -19.453098) (xy 391.020046 -19.459956)
			(xy 391.027158 -19.47799) (xy 391.033762 -19.484848) (xy 391.053039 -19.506169) (xy 391.085606 -19.553532)
			(xy 391.110698 -19.605245) (xy 391.127748 -19.660137) (xy 391.13637 -19.716965) (xy 391.13637 -19.774444)
			(xy 391.127746 -19.831272) (xy 391.110695 -19.886163) (xy 391.085601 -19.937875) (xy 391.053034 -19.985238)
			(xy 391.033762 -20.006564) (xy 391.027158 -20.013422) (xy 391.020046 -20.031456) (xy 391.020046 -20.120356)
			(xy 391.027158 -20.13839) (xy 391.033762 -20.145248) (xy 391.053039 -20.166569) (xy 391.085606 -20.213932)
			(xy 391.110698 -20.265645) (xy 391.127748 -20.320537) (xy 391.13637 -20.377365) (xy 391.13637 -20.434844)
			(xy 391.131403 -20.467574) (xy 398.587466 -20.467574) (xy 398.591537 -20.411952) (xy 398.603663 -20.357515)
			(xy 398.623586 -20.305424) (xy 398.650882 -20.256789) (xy 398.684968 -20.212646) (xy 398.725117 -20.173937)
			(xy 398.770475 -20.141486) (xy 398.820075 -20.115985) (xy 398.872859 -20.097978) (xy 398.927702 -20.087848)
			(xy 398.983436 -20.085811) (xy 399.038873 -20.091911) (xy 399.09283 -20.106017) (xy 399.144159 -20.127829)
			(xy 399.191765 -20.156883) (xy 399.234633 -20.192558) (xy 399.27185 -20.234095) (xy 399.302623 -20.280608)
			(xy 399.326295 -20.331105) (xy 399.342363 -20.384512) (xy 399.350483 -20.439688) (xy 399.350992 -20.467574)
			(xy 399.350483 -20.49546) (xy 399.342363 -20.550636) (xy 399.326295 -20.604043) (xy 399.302623 -20.65454)
			(xy 399.27185 -20.701053) (xy 399.250277 -20.72513) (xy 405.480532 -20.72513) (xy 405.484502 -20.594996)
			(xy 405.496398 -20.465346) (xy 405.516177 -20.336663) (xy 405.543763 -20.209424) (xy 405.579056 -20.084105)
			(xy 405.621922 -19.961169) (xy 405.672204 -19.841076) (xy 405.729713 -19.724272) (xy 405.794237 -19.61119)
			(xy 405.865534 -19.502253) (xy 405.943339 -19.397865) (xy 406.027364 -19.298414) (xy 406.117296 -19.204271)
			(xy 406.2128 -19.115786) (xy 406.31352 -19.033287) (xy 406.419082 -18.957082) (xy 406.529094 -18.887455)
			(xy 406.643146 -18.824664) (xy 406.760814 -18.768942) (xy 406.88166 -18.720498) (xy 407.005235 -18.679511)
			(xy 407.131078 -18.646134) (xy 407.258723 -18.620491) (xy 407.387693 -18.602677) (xy 407.517509 -18.592759)
			(xy 407.647688 -18.590774) (xy 407.777747 -18.596728) (xy 407.9072 -18.610601) (xy 408.035567 -18.632339)
			(xy 408.16237 -18.661863) (xy 408.287137 -18.699062) (xy 408.409404 -18.743798) (xy 408.528717 -18.795906)
			(xy 408.64463 -18.855189) (xy 408.756715 -18.92143) (xy 408.864552 -18.99438) (xy 408.967741 -19.073768)
			(xy 409.065899 -19.1593) (xy 409.15866 -19.250657) (xy 409.245679 -19.347499) (xy 409.326632 -19.449466)
			(xy 409.401218 -19.556178) (xy 409.469159 -19.667239) (xy 409.530204 -19.782235) (xy 409.584125 -19.900739)
			(xy 409.63072 -20.02231) (xy 409.669818 -20.146495) (xy 409.701272 -20.272833) (xy 409.724966 -20.400854)
			(xy 409.74081 -20.53008) (xy 409.748748 -20.660033) (xy 409.749244 -20.72513) (xy 409.748748 -20.790227)
			(xy 409.74081 -20.92018) (xy 409.724966 -21.049406) (xy 409.701272 -21.177427) (xy 409.669818 -21.303765)
			(xy 409.63072 -21.42795) (xy 409.584125 -21.549521) (xy 409.530204 -21.668025) (xy 409.498947 -21.726906)
			(xy 416.373818 -21.726906) (xy 416.374367 -21.698168) (xy 416.382987 -21.641343) (xy 416.400032 -21.586453)
			(xy 416.425118 -21.534741) (xy 416.457675 -21.487377) (xy 416.476942 -21.466048) (xy 416.483546 -21.45919)
			(xy 416.490658 -21.441156) (xy 416.490658 -21.352256) (xy 416.483546 -21.334222) (xy 416.476942 -21.327364)
			(xy 416.457676 -21.306032) (xy 416.425109 -21.258671) (xy 416.400016 -21.20696) (xy 416.382965 -21.15207)
			(xy 416.374341 -21.095243) (xy 416.374341 -21.037766) (xy 416.382963 -20.980938) (xy 416.400013 -20.926048)
			(xy 416.425105 -20.874336) (xy 416.457671 -20.826974) (xy 416.476942 -20.805648) (xy 416.483546 -20.79879)
			(xy 416.490658 -20.780756) (xy 416.490658 -20.691856) (xy 416.483546 -20.673822) (xy 416.476942 -20.666964)
			(xy 416.457676 -20.645632) (xy 416.425109 -20.598271) (xy 416.400016 -20.54656) (xy 416.382965 -20.49167)
			(xy 416.374341 -20.434843) (xy 416.374341 -20.377366) (xy 416.382963 -20.320538) (xy 416.400013 -20.265648)
			(xy 416.425105 -20.213936) (xy 416.457671 -20.166574) (xy 416.476942 -20.145248) (xy 416.483546 -20.13839)
			(xy 416.490658 -20.120356) (xy 416.490658 -20.031456) (xy 416.483546 -20.013422) (xy 416.476942 -20.006564)
			(xy 416.457676 -19.985232) (xy 416.425109 -19.937871) (xy 416.400016 -19.88616) (xy 416.382965 -19.83127)
			(xy 416.374341 -19.774443) (xy 416.374341 -19.716966) (xy 416.382963 -19.660138) (xy 416.400013 -19.605248)
			(xy 416.425105 -19.553536) (xy 416.457671 -19.506174) (xy 416.476942 -19.484848) (xy 416.483546 -19.47799)
			(xy 416.490658 -19.459956) (xy 416.490658 -19.371056) (xy 416.483546 -19.353022) (xy 416.476942 -19.346164)
			(xy 416.457675 -19.324834) (xy 416.425108 -19.277473) (xy 416.400015 -19.225762) (xy 416.382963 -19.170872)
			(xy 416.374339 -19.114045) (xy 416.373818 -19.085306) (xy 416.374304 -19.058055) (xy 416.38206 -19.004107)
			(xy 416.397415 -18.951812) (xy 416.420057 -18.902235) (xy 416.449523 -18.856385) (xy 416.485214 -18.815194)
			(xy 416.526405 -18.779503) (xy 416.572255 -18.750037) (xy 416.621832 -18.727395) (xy 416.674127 -18.71204)
			(xy 416.728075 -18.704284) (xy 416.782577 -18.704284) (xy 416.836525 -18.71204) (xy 416.88882 -18.727395)
			(xy 416.938397 -18.750037) (xy 416.984247 -18.779503) (xy 417.025438 -18.815194) (xy 417.061129 -18.856385)
			(xy 417.090595 -18.902235) (xy 417.113237 -18.951812) (xy 417.128592 -19.004107) (xy 417.136348 -19.058055)
			(xy 417.136834 -19.085306) (xy 417.136305 -19.114045) (xy 417.127682 -19.170871) (xy 417.110633 -19.225762)
			(xy 417.085543 -19.277473) (xy 417.05298 -19.324837) (xy 417.03371 -19.346164) (xy 417.027106 -19.353022)
			(xy 417.019994 -19.371056) (xy 417.019994 -19.453098) (xy 422.576242 -19.453098) (xy 422.580313 -19.397476)
			(xy 422.592439 -19.343039) (xy 422.612362 -19.290948) (xy 422.639658 -19.242313) (xy 422.673744 -19.19817)
			(xy 422.713893 -19.159461) (xy 422.759251 -19.12701) (xy 422.808851 -19.101509) (xy 422.861635 -19.083502)
			(xy 422.916478 -19.073372) (xy 422.972212 -19.071335) (xy 423.027649 -19.077435) (xy 423.081606 -19.091541)
			(xy 423.132935 -19.113353) (xy 423.180541 -19.142407) (xy 423.223409 -19.178082) (xy 423.260626 -19.219619)
			(xy 423.291399 -19.266132) (xy 423.315071 -19.316629) (xy 423.331139 -19.370036) (xy 423.339259 -19.425212)
			(xy 423.339768 -19.453098) (xy 423.339259 -19.480984) (xy 423.331139 -19.53616) (xy 423.315071 -19.589567)
			(xy 423.291399 -19.640064) (xy 423.260626 -19.686577) (xy 423.223409 -19.728114) (xy 423.180541 -19.763789)
			(xy 423.132935 -19.792843) (xy 423.081606 -19.814655) (xy 423.027649 -19.828761) (xy 422.972212 -19.834861)
			(xy 422.916478 -19.832824) (xy 422.861635 -19.822694) (xy 422.808851 -19.804687) (xy 422.759251 -19.779186)
			(xy 422.713893 -19.746735) (xy 422.673744 -19.708026) (xy 422.639658 -19.663883) (xy 422.612362 -19.615248)
			(xy 422.592439 -19.563157) (xy 422.580313 -19.50872) (xy 422.576242 -19.453098) (xy 417.019994 -19.453098)
			(xy 417.019994 -19.459956) (xy 417.027106 -19.47799) (xy 417.03371 -19.484848) (xy 417.052985 -19.50617)
			(xy 417.085547 -19.553535) (xy 417.110636 -19.605247) (xy 417.127684 -19.660138) (xy 417.136306 -19.716966)
			(xy 417.136305 -19.774443) (xy 417.127682 -19.83127) (xy 417.110633 -19.886161) (xy 417.085543 -19.937873)
			(xy 417.05298 -19.985236) (xy 417.03371 -20.006564) (xy 417.027106 -20.013422) (xy 417.019994 -20.031456)
			(xy 417.019994 -20.120356) (xy 417.027106 -20.13839) (xy 417.03371 -20.145248) (xy 417.052985 -20.16657)
			(xy 417.085547 -20.213935) (xy 417.110636 -20.265647) (xy 417.127684 -20.320538) (xy 417.136306 -20.377366)
			(xy 417.136305 -20.434843) (xy 417.131338 -20.467574) (xy 424.587414 -20.467574) (xy 424.591485 -20.411952)
			(xy 424.603611 -20.357515) (xy 424.623534 -20.305424) (xy 424.65083 -20.256789) (xy 424.684916 -20.212646)
			(xy 424.725065 -20.173937) (xy 424.770423 -20.141486) (xy 424.820023 -20.115985) (xy 424.872807 -20.097978)
			(xy 424.92765 -20.087848) (xy 424.983384 -20.085811) (xy 425.038821 -20.091911) (xy 425.092778 -20.106017)
			(xy 425.144107 -20.127829) (xy 425.191713 -20.156883) (xy 425.234581 -20.192558) (xy 425.271798 -20.234095)
			(xy 425.302571 -20.280608) (xy 425.326243 -20.331105) (xy 425.342311 -20.384512) (xy 425.350431 -20.439688)
			(xy 425.35094 -20.467574) (xy 425.350431 -20.49546) (xy 425.342311 -20.550636) (xy 425.326243 -20.604043)
			(xy 425.302571 -20.65454) (xy 425.271798 -20.701053) (xy 425.250225 -20.72513) (xy 431.48048 -20.72513)
			(xy 431.48445 -20.594996) (xy 431.496346 -20.465346) (xy 431.516125 -20.336663) (xy 431.543711 -20.209424)
			(xy 431.579004 -20.084105) (xy 431.62187 -19.961169) (xy 431.672152 -19.841076) (xy 431.729661 -19.724272)
			(xy 431.794185 -19.61119) (xy 431.865482 -19.502253) (xy 431.943287 -19.397865) (xy 432.027312 -19.298414)
			(xy 432.117244 -19.204271) (xy 432.212748 -19.115786) (xy 432.313468 -19.033287) (xy 432.41903 -18.957082)
			(xy 432.529042 -18.887455) (xy 432.643094 -18.824664) (xy 432.760762 -18.768942) (xy 432.881608 -18.720498)
			(xy 433.005183 -18.679511) (xy 433.131026 -18.646134) (xy 433.258671 -18.620491) (xy 433.387641 -18.602677)
			(xy 433.517457 -18.592759) (xy 433.647636 -18.590774) (xy 433.777695 -18.596728) (xy 433.907148 -18.610601)
			(xy 434.035515 -18.632339) (xy 434.162318 -18.661863) (xy 434.287085 -18.699062) (xy 434.409352 -18.743798)
			(xy 434.528665 -18.795906) (xy 434.644578 -18.855189) (xy 434.756663 -18.92143) (xy 434.8645 -18.99438)
			(xy 434.967689 -19.073768) (xy 435.065847 -19.1593) (xy 435.158608 -19.250657) (xy 435.245627 -19.347499)
			(xy 435.32658 -19.449466) (xy 435.401166 -19.556178) (xy 435.469107 -19.667239) (xy 435.530152 -19.782235)
			(xy 435.584073 -19.900739) (xy 435.630668 -20.02231) (xy 435.669766 -20.146495) (xy 435.70122 -20.272833)
			(xy 435.724914 -20.400854) (xy 435.740758 -20.53008) (xy 435.748696 -20.660033) (xy 435.749192 -20.72513)
			(xy 435.748696 -20.790227) (xy 435.740758 -20.92018) (xy 435.724914 -21.049406) (xy 435.70122 -21.177427)
			(xy 435.669766 -21.303765) (xy 435.630668 -21.42795) (xy 435.584073 -21.549521) (xy 435.530152 -21.668025)
			(xy 435.498895 -21.726906) (xy 442.373766 -21.726906) (xy 442.374302 -21.698168) (xy 442.382923 -21.641341)
			(xy 442.399971 -21.586451) (xy 442.425059 -21.534739) (xy 442.457621 -21.487376) (xy 442.47689 -21.466048)
			(xy 442.483494 -21.45919) (xy 442.490606 -21.441156) (xy 442.490606 -21.352256) (xy 442.483494 -21.334222)
			(xy 442.47689 -21.327364) (xy 442.457627 -21.306031) (xy 442.425064 -21.258669) (xy 442.399974 -21.206958)
			(xy 442.382926 -21.152068) (xy 442.374303 -21.095243) (xy 442.374303 -21.037766) (xy 442.382924 -20.98094)
			(xy 442.399971 -20.92605) (xy 442.42506 -20.874339) (xy 442.457621 -20.826976) (xy 442.47689 -20.805648)
			(xy 442.483494 -20.79879) (xy 442.490606 -20.780756) (xy 442.490606 -20.691856) (xy 442.483494 -20.673822)
			(xy 442.47689 -20.666964) (xy 442.457627 -20.645631) (xy 442.425064 -20.598269) (xy 442.399974 -20.546558)
			(xy 442.382926 -20.491668) (xy 442.374303 -20.434843) (xy 442.374303 -20.377366) (xy 442.382924 -20.32054)
			(xy 442.399971 -20.26565) (xy 442.42506 -20.213939) (xy 442.457621 -20.166576) (xy 442.47689 -20.145248)
			(xy 442.483494 -20.13839) (xy 442.490606 -20.120356) (xy 442.490606 -20.031456) (xy 442.483494 -20.013422)
			(xy 442.47689 -20.006564) (xy 442.457627 -19.985231) (xy 442.425064 -19.937869) (xy 442.399974 -19.886158)
			(xy 442.382926 -19.831268) (xy 442.374303 -19.774443) (xy 442.374303 -19.716966) (xy 442.382924 -19.66014)
			(xy 442.399971 -19.60525) (xy 442.42506 -19.553539) (xy 442.457621 -19.506176) (xy 442.47689 -19.484848)
			(xy 442.483494 -19.47799) (xy 442.490606 -19.459956) (xy 442.490606 -19.371056) (xy 442.483494 -19.353022)
			(xy 442.47689 -19.346164) (xy 442.457631 -19.324827) (xy 442.425061 -19.277468) (xy 442.399966 -19.225759)
			(xy 442.382913 -19.170871) (xy 442.374288 -19.114044) (xy 442.373766 -19.085306) (xy 442.374252 -19.058055)
			(xy 442.382008 -19.004107) (xy 442.397363 -18.951812) (xy 442.420005 -18.902235) (xy 442.449471 -18.856385)
			(xy 442.485162 -18.815194) (xy 442.526353 -18.779503) (xy 442.572203 -18.750037) (xy 442.62178 -18.727395)
			(xy 442.674075 -18.71204) (xy 442.728023 -18.704284) (xy 442.782525 -18.704284) (xy 442.836473 -18.71204)
			(xy 442.888768 -18.727395) (xy 442.938345 -18.750037) (xy 442.984195 -18.779503) (xy 443.025386 -18.815194)
			(xy 443.061077 -18.856385) (xy 443.090543 -18.902235) (xy 443.113185 -18.951812) (xy 443.12854 -19.004107)
			(xy 443.136296 -19.058055) (xy 443.136782 -19.085306) (xy 443.13624 -19.114044) (xy 443.127619 -19.17087)
			(xy 443.110572 -19.225759) (xy 443.085485 -19.277471) (xy 443.052925 -19.324835) (xy 443.033658 -19.346164)
			(xy 443.027054 -19.353022) (xy 443.019942 -19.371056) (xy 443.019942 -19.453098) (xy 448.57619 -19.453098)
			(xy 448.580261 -19.397476) (xy 448.592387 -19.343039) (xy 448.61231 -19.290948) (xy 448.639606 -19.242313)
			(xy 448.673692 -19.19817) (xy 448.713841 -19.159461) (xy 448.759199 -19.12701) (xy 448.808799 -19.101509)
			(xy 448.861583 -19.083502) (xy 448.916426 -19.073372) (xy 448.97216 -19.071335) (xy 449.027597 -19.077435)
			(xy 449.081554 -19.091541) (xy 449.132883 -19.113353) (xy 449.180489 -19.142407) (xy 449.223357 -19.178082)
			(xy 449.260574 -19.219619) (xy 449.291347 -19.266132) (xy 449.315019 -19.316629) (xy 449.331087 -19.370036)
			(xy 449.339207 -19.425212) (xy 449.339716 -19.453098) (xy 449.339207 -19.480984) (xy 449.331087 -19.53616)
			(xy 449.315019 -19.589567) (xy 449.294572 -19.633184) (xy 454.554334 -19.633184) (xy 454.558405 -19.577562)
			(xy 454.570531 -19.523125) (xy 454.590454 -19.471034) (xy 454.61775 -19.422399) (xy 454.651836 -19.378256)
			(xy 454.691985 -19.339547) (xy 454.737343 -19.307096) (xy 454.786943 -19.281595) (xy 454.839727 -19.263588)
			(xy 454.89457 -19.253458) (xy 454.950304 -19.251421) (xy 455.005741 -19.257521) (xy 455.059698 -19.271627)
			(xy 455.111027 -19.293439) (xy 455.158633 -19.322493) (xy 455.201501 -19.358168) (xy 455.238718 -19.399705)
			(xy 455.269491 -19.446218) (xy 455.293163 -19.496715) (xy 455.309231 -19.550122) (xy 455.317351 -19.605298)
			(xy 455.31786 -19.633184) (xy 455.317351 -19.66107) (xy 455.309231 -19.716246) (xy 455.293163 -19.769653)
			(xy 455.269491 -19.82015) (xy 455.238718 -19.866663) (xy 455.201501 -19.9082) (xy 455.158633 -19.943875)
			(xy 455.111027 -19.972929) (xy 455.059698 -19.994741) (xy 455.005741 -20.008847) (xy 454.950304 -20.014947)
			(xy 454.89457 -20.01291) (xy 454.839727 -20.00278) (xy 454.786943 -19.984773) (xy 454.737343 -19.959272)
			(xy 454.691985 -19.926821) (xy 454.651836 -19.888112) (xy 454.61775 -19.843969) (xy 454.590454 -19.795334)
			(xy 454.570531 -19.743243) (xy 454.558405 -19.688806) (xy 454.554334 -19.633184) (xy 449.294572 -19.633184)
			(xy 449.291347 -19.640064) (xy 449.260574 -19.686577) (xy 449.223357 -19.728114) (xy 449.180489 -19.763789)
			(xy 449.132883 -19.792843) (xy 449.081554 -19.814655) (xy 449.027597 -19.828761) (xy 448.97216 -19.834861)
			(xy 448.916426 -19.832824) (xy 448.861583 -19.822694) (xy 448.808799 -19.804687) (xy 448.759199 -19.779186)
			(xy 448.713841 -19.746735) (xy 448.673692 -19.708026) (xy 448.639606 -19.663883) (xy 448.61231 -19.615248)
			(xy 448.592387 -19.563157) (xy 448.580261 -19.50872) (xy 448.57619 -19.453098) (xy 443.019942 -19.453098)
			(xy 443.019942 -19.459956) (xy 443.027054 -19.47799) (xy 443.033658 -19.484848) (xy 443.052936 -19.506169)
			(xy 443.085502 -19.553532) (xy 443.110595 -19.605245) (xy 443.127645 -19.660136) (xy 443.136267 -19.716965)
			(xy 443.136267 -19.774444) (xy 443.127643 -19.831272) (xy 443.110591 -19.886163) (xy 443.085498 -19.937875)
			(xy 443.05293 -19.985238) (xy 443.033658 -20.006564) (xy 443.027054 -20.013422) (xy 443.019942 -20.031456)
			(xy 443.019942 -20.120356) (xy 443.027054 -20.13839) (xy 443.033658 -20.145248) (xy 443.052936 -20.166569)
			(xy 443.085502 -20.213932) (xy 443.110595 -20.265645) (xy 443.127645 -20.320536) (xy 443.136267 -20.377365)
			(xy 443.136267 -20.434844) (xy 443.1313 -20.467574) (xy 450.587362 -20.467574) (xy 450.591433 -20.411952)
			(xy 450.603559 -20.357515) (xy 450.623482 -20.305424) (xy 450.650778 -20.256789) (xy 450.684864 -20.212646)
			(xy 450.725013 -20.173937) (xy 450.770371 -20.141486) (xy 450.819971 -20.115985) (xy 450.872755 -20.097978)
			(xy 450.927598 -20.087848) (xy 450.983332 -20.085811) (xy 451.038769 -20.091911) (xy 451.092726 -20.106017)
			(xy 451.144055 -20.127829) (xy 451.191661 -20.156883) (xy 451.234529 -20.192558) (xy 451.271746 -20.234095)
			(xy 451.302519 -20.280608) (xy 451.326191 -20.331105) (xy 451.342259 -20.384512) (xy 451.350379 -20.439688)
			(xy 451.350888 -20.467574) (xy 451.350379 -20.49546) (xy 451.342259 -20.550636) (xy 451.326191 -20.604043)
			(xy 451.302519 -20.65454) (xy 451.271746 -20.701053) (xy 451.234529 -20.74259) (xy 451.219494 -20.755102)
			(xy 454.45883 -20.755102) (xy 454.462901 -20.69948) (xy 454.475027 -20.645043) (xy 454.49495 -20.592952)
			(xy 454.522246 -20.544317) (xy 454.556332 -20.500174) (xy 454.596481 -20.461465) (xy 454.641839 -20.429014)
			(xy 454.691439 -20.403513) (xy 454.744223 -20.385506) (xy 454.799066 -20.375376) (xy 454.8548 -20.373339)
			(xy 454.910237 -20.379439) (xy 454.964194 -20.393545) (xy 455.015523 -20.415357) (xy 455.063129 -20.444411)
			(xy 455.105997 -20.480086) (xy 455.143214 -20.521623) (xy 455.173987 -20.568136) (xy 455.197659 -20.618633)
			(xy 455.213727 -20.67204) (xy 455.221847 -20.727216) (xy 455.222356 -20.755102) (xy 455.221847 -20.782988)
			(xy 455.213727 -20.838164) (xy 455.197659 -20.891571) (xy 455.173987 -20.942068) (xy 455.143214 -20.988581)
			(xy 455.105997 -21.030118) (xy 455.063129 -21.065793) (xy 455.015523 -21.094847) (xy 454.964194 -21.116659)
			(xy 454.910237 -21.130765) (xy 454.8548 -21.136865) (xy 454.799066 -21.134828) (xy 454.744223 -21.124698)
			(xy 454.691439 -21.106691) (xy 454.641839 -21.08119) (xy 454.596481 -21.048739) (xy 454.556332 -21.01003)
			(xy 454.522246 -20.965887) (xy 454.49495 -20.917252) (xy 454.475027 -20.865161) (xy 454.462901 -20.810724)
			(xy 454.45883 -20.755102) (xy 451.219494 -20.755102) (xy 451.191661 -20.778265) (xy 451.144055 -20.807319)
			(xy 451.092726 -20.829131) (xy 451.038769 -20.843237) (xy 450.983332 -20.849337) (xy 450.927598 -20.8473)
			(xy 450.872755 -20.83717) (xy 450.819971 -20.819163) (xy 450.770371 -20.793662) (xy 450.725013 -20.761211)
			(xy 450.684864 -20.722502) (xy 450.650778 -20.678359) (xy 450.623482 -20.629724) (xy 450.603559 -20.577633)
			(xy 450.591433 -20.523196) (xy 450.587362 -20.467574) (xy 443.1313 -20.467574) (xy 443.127643 -20.491672)
			(xy 443.110591 -20.546563) (xy 443.085498 -20.598275) (xy 443.05293 -20.645638) (xy 443.033658 -20.666964)
			(xy 443.027054 -20.673822) (xy 443.019942 -20.691856) (xy 443.019942 -20.780756) (xy 443.027054 -20.79879)
			(xy 443.033658 -20.805648) (xy 443.052936 -20.826969) (xy 443.085502 -20.874332) (xy 443.110595 -20.926045)
			(xy 443.127645 -20.980936) (xy 443.136267 -21.037765) (xy 443.136267 -21.095244) (xy 443.127643 -21.152072)
			(xy 443.110591 -21.206963) (xy 443.085498 -21.258675) (xy 443.05293 -21.306038) (xy 443.033658 -21.327364)
			(xy 443.027054 -21.334222) (xy 443.019942 -21.352256) (xy 443.019942 -21.441156) (xy 443.027054 -21.45919)
			(xy 443.033658 -21.466048) (xy 443.052931 -21.487373) (xy 443.085497 -21.534736) (xy 443.110589 -21.586448)
			(xy 443.127639 -21.641339) (xy 443.136261 -21.698167) (xy 443.136782 -21.726906) (xy 443.136296 -21.754157)
			(xy 443.133203 -21.775674) (xy 452.235822 -21.775674) (xy 452.239893 -21.720052) (xy 452.252019 -21.665615)
			(xy 452.271942 -21.613524) (xy 452.299238 -21.564889) (xy 452.333324 -21.520746) (xy 452.373473 -21.482037)
			(xy 452.418831 -21.449586) (xy 452.468431 -21.424085) (xy 452.521215 -21.406078) (xy 452.576058 -21.395948)
			(xy 452.631792 -21.393911) (xy 452.687229 -21.400011) (xy 452.741186 -21.414117) (xy 452.792515 -21.435929)
			(xy 452.840121 -21.464983) (xy 452.882989 -21.500658) (xy 452.920206 -21.542195) (xy 452.950979 -21.588708)
			(xy 452.974651 -21.639205) (xy 452.990719 -21.692612) (xy 452.998839 -21.747788) (xy 452.999348 -21.775674)
			(xy 452.998839 -21.80356) (xy 452.995766 -21.824442) (xy 453.380346 -21.824442) (xy 453.384417 -21.76882)
			(xy 453.396543 -21.714383) (xy 453.416466 -21.662292) (xy 453.443762 -21.613657) (xy 453.477848 -21.569514)
			(xy 453.517997 -21.530805) (xy 453.563355 -21.498354) (xy 453.612955 -21.472853) (xy 453.665739 -21.454846)
			(xy 453.720582 -21.444716) (xy 453.776316 -21.442679) (xy 453.831753 -21.448779) (xy 453.88571 -21.462885)
			(xy 453.937039 -21.484697) (xy 453.984645 -21.513751) (xy 454.027513 -21.549426) (xy 454.06473 -21.590963)
			(xy 454.095503 -21.637476) (xy 454.119175 -21.687973) (xy 454.135243 -21.74138) (xy 454.143363 -21.796556)
			(xy 454.143872 -21.824442) (xy 454.143363 -21.852328) (xy 454.135243 -21.907504) (xy 454.119175 -21.960911)
			(xy 454.095503 -22.011408) (xy 454.06473 -22.057921) (xy 454.027513 -22.099458) (xy 453.984645 -22.135133)
			(xy 453.937039 -22.164187) (xy 453.88571 -22.185999) (xy 453.831753 -22.200105) (xy 453.776316 -22.206205)
			(xy 453.720582 -22.204168) (xy 453.665739 -22.194038) (xy 453.612955 -22.176031) (xy 453.563355 -22.15053)
			(xy 453.517997 -22.118079) (xy 453.477848 -22.07937) (xy 453.443762 -22.035227) (xy 453.416466 -21.986592)
			(xy 453.396543 -21.934501) (xy 453.384417 -21.880064) (xy 453.380346 -21.824442) (xy 452.995766 -21.824442)
			(xy 452.990719 -21.858736) (xy 452.974651 -21.912143) (xy 452.950979 -21.96264) (xy 452.920206 -22.009153)
			(xy 452.882989 -22.05069) (xy 452.840121 -22.086365) (xy 452.792515 -22.115419) (xy 452.741186 -22.137231)
			(xy 452.687229 -22.151337) (xy 452.631792 -22.157437) (xy 452.576058 -22.1554) (xy 452.521215 -22.14527)
			(xy 452.468431 -22.127263) (xy 452.418831 -22.101762) (xy 452.373473 -22.069311) (xy 452.333324 -22.030602)
			(xy 452.299238 -21.986459) (xy 452.271942 -21.937824) (xy 452.252019 -21.885733) (xy 452.239893 -21.831296)
			(xy 452.235822 -21.775674) (xy 443.133203 -21.775674) (xy 443.12854 -21.808105) (xy 443.113185 -21.8604)
			(xy 443.090543 -21.909977) (xy 443.061077 -21.955827) (xy 443.025386 -21.997018) (xy 442.984195 -22.032709)
			(xy 442.938345 -22.062175) (xy 442.888768 -22.084817) (xy 442.836473 -22.100172) (xy 442.782525 -22.107928)
			(xy 442.728023 -22.107928) (xy 442.674075 -22.100172) (xy 442.62178 -22.084817) (xy 442.572203 -22.062175)
			(xy 442.526353 -22.032709) (xy 442.485162 -21.997018) (xy 442.449471 -21.955827) (xy 442.420005 -21.909977)
			(xy 442.397363 -21.8604) (xy 442.382008 -21.808105) (xy 442.374252 -21.754157) (xy 442.373766 -21.726906)
			(xy 435.498895 -21.726906) (xy 435.469107 -21.783021) (xy 435.401166 -21.894082) (xy 435.32658 -22.000794)
			(xy 435.245627 -22.102761) (xy 435.158608 -22.199603) (xy 435.065847 -22.29096) (xy 434.967689 -22.376492)
			(xy 434.8645 -22.45588) (xy 434.756663 -22.52883) (xy 434.711613 -22.555454) (xy 451.636382 -22.555454)
			(xy 451.640453 -22.499832) (xy 451.652579 -22.445395) (xy 451.672502 -22.393304) (xy 451.699798 -22.344669)
			(xy 451.733884 -22.300526) (xy 451.774033 -22.261817) (xy 451.819391 -22.229366) (xy 451.868991 -22.203865)
			(xy 451.921775 -22.185858) (xy 451.976618 -22.175728) (xy 452.032352 -22.173691) (xy 452.087789 -22.179791)
			(xy 452.141746 -22.193897) (xy 452.193075 -22.215709) (xy 452.240681 -22.244763) (xy 452.283549 -22.280438)
			(xy 452.320766 -22.321975) (xy 452.351539 -22.368488) (xy 452.375211 -22.418985) (xy 452.391279 -22.472392)
			(xy 452.399399 -22.527568) (xy 452.399908 -22.555454) (xy 452.399399 -22.58334) (xy 452.391279 -22.638516)
			(xy 452.375211 -22.691923) (xy 452.351539 -22.74242) (xy 452.320766 -22.788933) (xy 452.283549 -22.83047)
			(xy 452.240681 -22.866145) (xy 452.193075 -22.895199) (xy 452.141746 -22.917011) (xy 452.087789 -22.931117)
			(xy 452.032352 -22.937217) (xy 451.976618 -22.93518) (xy 451.921775 -22.92505) (xy 451.868991 -22.907043)
			(xy 451.819391 -22.881542) (xy 451.774033 -22.849091) (xy 451.733884 -22.810382) (xy 451.699798 -22.766239)
			(xy 451.672502 -22.717604) (xy 451.652579 -22.665513) (xy 451.640453 -22.611076) (xy 451.636382 -22.555454)
			(xy 434.711613 -22.555454) (xy 434.644578 -22.595071) (xy 434.528665 -22.654354) (xy 434.409352 -22.706462)
			(xy 434.287085 -22.751198) (xy 434.162318 -22.788397) (xy 434.035515 -22.817921) (xy 433.907148 -22.839659)
			(xy 433.777695 -22.853532) (xy 433.647636 -22.859486) (xy 433.517457 -22.857501) (xy 433.387641 -22.847583)
			(xy 433.258671 -22.829769) (xy 433.131026 -22.804126) (xy 433.005183 -22.770749) (xy 432.881608 -22.729762)
			(xy 432.760762 -22.681318) (xy 432.643094 -22.625596) (xy 432.529042 -22.562805) (xy 432.41903 -22.493178)
			(xy 432.313468 -22.416973) (xy 432.212748 -22.334474) (xy 432.117244 -22.245989) (xy 432.027312 -22.151846)
			(xy 431.943287 -22.052395) (xy 431.865482 -21.948007) (xy 431.794185 -21.83907) (xy 431.729661 -21.725988)
			(xy 431.672152 -21.609184) (xy 431.62187 -21.489091) (xy 431.579004 -21.366155) (xy 431.543711 -21.240836)
			(xy 431.516125 -21.113597) (xy 431.496346 -20.984914) (xy 431.48445 -20.855264) (xy 431.48048 -20.72513)
			(xy 425.250225 -20.72513) (xy 425.234581 -20.74259) (xy 425.191713 -20.778265) (xy 425.144107 -20.807319)
			(xy 425.092778 -20.829131) (xy 425.038821 -20.843237) (xy 424.983384 -20.849337) (xy 424.92765 -20.8473)
			(xy 424.872807 -20.83717) (xy 424.820023 -20.819163) (xy 424.770423 -20.793662) (xy 424.725065 -20.761211)
			(xy 424.684916 -20.722502) (xy 424.65083 -20.678359) (xy 424.623534 -20.629724) (xy 424.603611 -20.577633)
			(xy 424.591485 -20.523196) (xy 424.587414 -20.467574) (xy 417.131338 -20.467574) (xy 417.127682 -20.49167)
			(xy 417.110633 -20.546561) (xy 417.085543 -20.598273) (xy 417.05298 -20.645636) (xy 417.03371 -20.666964)
			(xy 417.027106 -20.673822) (xy 417.019994 -20.691856) (xy 417.019994 -20.780756) (xy 417.027106 -20.79879)
			(xy 417.03371 -20.805648) (xy 417.052985 -20.82697) (xy 417.085547 -20.874335) (xy 417.110636 -20.926047)
			(xy 417.127684 -20.980938) (xy 417.136306 -21.037766) (xy 417.136305 -21.095243) (xy 417.127682 -21.15207)
			(xy 417.110633 -21.206961) (xy 417.085543 -21.258673) (xy 417.05298 -21.306036) (xy 417.03371 -21.327364)
			(xy 417.027106 -21.334222) (xy 417.019994 -21.352256) (xy 417.019994 -21.441156) (xy 417.027106 -21.45919)
			(xy 417.03371 -21.466048) (xy 417.052975 -21.487381) (xy 417.085544 -21.53474) (xy 417.110638 -21.58645)
			(xy 417.12769 -21.64134) (xy 417.136313 -21.698167) (xy 417.136834 -21.726906) (xy 417.136348 -21.754157)
			(xy 417.133255 -21.775674) (xy 426.235874 -21.775674) (xy 426.239945 -21.720052) (xy 426.252071 -21.665615)
			(xy 426.271994 -21.613524) (xy 426.29929 -21.564889) (xy 426.333376 -21.520746) (xy 426.373525 -21.482037)
			(xy 426.418883 -21.449586) (xy 426.468483 -21.424085) (xy 426.521267 -21.406078) (xy 426.57611 -21.395948)
			(xy 426.631844 -21.393911) (xy 426.687281 -21.400011) (xy 426.741238 -21.414117) (xy 426.792567 -21.435929)
			(xy 426.840173 -21.464983) (xy 426.883041 -21.500658) (xy 426.920258 -21.542195) (xy 426.951031 -21.588708)
			(xy 426.974703 -21.639205) (xy 426.990771 -21.692612) (xy 426.998891 -21.747788) (xy 426.9994 -21.775674)
			(xy 426.998891 -21.80356) (xy 426.99122 -21.855684) (xy 427.13859 -21.855684) (xy 427.142661 -21.800062)
			(xy 427.154787 -21.745625) (xy 427.17471 -21.693534) (xy 427.202006 -21.644899) (xy 427.236092 -21.600756)
			(xy 427.276241 -21.562047) (xy 427.321599 -21.529596) (xy 427.371199 -21.504095) (xy 427.423983 -21.486088)
			(xy 427.478826 -21.475958) (xy 427.53456 -21.473921) (xy 427.589997 -21.480021) (xy 427.643954 -21.494127)
			(xy 427.695283 -21.515939) (xy 427.742889 -21.544993) (xy 427.785757 -21.580668) (xy 427.822974 -21.622205)
			(xy 427.853747 -21.668718) (xy 427.877419 -21.719215) (xy 427.893487 -21.772622) (xy 427.901607 -21.827798)
			(xy 427.901958 -21.847048) (xy 428.372776 -21.847048) (xy 428.376847 -21.791426) (xy 428.388973 -21.736989)
			(xy 428.408896 -21.684898) (xy 428.436192 -21.636263) (xy 428.470278 -21.59212) (xy 428.510427 -21.553411)
			(xy 428.555785 -21.52096) (xy 428.605385 -21.495459) (xy 428.658169 -21.477452) (xy 428.713012 -21.467322)
			(xy 428.768746 -21.465285) (xy 428.824183 -21.471385) (xy 428.87814 -21.485491) (xy 428.929469 -21.507303)
			(xy 428.977075 -21.536357) (xy 429.019943 -21.572032) (xy 429.05716 -21.613569) (xy 429.087933 -21.660082)
			(xy 429.111605 -21.710579) (xy 429.127673 -21.763986) (xy 429.135793 -21.819162) (xy 429.136302 -21.847048)
			(xy 429.135793 -21.874934) (xy 429.127673 -21.93011) (xy 429.111605 -21.983517) (xy 429.087933 -22.034014)
			(xy 429.05716 -22.080527) (xy 429.019943 -22.122064) (xy 428.977075 -22.157739) (xy 428.929469 -22.186793)
			(xy 428.87814 -22.208605) (xy 428.824183 -22.222711) (xy 428.768746 -22.228811) (xy 428.713012 -22.226774)
			(xy 428.658169 -22.216644) (xy 428.605385 -22.198637) (xy 428.555785 -22.173136) (xy 428.510427 -22.140685)
			(xy 428.470278 -22.101976) (xy 428.436192 -22.057833) (xy 428.408896 -22.009198) (xy 428.388973 -21.957107)
			(xy 428.376847 -21.90267) (xy 428.372776 -21.847048) (xy 427.901958 -21.847048) (xy 427.902116 -21.855684)
			(xy 427.901607 -21.88357) (xy 427.893487 -21.938746) (xy 427.877419 -21.992153) (xy 427.853747 -22.04265)
			(xy 427.822974 -22.089163) (xy 427.785757 -22.1307) (xy 427.742889 -22.166375) (xy 427.695283 -22.195429)
			(xy 427.643954 -22.217241) (xy 427.589997 -22.231347) (xy 427.53456 -22.237447) (xy 427.478826 -22.23541)
			(xy 427.423983 -22.22528) (xy 427.371199 -22.207273) (xy 427.321599 -22.181772) (xy 427.276241 -22.149321)
			(xy 427.236092 -22.110612) (xy 427.202006 -22.066469) (xy 427.17471 -22.017834) (xy 427.154787 -21.965743)
			(xy 427.142661 -21.911306) (xy 427.13859 -21.855684) (xy 426.99122 -21.855684) (xy 426.990771 -21.858736)
			(xy 426.974703 -21.912143) (xy 426.951031 -21.96264) (xy 426.920258 -22.009153) (xy 426.883041 -22.05069)
			(xy 426.840173 -22.086365) (xy 426.792567 -22.115419) (xy 426.741238 -22.137231) (xy 426.687281 -22.151337)
			(xy 426.631844 -22.157437) (xy 426.57611 -22.1554) (xy 426.521267 -22.14527) (xy 426.468483 -22.127263)
			(xy 426.418883 -22.101762) (xy 426.373525 -22.069311) (xy 426.333376 -22.030602) (xy 426.29929 -21.986459)
			(xy 426.271994 -21.937824) (xy 426.252071 -21.885733) (xy 426.239945 -21.831296) (xy 426.235874 -21.775674)
			(xy 417.133255 -21.775674) (xy 417.128592 -21.808105) (xy 417.113237 -21.8604) (xy 417.090595 -21.909977)
			(xy 417.061129 -21.955827) (xy 417.025438 -21.997018) (xy 416.984247 -22.032709) (xy 416.938397 -22.062175)
			(xy 416.88882 -22.084817) (xy 416.836525 -22.100172) (xy 416.782577 -22.107928) (xy 416.728075 -22.107928)
			(xy 416.674127 -22.100172) (xy 416.621832 -22.084817) (xy 416.572255 -22.062175) (xy 416.526405 -22.032709)
			(xy 416.485214 -21.997018) (xy 416.449523 -21.955827) (xy 416.420057 -21.909977) (xy 416.397415 -21.8604)
			(xy 416.38206 -21.808105) (xy 416.374304 -21.754157) (xy 416.373818 -21.726906) (xy 409.498947 -21.726906)
			(xy 409.469159 -21.783021) (xy 409.401218 -21.894082) (xy 409.326632 -22.000794) (xy 409.245679 -22.102761)
			(xy 409.15866 -22.199603) (xy 409.065899 -22.29096) (xy 408.967741 -22.376492) (xy 408.864552 -22.45588)
			(xy 408.756715 -22.52883) (xy 408.711665 -22.555454) (xy 425.636434 -22.555454) (xy 425.640505 -22.499832)
			(xy 425.652631 -22.445395) (xy 425.672554 -22.393304) (xy 425.69985 -22.344669) (xy 425.733936 -22.300526)
			(xy 425.774085 -22.261817) (xy 425.819443 -22.229366) (xy 425.869043 -22.203865) (xy 425.921827 -22.185858)
			(xy 425.97667 -22.175728) (xy 426.032404 -22.173691) (xy 426.087841 -22.179791) (xy 426.141798 -22.193897)
			(xy 426.193127 -22.215709) (xy 426.240733 -22.244763) (xy 426.283601 -22.280438) (xy 426.320818 -22.321975)
			(xy 426.351591 -22.368488) (xy 426.375263 -22.418985) (xy 426.391331 -22.472392) (xy 426.399451 -22.527568)
			(xy 426.39996 -22.555454) (xy 426.399451 -22.58334) (xy 426.391331 -22.638516) (xy 426.375263 -22.691923)
			(xy 426.351591 -22.74242) (xy 426.320818 -22.788933) (xy 426.283601 -22.83047) (xy 426.240733 -22.866145)
			(xy 426.193127 -22.895199) (xy 426.141798 -22.917011) (xy 426.087841 -22.931117) (xy 426.032404 -22.937217)
			(xy 425.97667 -22.93518) (xy 425.921827 -22.92505) (xy 425.869043 -22.907043) (xy 425.819443 -22.881542)
			(xy 425.774085 -22.849091) (xy 425.733936 -22.810382) (xy 425.69985 -22.766239) (xy 425.672554 -22.717604)
			(xy 425.652631 -22.665513) (xy 425.640505 -22.611076) (xy 425.636434 -22.555454) (xy 408.711665 -22.555454)
			(xy 408.64463 -22.595071) (xy 408.528717 -22.654354) (xy 408.409404 -22.706462) (xy 408.287137 -22.751198)
			(xy 408.16237 -22.788397) (xy 408.035567 -22.817921) (xy 407.9072 -22.839659) (xy 407.777747 -22.853532)
			(xy 407.647688 -22.859486) (xy 407.517509 -22.857501) (xy 407.387693 -22.847583) (xy 407.258723 -22.829769)
			(xy 407.131078 -22.804126) (xy 407.005235 -22.770749) (xy 406.88166 -22.729762) (xy 406.760814 -22.681318)
			(xy 406.643146 -22.625596) (xy 406.529094 -22.562805) (xy 406.419082 -22.493178) (xy 406.31352 -22.416973)
			(xy 406.2128 -22.334474) (xy 406.117296 -22.245989) (xy 406.027364 -22.151846) (xy 405.943339 -22.052395)
			(xy 405.865534 -21.948007) (xy 405.794237 -21.83907) (xy 405.729713 -21.725988) (xy 405.672204 -21.609184)
			(xy 405.621922 -21.489091) (xy 405.579056 -21.366155) (xy 405.543763 -21.240836) (xy 405.516177 -21.113597)
			(xy 405.496398 -20.984914) (xy 405.484502 -20.855264) (xy 405.480532 -20.72513) (xy 399.250277 -20.72513)
			(xy 399.234633 -20.74259) (xy 399.191765 -20.778265) (xy 399.144159 -20.807319) (xy 399.09283 -20.829131)
			(xy 399.038873 -20.843237) (xy 398.983436 -20.849337) (xy 398.927702 -20.8473) (xy 398.872859 -20.83717)
			(xy 398.820075 -20.819163) (xy 398.770475 -20.793662) (xy 398.725117 -20.761211) (xy 398.684968 -20.722502)
			(xy 398.650882 -20.678359) (xy 398.623586 -20.629724) (xy 398.603663 -20.577633) (xy 398.591537 -20.523196)
			(xy 398.587466 -20.467574) (xy 391.131403 -20.467574) (xy 391.127746 -20.491672) (xy 391.110695 -20.546563)
			(xy 391.085601 -20.598275) (xy 391.053034 -20.645638) (xy 391.033762 -20.666964) (xy 391.027158 -20.673822)
			(xy 391.020046 -20.691856) (xy 391.020046 -20.780756) (xy 391.027158 -20.79879) (xy 391.033762 -20.805648)
			(xy 391.053039 -20.826969) (xy 391.085606 -20.874332) (xy 391.110698 -20.926045) (xy 391.127748 -20.980937)
			(xy 391.13637 -21.037765) (xy 391.13637 -21.095244) (xy 391.127746 -21.152072) (xy 391.110695 -21.206963)
			(xy 391.085601 -21.258675) (xy 391.053034 -21.306038) (xy 391.033762 -21.327364) (xy 391.027158 -21.334222)
			(xy 391.020046 -21.352256) (xy 391.020046 -21.441156) (xy 391.027158 -21.45919) (xy 391.033762 -21.466048)
			(xy 391.053036 -21.487373) (xy 391.085601 -21.534735) (xy 391.110693 -21.586448) (xy 391.127743 -21.641339)
			(xy 391.136365 -21.698167) (xy 391.136886 -21.726906) (xy 391.1364 -21.754157) (xy 391.133307 -21.775674)
			(xy 400.235926 -21.775674) (xy 400.239997 -21.720052) (xy 400.252123 -21.665615) (xy 400.272046 -21.613524)
			(xy 400.299342 -21.564889) (xy 400.333428 -21.520746) (xy 400.373577 -21.482037) (xy 400.418935 -21.449586)
			(xy 400.468535 -21.424085) (xy 400.521319 -21.406078) (xy 400.576162 -21.395948) (xy 400.631896 -21.393911)
			(xy 400.687333 -21.400011) (xy 400.74129 -21.414117) (xy 400.792619 -21.435929) (xy 400.840225 -21.464983)
			(xy 400.883093 -21.500658) (xy 400.92031 -21.542195) (xy 400.951083 -21.588708) (xy 400.974755 -21.639205)
			(xy 400.990823 -21.692612) (xy 400.998943 -21.747788) (xy 400.999452 -21.775674) (xy 400.998943 -21.80356)
			(xy 400.991272 -21.855684) (xy 401.138642 -21.855684) (xy 401.142713 -21.800062) (xy 401.154839 -21.745625)
			(xy 401.174762 -21.693534) (xy 401.202058 -21.644899) (xy 401.236144 -21.600756) (xy 401.276293 -21.562047)
			(xy 401.321651 -21.529596) (xy 401.371251 -21.504095) (xy 401.424035 -21.486088) (xy 401.478878 -21.475958)
			(xy 401.534612 -21.473921) (xy 401.590049 -21.480021) (xy 401.644006 -21.494127) (xy 401.695335 -21.515939)
			(xy 401.742941 -21.544993) (xy 401.785809 -21.580668) (xy 401.823026 -21.622205) (xy 401.853799 -21.668718)
			(xy 401.877471 -21.719215) (xy 401.893539 -21.772622) (xy 401.901659 -21.827798) (xy 401.90201 -21.847048)
			(xy 402.372828 -21.847048) (xy 402.376899 -21.791426) (xy 402.389025 -21.736989) (xy 402.408948 -21.684898)
			(xy 402.436244 -21.636263) (xy 402.47033 -21.59212) (xy 402.510479 -21.553411) (xy 402.555837 -21.52096)
			(xy 402.605437 -21.495459) (xy 402.658221 -21.477452) (xy 402.713064 -21.467322) (xy 402.768798 -21.465285)
			(xy 402.824235 -21.471385) (xy 402.878192 -21.485491) (xy 402.929521 -21.507303) (xy 402.977127 -21.536357)
			(xy 403.019995 -21.572032) (xy 403.057212 -21.613569) (xy 403.087985 -21.660082) (xy 403.111657 -21.710579)
			(xy 403.127725 -21.763986) (xy 403.135845 -21.819162) (xy 403.136354 -21.847048) (xy 403.135845 -21.874934)
			(xy 403.127725 -21.93011) (xy 403.111657 -21.983517) (xy 403.087985 -22.034014) (xy 403.057212 -22.080527)
			(xy 403.019995 -22.122064) (xy 402.977127 -22.157739) (xy 402.929521 -22.186793) (xy 402.878192 -22.208605)
			(xy 402.824235 -22.222711) (xy 402.768798 -22.228811) (xy 402.713064 -22.226774) (xy 402.658221 -22.216644)
			(xy 402.605437 -22.198637) (xy 402.555837 -22.173136) (xy 402.510479 -22.140685) (xy 402.47033 -22.101976)
			(xy 402.436244 -22.057833) (xy 402.408948 -22.009198) (xy 402.389025 -21.957107) (xy 402.376899 -21.90267)
			(xy 402.372828 -21.847048) (xy 401.90201 -21.847048) (xy 401.902168 -21.855684) (xy 401.901659 -21.88357)
			(xy 401.893539 -21.938746) (xy 401.877471 -21.992153) (xy 401.853799 -22.04265) (xy 401.823026 -22.089163)
			(xy 401.785809 -22.1307) (xy 401.742941 -22.166375) (xy 401.695335 -22.195429) (xy 401.644006 -22.217241)
			(xy 401.590049 -22.231347) (xy 401.534612 -22.237447) (xy 401.478878 -22.23541) (xy 401.424035 -22.22528)
			(xy 401.371251 -22.207273) (xy 401.321651 -22.181772) (xy 401.276293 -22.149321) (xy 401.236144 -22.110612)
			(xy 401.202058 -22.066469) (xy 401.174762 -22.017834) (xy 401.154839 -21.965743) (xy 401.142713 -21.911306)
			(xy 401.138642 -21.855684) (xy 400.991272 -21.855684) (xy 400.990823 -21.858736) (xy 400.974755 -21.912143)
			(xy 400.951083 -21.96264) (xy 400.92031 -22.009153) (xy 400.883093 -22.05069) (xy 400.840225 -22.086365)
			(xy 400.792619 -22.115419) (xy 400.74129 -22.137231) (xy 400.687333 -22.151337) (xy 400.631896 -22.157437)
			(xy 400.576162 -22.1554) (xy 400.521319 -22.14527) (xy 400.468535 -22.127263) (xy 400.418935 -22.101762)
			(xy 400.373577 -22.069311) (xy 400.333428 -22.030602) (xy 400.299342 -21.986459) (xy 400.272046 -21.937824)
			(xy 400.252123 -21.885733) (xy 400.239997 -21.831296) (xy 400.235926 -21.775674) (xy 391.133307 -21.775674)
			(xy 391.128644 -21.808105) (xy 391.113289 -21.8604) (xy 391.090647 -21.909977) (xy 391.061181 -21.955827)
			(xy 391.02549 -21.997018) (xy 390.984299 -22.032709) (xy 390.938449 -22.062175) (xy 390.888872 -22.084817)
			(xy 390.836577 -22.100172) (xy 390.782629 -22.107928) (xy 390.728127 -22.107928) (xy 390.674179 -22.100172)
			(xy 390.621884 -22.084817) (xy 390.572307 -22.062175) (xy 390.526457 -22.032709) (xy 390.485266 -21.997018)
			(xy 390.449575 -21.955827) (xy 390.420109 -21.909977) (xy 390.397467 -21.8604) (xy 390.382112 -21.808105)
			(xy 390.374356 -21.754157) (xy 390.37387 -21.726906) (xy 383.501129 -21.726906) (xy 383.474037 -21.777941)
			(xy 383.406096 -21.889002) (xy 383.33151 -21.995714) (xy 383.250557 -22.097681) (xy 383.163538 -22.194523)
			(xy 383.070777 -22.28588) (xy 382.972619 -22.371412) (xy 382.86943 -22.4508) (xy 382.761593 -22.52375)
			(xy 382.707947 -22.555454) (xy 399.636486 -22.555454) (xy 399.640557 -22.499832) (xy 399.652683 -22.445395)
			(xy 399.672606 -22.393304) (xy 399.699902 -22.344669) (xy 399.733988 -22.300526) (xy 399.774137 -22.261817)
			(xy 399.819495 -22.229366) (xy 399.869095 -22.203865) (xy 399.921879 -22.185858) (xy 399.976722 -22.175728)
			(xy 400.032456 -22.173691) (xy 400.087893 -22.179791) (xy 400.14185 -22.193897) (xy 400.193179 -22.215709)
			(xy 400.240785 -22.244763) (xy 400.283653 -22.280438) (xy 400.32087 -22.321975) (xy 400.351643 -22.368488)
			(xy 400.375315 -22.418985) (xy 400.391383 -22.472392) (xy 400.399503 -22.527568) (xy 400.400012 -22.555454)
			(xy 400.399503 -22.58334) (xy 400.391383 -22.638516) (xy 400.375315 -22.691923) (xy 400.351643 -22.74242)
			(xy 400.32087 -22.788933) (xy 400.283653 -22.83047) (xy 400.240785 -22.866145) (xy 400.193179 -22.895199)
			(xy 400.14185 -22.917011) (xy 400.087893 -22.931117) (xy 400.032456 -22.937217) (xy 399.976722 -22.93518)
			(xy 399.921879 -22.92505) (xy 399.869095 -22.907043) (xy 399.819495 -22.881542) (xy 399.774137 -22.849091)
			(xy 399.733988 -22.810382) (xy 399.699902 -22.766239) (xy 399.672606 -22.717604) (xy 399.652683 -22.665513)
			(xy 399.640557 -22.611076) (xy 399.636486 -22.555454) (xy 382.707947 -22.555454) (xy 382.649508 -22.589991)
			(xy 382.533595 -22.649274) (xy 382.414282 -22.701382) (xy 382.292015 -22.746118) (xy 382.167248 -22.783317)
			(xy 382.040445 -22.812841) (xy 381.912078 -22.834579) (xy 381.782625 -22.848452) (xy 381.652566 -22.854406)
			(xy 381.522387 -22.852421) (xy 381.392571 -22.842503) (xy 381.263601 -22.824689) (xy 381.135956 -22.799046)
			(xy 381.010113 -22.765669) (xy 380.886538 -22.724682) (xy 380.765692 -22.676238) (xy 380.648024 -22.620516)
			(xy 380.533972 -22.557725) (xy 380.42396 -22.488098) (xy 380.318398 -22.411893) (xy 380.217678 -22.329394)
			(xy 380.122174 -22.240909) (xy 380.032242 -22.146766) (xy 379.948217 -22.047315) (xy 379.870412 -21.942927)
			(xy 379.799115 -21.83399) (xy 379.734591 -21.720908) (xy 379.677082 -21.604104) (xy 379.6268 -21.484011)
			(xy 379.583934 -21.361075) (xy 379.548641 -21.235756) (xy 379.521055 -21.108517) (xy 379.501276 -20.979834)
			(xy 379.48938 -20.850184) (xy 379.48541 -20.72005) (xy 373.254881 -20.72005) (xy 373.234685 -20.74259)
			(xy 373.191817 -20.778265) (xy 373.144211 -20.807319) (xy 373.092882 -20.829131) (xy 373.038925 -20.843237)
			(xy 372.983488 -20.849337) (xy 372.927754 -20.8473) (xy 372.872911 -20.83717) (xy 372.820127 -20.819163)
			(xy 372.770527 -20.793662) (xy 372.725169 -20.761211) (xy 372.68502 -20.722502) (xy 372.650934 -20.678359)
			(xy 372.623638 -20.629724) (xy 372.603715 -20.577633) (xy 372.591589 -20.523196) (xy 372.587518 -20.467574)
			(xy 365.106424 -20.467574) (xy 365.08565 -20.510388) (xy 365.053085 -20.557752) (xy 365.033814 -20.57908)
			(xy 365.02721 -20.585938) (xy 365.020098 -20.603972) (xy 365.020098 -20.692872) (xy 365.02721 -20.710906)
			(xy 365.033814 -20.717764) (xy 365.053105 -20.739073) (xy 365.085666 -20.786439) (xy 365.110754 -20.838154)
			(xy 365.127801 -20.893047) (xy 365.13642 -20.949877) (xy 365.136418 -21.007356) (xy 365.127793 -21.064184)
			(xy 365.110742 -21.119076) (xy 365.08565 -21.170788) (xy 365.053085 -21.218152) (xy 365.033814 -21.23948)
			(xy 365.02721 -21.246338) (xy 365.020098 -21.264372) (xy 365.020098 -21.353272) (xy 365.02721 -21.371306)
			(xy 365.033814 -21.378164) (xy 365.053087 -21.399489) (xy 365.085655 -21.446851) (xy 365.110748 -21.498563)
			(xy 365.127798 -21.553454) (xy 365.136419 -21.610283) (xy 365.136938 -21.639022) (xy 365.136452 -21.666273)
			(xy 365.128696 -21.720221) (xy 365.113341 -21.772516) (xy 365.111899 -21.775674) (xy 374.235978 -21.775674)
			(xy 374.240049 -21.720052) (xy 374.252175 -21.665615) (xy 374.272098 -21.613524) (xy 374.299394 -21.564889)
			(xy 374.33348 -21.520746) (xy 374.373629 -21.482037) (xy 374.418987 -21.449586) (xy 374.468587 -21.424085)
			(xy 374.521371 -21.406078) (xy 374.576214 -21.395948) (xy 374.631948 -21.393911) (xy 374.687385 -21.400011)
			(xy 374.741342 -21.414117) (xy 374.792671 -21.435929) (xy 374.840277 -21.464983) (xy 374.883145 -21.500658)
			(xy 374.920362 -21.542195) (xy 374.951135 -21.588708) (xy 374.974807 -21.639205) (xy 374.990875 -21.692612)
			(xy 374.998995 -21.747788) (xy 374.999504 -21.775674) (xy 374.998995 -21.80356) (xy 374.991324 -21.855684)
			(xy 375.138694 -21.855684) (xy 375.142765 -21.800062) (xy 375.154891 -21.745625) (xy 375.174814 -21.693534)
			(xy 375.20211 -21.644899) (xy 375.236196 -21.600756) (xy 375.276345 -21.562047) (xy 375.321703 -21.529596)
			(xy 375.371303 -21.504095) (xy 375.424087 -21.486088) (xy 375.47893 -21.475958) (xy 375.534664 -21.473921)
			(xy 375.590101 -21.480021) (xy 375.644058 -21.494127) (xy 375.695387 -21.515939) (xy 375.742993 -21.544993)
			(xy 375.785861 -21.580668) (xy 375.823078 -21.622205) (xy 375.853851 -21.668718) (xy 375.877523 -21.719215)
			(xy 375.893591 -21.772622) (xy 375.901711 -21.827798) (xy 375.902062 -21.847048) (xy 376.37288 -21.847048)
			(xy 376.376951 -21.791426) (xy 376.389077 -21.736989) (xy 376.409 -21.684898) (xy 376.436296 -21.636263)
			(xy 376.470382 -21.59212) (xy 376.510531 -21.553411) (xy 376.555889 -21.52096) (xy 376.605489 -21.495459)
			(xy 376.658273 -21.477452) (xy 376.713116 -21.467322) (xy 376.76885 -21.465285) (xy 376.824287 -21.471385)
			(xy 376.878244 -21.485491) (xy 376.929573 -21.507303) (xy 376.977179 -21.536357) (xy 377.020047 -21.572032)
			(xy 377.057264 -21.613569) (xy 377.088037 -21.660082) (xy 377.111709 -21.710579) (xy 377.127777 -21.763986)
			(xy 377.135897 -21.819162) (xy 377.136406 -21.847048) (xy 377.135897 -21.874934) (xy 377.127777 -21.93011)
			(xy 377.111709 -21.983517) (xy 377.088037 -22.034014) (xy 377.057264 -22.080527) (xy 377.020047 -22.122064)
			(xy 376.977179 -22.157739) (xy 376.929573 -22.186793) (xy 376.878244 -22.208605) (xy 376.824287 -22.222711)
			(xy 376.76885 -22.228811) (xy 376.713116 -22.226774) (xy 376.658273 -22.216644) (xy 376.605489 -22.198637)
			(xy 376.555889 -22.173136) (xy 376.510531 -22.140685) (xy 376.470382 -22.101976) (xy 376.436296 -22.057833)
			(xy 376.409 -22.009198) (xy 376.389077 -21.957107) (xy 376.376951 -21.90267) (xy 376.37288 -21.847048)
			(xy 375.902062 -21.847048) (xy 375.90222 -21.855684) (xy 375.901711 -21.88357) (xy 375.893591 -21.938746)
			(xy 375.877523 -21.992153) (xy 375.853851 -22.04265) (xy 375.823078 -22.089163) (xy 375.785861 -22.1307)
			(xy 375.742993 -22.166375) (xy 375.695387 -22.195429) (xy 375.644058 -22.217241) (xy 375.590101 -22.231347)
			(xy 375.534664 -22.237447) (xy 375.47893 -22.23541) (xy 375.424087 -22.22528) (xy 375.371303 -22.207273)
			(xy 375.321703 -22.181772) (xy 375.276345 -22.149321) (xy 375.236196 -22.110612) (xy 375.20211 -22.066469)
			(xy 375.174814 -22.017834) (xy 375.154891 -21.965743) (xy 375.142765 -21.911306) (xy 375.138694 -21.855684)
			(xy 374.991324 -21.855684) (xy 374.990875 -21.858736) (xy 374.974807 -21.912143) (xy 374.951135 -21.96264)
			(xy 374.920362 -22.009153) (xy 374.883145 -22.05069) (xy 374.840277 -22.086365) (xy 374.792671 -22.115419)
			(xy 374.741342 -22.137231) (xy 374.687385 -22.151337) (xy 374.631948 -22.157437) (xy 374.576214 -22.1554)
			(xy 374.521371 -22.14527) (xy 374.468587 -22.127263) (xy 374.418987 -22.101762) (xy 374.373629 -22.069311)
			(xy 374.33348 -22.030602) (xy 374.299394 -21.986459) (xy 374.272098 -21.937824) (xy 374.252175 -21.885733)
			(xy 374.240049 -21.831296) (xy 374.235978 -21.775674) (xy 365.111899 -21.775674) (xy 365.090699 -21.822093)
			(xy 365.061233 -21.867943) (xy 365.025542 -21.909134) (xy 364.984351 -21.944825) (xy 364.938501 -21.974291)
			(xy 364.888924 -21.996933) (xy 364.836629 -22.012288) (xy 364.782681 -22.020044) (xy 364.728179 -22.020044)
			(xy 364.674231 -22.012288) (xy 364.621936 -21.996933) (xy 364.572359 -21.974291) (xy 364.526509 -21.944825)
			(xy 364.485318 -21.909134) (xy 364.449627 -21.867943) (xy 364.420161 -21.822093) (xy 364.397519 -21.772516)
			(xy 364.382164 -21.720221) (xy 364.374408 -21.666273) (xy 364.373922 -21.639022) (xy 357.543505 -21.639022)
			(xy 357.530308 -21.668025) (xy 357.469263 -21.783021) (xy 357.401322 -21.894082) (xy 357.326736 -22.000794)
			(xy 357.245783 -22.102761) (xy 357.158764 -22.199603) (xy 357.066003 -22.29096) (xy 356.967845 -22.376492)
			(xy 356.864656 -22.45588) (xy 356.756819 -22.52883) (xy 356.711769 -22.555454) (xy 373.636538 -22.555454)
			(xy 373.640609 -22.499832) (xy 373.652735 -22.445395) (xy 373.672658 -22.393304) (xy 373.699954 -22.344669)
			(xy 373.73404 -22.300526) (xy 373.774189 -22.261817) (xy 373.819547 -22.229366) (xy 373.869147 -22.203865)
			(xy 373.921931 -22.185858) (xy 373.976774 -22.175728) (xy 374.032508 -22.173691) (xy 374.087945 -22.179791)
			(xy 374.141902 -22.193897) (xy 374.193231 -22.215709) (xy 374.240837 -22.244763) (xy 374.283705 -22.280438)
			(xy 374.320922 -22.321975) (xy 374.351695 -22.368488) (xy 374.375367 -22.418985) (xy 374.391435 -22.472392)
			(xy 374.399555 -22.527568) (xy 374.400064 -22.555454) (xy 374.399555 -22.58334) (xy 374.391435 -22.638516)
			(xy 374.375367 -22.691923) (xy 374.351695 -22.74242) (xy 374.320922 -22.788933) (xy 374.283705 -22.83047)
			(xy 374.240837 -22.866145) (xy 374.193231 -22.895199) (xy 374.141902 -22.917011) (xy 374.087945 -22.931117)
			(xy 374.032508 -22.937217) (xy 373.976774 -22.93518) (xy 373.921931 -22.92505) (xy 373.869147 -22.907043)
			(xy 373.819547 -22.881542) (xy 373.774189 -22.849091) (xy 373.73404 -22.810382) (xy 373.699954 -22.766239)
			(xy 373.672658 -22.717604) (xy 373.652735 -22.665513) (xy 373.640609 -22.611076) (xy 373.636538 -22.555454)
			(xy 356.711769 -22.555454) (xy 356.644734 -22.595071) (xy 356.528821 -22.654354) (xy 356.409508 -22.706462)
			(xy 356.287241 -22.751198) (xy 356.162474 -22.788397) (xy 356.035671 -22.817921) (xy 355.907304 -22.839659)
			(xy 355.777851 -22.853532) (xy 355.647792 -22.859486) (xy 355.517613 -22.857501) (xy 355.387797 -22.847583)
			(xy 355.258827 -22.829769) (xy 355.131182 -22.804126) (xy 355.005339 -22.770749) (xy 354.881764 -22.729762)
			(xy 354.760918 -22.681318) (xy 354.64325 -22.625596) (xy 354.529198 -22.562805) (xy 354.419186 -22.493178)
			(xy 354.313624 -22.416973) (xy 354.212904 -22.334474) (xy 354.1174 -22.245989) (xy 354.027468 -22.151846)
			(xy 353.943443 -22.052395) (xy 353.865638 -21.948007) (xy 353.794341 -21.83907) (xy 353.729817 -21.725988)
			(xy 353.672308 -21.609184) (xy 353.622026 -21.489091) (xy 353.57916 -21.366155) (xy 353.543867 -21.240836)
			(xy 353.516281 -21.113597) (xy 353.496502 -20.984914) (xy 353.484606 -20.855264) (xy 353.480636 -20.72513)
			(xy 326.919844 -20.72513) (xy 326.919844 -20.780756) (xy 326.926956 -20.79879) (xy 326.93356 -20.805648)
			(xy 326.952837 -20.826969) (xy 326.985404 -20.874332) (xy 327.010496 -20.926045) (xy 327.027547 -20.980937)
			(xy 327.036169 -21.037765) (xy 327.036168 -21.095244) (xy 327.027545 -21.152072) (xy 327.010493 -21.206963)
			(xy 326.985399 -21.258675) (xy 326.952832 -21.306038) (xy 326.93356 -21.327364) (xy 326.926956 -21.334222)
			(xy 326.919844 -21.352256) (xy 326.919844 -21.441156) (xy 326.926956 -21.45919) (xy 326.93356 -21.466048)
			(xy 326.952833 -21.487373) (xy 326.985399 -21.534735) (xy 327.010491 -21.586448) (xy 327.027541 -21.641339)
			(xy 327.036163 -21.698167) (xy 327.036684 -21.726906) (xy 327.036198 -21.754157) (xy 327.028442 -21.808105)
			(xy 327.013087 -21.8604) (xy 326.990445 -21.909977) (xy 326.960979 -21.955827) (xy 326.925288 -21.997018)
			(xy 326.884097 -22.032709) (xy 326.838247 -22.062175) (xy 326.78867 -22.084817) (xy 326.736375 -22.100172)
			(xy 326.682427 -22.107928) (xy 326.627925 -22.107928) (xy 326.573977 -22.100172) (xy 326.521682 -22.084817)
			(xy 326.472105 -22.062175) (xy 326.426255 -22.032709) (xy 326.385064 -21.997018) (xy 326.349373 -21.955827)
			(xy 326.319907 -21.909977) (xy 326.297265 -21.8604) (xy 326.28191 -21.808105) (xy 326.274154 -21.754157)
			(xy 326.273668 -21.726906) (xy 319.399051 -21.726906) (xy 319.369263 -21.783021) (xy 319.301322 -21.894082)
			(xy 319.226736 -22.000794) (xy 319.145783 -22.102761) (xy 319.058764 -22.199603) (xy 318.966003 -22.29096)
			(xy 318.867845 -22.376492) (xy 318.764656 -22.45588) (xy 318.656819 -22.52883) (xy 318.544734 -22.595071)
			(xy 318.428821 -22.654354) (xy 318.309508 -22.706462) (xy 318.187241 -22.751198) (xy 318.062474 -22.788397)
			(xy 317.935671 -22.817921) (xy 317.807304 -22.839659) (xy 317.677851 -22.853532) (xy 317.547792 -22.859486)
			(xy 317.417613 -22.857501) (xy 317.287797 -22.847583) (xy 317.158827 -22.829769) (xy 317.031182 -22.804126)
			(xy 316.905339 -22.770749) (xy 316.781764 -22.729762) (xy 316.660918 -22.681318) (xy 316.54325 -22.625596)
			(xy 316.429198 -22.562805) (xy 316.319186 -22.493178) (xy 316.213624 -22.416973) (xy 316.112904 -22.334474)
			(xy 316.0174 -22.245989) (xy 315.927468 -22.151846) (xy 315.843443 -22.052395) (xy 315.765638 -21.948007)
			(xy 315.694341 -21.83907) (xy 315.629817 -21.725988) (xy 315.572308 -21.609184) (xy 315.522026 -21.489091)
			(xy 315.47916 -21.366155) (xy 315.443867 -21.240836) (xy 315.416281 -21.113597) (xy 315.396502 -20.984914)
			(xy 315.384606 -20.855264) (xy 315.380636 -20.72513) (xy 309.150127 -20.72513) (xy 309.134483 -20.74259)
			(xy 309.091615 -20.778265) (xy 309.044009 -20.807319) (xy 308.99268 -20.829131) (xy 308.938723 -20.843237)
			(xy 308.883286 -20.849337) (xy 308.827552 -20.8473) (xy 308.772709 -20.83717) (xy 308.719925 -20.819163)
			(xy 308.670325 -20.793662) (xy 308.624967 -20.761211) (xy 308.584818 -20.722502) (xy 308.550732 -20.678359)
			(xy 308.523436 -20.629724) (xy 308.503513 -20.577633) (xy 308.491387 -20.523196) (xy 308.487316 -20.467574)
			(xy 301.006223 -20.467574) (xy 300.985448 -20.510389) (xy 300.952883 -20.557752) (xy 300.933612 -20.57908)
			(xy 300.927008 -20.585938) (xy 300.919896 -20.603972) (xy 300.919896 -20.692872) (xy 300.927008 -20.710906)
			(xy 300.933612 -20.717764) (xy 300.952903 -20.739073) (xy 300.985465 -20.786439) (xy 301.010552 -20.838154)
			(xy 301.027599 -20.893047) (xy 301.036219 -20.949876) (xy 301.036216 -21.007356) (xy 301.027592 -21.064184)
			(xy 301.010541 -21.119076) (xy 300.985448 -21.170789) (xy 300.952883 -21.218152) (xy 300.933612 -21.23948)
			(xy 300.927008 -21.246338) (xy 300.919896 -21.264372) (xy 300.919896 -21.353272) (xy 300.927008 -21.371306)
			(xy 300.933612 -21.378164) (xy 300.952885 -21.399489) (xy 300.985453 -21.446851) (xy 301.010546 -21.498563)
			(xy 301.027596 -21.553454) (xy 301.036217 -21.610283) (xy 301.036736 -21.639022) (xy 301.03625 -21.666273)
			(xy 301.028494 -21.720221) (xy 301.013139 -21.772516) (xy 301.011697 -21.775674) (xy 310.135776 -21.775674)
			(xy 310.139847 -21.720052) (xy 310.151973 -21.665615) (xy 310.171896 -21.613524) (xy 310.199192 -21.564889)
			(xy 310.233278 -21.520746) (xy 310.273427 -21.482037) (xy 310.318785 -21.449586) (xy 310.368385 -21.424085)
			(xy 310.421169 -21.406078) (xy 310.476012 -21.395948) (xy 310.531746 -21.393911) (xy 310.587183 -21.400011)
			(xy 310.64114 -21.414117) (xy 310.692469 -21.435929) (xy 310.740075 -21.464983) (xy 310.782943 -21.500658)
			(xy 310.82016 -21.542195) (xy 310.850933 -21.588708) (xy 310.874605 -21.639205) (xy 310.890673 -21.692612)
			(xy 310.898793 -21.747788) (xy 310.899302 -21.775674) (xy 310.898793 -21.80356) (xy 310.891122 -21.855684)
			(xy 311.038492 -21.855684) (xy 311.042563 -21.800062) (xy 311.054689 -21.745625) (xy 311.074612 -21.693534)
			(xy 311.101908 -21.644899) (xy 311.135994 -21.600756) (xy 311.176143 -21.562047) (xy 311.221501 -21.529596)
			(xy 311.271101 -21.504095) (xy 311.323885 -21.486088) (xy 311.378728 -21.475958) (xy 311.434462 -21.473921)
			(xy 311.489899 -21.480021) (xy 311.543856 -21.494127) (xy 311.595185 -21.515939) (xy 311.642791 -21.544993)
			(xy 311.685659 -21.580668) (xy 311.722876 -21.622205) (xy 311.753649 -21.668718) (xy 311.777321 -21.719215)
			(xy 311.793389 -21.772622) (xy 311.801509 -21.827798) (xy 311.80186 -21.847048) (xy 312.272678 -21.847048)
			(xy 312.276749 -21.791426) (xy 312.288875 -21.736989) (xy 312.308798 -21.684898) (xy 312.336094 -21.636263)
			(xy 312.37018 -21.59212) (xy 312.410329 -21.553411) (xy 312.455687 -21.52096) (xy 312.505287 -21.495459)
			(xy 312.558071 -21.477452) (xy 312.612914 -21.467322) (xy 312.668648 -21.465285) (xy 312.724085 -21.471385)
			(xy 312.778042 -21.485491) (xy 312.829371 -21.507303) (xy 312.876977 -21.536357) (xy 312.919845 -21.572032)
			(xy 312.957062 -21.613569) (xy 312.987835 -21.660082) (xy 313.011507 -21.710579) (xy 313.027575 -21.763986)
			(xy 313.035695 -21.819162) (xy 313.036204 -21.847048) (xy 313.035695 -21.874934) (xy 313.027575 -21.93011)
			(xy 313.011507 -21.983517) (xy 312.987835 -22.034014) (xy 312.957062 -22.080527) (xy 312.919845 -22.122064)
			(xy 312.876977 -22.157739) (xy 312.829371 -22.186793) (xy 312.778042 -22.208605) (xy 312.724085 -22.222711)
			(xy 312.668648 -22.228811) (xy 312.612914 -22.226774) (xy 312.558071 -22.216644) (xy 312.505287 -22.198637)
			(xy 312.455687 -22.173136) (xy 312.410329 -22.140685) (xy 312.37018 -22.101976) (xy 312.336094 -22.057833)
			(xy 312.308798 -22.009198) (xy 312.288875 -21.957107) (xy 312.276749 -21.90267) (xy 312.272678 -21.847048)
			(xy 311.80186 -21.847048) (xy 311.802018 -21.855684) (xy 311.801509 -21.88357) (xy 311.793389 -21.938746)
			(xy 311.777321 -21.992153) (xy 311.753649 -22.04265) (xy 311.722876 -22.089163) (xy 311.685659 -22.1307)
			(xy 311.642791 -22.166375) (xy 311.595185 -22.195429) (xy 311.543856 -22.217241) (xy 311.489899 -22.231347)
			(xy 311.434462 -22.237447) (xy 311.378728 -22.23541) (xy 311.323885 -22.22528) (xy 311.271101 -22.207273)
			(xy 311.221501 -22.181772) (xy 311.176143 -22.149321) (xy 311.135994 -22.110612) (xy 311.101908 -22.066469)
			(xy 311.074612 -22.017834) (xy 311.054689 -21.965743) (xy 311.042563 -21.911306) (xy 311.038492 -21.855684)
			(xy 310.891122 -21.855684) (xy 310.890673 -21.858736) (xy 310.874605 -21.912143) (xy 310.850933 -21.96264)
			(xy 310.82016 -22.009153) (xy 310.782943 -22.05069) (xy 310.740075 -22.086365) (xy 310.692469 -22.115419)
			(xy 310.64114 -22.137231) (xy 310.587183 -22.151337) (xy 310.531746 -22.157437) (xy 310.476012 -22.1554)
			(xy 310.421169 -22.14527) (xy 310.368385 -22.127263) (xy 310.318785 -22.101762) (xy 310.273427 -22.069311)
			(xy 310.233278 -22.030602) (xy 310.199192 -21.986459) (xy 310.171896 -21.937824) (xy 310.151973 -21.885733)
			(xy 310.139847 -21.831296) (xy 310.135776 -21.775674) (xy 301.011697 -21.775674) (xy 300.990497 -21.822093)
			(xy 300.961031 -21.867943) (xy 300.92534 -21.909134) (xy 300.884149 -21.944825) (xy 300.838299 -21.974291)
			(xy 300.788722 -21.996933) (xy 300.736427 -22.012288) (xy 300.682479 -22.020044) (xy 300.627977 -22.020044)
			(xy 300.574029 -22.012288) (xy 300.521734 -21.996933) (xy 300.472157 -21.974291) (xy 300.426307 -21.944825)
			(xy 300.385116 -21.909134) (xy 300.349425 -21.867943) (xy 300.319959 -21.822093) (xy 300.297317 -21.772516)
			(xy 300.281962 -21.720221) (xy 300.274206 -21.666273) (xy 300.27372 -21.639022) (xy 293.443303 -21.639022)
			(xy 293.430106 -21.668025) (xy 293.369061 -21.783021) (xy 293.30112 -21.894082) (xy 293.226534 -22.000794)
			(xy 293.145581 -22.102761) (xy 293.058562 -22.199603) (xy 292.965801 -22.29096) (xy 292.867643 -22.376492)
			(xy 292.764454 -22.45588) (xy 292.656617 -22.52883) (xy 292.611567 -22.555454) (xy 309.536336 -22.555454)
			(xy 309.540407 -22.499832) (xy 309.552533 -22.445395) (xy 309.572456 -22.393304) (xy 309.599752 -22.344669)
			(xy 309.633838 -22.300526) (xy 309.673987 -22.261817) (xy 309.719345 -22.229366) (xy 309.768945 -22.203865)
			(xy 309.821729 -22.185858) (xy 309.876572 -22.175728) (xy 309.932306 -22.173691) (xy 309.987743 -22.179791)
			(xy 310.0417 -22.193897) (xy 310.093029 -22.215709) (xy 310.140635 -22.244763) (xy 310.183503 -22.280438)
			(xy 310.22072 -22.321975) (xy 310.251493 -22.368488) (xy 310.275165 -22.418985) (xy 310.291233 -22.472392)
			(xy 310.299353 -22.527568) (xy 310.299862 -22.555454) (xy 310.299353 -22.58334) (xy 310.291233 -22.638516)
			(xy 310.275165 -22.691923) (xy 310.251493 -22.74242) (xy 310.22072 -22.788933) (xy 310.183503 -22.83047)
			(xy 310.140635 -22.866145) (xy 310.093029 -22.895199) (xy 310.0417 -22.917011) (xy 309.987743 -22.931117)
			(xy 309.932306 -22.937217) (xy 309.876572 -22.93518) (xy 309.821729 -22.92505) (xy 309.768945 -22.907043)
			(xy 309.719345 -22.881542) (xy 309.673987 -22.849091) (xy 309.633838 -22.810382) (xy 309.599752 -22.766239)
			(xy 309.572456 -22.717604) (xy 309.552533 -22.665513) (xy 309.540407 -22.611076) (xy 309.536336 -22.555454)
			(xy 292.611567 -22.555454) (xy 292.544532 -22.595071) (xy 292.428619 -22.654354) (xy 292.309306 -22.706462)
			(xy 292.187039 -22.751198) (xy 292.062272 -22.788397) (xy 291.935469 -22.817921) (xy 291.807102 -22.839659)
			(xy 291.677649 -22.853532) (xy 291.54759 -22.859486) (xy 291.417411 -22.857501) (xy 291.287595 -22.847583)
			(xy 291.158625 -22.829769) (xy 291.03098 -22.804126) (xy 290.905137 -22.770749) (xy 290.781562 -22.729762)
			(xy 290.660716 -22.681318) (xy 290.543048 -22.625596) (xy 290.428996 -22.562805) (xy 290.318984 -22.493178)
			(xy 290.213422 -22.416973) (xy 290.112702 -22.334474) (xy 290.017198 -22.245989) (xy 289.927266 -22.151846)
			(xy 289.843241 -22.052395) (xy 289.765436 -21.948007) (xy 289.694139 -21.83907) (xy 289.629615 -21.725988)
			(xy 289.572106 -21.609184) (xy 289.521824 -21.489091) (xy 289.478958 -21.366155) (xy 289.443665 -21.240836)
			(xy 289.416079 -21.113597) (xy 289.3963 -20.984914) (xy 289.384404 -20.855264) (xy 289.380434 -20.72513)
			(xy 283.150179 -20.72513) (xy 283.134535 -20.74259) (xy 283.091667 -20.778265) (xy 283.044061 -20.807319)
			(xy 282.992732 -20.829131) (xy 282.938775 -20.843237) (xy 282.883338 -20.849337) (xy 282.827604 -20.8473)
			(xy 282.772761 -20.83717) (xy 282.719977 -20.819163) (xy 282.670377 -20.793662) (xy 282.625019 -20.761211)
			(xy 282.58487 -20.722502) (xy 282.550784 -20.678359) (xy 282.523488 -20.629724) (xy 282.503565 -20.577633)
			(xy 282.491439 -20.523196) (xy 282.487368 -20.467574) (xy 275.006285 -20.467574) (xy 274.985506 -20.510391)
			(xy 274.952937 -20.557753) (xy 274.933664 -20.57908) (xy 274.92706 -20.585938) (xy 274.919948 -20.603972)
			(xy 274.919948 -20.692872) (xy 274.92706 -20.710906) (xy 274.933664 -20.717764) (xy 274.952957 -20.739072)
			(xy 274.985523 -20.786437) (xy 275.010614 -20.838152) (xy 275.027663 -20.893046) (xy 275.036284 -20.949876)
			(xy 275.036281 -21.007356) (xy 275.027656 -21.064186) (xy 275.010602 -21.119078) (xy 274.985506 -21.170791)
			(xy 274.952937 -21.218153) (xy 274.933664 -21.23948) (xy 274.92706 -21.246338) (xy 274.919948 -21.264372)
			(xy 274.919948 -21.353272) (xy 274.92706 -21.371306) (xy 274.933664 -21.378164) (xy 274.952945 -21.399482)
			(xy 274.98551 -21.446846) (xy 275.010601 -21.49856) (xy 275.027649 -21.553453) (xy 275.036269 -21.610282)
			(xy 275.036788 -21.639022) (xy 275.036302 -21.666273) (xy 275.028546 -21.720221) (xy 275.013191 -21.772516)
			(xy 275.011749 -21.775674) (xy 284.135828 -21.775674) (xy 284.139899 -21.720052) (xy 284.152025 -21.665615)
			(xy 284.171948 -21.613524) (xy 284.199244 -21.564889) (xy 284.23333 -21.520746) (xy 284.273479 -21.482037)
			(xy 284.318837 -21.449586) (xy 284.368437 -21.424085) (xy 284.421221 -21.406078) (xy 284.476064 -21.395948)
			(xy 284.531798 -21.393911) (xy 284.587235 -21.400011) (xy 284.641192 -21.414117) (xy 284.692521 -21.435929)
			(xy 284.740127 -21.464983) (xy 284.782995 -21.500658) (xy 284.820212 -21.542195) (xy 284.850985 -21.588708)
			(xy 284.874657 -21.639205) (xy 284.890725 -21.692612) (xy 284.898845 -21.747788) (xy 284.899354 -21.775674)
			(xy 284.898845 -21.80356) (xy 284.891174 -21.855684) (xy 285.038544 -21.855684) (xy 285.042615 -21.800062)
			(xy 285.054741 -21.745625) (xy 285.074664 -21.693534) (xy 285.10196 -21.644899) (xy 285.136046 -21.600756)
			(xy 285.176195 -21.562047) (xy 285.221553 -21.529596) (xy 285.271153 -21.504095) (xy 285.323937 -21.486088)
			(xy 285.37878 -21.475958) (xy 285.434514 -21.473921) (xy 285.489951 -21.480021) (xy 285.543908 -21.494127)
			(xy 285.595237 -21.515939) (xy 285.642843 -21.544993) (xy 285.685711 -21.580668) (xy 285.722928 -21.622205)
			(xy 285.753701 -21.668718) (xy 285.777373 -21.719215) (xy 285.793441 -21.772622) (xy 285.801561 -21.827798)
			(xy 285.801912 -21.847048) (xy 286.27273 -21.847048) (xy 286.276801 -21.791426) (xy 286.288927 -21.736989)
			(xy 286.30885 -21.684898) (xy 286.336146 -21.636263) (xy 286.370232 -21.59212) (xy 286.410381 -21.553411)
			(xy 286.455739 -21.52096) (xy 286.505339 -21.495459) (xy 286.558123 -21.477452) (xy 286.612966 -21.467322)
			(xy 286.6687 -21.465285) (xy 286.724137 -21.471385) (xy 286.778094 -21.485491) (xy 286.829423 -21.507303)
			(xy 286.877029 -21.536357) (xy 286.919897 -21.572032) (xy 286.957114 -21.613569) (xy 286.987887 -21.660082)
			(xy 287.011559 -21.710579) (xy 287.027627 -21.763986) (xy 287.035747 -21.819162) (xy 287.036256 -21.847048)
			(xy 287.035747 -21.874934) (xy 287.027627 -21.93011) (xy 287.011559 -21.983517) (xy 286.987887 -22.034014)
			(xy 286.957114 -22.080527) (xy 286.919897 -22.122064) (xy 286.877029 -22.157739) (xy 286.829423 -22.186793)
			(xy 286.778094 -22.208605) (xy 286.724137 -22.222711) (xy 286.6687 -22.228811) (xy 286.612966 -22.226774)
			(xy 286.558123 -22.216644) (xy 286.505339 -22.198637) (xy 286.455739 -22.173136) (xy 286.410381 -22.140685)
			(xy 286.370232 -22.101976) (xy 286.336146 -22.057833) (xy 286.30885 -22.009198) (xy 286.288927 -21.957107)
			(xy 286.276801 -21.90267) (xy 286.27273 -21.847048) (xy 285.801912 -21.847048) (xy 285.80207 -21.855684)
			(xy 285.801561 -21.88357) (xy 285.793441 -21.938746) (xy 285.777373 -21.992153) (xy 285.753701 -22.04265)
			(xy 285.722928 -22.089163) (xy 285.685711 -22.1307) (xy 285.642843 -22.166375) (xy 285.595237 -22.195429)
			(xy 285.543908 -22.217241) (xy 285.489951 -22.231347) (xy 285.434514 -22.237447) (xy 285.37878 -22.23541)
			(xy 285.323937 -22.22528) (xy 285.271153 -22.207273) (xy 285.221553 -22.181772) (xy 285.176195 -22.149321)
			(xy 285.136046 -22.110612) (xy 285.10196 -22.066469) (xy 285.074664 -22.017834) (xy 285.054741 -21.965743)
			(xy 285.042615 -21.911306) (xy 285.038544 -21.855684) (xy 284.891174 -21.855684) (xy 284.890725 -21.858736)
			(xy 284.874657 -21.912143) (xy 284.850985 -21.96264) (xy 284.820212 -22.009153) (xy 284.782995 -22.05069)
			(xy 284.740127 -22.086365) (xy 284.692521 -22.115419) (xy 284.641192 -22.137231) (xy 284.587235 -22.151337)
			(xy 284.531798 -22.157437) (xy 284.476064 -22.1554) (xy 284.421221 -22.14527) (xy 284.368437 -22.127263)
			(xy 284.318837 -22.101762) (xy 284.273479 -22.069311) (xy 284.23333 -22.030602) (xy 284.199244 -21.986459)
			(xy 284.171948 -21.937824) (xy 284.152025 -21.885733) (xy 284.139899 -21.831296) (xy 284.135828 -21.775674)
			(xy 275.011749 -21.775674) (xy 274.990549 -21.822093) (xy 274.961083 -21.867943) (xy 274.925392 -21.909134)
			(xy 274.884201 -21.944825) (xy 274.838351 -21.974291) (xy 274.788774 -21.996933) (xy 274.736479 -22.012288)
			(xy 274.682531 -22.020044) (xy 274.628029 -22.020044) (xy 274.574081 -22.012288) (xy 274.521786 -21.996933)
			(xy 274.472209 -21.974291) (xy 274.426359 -21.944825) (xy 274.385168 -21.909134) (xy 274.349477 -21.867943)
			(xy 274.320011 -21.822093) (xy 274.297369 -21.772516) (xy 274.282014 -21.720221) (xy 274.274258 -21.666273)
			(xy 274.273772 -21.639022) (xy 267.443355 -21.639022) (xy 267.430158 -21.668025) (xy 267.369113 -21.783021)
			(xy 267.301172 -21.894082) (xy 267.226586 -22.000794) (xy 267.145633 -22.102761) (xy 267.058614 -22.199603)
			(xy 266.965853 -22.29096) (xy 266.867695 -22.376492) (xy 266.764506 -22.45588) (xy 266.656669 -22.52883)
			(xy 266.611619 -22.555454) (xy 283.536388 -22.555454) (xy 283.540459 -22.499832) (xy 283.552585 -22.445395)
			(xy 283.572508 -22.393304) (xy 283.599804 -22.344669) (xy 283.63389 -22.300526) (xy 283.674039 -22.261817)
			(xy 283.719397 -22.229366) (xy 283.768997 -22.203865) (xy 283.821781 -22.185858) (xy 283.876624 -22.175728)
			(xy 283.932358 -22.173691) (xy 283.987795 -22.179791) (xy 284.041752 -22.193897) (xy 284.093081 -22.215709)
			(xy 284.140687 -22.244763) (xy 284.183555 -22.280438) (xy 284.220772 -22.321975) (xy 284.251545 -22.368488)
			(xy 284.275217 -22.418985) (xy 284.291285 -22.472392) (xy 284.299405 -22.527568) (xy 284.299914 -22.555454)
			(xy 284.299405 -22.58334) (xy 284.291285 -22.638516) (xy 284.275217 -22.691923) (xy 284.251545 -22.74242)
			(xy 284.220772 -22.788933) (xy 284.183555 -22.83047) (xy 284.140687 -22.866145) (xy 284.093081 -22.895199)
			(xy 284.041752 -22.917011) (xy 283.987795 -22.931117) (xy 283.932358 -22.937217) (xy 283.876624 -22.93518)
			(xy 283.821781 -22.92505) (xy 283.768997 -22.907043) (xy 283.719397 -22.881542) (xy 283.674039 -22.849091)
			(xy 283.63389 -22.810382) (xy 283.599804 -22.766239) (xy 283.572508 -22.717604) (xy 283.552585 -22.665513)
			(xy 283.540459 -22.611076) (xy 283.536388 -22.555454) (xy 266.611619 -22.555454) (xy 266.544584 -22.595071)
			(xy 266.428671 -22.654354) (xy 266.309358 -22.706462) (xy 266.187091 -22.751198) (xy 266.062324 -22.788397)
			(xy 265.935521 -22.817921) (xy 265.807154 -22.839659) (xy 265.677701 -22.853532) (xy 265.547642 -22.859486)
			(xy 265.417463 -22.857501) (xy 265.287647 -22.847583) (xy 265.158677 -22.829769) (xy 265.031032 -22.804126)
			(xy 264.905189 -22.770749) (xy 264.781614 -22.729762) (xy 264.660768 -22.681318) (xy 264.5431 -22.625596)
			(xy 264.429048 -22.562805) (xy 264.319036 -22.493178) (xy 264.213474 -22.416973) (xy 264.112754 -22.334474)
			(xy 264.01725 -22.245989) (xy 263.927318 -22.151846) (xy 263.843293 -22.052395) (xy 263.765488 -21.948007)
			(xy 263.694191 -21.83907) (xy 263.629667 -21.725988) (xy 263.572158 -21.609184) (xy 263.521876 -21.489091)
			(xy 263.47901 -21.366155) (xy 263.443717 -21.240836) (xy 263.416131 -21.113597) (xy 263.396352 -20.984914)
			(xy 263.384456 -20.855264) (xy 263.380486 -20.72513) (xy 257.150231 -20.72513) (xy 257.134587 -20.74259)
			(xy 257.091719 -20.778265) (xy 257.044113 -20.807319) (xy 256.992784 -20.829131) (xy 256.938827 -20.843237)
			(xy 256.88339 -20.849337) (xy 256.827656 -20.8473) (xy 256.772813 -20.83717) (xy 256.720029 -20.819163)
			(xy 256.670429 -20.793662) (xy 256.625071 -20.761211) (xy 256.584922 -20.722502) (xy 256.550836 -20.678359)
			(xy 256.52354 -20.629724) (xy 256.503617 -20.577633) (xy 256.491491 -20.523196) (xy 256.48742 -20.467574)
			(xy 249.006326 -20.467574) (xy 248.985552 -20.510388) (xy 248.952987 -20.557752) (xy 248.933716 -20.57908)
			(xy 248.927112 -20.585938) (xy 248.92 -20.603972) (xy 248.92 -20.692872) (xy 248.927112 -20.710906)
			(xy 248.933716 -20.717764) (xy 248.953007 -20.739073) (xy 248.985568 -20.786439) (xy 249.010656 -20.838154)
			(xy 249.027702 -20.893048) (xy 249.036322 -20.949877) (xy 249.036319 -21.007356) (xy 249.027695 -21.064184)
			(xy 249.010644 -21.119075) (xy 248.985552 -21.170788) (xy 248.952987 -21.218152) (xy 248.933716 -21.23948)
			(xy 248.927112 -21.246338) (xy 248.92 -21.264372) (xy 248.92 -21.353272) (xy 248.927112 -21.371306)
			(xy 248.933716 -21.378164) (xy 248.95299 -21.399489) (xy 248.985557 -21.446851) (xy 249.01065 -21.498563)
			(xy 249.0277 -21.553454) (xy 249.036321 -21.610283) (xy 249.03684 -21.639022) (xy 249.036354 -21.666273)
			(xy 249.028598 -21.720221) (xy 249.013243 -21.772516) (xy 249.011801 -21.775674) (xy 258.13588 -21.775674)
			(xy 258.139951 -21.720052) (xy 258.152077 -21.665615) (xy 258.172 -21.613524) (xy 258.199296 -21.564889)
			(xy 258.233382 -21.520746) (xy 258.273531 -21.482037) (xy 258.318889 -21.449586) (xy 258.368489 -21.424085)
			(xy 258.421273 -21.406078) (xy 258.476116 -21.395948) (xy 258.53185 -21.393911) (xy 258.587287 -21.400011)
			(xy 258.641244 -21.414117) (xy 258.692573 -21.435929) (xy 258.740179 -21.464983) (xy 258.783047 -21.500658)
			(xy 258.820264 -21.542195) (xy 258.851037 -21.588708) (xy 258.874709 -21.639205) (xy 258.890777 -21.692612)
			(xy 258.898897 -21.747788) (xy 258.899406 -21.775674) (xy 258.898897 -21.80356) (xy 258.891226 -21.855684)
			(xy 259.038596 -21.855684) (xy 259.042667 -21.800062) (xy 259.054793 -21.745625) (xy 259.074716 -21.693534)
			(xy 259.102012 -21.644899) (xy 259.136098 -21.600756) (xy 259.176247 -21.562047) (xy 259.221605 -21.529596)
			(xy 259.271205 -21.504095) (xy 259.323989 -21.486088) (xy 259.378832 -21.475958) (xy 259.434566 -21.473921)
			(xy 259.490003 -21.480021) (xy 259.54396 -21.494127) (xy 259.595289 -21.515939) (xy 259.642895 -21.544993)
			(xy 259.685763 -21.580668) (xy 259.72298 -21.622205) (xy 259.753753 -21.668718) (xy 259.777425 -21.719215)
			(xy 259.793493 -21.772622) (xy 259.801613 -21.827798) (xy 259.801964 -21.847048) (xy 260.272782 -21.847048)
			(xy 260.276853 -21.791426) (xy 260.288979 -21.736989) (xy 260.308902 -21.684898) (xy 260.336198 -21.636263)
			(xy 260.370284 -21.59212) (xy 260.410433 -21.553411) (xy 260.455791 -21.52096) (xy 260.505391 -21.495459)
			(xy 260.558175 -21.477452) (xy 260.613018 -21.467322) (xy 260.668752 -21.465285) (xy 260.724189 -21.471385)
			(xy 260.778146 -21.485491) (xy 260.829475 -21.507303) (xy 260.877081 -21.536357) (xy 260.919949 -21.572032)
			(xy 260.957166 -21.613569) (xy 260.987939 -21.660082) (xy 261.011611 -21.710579) (xy 261.027679 -21.763986)
			(xy 261.035799 -21.819162) (xy 261.036308 -21.847048) (xy 261.035799 -21.874934) (xy 261.027679 -21.93011)
			(xy 261.011611 -21.983517) (xy 260.987939 -22.034014) (xy 260.957166 -22.080527) (xy 260.919949 -22.122064)
			(xy 260.877081 -22.157739) (xy 260.829475 -22.186793) (xy 260.778146 -22.208605) (xy 260.724189 -22.222711)
			(xy 260.668752 -22.228811) (xy 260.613018 -22.226774) (xy 260.558175 -22.216644) (xy 260.505391 -22.198637)
			(xy 260.455791 -22.173136) (xy 260.410433 -22.140685) (xy 260.370284 -22.101976) (xy 260.336198 -22.057833)
			(xy 260.308902 -22.009198) (xy 260.288979 -21.957107) (xy 260.276853 -21.90267) (xy 260.272782 -21.847048)
			(xy 259.801964 -21.847048) (xy 259.802122 -21.855684) (xy 259.801613 -21.88357) (xy 259.793493 -21.938746)
			(xy 259.777425 -21.992153) (xy 259.753753 -22.04265) (xy 259.72298 -22.089163) (xy 259.685763 -22.1307)
			(xy 259.642895 -22.166375) (xy 259.595289 -22.195429) (xy 259.54396 -22.217241) (xy 259.490003 -22.231347)
			(xy 259.434566 -22.237447) (xy 259.378832 -22.23541) (xy 259.323989 -22.22528) (xy 259.271205 -22.207273)
			(xy 259.221605 -22.181772) (xy 259.176247 -22.149321) (xy 259.136098 -22.110612) (xy 259.102012 -22.066469)
			(xy 259.074716 -22.017834) (xy 259.054793 -21.965743) (xy 259.042667 -21.911306) (xy 259.038596 -21.855684)
			(xy 258.891226 -21.855684) (xy 258.890777 -21.858736) (xy 258.874709 -21.912143) (xy 258.851037 -21.96264)
			(xy 258.820264 -22.009153) (xy 258.783047 -22.05069) (xy 258.740179 -22.086365) (xy 258.692573 -22.115419)
			(xy 258.641244 -22.137231) (xy 258.587287 -22.151337) (xy 258.53185 -22.157437) (xy 258.476116 -22.1554)
			(xy 258.421273 -22.14527) (xy 258.368489 -22.127263) (xy 258.318889 -22.101762) (xy 258.273531 -22.069311)
			(xy 258.233382 -22.030602) (xy 258.199296 -21.986459) (xy 258.172 -21.937824) (xy 258.152077 -21.885733)
			(xy 258.139951 -21.831296) (xy 258.13588 -21.775674) (xy 249.011801 -21.775674) (xy 248.990601 -21.822093)
			(xy 248.961135 -21.867943) (xy 248.925444 -21.909134) (xy 248.884253 -21.944825) (xy 248.838403 -21.974291)
			(xy 248.788826 -21.996933) (xy 248.736531 -22.012288) (xy 248.682583 -22.020044) (xy 248.628081 -22.020044)
			(xy 248.574133 -22.012288) (xy 248.521838 -21.996933) (xy 248.472261 -21.974291) (xy 248.426411 -21.944825)
			(xy 248.38522 -21.909134) (xy 248.349529 -21.867943) (xy 248.320063 -21.822093) (xy 248.297421 -21.772516)
			(xy 248.282066 -21.720221) (xy 248.27431 -21.666273) (xy 248.273824 -21.639022) (xy 241.443407 -21.639022)
			(xy 241.43021 -21.668025) (xy 241.369165 -21.783021) (xy 241.301224 -21.894082) (xy 241.226638 -22.000794)
			(xy 241.145685 -22.102761) (xy 241.058666 -22.199603) (xy 240.965905 -22.29096) (xy 240.867747 -22.376492)
			(xy 240.764558 -22.45588) (xy 240.656721 -22.52883) (xy 240.611671 -22.555454) (xy 257.53644 -22.555454)
			(xy 257.540511 -22.499832) (xy 257.552637 -22.445395) (xy 257.57256 -22.393304) (xy 257.599856 -22.344669)
			(xy 257.633942 -22.300526) (xy 257.674091 -22.261817) (xy 257.719449 -22.229366) (xy 257.769049 -22.203865)
			(xy 257.821833 -22.185858) (xy 257.876676 -22.175728) (xy 257.93241 -22.173691) (xy 257.987847 -22.179791)
			(xy 258.041804 -22.193897) (xy 258.093133 -22.215709) (xy 258.140739 -22.244763) (xy 258.183607 -22.280438)
			(xy 258.220824 -22.321975) (xy 258.251597 -22.368488) (xy 258.275269 -22.418985) (xy 258.291337 -22.472392)
			(xy 258.299457 -22.527568) (xy 258.299966 -22.555454) (xy 258.299457 -22.58334) (xy 258.291337 -22.638516)
			(xy 258.275269 -22.691923) (xy 258.251597 -22.74242) (xy 258.220824 -22.788933) (xy 258.183607 -22.83047)
			(xy 258.140739 -22.866145) (xy 258.093133 -22.895199) (xy 258.041804 -22.917011) (xy 257.987847 -22.931117)
			(xy 257.93241 -22.937217) (xy 257.876676 -22.93518) (xy 257.821833 -22.92505) (xy 257.769049 -22.907043)
			(xy 257.719449 -22.881542) (xy 257.674091 -22.849091) (xy 257.633942 -22.810382) (xy 257.599856 -22.766239)
			(xy 257.57256 -22.717604) (xy 257.552637 -22.665513) (xy 257.540511 -22.611076) (xy 257.53644 -22.555454)
			(xy 240.611671 -22.555454) (xy 240.544636 -22.595071) (xy 240.428723 -22.654354) (xy 240.30941 -22.706462)
			(xy 240.187143 -22.751198) (xy 240.062376 -22.788397) (xy 239.935573 -22.817921) (xy 239.807206 -22.839659)
			(xy 239.677753 -22.853532) (xy 239.547694 -22.859486) (xy 239.417515 -22.857501) (xy 239.287699 -22.847583)
			(xy 239.158729 -22.829769) (xy 239.031084 -22.804126) (xy 238.905241 -22.770749) (xy 238.781666 -22.729762)
			(xy 238.66082 -22.681318) (xy 238.543152 -22.625596) (xy 238.4291 -22.562805) (xy 238.319088 -22.493178)
			(xy 238.213526 -22.416973) (xy 238.112806 -22.334474) (xy 238.017302 -22.245989) (xy 237.92737 -22.151846)
			(xy 237.843345 -22.052395) (xy 237.76554 -21.948007) (xy 237.694243 -21.83907) (xy 237.629719 -21.725988)
			(xy 237.57221 -21.609184) (xy 237.521928 -21.489091) (xy 237.479062 -21.366155) (xy 237.443769 -21.240836)
			(xy 237.416183 -21.113597) (xy 237.396404 -20.984914) (xy 237.384508 -20.855264) (xy 237.380538 -20.72513)
			(xy 219.050231 -20.72513) (xy 219.034587 -20.74259) (xy 218.991719 -20.778265) (xy 218.944113 -20.807319)
			(xy 218.892784 -20.829131) (xy 218.838827 -20.843237) (xy 218.78339 -20.849337) (xy 218.727656 -20.8473)
			(xy 218.672813 -20.83717) (xy 218.620029 -20.819163) (xy 218.570429 -20.793662) (xy 218.525071 -20.761211)
			(xy 218.484922 -20.722502) (xy 218.450836 -20.678359) (xy 218.42354 -20.629724) (xy 218.403617 -20.577633)
			(xy 218.391491 -20.523196) (xy 218.38742 -20.467574) (xy 210.906326 -20.467574) (xy 210.885552 -20.510388)
			(xy 210.852987 -20.557752) (xy 210.833716 -20.57908) (xy 210.827112 -20.585938) (xy 210.82 -20.603972)
			(xy 210.82 -20.692872) (xy 210.827112 -20.710906) (xy 210.833716 -20.717764) (xy 210.853007 -20.739073)
			(xy 210.885568 -20.786439) (xy 210.910656 -20.838154) (xy 210.927702 -20.893048) (xy 210.936322 -20.949877)
			(xy 210.936319 -21.007356) (xy 210.927695 -21.064184) (xy 210.910644 -21.119075) (xy 210.885552 -21.170788)
			(xy 210.852987 -21.218152) (xy 210.833716 -21.23948) (xy 210.827112 -21.246338) (xy 210.82 -21.264372)
			(xy 210.82 -21.353272) (xy 210.827112 -21.371306) (xy 210.833716 -21.378164) (xy 210.85299 -21.399489)
			(xy 210.885557 -21.446851) (xy 210.91065 -21.498563) (xy 210.9277 -21.553454) (xy 210.936321 -21.610283)
			(xy 210.93684 -21.639022) (xy 210.936354 -21.666273) (xy 210.928598 -21.720221) (xy 210.913243 -21.772516)
			(xy 210.911801 -21.775674) (xy 220.03588 -21.775674) (xy 220.039951 -21.720052) (xy 220.052077 -21.665615)
			(xy 220.072 -21.613524) (xy 220.099296 -21.564889) (xy 220.133382 -21.520746) (xy 220.173531 -21.482037)
			(xy 220.218889 -21.449586) (xy 220.268489 -21.424085) (xy 220.321273 -21.406078) (xy 220.376116 -21.395948)
			(xy 220.43185 -21.393911) (xy 220.487287 -21.400011) (xy 220.541244 -21.414117) (xy 220.592573 -21.435929)
			(xy 220.640179 -21.464983) (xy 220.683047 -21.500658) (xy 220.720264 -21.542195) (xy 220.751037 -21.588708)
			(xy 220.774709 -21.639205) (xy 220.790777 -21.692612) (xy 220.798897 -21.747788) (xy 220.799406 -21.775674)
			(xy 220.798897 -21.80356) (xy 220.791226 -21.855684) (xy 220.938596 -21.855684) (xy 220.942667 -21.800062)
			(xy 220.954793 -21.745625) (xy 220.974716 -21.693534) (xy 221.002012 -21.644899) (xy 221.036098 -21.600756)
			(xy 221.076247 -21.562047) (xy 221.121605 -21.529596) (xy 221.171205 -21.504095) (xy 221.223989 -21.486088)
			(xy 221.278832 -21.475958) (xy 221.334566 -21.473921) (xy 221.390003 -21.480021) (xy 221.44396 -21.494127)
			(xy 221.495289 -21.515939) (xy 221.542895 -21.544993) (xy 221.585763 -21.580668) (xy 221.62298 -21.622205)
			(xy 221.653753 -21.668718) (xy 221.677425 -21.719215) (xy 221.693493 -21.772622) (xy 221.701613 -21.827798)
			(xy 221.701964 -21.847048) (xy 222.172782 -21.847048) (xy 222.176853 -21.791426) (xy 222.188979 -21.736989)
			(xy 222.208902 -21.684898) (xy 222.236198 -21.636263) (xy 222.270284 -21.59212) (xy 222.310433 -21.553411)
			(xy 222.355791 -21.52096) (xy 222.405391 -21.495459) (xy 222.458175 -21.477452) (xy 222.513018 -21.467322)
			(xy 222.568752 -21.465285) (xy 222.624189 -21.471385) (xy 222.678146 -21.485491) (xy 222.729475 -21.507303)
			(xy 222.777081 -21.536357) (xy 222.819949 -21.572032) (xy 222.857166 -21.613569) (xy 222.887939 -21.660082)
			(xy 222.911611 -21.710579) (xy 222.927679 -21.763986) (xy 222.935799 -21.819162) (xy 222.936308 -21.847048)
			(xy 222.935799 -21.874934) (xy 222.927679 -21.93011) (xy 222.911611 -21.983517) (xy 222.887939 -22.034014)
			(xy 222.857166 -22.080527) (xy 222.819949 -22.122064) (xy 222.777081 -22.157739) (xy 222.729475 -22.186793)
			(xy 222.678146 -22.208605) (xy 222.624189 -22.222711) (xy 222.568752 -22.228811) (xy 222.513018 -22.226774)
			(xy 222.458175 -22.216644) (xy 222.405391 -22.198637) (xy 222.355791 -22.173136) (xy 222.310433 -22.140685)
			(xy 222.270284 -22.101976) (xy 222.236198 -22.057833) (xy 222.208902 -22.009198) (xy 222.188979 -21.957107)
			(xy 222.176853 -21.90267) (xy 222.172782 -21.847048) (xy 221.701964 -21.847048) (xy 221.702122 -21.855684)
			(xy 221.701613 -21.88357) (xy 221.693493 -21.938746) (xy 221.677425 -21.992153) (xy 221.653753 -22.04265)
			(xy 221.62298 -22.089163) (xy 221.585763 -22.1307) (xy 221.542895 -22.166375) (xy 221.495289 -22.195429)
			(xy 221.44396 -22.217241) (xy 221.390003 -22.231347) (xy 221.334566 -22.237447) (xy 221.278832 -22.23541)
			(xy 221.223989 -22.22528) (xy 221.171205 -22.207273) (xy 221.121605 -22.181772) (xy 221.076247 -22.149321)
			(xy 221.036098 -22.110612) (xy 221.002012 -22.066469) (xy 220.974716 -22.017834) (xy 220.954793 -21.965743)
			(xy 220.942667 -21.911306) (xy 220.938596 -21.855684) (xy 220.791226 -21.855684) (xy 220.790777 -21.858736)
			(xy 220.774709 -21.912143) (xy 220.751037 -21.96264) (xy 220.720264 -22.009153) (xy 220.683047 -22.05069)
			(xy 220.640179 -22.086365) (xy 220.592573 -22.115419) (xy 220.541244 -22.137231) (xy 220.487287 -22.151337)
			(xy 220.43185 -22.157437) (xy 220.376116 -22.1554) (xy 220.321273 -22.14527) (xy 220.268489 -22.127263)
			(xy 220.218889 -22.101762) (xy 220.173531 -22.069311) (xy 220.133382 -22.030602) (xy 220.099296 -21.986459)
			(xy 220.072 -21.937824) (xy 220.052077 -21.885733) (xy 220.039951 -21.831296) (xy 220.03588 -21.775674)
			(xy 210.911801 -21.775674) (xy 210.890601 -21.822093) (xy 210.861135 -21.867943) (xy 210.825444 -21.909134)
			(xy 210.784253 -21.944825) (xy 210.738403 -21.974291) (xy 210.688826 -21.996933) (xy 210.636531 -22.012288)
			(xy 210.582583 -22.020044) (xy 210.528081 -22.020044) (xy 210.474133 -22.012288) (xy 210.421838 -21.996933)
			(xy 210.372261 -21.974291) (xy 210.326411 -21.944825) (xy 210.28522 -21.909134) (xy 210.249529 -21.867943)
			(xy 210.220063 -21.822093) (xy 210.197421 -21.772516) (xy 210.182066 -21.720221) (xy 210.17431 -21.666273)
			(xy 210.173824 -21.639022) (xy 203.343407 -21.639022) (xy 203.33021 -21.668025) (xy 203.269165 -21.783021)
			(xy 203.201224 -21.894082) (xy 203.126638 -22.000794) (xy 203.045685 -22.102761) (xy 202.958666 -22.199603)
			(xy 202.865905 -22.29096) (xy 202.767747 -22.376492) (xy 202.664558 -22.45588) (xy 202.556721 -22.52883)
			(xy 202.511671 -22.555454) (xy 219.43644 -22.555454) (xy 219.440511 -22.499832) (xy 219.452637 -22.445395)
			(xy 219.47256 -22.393304) (xy 219.499856 -22.344669) (xy 219.533942 -22.300526) (xy 219.574091 -22.261817)
			(xy 219.619449 -22.229366) (xy 219.669049 -22.203865) (xy 219.721833 -22.185858) (xy 219.776676 -22.175728)
			(xy 219.83241 -22.173691) (xy 219.887847 -22.179791) (xy 219.941804 -22.193897) (xy 219.993133 -22.215709)
			(xy 220.040739 -22.244763) (xy 220.083607 -22.280438) (xy 220.120824 -22.321975) (xy 220.151597 -22.368488)
			(xy 220.175269 -22.418985) (xy 220.191337 -22.472392) (xy 220.199457 -22.527568) (xy 220.199966 -22.555454)
			(xy 220.199457 -22.58334) (xy 220.191337 -22.638516) (xy 220.175269 -22.691923) (xy 220.151597 -22.74242)
			(xy 220.120824 -22.788933) (xy 220.083607 -22.83047) (xy 220.040739 -22.866145) (xy 219.993133 -22.895199)
			(xy 219.941804 -22.917011) (xy 219.887847 -22.931117) (xy 219.83241 -22.937217) (xy 219.776676 -22.93518)
			(xy 219.721833 -22.92505) (xy 219.669049 -22.907043) (xy 219.619449 -22.881542) (xy 219.574091 -22.849091)
			(xy 219.533942 -22.810382) (xy 219.499856 -22.766239) (xy 219.47256 -22.717604) (xy 219.452637 -22.665513)
			(xy 219.440511 -22.611076) (xy 219.43644 -22.555454) (xy 202.511671 -22.555454) (xy 202.444636 -22.595071)
			(xy 202.328723 -22.654354) (xy 202.20941 -22.706462) (xy 202.087143 -22.751198) (xy 201.962376 -22.788397)
			(xy 201.835573 -22.817921) (xy 201.707206 -22.839659) (xy 201.577753 -22.853532) (xy 201.447694 -22.859486)
			(xy 201.317515 -22.857501) (xy 201.187699 -22.847583) (xy 201.058729 -22.829769) (xy 200.931084 -22.804126)
			(xy 200.805241 -22.770749) (xy 200.681666 -22.729762) (xy 200.56082 -22.681318) (xy 200.443152 -22.625596)
			(xy 200.3291 -22.562805) (xy 200.219088 -22.493178) (xy 200.113526 -22.416973) (xy 200.012806 -22.334474)
			(xy 199.917302 -22.245989) (xy 199.82737 -22.151846) (xy 199.743345 -22.052395) (xy 199.66554 -21.948007)
			(xy 199.594243 -21.83907) (xy 199.529719 -21.725988) (xy 199.47221 -21.609184) (xy 199.421928 -21.489091)
			(xy 199.379062 -21.366155) (xy 199.343769 -21.240836) (xy 199.316183 -21.113597) (xy 199.296404 -20.984914)
			(xy 199.284508 -20.855264) (xy 199.280538 -20.72513) (xy 193.050283 -20.72513) (xy 193.034639 -20.74259)
			(xy 192.991771 -20.778265) (xy 192.944165 -20.807319) (xy 192.892836 -20.829131) (xy 192.838879 -20.843237)
			(xy 192.783442 -20.849337) (xy 192.727708 -20.8473) (xy 192.672865 -20.83717) (xy 192.620081 -20.819163)
			(xy 192.570481 -20.793662) (xy 192.525123 -20.761211) (xy 192.484974 -20.722502) (xy 192.450888 -20.678359)
			(xy 192.423592 -20.629724) (xy 192.403669 -20.577633) (xy 192.391543 -20.523196) (xy 192.387472 -20.467574)
			(xy 184.906388 -20.467574) (xy 184.88561 -20.510391) (xy 184.853041 -20.557753) (xy 184.833768 -20.57908)
			(xy 184.827164 -20.585938) (xy 184.820052 -20.603972) (xy 184.820052 -20.692872) (xy 184.827164 -20.710906)
			(xy 184.833768 -20.717764) (xy 184.853061 -20.739072) (xy 184.885626 -20.786437) (xy 184.910717 -20.838152)
			(xy 184.927766 -20.893046) (xy 184.936387 -20.949876) (xy 184.936384 -21.007356) (xy 184.927759 -21.064186)
			(xy 184.910705 -21.119078) (xy 184.88561 -21.170791) (xy 184.853041 -21.218153) (xy 184.833768 -21.23948)
			(xy 184.827164 -21.246338) (xy 184.820052 -21.264372) (xy 184.820052 -21.353272) (xy 184.827164 -21.371306)
			(xy 184.833768 -21.378164) (xy 184.85305 -21.399481) (xy 184.885615 -21.446846) (xy 184.910705 -21.49856)
			(xy 184.927753 -21.553453) (xy 184.936373 -21.610282) (xy 184.936892 -21.639022) (xy 184.936406 -21.666273)
			(xy 184.92865 -21.720221) (xy 184.913295 -21.772516) (xy 184.911853 -21.775674) (xy 194.035932 -21.775674)
			(xy 194.040003 -21.720052) (xy 194.052129 -21.665615) (xy 194.072052 -21.613524) (xy 194.099348 -21.564889)
			(xy 194.133434 -21.520746) (xy 194.173583 -21.482037) (xy 194.218941 -21.449586) (xy 194.268541 -21.424085)
			(xy 194.321325 -21.406078) (xy 194.376168 -21.395948) (xy 194.431902 -21.393911) (xy 194.487339 -21.400011)
			(xy 194.541296 -21.414117) (xy 194.592625 -21.435929) (xy 194.640231 -21.464983) (xy 194.683099 -21.500658)
			(xy 194.720316 -21.542195) (xy 194.751089 -21.588708) (xy 194.774761 -21.639205) (xy 194.790829 -21.692612)
			(xy 194.798949 -21.747788) (xy 194.799458 -21.775674) (xy 194.798949 -21.80356) (xy 194.791278 -21.855684)
			(xy 194.938648 -21.855684) (xy 194.942719 -21.800062) (xy 194.954845 -21.745625) (xy 194.974768 -21.693534)
			(xy 195.002064 -21.644899) (xy 195.03615 -21.600756) (xy 195.076299 -21.562047) (xy 195.121657 -21.529596)
			(xy 195.171257 -21.504095) (xy 195.224041 -21.486088) (xy 195.278884 -21.475958) (xy 195.334618 -21.473921)
			(xy 195.390055 -21.480021) (xy 195.444012 -21.494127) (xy 195.495341 -21.515939) (xy 195.542947 -21.544993)
			(xy 195.585815 -21.580668) (xy 195.623032 -21.622205) (xy 195.653805 -21.668718) (xy 195.677477 -21.719215)
			(xy 195.693545 -21.772622) (xy 195.701665 -21.827798) (xy 195.702016 -21.847048) (xy 196.172834 -21.847048)
			(xy 196.176905 -21.791426) (xy 196.189031 -21.736989) (xy 196.208954 -21.684898) (xy 196.23625 -21.636263)
			(xy 196.270336 -21.59212) (xy 196.310485 -21.553411) (xy 196.355843 -21.52096) (xy 196.405443 -21.495459)
			(xy 196.458227 -21.477452) (xy 196.51307 -21.467322) (xy 196.568804 -21.465285) (xy 196.624241 -21.471385)
			(xy 196.678198 -21.485491) (xy 196.729527 -21.507303) (xy 196.777133 -21.536357) (xy 196.820001 -21.572032)
			(xy 196.857218 -21.613569) (xy 196.887991 -21.660082) (xy 196.911663 -21.710579) (xy 196.927731 -21.763986)
			(xy 196.935851 -21.819162) (xy 196.93636 -21.847048) (xy 196.935851 -21.874934) (xy 196.927731 -21.93011)
			(xy 196.911663 -21.983517) (xy 196.887991 -22.034014) (xy 196.857218 -22.080527) (xy 196.820001 -22.122064)
			(xy 196.777133 -22.157739) (xy 196.729527 -22.186793) (xy 196.678198 -22.208605) (xy 196.624241 -22.222711)
			(xy 196.568804 -22.228811) (xy 196.51307 -22.226774) (xy 196.458227 -22.216644) (xy 196.405443 -22.198637)
			(xy 196.355843 -22.173136) (xy 196.310485 -22.140685) (xy 196.270336 -22.101976) (xy 196.23625 -22.057833)
			(xy 196.208954 -22.009198) (xy 196.189031 -21.957107) (xy 196.176905 -21.90267) (xy 196.172834 -21.847048)
			(xy 195.702016 -21.847048) (xy 195.702174 -21.855684) (xy 195.701665 -21.88357) (xy 195.693545 -21.938746)
			(xy 195.677477 -21.992153) (xy 195.653805 -22.04265) (xy 195.623032 -22.089163) (xy 195.585815 -22.1307)
			(xy 195.542947 -22.166375) (xy 195.495341 -22.195429) (xy 195.444012 -22.217241) (xy 195.390055 -22.231347)
			(xy 195.334618 -22.237447) (xy 195.278884 -22.23541) (xy 195.224041 -22.22528) (xy 195.171257 -22.207273)
			(xy 195.121657 -22.181772) (xy 195.076299 -22.149321) (xy 195.03615 -22.110612) (xy 195.002064 -22.066469)
			(xy 194.974768 -22.017834) (xy 194.954845 -21.965743) (xy 194.942719 -21.911306) (xy 194.938648 -21.855684)
			(xy 194.791278 -21.855684) (xy 194.790829 -21.858736) (xy 194.774761 -21.912143) (xy 194.751089 -21.96264)
			(xy 194.720316 -22.009153) (xy 194.683099 -22.05069) (xy 194.640231 -22.086365) (xy 194.592625 -22.115419)
			(xy 194.541296 -22.137231) (xy 194.487339 -22.151337) (xy 194.431902 -22.157437) (xy 194.376168 -22.1554)
			(xy 194.321325 -22.14527) (xy 194.268541 -22.127263) (xy 194.218941 -22.101762) (xy 194.173583 -22.069311)
			(xy 194.133434 -22.030602) (xy 194.099348 -21.986459) (xy 194.072052 -21.937824) (xy 194.052129 -21.885733)
			(xy 194.040003 -21.831296) (xy 194.035932 -21.775674) (xy 184.911853 -21.775674) (xy 184.890653 -21.822093)
			(xy 184.861187 -21.867943) (xy 184.825496 -21.909134) (xy 184.784305 -21.944825) (xy 184.738455 -21.974291)
			(xy 184.688878 -21.996933) (xy 184.636583 -22.012288) (xy 184.582635 -22.020044) (xy 184.528133 -22.020044)
			(xy 184.474185 -22.012288) (xy 184.42189 -21.996933) (xy 184.372313 -21.974291) (xy 184.326463 -21.944825)
			(xy 184.285272 -21.909134) (xy 184.249581 -21.867943) (xy 184.220115 -21.822093) (xy 184.197473 -21.772516)
			(xy 184.182118 -21.720221) (xy 184.174362 -21.666273) (xy 184.173876 -21.639022) (xy 177.343459 -21.639022)
			(xy 177.330262 -21.668025) (xy 177.269217 -21.783021) (xy 177.201276 -21.894082) (xy 177.12669 -22.000794)
			(xy 177.045737 -22.102761) (xy 176.958718 -22.199603) (xy 176.865957 -22.29096) (xy 176.767799 -22.376492)
			(xy 176.66461 -22.45588) (xy 176.556773 -22.52883) (xy 176.511723 -22.555454) (xy 193.436492 -22.555454)
			(xy 193.440563 -22.499832) (xy 193.452689 -22.445395) (xy 193.472612 -22.393304) (xy 193.499908 -22.344669)
			(xy 193.533994 -22.300526) (xy 193.574143 -22.261817) (xy 193.619501 -22.229366) (xy 193.669101 -22.203865)
			(xy 193.721885 -22.185858) (xy 193.776728 -22.175728) (xy 193.832462 -22.173691) (xy 193.887899 -22.179791)
			(xy 193.941856 -22.193897) (xy 193.993185 -22.215709) (xy 194.040791 -22.244763) (xy 194.083659 -22.280438)
			(xy 194.120876 -22.321975) (xy 194.151649 -22.368488) (xy 194.175321 -22.418985) (xy 194.191389 -22.472392)
			(xy 194.199509 -22.527568) (xy 194.200018 -22.555454) (xy 194.199509 -22.58334) (xy 194.191389 -22.638516)
			(xy 194.175321 -22.691923) (xy 194.151649 -22.74242) (xy 194.120876 -22.788933) (xy 194.083659 -22.83047)
			(xy 194.040791 -22.866145) (xy 193.993185 -22.895199) (xy 193.941856 -22.917011) (xy 193.887899 -22.931117)
			(xy 193.832462 -22.937217) (xy 193.776728 -22.93518) (xy 193.721885 -22.92505) (xy 193.669101 -22.907043)
			(xy 193.619501 -22.881542) (xy 193.574143 -22.849091) (xy 193.533994 -22.810382) (xy 193.499908 -22.766239)
			(xy 193.472612 -22.717604) (xy 193.452689 -22.665513) (xy 193.440563 -22.611076) (xy 193.436492 -22.555454)
			(xy 176.511723 -22.555454) (xy 176.444688 -22.595071) (xy 176.328775 -22.654354) (xy 176.209462 -22.706462)
			(xy 176.087195 -22.751198) (xy 175.962428 -22.788397) (xy 175.835625 -22.817921) (xy 175.707258 -22.839659)
			(xy 175.577805 -22.853532) (xy 175.447746 -22.859486) (xy 175.317567 -22.857501) (xy 175.187751 -22.847583)
			(xy 175.058781 -22.829769) (xy 174.931136 -22.804126) (xy 174.805293 -22.770749) (xy 174.681718 -22.729762)
			(xy 174.560872 -22.681318) (xy 174.443204 -22.625596) (xy 174.329152 -22.562805) (xy 174.21914 -22.493178)
			(xy 174.113578 -22.416973) (xy 174.012858 -22.334474) (xy 173.917354 -22.245989) (xy 173.827422 -22.151846)
			(xy 173.743397 -22.052395) (xy 173.665592 -21.948007) (xy 173.594295 -21.83907) (xy 173.529771 -21.725988)
			(xy 173.472262 -21.609184) (xy 173.42198 -21.489091) (xy 173.379114 -21.366155) (xy 173.343821 -21.240836)
			(xy 173.316235 -21.113597) (xy 173.296456 -20.984914) (xy 173.28456 -20.855264) (xy 173.28059 -20.72513)
			(xy 167.050335 -20.72513) (xy 167.034691 -20.74259) (xy 166.991823 -20.778265) (xy 166.944217 -20.807319)
			(xy 166.892888 -20.829131) (xy 166.838931 -20.843237) (xy 166.783494 -20.849337) (xy 166.72776 -20.8473)
			(xy 166.672917 -20.83717) (xy 166.620133 -20.819163) (xy 166.570533 -20.793662) (xy 166.525175 -20.761211)
			(xy 166.485026 -20.722502) (xy 166.45094 -20.678359) (xy 166.423644 -20.629724) (xy 166.403721 -20.577633)
			(xy 166.391595 -20.523196) (xy 166.387524 -20.467574) (xy 158.906429 -20.467574) (xy 158.885655 -20.510388)
			(xy 158.85309 -20.557752) (xy 158.83382 -20.57908) (xy 158.827216 -20.585938) (xy 158.820104 -20.603972)
			(xy 158.820104 -20.692872) (xy 158.827216 -20.710906) (xy 158.83382 -20.717764) (xy 158.853111 -20.739073)
			(xy 158.885671 -20.78644) (xy 158.910759 -20.838155) (xy 158.927805 -20.893048) (xy 158.936425 -20.949877)
			(xy 158.936422 -21.007355) (xy 158.927798 -21.064184) (xy 158.910747 -21.119075) (xy 158.885655 -21.170788)
			(xy 158.85309 -21.218152) (xy 158.83382 -21.23948) (xy 158.827216 -21.246338) (xy 158.820104 -21.264372)
			(xy 158.820104 -21.353272) (xy 158.827216 -21.371306) (xy 158.83382 -21.378164) (xy 158.853094 -21.399488)
			(xy 158.885662 -21.44685) (xy 158.910754 -21.498562) (xy 158.927804 -21.553454) (xy 158.936425 -21.610283)
			(xy 158.936944 -21.639022) (xy 158.936458 -21.666273) (xy 158.928702 -21.720221) (xy 158.913347 -21.772516)
			(xy 158.911905 -21.775674) (xy 168.035984 -21.775674) (xy 168.040055 -21.720052) (xy 168.052181 -21.665615)
			(xy 168.072104 -21.613524) (xy 168.0994 -21.564889) (xy 168.133486 -21.520746) (xy 168.173635 -21.482037)
			(xy 168.218993 -21.449586) (xy 168.268593 -21.424085) (xy 168.321377 -21.406078) (xy 168.37622 -21.395948)
			(xy 168.431954 -21.393911) (xy 168.487391 -21.400011) (xy 168.541348 -21.414117) (xy 168.592677 -21.435929)
			(xy 168.640283 -21.464983) (xy 168.683151 -21.500658) (xy 168.720368 -21.542195) (xy 168.751141 -21.588708)
			(xy 168.774813 -21.639205) (xy 168.790881 -21.692612) (xy 168.799001 -21.747788) (xy 168.79951 -21.775674)
			(xy 168.799001 -21.80356) (xy 168.79133 -21.855684) (xy 168.9387 -21.855684) (xy 168.942771 -21.800062)
			(xy 168.954897 -21.745625) (xy 168.97482 -21.693534) (xy 169.002116 -21.644899) (xy 169.036202 -21.600756)
			(xy 169.076351 -21.562047) (xy 169.121709 -21.529596) (xy 169.171309 -21.504095) (xy 169.224093 -21.486088)
			(xy 169.278936 -21.475958) (xy 169.33467 -21.473921) (xy 169.390107 -21.480021) (xy 169.444064 -21.494127)
			(xy 169.495393 -21.515939) (xy 169.542999 -21.544993) (xy 169.585867 -21.580668) (xy 169.623084 -21.622205)
			(xy 169.653857 -21.668718) (xy 169.677529 -21.719215) (xy 169.693597 -21.772622) (xy 169.701717 -21.827798)
			(xy 169.702068 -21.847048) (xy 170.172886 -21.847048) (xy 170.176957 -21.791426) (xy 170.189083 -21.736989)
			(xy 170.209006 -21.684898) (xy 170.236302 -21.636263) (xy 170.270388 -21.59212) (xy 170.310537 -21.553411)
			(xy 170.355895 -21.52096) (xy 170.405495 -21.495459) (xy 170.458279 -21.477452) (xy 170.513122 -21.467322)
			(xy 170.568856 -21.465285) (xy 170.624293 -21.471385) (xy 170.67825 -21.485491) (xy 170.729579 -21.507303)
			(xy 170.777185 -21.536357) (xy 170.820053 -21.572032) (xy 170.85727 -21.613569) (xy 170.888043 -21.660082)
			(xy 170.911715 -21.710579) (xy 170.927783 -21.763986) (xy 170.935903 -21.819162) (xy 170.936412 -21.847048)
			(xy 170.935903 -21.874934) (xy 170.927783 -21.93011) (xy 170.911715 -21.983517) (xy 170.888043 -22.034014)
			(xy 170.85727 -22.080527) (xy 170.820053 -22.122064) (xy 170.777185 -22.157739) (xy 170.729579 -22.186793)
			(xy 170.67825 -22.208605) (xy 170.624293 -22.222711) (xy 170.568856 -22.228811) (xy 170.513122 -22.226774)
			(xy 170.458279 -22.216644) (xy 170.405495 -22.198637) (xy 170.355895 -22.173136) (xy 170.310537 -22.140685)
			(xy 170.270388 -22.101976) (xy 170.236302 -22.057833) (xy 170.209006 -22.009198) (xy 170.189083 -21.957107)
			(xy 170.176957 -21.90267) (xy 170.172886 -21.847048) (xy 169.702068 -21.847048) (xy 169.702226 -21.855684)
			(xy 169.701717 -21.88357) (xy 169.693597 -21.938746) (xy 169.677529 -21.992153) (xy 169.653857 -22.04265)
			(xy 169.623084 -22.089163) (xy 169.585867 -22.1307) (xy 169.542999 -22.166375) (xy 169.495393 -22.195429)
			(xy 169.444064 -22.217241) (xy 169.390107 -22.231347) (xy 169.33467 -22.237447) (xy 169.278936 -22.23541)
			(xy 169.224093 -22.22528) (xy 169.171309 -22.207273) (xy 169.121709 -22.181772) (xy 169.076351 -22.149321)
			(xy 169.036202 -22.110612) (xy 169.002116 -22.066469) (xy 168.97482 -22.017834) (xy 168.954897 -21.965743)
			(xy 168.942771 -21.911306) (xy 168.9387 -21.855684) (xy 168.79133 -21.855684) (xy 168.790881 -21.858736)
			(xy 168.774813 -21.912143) (xy 168.751141 -21.96264) (xy 168.720368 -22.009153) (xy 168.683151 -22.05069)
			(xy 168.640283 -22.086365) (xy 168.592677 -22.115419) (xy 168.541348 -22.137231) (xy 168.487391 -22.151337)
			(xy 168.431954 -22.157437) (xy 168.37622 -22.1554) (xy 168.321377 -22.14527) (xy 168.268593 -22.127263)
			(xy 168.218993 -22.101762) (xy 168.173635 -22.069311) (xy 168.133486 -22.030602) (xy 168.0994 -21.986459)
			(xy 168.072104 -21.937824) (xy 168.052181 -21.885733) (xy 168.040055 -21.831296) (xy 168.035984 -21.775674)
			(xy 158.911905 -21.775674) (xy 158.890705 -21.822093) (xy 158.861239 -21.867943) (xy 158.825548 -21.909134)
			(xy 158.784357 -21.944825) (xy 158.738507 -21.974291) (xy 158.68893 -21.996933) (xy 158.636635 -22.012288)
			(xy 158.582687 -22.020044) (xy 158.528185 -22.020044) (xy 158.474237 -22.012288) (xy 158.421942 -21.996933)
			(xy 158.372365 -21.974291) (xy 158.326515 -21.944825) (xy 158.285324 -21.909134) (xy 158.249633 -21.867943)
			(xy 158.220167 -21.822093) (xy 158.197525 -21.772516) (xy 158.18217 -21.720221) (xy 158.174414 -21.666273)
			(xy 158.173928 -21.639022) (xy 151.343141 -21.639022) (xy 151.33006 -21.667771) (xy 151.269015 -21.782767)
			(xy 151.201074 -21.893828) (xy 151.126488 -22.00054) (xy 151.045535 -22.102507) (xy 150.958516 -22.199349)
			(xy 150.865755 -22.290706) (xy 150.767597 -22.376238) (xy 150.664408 -22.455626) (xy 150.556571 -22.528576)
			(xy 150.511091 -22.555454) (xy 167.436544 -22.555454) (xy 167.440615 -22.499832) (xy 167.452741 -22.445395)
			(xy 167.472664 -22.393304) (xy 167.49996 -22.344669) (xy 167.534046 -22.300526) (xy 167.574195 -22.261817)
			(xy 167.619553 -22.229366) (xy 167.669153 -22.203865) (xy 167.721937 -22.185858) (xy 167.77678 -22.175728)
			(xy 167.832514 -22.173691) (xy 167.887951 -22.179791) (xy 167.941908 -22.193897) (xy 167.993237 -22.215709)
			(xy 168.040843 -22.244763) (xy 168.083711 -22.280438) (xy 168.120928 -22.321975) (xy 168.151701 -22.368488)
			(xy 168.175373 -22.418985) (xy 168.191441 -22.472392) (xy 168.199561 -22.527568) (xy 168.20007 -22.555454)
			(xy 168.199561 -22.58334) (xy 168.191441 -22.638516) (xy 168.175373 -22.691923) (xy 168.151701 -22.74242)
			(xy 168.120928 -22.788933) (xy 168.083711 -22.83047) (xy 168.040843 -22.866145) (xy 167.993237 -22.895199)
			(xy 167.941908 -22.917011) (xy 167.887951 -22.931117) (xy 167.832514 -22.937217) (xy 167.77678 -22.93518)
			(xy 167.721937 -22.92505) (xy 167.669153 -22.907043) (xy 167.619553 -22.881542) (xy 167.574195 -22.849091)
			(xy 167.534046 -22.810382) (xy 167.49996 -22.766239) (xy 167.472664 -22.717604) (xy 167.452741 -22.665513)
			(xy 167.440615 -22.611076) (xy 167.436544 -22.555454) (xy 150.511091 -22.555454) (xy 150.444486 -22.594817)
			(xy 150.328573 -22.6541) (xy 150.20926 -22.706208) (xy 150.086993 -22.750944) (xy 149.962226 -22.788143)
			(xy 149.835423 -22.817667) (xy 149.707056 -22.839405) (xy 149.577603 -22.853278) (xy 149.447544 -22.859232)
			(xy 149.317365 -22.857247) (xy 149.187549 -22.847329) (xy 149.058579 -22.829515) (xy 148.930934 -22.803872)
			(xy 148.805091 -22.770495) (xy 148.681516 -22.729508) (xy 148.56067 -22.681064) (xy 148.443002 -22.625342)
			(xy 148.32895 -22.562551) (xy 148.218938 -22.492924) (xy 148.113376 -22.416719) (xy 148.012656 -22.33422)
			(xy 147.917152 -22.245735) (xy 147.82722 -22.151592) (xy 147.743195 -22.052141) (xy 147.66539 -21.947753)
			(xy 147.594093 -21.838816) (xy 147.529569 -21.725734) (xy 147.47206 -21.60893) (xy 147.421778 -21.488837)
			(xy 147.378912 -21.365901) (xy 147.343619 -21.240582) (xy 147.316033 -21.113343) (xy 147.296254 -20.98466)
			(xy 147.284358 -20.85501) (xy 147.280388 -20.724876) (xy 141.050615 -20.724876) (xy 141.034743 -20.74259)
			(xy 140.991875 -20.778265) (xy 140.944269 -20.807319) (xy 140.89294 -20.829131) (xy 140.838983 -20.843237)
			(xy 140.783546 -20.849337) (xy 140.727812 -20.8473) (xy 140.672969 -20.83717) (xy 140.620185 -20.819163)
			(xy 140.570585 -20.793662) (xy 140.525227 -20.761211) (xy 140.485078 -20.722502) (xy 140.450992 -20.678359)
			(xy 140.423696 -20.629724) (xy 140.403773 -20.577633) (xy 140.391647 -20.523196) (xy 140.387576 -20.467574)
			(xy 132.906491 -20.467574) (xy 132.885713 -20.51039) (xy 132.853145 -20.557753) (xy 132.833872 -20.57908)
			(xy 132.827268 -20.585938) (xy 132.820156 -20.603972) (xy 132.820156 -20.692872) (xy 132.827268 -20.710906)
			(xy 132.833872 -20.717764) (xy 132.853165 -20.739072) (xy 132.88573 -20.786437) (xy 132.91082 -20.838152)
			(xy 132.927869 -20.893046) (xy 132.93649 -20.949876) (xy 132.936487 -21.007356) (xy 132.927862 -21.064185)
			(xy 132.910808 -21.119078) (xy 132.885713 -21.17079) (xy 132.853145 -21.218153) (xy 132.833872 -21.23948)
			(xy 132.827268 -21.246338) (xy 132.820156 -21.264372) (xy 132.820156 -21.353272) (xy 132.827268 -21.371306)
			(xy 132.833872 -21.378164) (xy 132.853155 -21.399481) (xy 132.885719 -21.446846) (xy 132.910809 -21.49856)
			(xy 132.927857 -21.553453) (xy 132.936477 -21.610282) (xy 132.936996 -21.639022) (xy 132.93651 -21.666273)
			(xy 132.928754 -21.720221) (xy 132.913399 -21.772516) (xy 132.911957 -21.775674) (xy 142.036036 -21.775674)
			(xy 142.040107 -21.720052) (xy 142.052233 -21.665615) (xy 142.072156 -21.613524) (xy 142.099452 -21.564889)
			(xy 142.133538 -21.520746) (xy 142.173687 -21.482037) (xy 142.219045 -21.449586) (xy 142.268645 -21.424085)
			(xy 142.321429 -21.406078) (xy 142.376272 -21.395948) (xy 142.432006 -21.393911) (xy 142.487443 -21.400011)
			(xy 142.5414 -21.414117) (xy 142.592729 -21.435929) (xy 142.640335 -21.464983) (xy 142.683203 -21.500658)
			(xy 142.72042 -21.542195) (xy 142.751193 -21.588708) (xy 142.774865 -21.639205) (xy 142.790933 -21.692612)
			(xy 142.799053 -21.747788) (xy 142.799562 -21.775674) (xy 142.799053 -21.80356) (xy 142.791382 -21.855684)
			(xy 142.938752 -21.855684) (xy 142.942823 -21.800062) (xy 142.954949 -21.745625) (xy 142.974872 -21.693534)
			(xy 143.002168 -21.644899) (xy 143.036254 -21.600756) (xy 143.076403 -21.562047) (xy 143.121761 -21.529596)
			(xy 143.171361 -21.504095) (xy 143.224145 -21.486088) (xy 143.278988 -21.475958) (xy 143.334722 -21.473921)
			(xy 143.390159 -21.480021) (xy 143.444116 -21.494127) (xy 143.495445 -21.515939) (xy 143.543051 -21.544993)
			(xy 143.585919 -21.580668) (xy 143.623136 -21.622205) (xy 143.653909 -21.668718) (xy 143.677581 -21.719215)
			(xy 143.693649 -21.772622) (xy 143.701769 -21.827798) (xy 143.70212 -21.847048) (xy 144.172938 -21.847048)
			(xy 144.177009 -21.791426) (xy 144.189135 -21.736989) (xy 144.209058 -21.684898) (xy 144.236354 -21.636263)
			(xy 144.27044 -21.59212) (xy 144.310589 -21.553411) (xy 144.355947 -21.52096) (xy 144.405547 -21.495459)
			(xy 144.458331 -21.477452) (xy 144.513174 -21.467322) (xy 144.568908 -21.465285) (xy 144.624345 -21.471385)
			(xy 144.678302 -21.485491) (xy 144.729631 -21.507303) (xy 144.777237 -21.536357) (xy 144.820105 -21.572032)
			(xy 144.857322 -21.613569) (xy 144.888095 -21.660082) (xy 144.911767 -21.710579) (xy 144.927835 -21.763986)
			(xy 144.935955 -21.819162) (xy 144.936464 -21.847048) (xy 144.935955 -21.874934) (xy 144.927835 -21.93011)
			(xy 144.911767 -21.983517) (xy 144.888095 -22.034014) (xy 144.857322 -22.080527) (xy 144.820105 -22.122064)
			(xy 144.777237 -22.157739) (xy 144.729631 -22.186793) (xy 144.678302 -22.208605) (xy 144.624345 -22.222711)
			(xy 144.568908 -22.228811) (xy 144.513174 -22.226774) (xy 144.458331 -22.216644) (xy 144.405547 -22.198637)
			(xy 144.355947 -22.173136) (xy 144.310589 -22.140685) (xy 144.27044 -22.101976) (xy 144.236354 -22.057833)
			(xy 144.209058 -22.009198) (xy 144.189135 -21.957107) (xy 144.177009 -21.90267) (xy 144.172938 -21.847048)
			(xy 143.70212 -21.847048) (xy 143.702278 -21.855684) (xy 143.701769 -21.88357) (xy 143.693649 -21.938746)
			(xy 143.677581 -21.992153) (xy 143.653909 -22.04265) (xy 143.623136 -22.089163) (xy 143.585919 -22.1307)
			(xy 143.543051 -22.166375) (xy 143.495445 -22.195429) (xy 143.444116 -22.217241) (xy 143.390159 -22.231347)
			(xy 143.334722 -22.237447) (xy 143.278988 -22.23541) (xy 143.224145 -22.22528) (xy 143.171361 -22.207273)
			(xy 143.121761 -22.181772) (xy 143.076403 -22.149321) (xy 143.036254 -22.110612) (xy 143.002168 -22.066469)
			(xy 142.974872 -22.017834) (xy 142.954949 -21.965743) (xy 142.942823 -21.911306) (xy 142.938752 -21.855684)
			(xy 142.791382 -21.855684) (xy 142.790933 -21.858736) (xy 142.774865 -21.912143) (xy 142.751193 -21.96264)
			(xy 142.72042 -22.009153) (xy 142.683203 -22.05069) (xy 142.640335 -22.086365) (xy 142.592729 -22.115419)
			(xy 142.5414 -22.137231) (xy 142.487443 -22.151337) (xy 142.432006 -22.157437) (xy 142.376272 -22.1554)
			(xy 142.321429 -22.14527) (xy 142.268645 -22.127263) (xy 142.219045 -22.101762) (xy 142.173687 -22.069311)
			(xy 142.133538 -22.030602) (xy 142.099452 -21.986459) (xy 142.072156 -21.937824) (xy 142.052233 -21.885733)
			(xy 142.040107 -21.831296) (xy 142.036036 -21.775674) (xy 132.911957 -21.775674) (xy 132.890757 -21.822093)
			(xy 132.861291 -21.867943) (xy 132.8256 -21.909134) (xy 132.784409 -21.944825) (xy 132.738559 -21.974291)
			(xy 132.688982 -21.996933) (xy 132.636687 -22.012288) (xy 132.582739 -22.020044) (xy 132.528237 -22.020044)
			(xy 132.474289 -22.012288) (xy 132.421994 -21.996933) (xy 132.372417 -21.974291) (xy 132.326567 -21.944825)
			(xy 132.285376 -21.909134) (xy 132.249685 -21.867943) (xy 132.220219 -21.822093) (xy 132.197577 -21.772516)
			(xy 132.182222 -21.720221) (xy 132.174466 -21.666273) (xy 132.17398 -21.639022) (xy 125.343309 -21.639022)
			(xy 125.330112 -21.668025) (xy 125.269067 -21.783021) (xy 125.201126 -21.894082) (xy 125.12654 -22.000794)
			(xy 125.045587 -22.102761) (xy 124.958568 -22.199603) (xy 124.865807 -22.29096) (xy 124.767649 -22.376492)
			(xy 124.66446 -22.45588) (xy 124.556623 -22.52883) (xy 124.511573 -22.555454) (xy 141.436596 -22.555454)
			(xy 141.440667 -22.499832) (xy 141.452793 -22.445395) (xy 141.472716 -22.393304) (xy 141.500012 -22.344669)
			(xy 141.534098 -22.300526) (xy 141.574247 -22.261817) (xy 141.619605 -22.229366) (xy 141.669205 -22.203865)
			(xy 141.721989 -22.185858) (xy 141.776832 -22.175728) (xy 141.832566 -22.173691) (xy 141.888003 -22.179791)
			(xy 141.94196 -22.193897) (xy 141.993289 -22.215709) (xy 142.040895 -22.244763) (xy 142.083763 -22.280438)
			(xy 142.12098 -22.321975) (xy 142.151753 -22.368488) (xy 142.175425 -22.418985) (xy 142.191493 -22.472392)
			(xy 142.199613 -22.527568) (xy 142.200122 -22.555454) (xy 142.199613 -22.58334) (xy 142.191493 -22.638516)
			(xy 142.175425 -22.691923) (xy 142.151753 -22.74242) (xy 142.12098 -22.788933) (xy 142.083763 -22.83047)
			(xy 142.040895 -22.866145) (xy 141.993289 -22.895199) (xy 141.94196 -22.917011) (xy 141.888003 -22.931117)
			(xy 141.832566 -22.937217) (xy 141.776832 -22.93518) (xy 141.721989 -22.92505) (xy 141.669205 -22.907043)
			(xy 141.619605 -22.881542) (xy 141.574247 -22.849091) (xy 141.534098 -22.810382) (xy 141.500012 -22.766239)
			(xy 141.472716 -22.717604) (xy 141.452793 -22.665513) (xy 141.440667 -22.611076) (xy 141.436596 -22.555454)
			(xy 124.511573 -22.555454) (xy 124.444538 -22.595071) (xy 124.328625 -22.654354) (xy 124.209312 -22.706462)
			(xy 124.087045 -22.751198) (xy 123.962278 -22.788397) (xy 123.835475 -22.817921) (xy 123.707108 -22.839659)
			(xy 123.577655 -22.853532) (xy 123.447596 -22.859486) (xy 123.317417 -22.857501) (xy 123.187601 -22.847583)
			(xy 123.058631 -22.829769) (xy 122.930986 -22.804126) (xy 122.805143 -22.770749) (xy 122.681568 -22.729762)
			(xy 122.560722 -22.681318) (xy 122.443054 -22.625596) (xy 122.329002 -22.562805) (xy 122.21899 -22.493178)
			(xy 122.113428 -22.416973) (xy 122.012708 -22.334474) (xy 121.917204 -22.245989) (xy 121.827272 -22.151846)
			(xy 121.743247 -22.052395) (xy 121.665442 -21.948007) (xy 121.594145 -21.83907) (xy 121.529621 -21.725988)
			(xy 121.472112 -21.609184) (xy 121.42183 -21.489091) (xy 121.378964 -21.366155) (xy 121.343671 -21.240836)
			(xy 121.316085 -21.113597) (xy 121.296306 -20.984914) (xy 121.28441 -20.855264) (xy 121.28044 -20.72513)
			(xy 94.740286 -20.72513) (xy 94.752909 -20.739073) (xy 94.78547 -20.78644) (xy 94.810557 -20.838155)
			(xy 94.827604 -20.893048) (xy 94.836223 -20.949877) (xy 94.836221 -21.007355) (xy 94.827597 -21.064184)
			(xy 94.810545 -21.119075) (xy 94.785454 -21.170788) (xy 94.752889 -21.218152) (xy 94.733618 -21.23948)
			(xy 94.727014 -21.246338) (xy 94.719902 -21.264372) (xy 94.719902 -21.353272) (xy 94.727014 -21.371306)
			(xy 94.733618 -21.378164) (xy 94.752892 -21.399489) (xy 94.785459 -21.44685) (xy 94.810552 -21.498563)
			(xy 94.827602 -21.553454) (xy 94.836223 -21.610283) (xy 94.836742 -21.639022) (xy 94.836256 -21.666273)
			(xy 94.8285 -21.720221) (xy 94.813145 -21.772516) (xy 94.790503 -21.822093) (xy 94.761037 -21.867943)
			(xy 94.725346 -21.909134) (xy 94.684155 -21.944825) (xy 94.638305 -21.974291) (xy 94.588728 -21.996933)
			(xy 94.536433 -22.012288) (xy 94.482485 -22.020044) (xy 94.427983 -22.020044) (xy 94.374035 -22.012288)
			(xy 94.32174 -21.996933) (xy 94.272163 -21.974291) (xy 94.226313 -21.944825) (xy 94.185122 -21.909134)
			(xy 94.149431 -21.867943) (xy 94.119965 -21.822093) (xy 94.097323 -21.772516) (xy 94.081968 -21.720221)
			(xy 94.074212 -21.666273) (xy 94.073726 -21.639022) (xy 87.246077 -21.639022) (xy 87.235192 -21.662945)
			(xy 87.174147 -21.777941) (xy 87.106206 -21.889002) (xy 87.03162 -21.995714) (xy 86.950667 -22.097681)
			(xy 86.863648 -22.194523) (xy 86.770887 -22.28588) (xy 86.672729 -22.371412) (xy 86.56954 -22.4508)
			(xy 86.461703 -22.52375) (xy 86.349618 -22.589991) (xy 86.233705 -22.649274) (xy 86.114392 -22.701382)
			(xy 85.992125 -22.746118) (xy 85.867358 -22.783317) (xy 85.740555 -22.812841) (xy 85.612188 -22.834579)
			(xy 85.482735 -22.848452) (xy 85.352676 -22.854406) (xy 85.222497 -22.852421) (xy 85.092681 -22.842503)
			(xy 84.963711 -22.824689) (xy 84.836066 -22.799046) (xy 84.710223 -22.765669) (xy 84.586648 -22.724682)
			(xy 84.465802 -22.676238) (xy 84.348134 -22.620516) (xy 84.234082 -22.557725) (xy 84.12407 -22.488098)
			(xy 84.018508 -22.411893) (xy 83.917788 -22.329394) (xy 83.822284 -22.240909) (xy 83.732352 -22.146766)
			(xy 83.648327 -22.047315) (xy 83.570522 -21.942927) (xy 83.499225 -21.83399) (xy 83.434701 -21.720908)
			(xy 83.377192 -21.604104) (xy 83.32691 -21.484011) (xy 83.284044 -21.361075) (xy 83.248751 -21.235756)
			(xy 83.221165 -21.108517) (xy 83.201386 -20.979834) (xy 83.18949 -20.850184) (xy 83.18552 -20.72005)
			(xy 76.954737 -20.72005) (xy 76.934541 -20.74259) (xy 76.891673 -20.778265) (xy 76.844067 -20.807319)
			(xy 76.792738 -20.829131) (xy 76.738781 -20.843237) (xy 76.683344 -20.849337) (xy 76.62761 -20.8473)
			(xy 76.572767 -20.83717) (xy 76.519983 -20.819163) (xy 76.470383 -20.793662) (xy 76.425025 -20.761211)
			(xy 76.384876 -20.722502) (xy 76.35079 -20.678359) (xy 76.323494 -20.629724) (xy 76.303571 -20.577633)
			(xy 76.291445 -20.523196) (xy 76.287374 -20.467574) (xy 68.80629 -20.467574) (xy 68.785512 -20.510391)
			(xy 68.752943 -20.557753) (xy 68.73367 -20.57908) (xy 68.727066 -20.585938) (xy 68.719954 -20.603972)
			(xy 68.719954 -20.692872) (xy 68.727066 -20.710906) (xy 68.73367 -20.717764) (xy 68.752963 -20.739072)
			(xy 68.785528 -20.786437) (xy 68.810619 -20.838152) (xy 68.827667 -20.893046) (xy 68.836288 -20.949876)
			(xy 68.836286 -21.007356) (xy 68.82766 -21.064186) (xy 68.810607 -21.119078) (xy 68.785512 -21.170791)
			(xy 68.752943 -21.218153) (xy 68.73367 -21.23948) (xy 68.727066 -21.246338) (xy 68.719954 -21.264372)
			(xy 68.719954 -21.353272) (xy 68.727066 -21.371306) (xy 68.73367 -21.378164) (xy 68.752952 -21.399481)
			(xy 68.785517 -21.446846) (xy 68.810607 -21.49856) (xy 68.827655 -21.553453) (xy 68.836275 -21.610282)
			(xy 68.836794 -21.639022) (xy 68.836308 -21.666273) (xy 68.828552 -21.720221) (xy 68.813197 -21.772516)
			(xy 68.811755 -21.775674) (xy 77.935834 -21.775674) (xy 77.939905 -21.720052) (xy 77.952031 -21.665615)
			(xy 77.971954 -21.613524) (xy 77.99925 -21.564889) (xy 78.033336 -21.520746) (xy 78.073485 -21.482037)
			(xy 78.118843 -21.449586) (xy 78.168443 -21.424085) (xy 78.221227 -21.406078) (xy 78.27607 -21.395948)
			(xy 78.331804 -21.393911) (xy 78.387241 -21.400011) (xy 78.441198 -21.414117) (xy 78.492527 -21.435929)
			(xy 78.540133 -21.464983) (xy 78.583001 -21.500658) (xy 78.620218 -21.542195) (xy 78.650991 -21.588708)
			(xy 78.674663 -21.639205) (xy 78.690731 -21.692612) (xy 78.698851 -21.747788) (xy 78.69936 -21.775674)
			(xy 78.698851 -21.80356) (xy 78.69118 -21.855684) (xy 78.83855 -21.855684) (xy 78.842621 -21.800062)
			(xy 78.854747 -21.745625) (xy 78.87467 -21.693534) (xy 78.901966 -21.644899) (xy 78.936052 -21.600756)
			(xy 78.976201 -21.562047) (xy 79.021559 -21.529596) (xy 79.071159 -21.504095) (xy 79.123943 -21.486088)
			(xy 79.178786 -21.475958) (xy 79.23452 -21.473921) (xy 79.289957 -21.480021) (xy 79.343914 -21.494127)
			(xy 79.395243 -21.515939) (xy 79.442849 -21.544993) (xy 79.485717 -21.580668) (xy 79.522934 -21.622205)
			(xy 79.553707 -21.668718) (xy 79.577379 -21.719215) (xy 79.593447 -21.772622) (xy 79.601567 -21.827798)
			(xy 79.601918 -21.847048) (xy 80.072736 -21.847048) (xy 80.076807 -21.791426) (xy 80.088933 -21.736989)
			(xy 80.108856 -21.684898) (xy 80.136152 -21.636263) (xy 80.170238 -21.59212) (xy 80.210387 -21.553411)
			(xy 80.255745 -21.52096) (xy 80.305345 -21.495459) (xy 80.358129 -21.477452) (xy 80.412972 -21.467322)
			(xy 80.468706 -21.465285) (xy 80.524143 -21.471385) (xy 80.5781 -21.485491) (xy 80.629429 -21.507303)
			(xy 80.677035 -21.536357) (xy 80.719903 -21.572032) (xy 80.75712 -21.613569) (xy 80.787893 -21.660082)
			(xy 80.811565 -21.710579) (xy 80.827633 -21.763986) (xy 80.835753 -21.819162) (xy 80.836262 -21.847048)
			(xy 80.835753 -21.874934) (xy 80.827633 -21.93011) (xy 80.811565 -21.983517) (xy 80.787893 -22.034014)
			(xy 80.75712 -22.080527) (xy 80.719903 -22.122064) (xy 80.677035 -22.157739) (xy 80.629429 -22.186793)
			(xy 80.5781 -22.208605) (xy 80.524143 -22.222711) (xy 80.468706 -22.228811) (xy 80.412972 -22.226774)
			(xy 80.358129 -22.216644) (xy 80.305345 -22.198637) (xy 80.255745 -22.173136) (xy 80.210387 -22.140685)
			(xy 80.170238 -22.101976) (xy 80.136152 -22.057833) (xy 80.108856 -22.009198) (xy 80.088933 -21.957107)
			(xy 80.076807 -21.90267) (xy 80.072736 -21.847048) (xy 79.601918 -21.847048) (xy 79.602076 -21.855684)
			(xy 79.601567 -21.88357) (xy 79.593447 -21.938746) (xy 79.577379 -21.992153) (xy 79.553707 -22.04265)
			(xy 79.522934 -22.089163) (xy 79.485717 -22.1307) (xy 79.442849 -22.166375) (xy 79.395243 -22.195429)
			(xy 79.343914 -22.217241) (xy 79.289957 -22.231347) (xy 79.23452 -22.237447) (xy 79.178786 -22.23541)
			(xy 79.123943 -22.22528) (xy 79.071159 -22.207273) (xy 79.021559 -22.181772) (xy 78.976201 -22.149321)
			(xy 78.936052 -22.110612) (xy 78.901966 -22.066469) (xy 78.87467 -22.017834) (xy 78.854747 -21.965743)
			(xy 78.842621 -21.911306) (xy 78.83855 -21.855684) (xy 78.69118 -21.855684) (xy 78.690731 -21.858736)
			(xy 78.674663 -21.912143) (xy 78.650991 -21.96264) (xy 78.620218 -22.009153) (xy 78.583001 -22.05069)
			(xy 78.540133 -22.086365) (xy 78.492527 -22.115419) (xy 78.441198 -22.137231) (xy 78.387241 -22.151337)
			(xy 78.331804 -22.157437) (xy 78.27607 -22.1554) (xy 78.221227 -22.14527) (xy 78.168443 -22.127263)
			(xy 78.118843 -22.101762) (xy 78.073485 -22.069311) (xy 78.033336 -22.030602) (xy 77.99925 -21.986459)
			(xy 77.971954 -21.937824) (xy 77.952031 -21.885733) (xy 77.939905 -21.831296) (xy 77.935834 -21.775674)
			(xy 68.811755 -21.775674) (xy 68.790555 -21.822093) (xy 68.761089 -21.867943) (xy 68.725398 -21.909134)
			(xy 68.684207 -21.944825) (xy 68.638357 -21.974291) (xy 68.58878 -21.996933) (xy 68.536485 -22.012288)
			(xy 68.482537 -22.020044) (xy 68.428035 -22.020044) (xy 68.374087 -22.012288) (xy 68.321792 -21.996933)
			(xy 68.272215 -21.974291) (xy 68.226365 -21.944825) (xy 68.185174 -21.909134) (xy 68.149483 -21.867943)
			(xy 68.120017 -21.822093) (xy 68.097375 -21.772516) (xy 68.08202 -21.720221) (xy 68.074264 -21.666273)
			(xy 68.073778 -21.639022) (xy 61.245875 -21.639022) (xy 61.23499 -21.662945) (xy 61.173945 -21.777941)
			(xy 61.106004 -21.889002) (xy 61.031418 -21.995714) (xy 60.950465 -22.097681) (xy 60.863446 -22.194523)
			(xy 60.770685 -22.28588) (xy 60.672527 -22.371412) (xy 60.569338 -22.4508) (xy 60.461501 -22.52375)
			(xy 60.407855 -22.555454) (xy 77.336394 -22.555454) (xy 77.340465 -22.499832) (xy 77.352591 -22.445395)
			(xy 77.372514 -22.393304) (xy 77.39981 -22.344669) (xy 77.433896 -22.300526) (xy 77.474045 -22.261817)
			(xy 77.519403 -22.229366) (xy 77.569003 -22.203865) (xy 77.621787 -22.185858) (xy 77.67663 -22.175728)
			(xy 77.732364 -22.173691) (xy 77.787801 -22.179791) (xy 77.841758 -22.193897) (xy 77.893087 -22.215709)
			(xy 77.940693 -22.244763) (xy 77.983561 -22.280438) (xy 78.020778 -22.321975) (xy 78.051551 -22.368488)
			(xy 78.075223 -22.418985) (xy 78.091291 -22.472392) (xy 78.099411 -22.527568) (xy 78.09992 -22.555454)
			(xy 78.099411 -22.58334) (xy 78.091291 -22.638516) (xy 78.075223 -22.691923) (xy 78.051551 -22.74242)
			(xy 78.020778 -22.788933) (xy 77.983561 -22.83047) (xy 77.940693 -22.866145) (xy 77.893087 -22.895199)
			(xy 77.841758 -22.917011) (xy 77.787801 -22.931117) (xy 77.732364 -22.937217) (xy 77.67663 -22.93518)
			(xy 77.621787 -22.92505) (xy 77.569003 -22.907043) (xy 77.519403 -22.881542) (xy 77.474045 -22.849091)
			(xy 77.433896 -22.810382) (xy 77.39981 -22.766239) (xy 77.372514 -22.717604) (xy 77.352591 -22.665513)
			(xy 77.340465 -22.611076) (xy 77.336394 -22.555454) (xy 60.407855 -22.555454) (xy 60.349416 -22.589991)
			(xy 60.233503 -22.649274) (xy 60.11419 -22.701382) (xy 59.991923 -22.746118) (xy 59.867156 -22.783317)
			(xy 59.740353 -22.812841) (xy 59.611986 -22.834579) (xy 59.482533 -22.848452) (xy 59.352474 -22.854406)
			(xy 59.222295 -22.852421) (xy 59.092479 -22.842503) (xy 58.963509 -22.824689) (xy 58.835864 -22.799046)
			(xy 58.710021 -22.765669) (xy 58.586446 -22.724682) (xy 58.4656 -22.676238) (xy 58.347932 -22.620516)
			(xy 58.23388 -22.557725) (xy 58.123868 -22.488098) (xy 58.018306 -22.411893) (xy 57.917586 -22.329394)
			(xy 57.822082 -22.240909) (xy 57.73215 -22.146766) (xy 57.648125 -22.047315) (xy 57.57032 -21.942927)
			(xy 57.499023 -21.83399) (xy 57.434499 -21.720908) (xy 57.37699 -21.604104) (xy 57.326708 -21.484011)
			(xy 57.283842 -21.361075) (xy 57.248549 -21.235756) (xy 57.220963 -21.108517) (xy 57.201184 -20.979834)
			(xy 57.189288 -20.850184) (xy 57.185318 -20.72005) (xy 50.954789 -20.72005) (xy 50.934593 -20.74259)
			(xy 50.891725 -20.778265) (xy 50.844119 -20.807319) (xy 50.79279 -20.829131) (xy 50.738833 -20.843237)
			(xy 50.683396 -20.849337) (xy 50.627662 -20.8473) (xy 50.572819 -20.83717) (xy 50.520035 -20.819163)
			(xy 50.470435 -20.793662) (xy 50.425077 -20.761211) (xy 50.384928 -20.722502) (xy 50.350842 -20.678359)
			(xy 50.323546 -20.629724) (xy 50.303623 -20.577633) (xy 50.291497 -20.523196) (xy 50.287426 -20.467574)
			(xy 42.806331 -20.467574) (xy 42.785557 -20.510388) (xy 42.752992 -20.557752) (xy 42.733722 -20.57908)
			(xy 42.727118 -20.585938) (xy 42.720006 -20.603972) (xy 42.720006 -20.692872) (xy 42.727118 -20.710906)
			(xy 42.733722 -20.717764) (xy 42.753013 -20.739073) (xy 42.785573 -20.78644) (xy 42.810661 -20.838155)
			(xy 42.827707 -20.893048) (xy 42.836326 -20.949877) (xy 42.836324 -21.007355) (xy 42.8277 -21.064184)
			(xy 42.810649 -21.119075) (xy 42.785557 -21.170788) (xy 42.752992 -21.218152) (xy 42.733722 -21.23948)
			(xy 42.727118 -21.246338) (xy 42.720006 -21.264372) (xy 42.720006 -21.353272) (xy 42.727118 -21.371306)
			(xy 42.733722 -21.378164) (xy 42.752997 -21.399488) (xy 42.785564 -21.44685) (xy 42.810656 -21.498562)
			(xy 42.827706 -21.553454) (xy 42.836327 -21.610283) (xy 42.836846 -21.639022) (xy 42.83636 -21.666273)
			(xy 42.828604 -21.720221) (xy 42.813249 -21.772516) (xy 42.811807 -21.775674) (xy 51.935886 -21.775674)
			(xy 51.939957 -21.720052) (xy 51.952083 -21.665615) (xy 51.972006 -21.613524) (xy 51.999302 -21.564889)
			(xy 52.033388 -21.520746) (xy 52.073537 -21.482037) (xy 52.118895 -21.449586) (xy 52.168495 -21.424085)
			(xy 52.221279 -21.406078) (xy 52.276122 -21.395948) (xy 52.331856 -21.393911) (xy 52.387293 -21.400011)
			(xy 52.44125 -21.414117) (xy 52.492579 -21.435929) (xy 52.540185 -21.464983) (xy 52.583053 -21.500658)
			(xy 52.62027 -21.542195) (xy 52.651043 -21.588708) (xy 52.674715 -21.639205) (xy 52.690783 -21.692612)
			(xy 52.698903 -21.747788) (xy 52.699412 -21.775674) (xy 52.698903 -21.80356) (xy 52.691232 -21.855684)
			(xy 52.838602 -21.855684) (xy 52.842673 -21.800062) (xy 52.854799 -21.745625) (xy 52.874722 -21.693534)
			(xy 52.902018 -21.644899) (xy 52.936104 -21.600756) (xy 52.976253 -21.562047) (xy 53.021611 -21.529596)
			(xy 53.071211 -21.504095) (xy 53.123995 -21.486088) (xy 53.178838 -21.475958) (xy 53.234572 -21.473921)
			(xy 53.290009 -21.480021) (xy 53.343966 -21.494127) (xy 53.395295 -21.515939) (xy 53.442901 -21.544993)
			(xy 53.485769 -21.580668) (xy 53.522986 -21.622205) (xy 53.553759 -21.668718) (xy 53.577431 -21.719215)
			(xy 53.593499 -21.772622) (xy 53.601619 -21.827798) (xy 53.60197 -21.847048) (xy 54.072788 -21.847048)
			(xy 54.076859 -21.791426) (xy 54.088985 -21.736989) (xy 54.108908 -21.684898) (xy 54.136204 -21.636263)
			(xy 54.17029 -21.59212) (xy 54.210439 -21.553411) (xy 54.255797 -21.52096) (xy 54.305397 -21.495459)
			(xy 54.358181 -21.477452) (xy 54.413024 -21.467322) (xy 54.468758 -21.465285) (xy 54.524195 -21.471385)
			(xy 54.578152 -21.485491) (xy 54.629481 -21.507303) (xy 54.677087 -21.536357) (xy 54.719955 -21.572032)
			(xy 54.757172 -21.613569) (xy 54.787945 -21.660082) (xy 54.811617 -21.710579) (xy 54.827685 -21.763986)
			(xy 54.835805 -21.819162) (xy 54.836314 -21.847048) (xy 54.835805 -21.874934) (xy 54.827685 -21.93011)
			(xy 54.811617 -21.983517) (xy 54.787945 -22.034014) (xy 54.757172 -22.080527) (xy 54.719955 -22.122064)
			(xy 54.677087 -22.157739) (xy 54.629481 -22.186793) (xy 54.578152 -22.208605) (xy 54.524195 -22.222711)
			(xy 54.468758 -22.228811) (xy 54.413024 -22.226774) (xy 54.358181 -22.216644) (xy 54.305397 -22.198637)
			(xy 54.255797 -22.173136) (xy 54.210439 -22.140685) (xy 54.17029 -22.101976) (xy 54.136204 -22.057833)
			(xy 54.108908 -22.009198) (xy 54.088985 -21.957107) (xy 54.076859 -21.90267) (xy 54.072788 -21.847048)
			(xy 53.60197 -21.847048) (xy 53.602128 -21.855684) (xy 53.601619 -21.88357) (xy 53.593499 -21.938746)
			(xy 53.577431 -21.992153) (xy 53.553759 -22.04265) (xy 53.522986 -22.089163) (xy 53.485769 -22.1307)
			(xy 53.442901 -22.166375) (xy 53.395295 -22.195429) (xy 53.343966 -22.217241) (xy 53.290009 -22.231347)
			(xy 53.234572 -22.237447) (xy 53.178838 -22.23541) (xy 53.123995 -22.22528) (xy 53.071211 -22.207273)
			(xy 53.021611 -22.181772) (xy 52.976253 -22.149321) (xy 52.936104 -22.110612) (xy 52.902018 -22.066469)
			(xy 52.874722 -22.017834) (xy 52.854799 -21.965743) (xy 52.842673 -21.911306) (xy 52.838602 -21.855684)
			(xy 52.691232 -21.855684) (xy 52.690783 -21.858736) (xy 52.674715 -21.912143) (xy 52.651043 -21.96264)
			(xy 52.62027 -22.009153) (xy 52.583053 -22.05069) (xy 52.540185 -22.086365) (xy 52.492579 -22.115419)
			(xy 52.44125 -22.137231) (xy 52.387293 -22.151337) (xy 52.331856 -22.157437) (xy 52.276122 -22.1554)
			(xy 52.221279 -22.14527) (xy 52.168495 -22.127263) (xy 52.118895 -22.101762) (xy 52.073537 -22.069311)
			(xy 52.033388 -22.030602) (xy 51.999302 -21.986459) (xy 51.972006 -21.937824) (xy 51.952083 -21.885733)
			(xy 51.939957 -21.831296) (xy 51.935886 -21.775674) (xy 42.811807 -21.775674) (xy 42.790607 -21.822093)
			(xy 42.761141 -21.867943) (xy 42.72545 -21.909134) (xy 42.684259 -21.944825) (xy 42.638409 -21.974291)
			(xy 42.588832 -21.996933) (xy 42.536537 -22.012288) (xy 42.482589 -22.020044) (xy 42.428087 -22.020044)
			(xy 42.374139 -22.012288) (xy 42.321844 -21.996933) (xy 42.272267 -21.974291) (xy 42.226417 -21.944825)
			(xy 42.185226 -21.909134) (xy 42.149535 -21.867943) (xy 42.120069 -21.822093) (xy 42.097427 -21.772516)
			(xy 42.082072 -21.720221) (xy 42.074316 -21.666273) (xy 42.07383 -21.639022) (xy 35.245927 -21.639022)
			(xy 35.235042 -21.662945) (xy 35.173997 -21.777941) (xy 35.106056 -21.889002) (xy 35.03147 -21.995714)
			(xy 34.950517 -22.097681) (xy 34.863498 -22.194523) (xy 34.770737 -22.28588) (xy 34.672579 -22.371412)
			(xy 34.56939 -22.4508) (xy 34.461553 -22.52375) (xy 34.407907 -22.555454) (xy 51.336446 -22.555454)
			(xy 51.340517 -22.499832) (xy 51.352643 -22.445395) (xy 51.372566 -22.393304) (xy 51.399862 -22.344669)
			(xy 51.433948 -22.300526) (xy 51.474097 -22.261817) (xy 51.519455 -22.229366) (xy 51.569055 -22.203865)
			(xy 51.621839 -22.185858) (xy 51.676682 -22.175728) (xy 51.732416 -22.173691) (xy 51.787853 -22.179791)
			(xy 51.84181 -22.193897) (xy 51.893139 -22.215709) (xy 51.940745 -22.244763) (xy 51.983613 -22.280438)
			(xy 52.02083 -22.321975) (xy 52.051603 -22.368488) (xy 52.075275 -22.418985) (xy 52.091343 -22.472392)
			(xy 52.099463 -22.527568) (xy 52.099972 -22.555454) (xy 52.099463 -22.58334) (xy 52.091343 -22.638516)
			(xy 52.075275 -22.691923) (xy 52.051603 -22.74242) (xy 52.02083 -22.788933) (xy 51.983613 -22.83047)
			(xy 51.940745 -22.866145) (xy 51.893139 -22.895199) (xy 51.84181 -22.917011) (xy 51.787853 -22.931117)
			(xy 51.732416 -22.937217) (xy 51.676682 -22.93518) (xy 51.621839 -22.92505) (xy 51.569055 -22.907043)
			(xy 51.519455 -22.881542) (xy 51.474097 -22.849091) (xy 51.433948 -22.810382) (xy 51.399862 -22.766239)
			(xy 51.372566 -22.717604) (xy 51.352643 -22.665513) (xy 51.340517 -22.611076) (xy 51.336446 -22.555454)
			(xy 34.407907 -22.555454) (xy 34.349468 -22.589991) (xy 34.233555 -22.649274) (xy 34.114242 -22.701382)
			(xy 33.991975 -22.746118) (xy 33.867208 -22.783317) (xy 33.740405 -22.812841) (xy 33.612038 -22.834579)
			(xy 33.482585 -22.848452) (xy 33.352526 -22.854406) (xy 33.222347 -22.852421) (xy 33.092531 -22.842503)
			(xy 32.963561 -22.824689) (xy 32.835916 -22.799046) (xy 32.710073 -22.765669) (xy 32.586498 -22.724682)
			(xy 32.465652 -22.676238) (xy 32.347984 -22.620516) (xy 32.233932 -22.557725) (xy 32.12392 -22.488098)
			(xy 32.018358 -22.411893) (xy 31.917638 -22.329394) (xy 31.822134 -22.240909) (xy 31.732202 -22.146766)
			(xy 31.648177 -22.047315) (xy 31.570372 -21.942927) (xy 31.499075 -21.83399) (xy 31.434551 -21.720908)
			(xy 31.377042 -21.604104) (xy 31.32676 -21.484011) (xy 31.283894 -21.361075) (xy 31.248601 -21.235756)
			(xy 31.221015 -21.108517) (xy 31.201236 -20.979834) (xy 31.18934 -20.850184) (xy 31.18537 -20.72005)
			(xy 16.735844 -20.72005) (xy 16.753067 -20.739072) (xy 16.785631 -20.786437) (xy 16.810722 -20.838152)
			(xy 16.82777 -20.893046) (xy 16.836391 -20.949876) (xy 16.836389 -21.007356) (xy 16.827763 -21.064185)
			(xy 16.81071 -21.119078) (xy 16.785615 -21.17079) (xy 16.753047 -21.218153) (xy 16.733774 -21.23948)
			(xy 16.72717 -21.246338) (xy 16.720058 -21.264372) (xy 16.720058 -21.353272) (xy 16.72717 -21.371306)
			(xy 16.733774 -21.378164) (xy 16.753057 -21.39948) (xy 16.785621 -21.446845) (xy 16.810711 -21.49856)
			(xy 16.827759 -21.553453) (xy 16.836379 -21.610282) (xy 16.836898 -21.639022) (xy 16.836412 -21.666273)
			(xy 16.828656 -21.720221) (xy 16.813301 -21.772516) (xy 16.790659 -21.822093) (xy 16.761193 -21.867943)
			(xy 16.725502 -21.909134) (xy 16.684311 -21.944825) (xy 16.638461 -21.974291) (xy 16.588884 -21.996933)
			(xy 16.536589 -22.012288) (xy 16.482641 -22.020044) (xy 16.428139 -22.020044) (xy 16.374191 -22.012288)
			(xy 16.321896 -21.996933) (xy 16.272319 -21.974291) (xy 16.226469 -21.944825) (xy 16.185278 -21.909134)
			(xy 16.149587 -21.867943) (xy 16.120121 -21.822093) (xy 16.097479 -21.772516) (xy 16.082124 -21.720221)
			(xy 16.074368 -21.666273) (xy 16.073882 -21.639022) (xy 9.245979 -21.639022) (xy 9.235094 -21.662945)
			(xy 9.174049 -21.777941) (xy 9.106108 -21.889002) (xy 9.031522 -21.995714) (xy 8.950569 -22.097681)
			(xy 8.86355 -22.194523) (xy 8.770789 -22.28588) (xy 8.672631 -22.371412) (xy 8.569442 -22.4508) (xy 8.461605 -22.52375)
			(xy 8.34952 -22.589991) (xy 8.233607 -22.649274) (xy 8.114294 -22.701382) (xy 7.992027 -22.746118)
			(xy 7.86726 -22.783317) (xy 7.740457 -22.812841) (xy 7.61209 -22.834579) (xy 7.482637 -22.848452)
			(xy 7.352578 -22.854406) (xy 7.222399 -22.852421) (xy 7.092583 -22.842503) (xy 6.963613 -22.824689)
			(xy 6.835968 -22.799046) (xy 6.710125 -22.765669) (xy 6.58655 -22.724682) (xy 6.465704 -22.676238)
			(xy 6.348036 -22.620516) (xy 6.233984 -22.557725) (xy 6.123972 -22.488098) (xy 6.01841 -22.411893)
			(xy 5.91769 -22.329394) (xy 5.822186 -22.240909) (xy 5.732254 -22.146766) (xy 5.648229 -22.047315)
			(xy 5.570424 -21.942927) (xy 5.499127 -21.83399) (xy 5.434603 -21.720908) (xy 5.377094 -21.604104)
			(xy 5.326812 -21.484011) (xy 5.283946 -21.361075) (xy 5.248653 -21.235756) (xy 5.221067 -21.108517)
			(xy 5.201288 -20.979834) (xy 5.189392 -20.850184) (xy 5.185422 -20.72005) (xy 1.49987 -20.72005)
			(xy 1.49987 -22.45995) (xy 1.849626 -22.45995) (xy 1.853697 -22.404328) (xy 1.865823 -22.349891)
			(xy 1.885746 -22.2978) (xy 1.913042 -22.249165) (xy 1.947128 -22.205022) (xy 1.987277 -22.166313)
			(xy 2.032635 -22.133862) (xy 2.082235 -22.108361) (xy 2.135019 -22.090354) (xy 2.189862 -22.080224)
			(xy 2.245596 -22.078187) (xy 2.301033 -22.084287) (xy 2.35499 -22.098393) (xy 2.406319 -22.120205)
			(xy 2.453925 -22.149259) (xy 2.496793 -22.184934) (xy 2.53401 -22.226471) (xy 2.564783 -22.272984)
			(xy 2.588455 -22.323481) (xy 2.589623 -22.327362) (xy 2.865626 -22.327362) (xy 2.869697 -22.27174)
			(xy 2.881823 -22.217303) (xy 2.901746 -22.165212) (xy 2.929042 -22.116577) (xy 2.963128 -22.072434)
			(xy 3.003277 -22.033725) (xy 3.048635 -22.001274) (xy 3.098235 -21.975773) (xy 3.151019 -21.957766)
			(xy 3.205862 -21.947636) (xy 3.261596 -21.945599) (xy 3.317033 -21.951699) (xy 3.37099 -21.965805)
			(xy 3.422319 -21.987617) (xy 3.469925 -22.016671) (xy 3.512793 -22.052346) (xy 3.55001 -22.093883)
			(xy 3.580783 -22.140396) (xy 3.604455 -22.190893) (xy 3.620523 -22.2443) (xy 3.628643 -22.299476)
			(xy 3.629152 -22.327362) (xy 3.628643 -22.355248) (xy 3.620523 -22.410424) (xy 3.604455 -22.463831)
			(xy 3.580783 -22.514328) (xy 3.55001 -22.560841) (xy 3.512793 -22.602378) (xy 3.469925 -22.638053)
			(xy 3.422319 -22.667107) (xy 3.37099 -22.688919) (xy 3.317033 -22.703025) (xy 3.261596 -22.709125)
			(xy 3.205862 -22.707088) (xy 3.151019 -22.696958) (xy 3.098235 -22.678951) (xy 3.048635 -22.65345)
			(xy 3.003277 -22.620999) (xy 2.963128 -22.58229) (xy 2.929042 -22.538147) (xy 2.901746 -22.489512)
			(xy 2.881823 -22.437421) (xy 2.869697 -22.382984) (xy 2.865626 -22.327362) (xy 2.589623 -22.327362)
			(xy 2.604523 -22.376888) (xy 2.612643 -22.432064) (xy 2.613152 -22.45995) (xy 2.612643 -22.487836)
			(xy 2.604523 -22.543012) (xy 2.588455 -22.596419) (xy 2.564783 -22.646916) (xy 2.53401 -22.693429)
			(xy 2.496793 -22.734966) (xy 2.453925 -22.770641) (xy 2.406319 -22.799695) (xy 2.35499 -22.821507)
			(xy 2.301033 -22.835613) (xy 2.245596 -22.841713) (xy 2.189862 -22.839676) (xy 2.135019 -22.829546)
			(xy 2.082235 -22.811539) (xy 2.032635 -22.786038) (xy 1.987277 -22.753587) (xy 1.947128 -22.714878)
			(xy 1.913042 -22.670735) (xy 1.885746 -22.6221) (xy 1.865823 -22.570009) (xy 1.853697 -22.515572)
			(xy 1.849626 -22.45995) (xy 1.49987 -22.45995) (xy 1.49987 -22.86) (xy 4.189982 -22.86) (xy 4.194053 -22.804378)
			(xy 4.206179 -22.749941) (xy 4.226102 -22.69785) (xy 4.253398 -22.649215) (xy 4.287484 -22.605072)
			(xy 4.327633 -22.566363) (xy 4.372991 -22.533912) (xy 4.422591 -22.508411) (xy 4.475375 -22.490404)
			(xy 4.530218 -22.480274) (xy 4.585952 -22.478237) (xy 4.641389 -22.484337) (xy 4.695346 -22.498443)
			(xy 4.746675 -22.520255) (xy 4.794281 -22.549309) (xy 4.837149 -22.584984) (xy 4.874366 -22.626521)
			(xy 4.905139 -22.673034) (xy 4.928811 -22.723531) (xy 4.944879 -22.776938) (xy 4.952999 -22.832114)
			(xy 4.953508 -22.86) (xy 4.952999 -22.887886) (xy 4.944879 -22.943062) (xy 4.930743 -22.990048) (xy 11.298934 -22.990048)
			(xy 11.303005 -22.934426) (xy 11.315131 -22.879989) (xy 11.335054 -22.827898) (xy 11.36235 -22.779263)
			(xy 11.396436 -22.73512) (xy 11.436585 -22.696411) (xy 11.481943 -22.66396) (xy 11.531543 -22.638459)
			(xy 11.584327 -22.620452) (xy 11.63917 -22.610322) (xy 11.694904 -22.608285) (xy 11.750341 -22.614385)
			(xy 11.804298 -22.628491) (xy 11.855627 -22.650303) (xy 11.903233 -22.679357) (xy 11.946101 -22.715032)
			(xy 11.983318 -22.756569) (xy 12.014091 -22.803082) (xy 12.037763 -22.853579) (xy 12.053831 -22.906986)
			(xy 12.061951 -22.962162) (xy 12.06246 -22.990048) (xy 12.061982 -23.01621) (xy 12.711682 -23.01621)
			(xy 12.715753 -22.960588) (xy 12.727879 -22.906151) (xy 12.747802 -22.85406) (xy 12.775098 -22.805425)
			(xy 12.809184 -22.761282) (xy 12.849333 -22.722573) (xy 12.894691 -22.690122) (xy 12.944291 -22.664621)
			(xy 12.997075 -22.646614) (xy 13.051918 -22.636484) (xy 13.107652 -22.634447) (xy 13.163089 -22.640547)
			(xy 13.217046 -22.654653) (xy 13.268375 -22.676465) (xy 13.315981 -22.705519) (xy 13.358849 -22.741194)
			(xy 13.396066 -22.782731) (xy 13.426839 -22.829244) (xy 13.450511 -22.879741) (xy 13.466579 -22.933148)
			(xy 13.474699 -22.988324) (xy 13.475208 -23.01621) (xy 13.475046 -23.0251) (xy 37.362382 -23.0251)
			(xy 37.366453 -22.969478) (xy 37.378579 -22.915041) (xy 37.398502 -22.86295) (xy 37.425798 -22.814315)
			(xy 37.459884 -22.770172) (xy 37.500033 -22.731463) (xy 37.545391 -22.699012) (xy 37.594991 -22.673511)
			(xy 37.647775 -22.655504) (xy 37.702618 -22.645374) (xy 37.758352 -22.643337) (xy 37.813789 -22.649437)
			(xy 37.867746 -22.663543) (xy 37.919075 -22.685355) (xy 37.966681 -22.714409) (xy 38.009549 -22.750084)
			(xy 38.046766 -22.791621) (xy 38.077539 -22.838134) (xy 38.101211 -22.888631) (xy 38.117279 -22.942038)
			(xy 38.125399 -22.997214) (xy 38.125746 -23.01621) (xy 38.71163 -23.01621) (xy 38.715701 -22.960588)
			(xy 38.727827 -22.906151) (xy 38.74775 -22.85406) (xy 38.775046 -22.805425) (xy 38.809132 -22.761282)
			(xy 38.849281 -22.722573) (xy 38.894639 -22.690122) (xy 38.944239 -22.664621) (xy 38.997023 -22.646614)
			(xy 39.051866 -22.636484) (xy 39.1076 -22.634447) (xy 39.163037 -22.640547) (xy 39.216994 -22.654653)
			(xy 39.268323 -22.676465) (xy 39.315929 -22.705519) (xy 39.358797 -22.741194) (xy 39.396014 -22.782731)
			(xy 39.426787 -22.829244) (xy 39.450459 -22.879741) (xy 39.466527 -22.933148) (xy 39.474647 -22.988324)
			(xy 39.475156 -23.01621) (xy 39.474994 -23.0251) (xy 63.36233 -23.0251) (xy 63.366401 -22.969478)
			(xy 63.378527 -22.915041) (xy 63.39845 -22.86295) (xy 63.425746 -22.814315) (xy 63.459832 -22.770172)
			(xy 63.499981 -22.731463) (xy 63.545339 -22.699012) (xy 63.594939 -22.673511) (xy 63.647723 -22.655504)
			(xy 63.702566 -22.645374) (xy 63.7583 -22.643337) (xy 63.813737 -22.649437) (xy 63.867694 -22.663543)
			(xy 63.919023 -22.685355) (xy 63.966629 -22.714409) (xy 64.009497 -22.750084) (xy 64.046714 -22.791621)
			(xy 64.077487 -22.838134) (xy 64.101159 -22.888631) (xy 64.117227 -22.942038) (xy 64.125347 -22.997214)
			(xy 64.125694 -23.01621) (xy 64.711578 -23.01621) (xy 64.715649 -22.960588) (xy 64.727775 -22.906151)
			(xy 64.747698 -22.85406) (xy 64.774994 -22.805425) (xy 64.80908 -22.761282) (xy 64.849229 -22.722573)
			(xy 64.894587 -22.690122) (xy 64.944187 -22.664621) (xy 64.996971 -22.646614) (xy 65.051814 -22.636484)
			(xy 65.107548 -22.634447) (xy 65.162985 -22.640547) (xy 65.216942 -22.654653) (xy 65.268271 -22.676465)
			(xy 65.315877 -22.705519) (xy 65.358745 -22.741194) (xy 65.395962 -22.782731) (xy 65.426735 -22.829244)
			(xy 65.450407 -22.879741) (xy 65.466475 -22.933148) (xy 65.474595 -22.988324) (xy 65.475104 -23.01621)
			(xy 65.474942 -23.0251) (xy 89.362278 -23.0251) (xy 89.366349 -22.969478) (xy 89.378475 -22.915041)
			(xy 89.398398 -22.86295) (xy 89.425694 -22.814315) (xy 89.45978 -22.770172) (xy 89.499929 -22.731463)
			(xy 89.545287 -22.699012) (xy 89.594887 -22.673511) (xy 89.647671 -22.655504) (xy 89.702514 -22.645374)
			(xy 89.758248 -22.643337) (xy 89.813685 -22.649437) (xy 89.867642 -22.663543) (xy 89.918971 -22.685355)
			(xy 89.966577 -22.714409) (xy 90.009445 -22.750084) (xy 90.046662 -22.791621) (xy 90.077435 -22.838134)
			(xy 90.101107 -22.888631) (xy 90.117175 -22.942038) (xy 90.125295 -22.997214) (xy 90.125642 -23.01621)
			(xy 90.711526 -23.01621) (xy 90.715597 -22.960588) (xy 90.727723 -22.906151) (xy 90.747646 -22.85406)
			(xy 90.774942 -22.805425) (xy 90.809028 -22.761282) (xy 90.849177 -22.722573) (xy 90.894535 -22.690122)
			(xy 90.944135 -22.664621) (xy 90.996919 -22.646614) (xy 91.051762 -22.636484) (xy 91.107496 -22.634447)
			(xy 91.162933 -22.640547) (xy 91.21689 -22.654653) (xy 91.268219 -22.676465) (xy 91.315825 -22.705519)
			(xy 91.358693 -22.741194) (xy 91.39591 -22.782731) (xy 91.426683 -22.829244) (xy 91.450355 -22.879741)
			(xy 91.466423 -22.933148) (xy 91.474543 -22.988324) (xy 91.475052 -23.01621) (xy 91.47489 -23.0251)
			(xy 127.462532 -23.0251) (xy 127.466603 -22.969478) (xy 127.478729 -22.915041) (xy 127.498652 -22.86295)
			(xy 127.525948 -22.814315) (xy 127.560034 -22.770172) (xy 127.600183 -22.731463) (xy 127.645541 -22.699012)
			(xy 127.695141 -22.673511) (xy 127.747925 -22.655504) (xy 127.802768 -22.645374) (xy 127.858502 -22.643337)
			(xy 127.913939 -22.649437) (xy 127.967896 -22.663543) (xy 128.019225 -22.685355) (xy 128.066831 -22.714409)
			(xy 128.109699 -22.750084) (xy 128.146916 -22.791621) (xy 128.177689 -22.838134) (xy 128.201361 -22.888631)
			(xy 128.217429 -22.942038) (xy 128.225549 -22.997214) (xy 128.225896 -23.01621) (xy 128.81178 -23.01621)
			(xy 128.815851 -22.960588) (xy 128.827977 -22.906151) (xy 128.8479 -22.85406) (xy 128.875196 -22.805425)
			(xy 128.909282 -22.761282) (xy 128.949431 -22.722573) (xy 128.994789 -22.690122) (xy 129.044389 -22.664621)
			(xy 129.097173 -22.646614) (xy 129.152016 -22.636484) (xy 129.20775 -22.634447) (xy 129.263187 -22.640547)
			(xy 129.317144 -22.654653) (xy 129.368473 -22.676465) (xy 129.416079 -22.705519) (xy 129.458947 -22.741194)
			(xy 129.496164 -22.782731) (xy 129.526937 -22.829244) (xy 129.550609 -22.879741) (xy 129.566677 -22.933148)
			(xy 129.574797 -22.988324) (xy 129.575306 -23.01621) (xy 129.575144 -23.0251) (xy 153.46248 -23.0251)
			(xy 153.466551 -22.969478) (xy 153.478677 -22.915041) (xy 153.4986 -22.86295) (xy 153.525896 -22.814315)
			(xy 153.559982 -22.770172) (xy 153.600131 -22.731463) (xy 153.645489 -22.699012) (xy 153.695089 -22.673511)
			(xy 153.747873 -22.655504) (xy 153.802716 -22.645374) (xy 153.85845 -22.643337) (xy 153.913887 -22.649437)
			(xy 153.967844 -22.663543) (xy 154.019173 -22.685355) (xy 154.066779 -22.714409) (xy 154.109647 -22.750084)
			(xy 154.146864 -22.791621) (xy 154.177637 -22.838134) (xy 154.201309 -22.888631) (xy 154.217377 -22.942038)
			(xy 154.225497 -22.997214) (xy 154.225844 -23.01621) (xy 154.811728 -23.01621) (xy 154.815799 -22.960588)
			(xy 154.827925 -22.906151) (xy 154.847848 -22.85406) (xy 154.875144 -22.805425) (xy 154.90923 -22.761282)
			(xy 154.949379 -22.722573) (xy 154.994737 -22.690122) (xy 155.044337 -22.664621) (xy 155.097121 -22.646614)
			(xy 155.151964 -22.636484) (xy 155.207698 -22.634447) (xy 155.263135 -22.640547) (xy 155.317092 -22.654653)
			(xy 155.368421 -22.676465) (xy 155.416027 -22.705519) (xy 155.458895 -22.741194) (xy 155.496112 -22.782731)
			(xy 155.526885 -22.829244) (xy 155.550557 -22.879741) (xy 155.566625 -22.933148) (xy 155.574745 -22.988324)
			(xy 155.575254 -23.01621) (xy 155.575092 -23.0251) (xy 179.462428 -23.0251) (xy 179.466499 -22.969478)
			(xy 179.478625 -22.915041) (xy 179.498548 -22.86295) (xy 179.525844 -22.814315) (xy 179.55993 -22.770172)
			(xy 179.600079 -22.731463) (xy 179.645437 -22.699012) (xy 179.695037 -22.673511) (xy 179.747821 -22.655504)
			(xy 179.802664 -22.645374) (xy 179.858398 -22.643337) (xy 179.913835 -22.649437) (xy 179.967792 -22.663543)
			(xy 180.019121 -22.685355) (xy 180.066727 -22.714409) (xy 180.109595 -22.750084) (xy 180.146812 -22.791621)
			(xy 180.177585 -22.838134) (xy 180.201257 -22.888631) (xy 180.217325 -22.942038) (xy 180.225445 -22.997214)
			(xy 180.225792 -23.01621) (xy 180.811676 -23.01621) (xy 180.815747 -22.960588) (xy 180.827873 -22.906151)
			(xy 180.847796 -22.85406) (xy 180.875092 -22.805425) (xy 180.909178 -22.761282) (xy 180.949327 -22.722573)
			(xy 180.994685 -22.690122) (xy 181.044285 -22.664621) (xy 181.097069 -22.646614) (xy 181.151912 -22.636484)
			(xy 181.207646 -22.634447) (xy 181.263083 -22.640547) (xy 181.31704 -22.654653) (xy 181.368369 -22.676465)
			(xy 181.415975 -22.705519) (xy 181.458843 -22.741194) (xy 181.49606 -22.782731) (xy 181.526833 -22.829244)
			(xy 181.550505 -22.879741) (xy 181.566573 -22.933148) (xy 181.574693 -22.988324) (xy 181.575202 -23.01621)
			(xy 181.57504 -23.0251) (xy 205.462376 -23.0251) (xy 205.466447 -22.969478) (xy 205.478573 -22.915041)
			(xy 205.498496 -22.86295) (xy 205.525792 -22.814315) (xy 205.559878 -22.770172) (xy 205.600027 -22.731463)
			(xy 205.645385 -22.699012) (xy 205.694985 -22.673511) (xy 205.747769 -22.655504) (xy 205.802612 -22.645374)
			(xy 205.858346 -22.643337) (xy 205.913783 -22.649437) (xy 205.96774 -22.663543) (xy 206.019069 -22.685355)
			(xy 206.066675 -22.714409) (xy 206.109543 -22.750084) (xy 206.14676 -22.791621) (xy 206.177533 -22.838134)
			(xy 206.201205 -22.888631) (xy 206.217273 -22.942038) (xy 206.225393 -22.997214) (xy 206.22574 -23.01621)
			(xy 206.811624 -23.01621) (xy 206.815695 -22.960588) (xy 206.827821 -22.906151) (xy 206.847744 -22.85406)
			(xy 206.87504 -22.805425) (xy 206.909126 -22.761282) (xy 206.949275 -22.722573) (xy 206.994633 -22.690122)
			(xy 207.044233 -22.664621) (xy 207.097017 -22.646614) (xy 207.15186 -22.636484) (xy 207.207594 -22.634447)
			(xy 207.263031 -22.640547) (xy 207.316988 -22.654653) (xy 207.368317 -22.676465) (xy 207.415923 -22.705519)
			(xy 207.458791 -22.741194) (xy 207.496008 -22.782731) (xy 207.526781 -22.829244) (xy 207.550453 -22.879741)
			(xy 207.566521 -22.933148) (xy 207.574641 -22.988324) (xy 207.57515 -23.01621) (xy 207.574988 -23.0251)
			(xy 243.562376 -23.0251) (xy 243.566447 -22.969478) (xy 243.578573 -22.915041) (xy 243.598496 -22.86295)
			(xy 243.625792 -22.814315) (xy 243.659878 -22.770172) (xy 243.700027 -22.731463) (xy 243.745385 -22.699012)
			(xy 243.794985 -22.673511) (xy 243.847769 -22.655504) (xy 243.902612 -22.645374) (xy 243.958346 -22.643337)
			(xy 244.013783 -22.649437) (xy 244.06774 -22.663543) (xy 244.119069 -22.685355) (xy 244.166675 -22.714409)
			(xy 244.209543 -22.750084) (xy 244.24676 -22.791621) (xy 244.277533 -22.838134) (xy 244.301205 -22.888631)
			(xy 244.317273 -22.942038) (xy 244.325393 -22.997214) (xy 244.32574 -23.01621) (xy 244.911624 -23.01621)
			(xy 244.915695 -22.960588) (xy 244.927821 -22.906151) (xy 244.947744 -22.85406) (xy 244.97504 -22.805425)
			(xy 245.009126 -22.761282) (xy 245.049275 -22.722573) (xy 245.094633 -22.690122) (xy 245.144233 -22.664621)
			(xy 245.197017 -22.646614) (xy 245.25186 -22.636484) (xy 245.307594 -22.634447) (xy 245.363031 -22.640547)
			(xy 245.416988 -22.654653) (xy 245.468317 -22.676465) (xy 245.515923 -22.705519) (xy 245.558791 -22.741194)
			(xy 245.596008 -22.782731) (xy 245.626781 -22.829244) (xy 245.650453 -22.879741) (xy 245.666521 -22.933148)
			(xy 245.674641 -22.988324) (xy 245.67515 -23.01621) (xy 245.674988 -23.0251) (xy 269.562324 -23.0251)
			(xy 269.566395 -22.969478) (xy 269.578521 -22.915041) (xy 269.598444 -22.86295) (xy 269.62574 -22.814315)
			(xy 269.659826 -22.770172) (xy 269.699975 -22.731463) (xy 269.745333 -22.699012) (xy 269.794933 -22.673511)
			(xy 269.847717 -22.655504) (xy 269.90256 -22.645374) (xy 269.958294 -22.643337) (xy 270.013731 -22.649437)
			(xy 270.067688 -22.663543) (xy 270.119017 -22.685355) (xy 270.166623 -22.714409) (xy 270.209491 -22.750084)
			(xy 270.246708 -22.791621) (xy 270.277481 -22.838134) (xy 270.301153 -22.888631) (xy 270.317221 -22.942038)
			(xy 270.325341 -22.997214) (xy 270.325688 -23.01621) (xy 270.911572 -23.01621) (xy 270.915643 -22.960588)
			(xy 270.927769 -22.906151) (xy 270.947692 -22.85406) (xy 270.974988 -22.805425) (xy 271.009074 -22.761282)
			(xy 271.049223 -22.722573) (xy 271.094581 -22.690122) (xy 271.144181 -22.664621) (xy 271.196965 -22.646614)
			(xy 271.251808 -22.636484) (xy 271.307542 -22.634447) (xy 271.362979 -22.640547) (xy 271.416936 -22.654653)
			(xy 271.468265 -22.676465) (xy 271.515871 -22.705519) (xy 271.558739 -22.741194) (xy 271.595956 -22.782731)
			(xy 271.626729 -22.829244) (xy 271.650401 -22.879741) (xy 271.666469 -22.933148) (xy 271.674589 -22.988324)
			(xy 271.675098 -23.01621) (xy 271.674936 -23.0251) (xy 295.562272 -23.0251) (xy 295.566343 -22.969478)
			(xy 295.578469 -22.915041) (xy 295.598392 -22.86295) (xy 295.625688 -22.814315) (xy 295.659774 -22.770172)
			(xy 295.699923 -22.731463) (xy 295.745281 -22.699012) (xy 295.794881 -22.673511) (xy 295.847665 -22.655504)
			(xy 295.902508 -22.645374) (xy 295.958242 -22.643337) (xy 296.013679 -22.649437) (xy 296.067636 -22.663543)
			(xy 296.118965 -22.685355) (xy 296.166571 -22.714409) (xy 296.209439 -22.750084) (xy 296.246656 -22.791621)
			(xy 296.277429 -22.838134) (xy 296.301101 -22.888631) (xy 296.317169 -22.942038) (xy 296.325289 -22.997214)
			(xy 296.325636 -23.01621) (xy 296.91152 -23.01621) (xy 296.915591 -22.960588) (xy 296.927717 -22.906151)
			(xy 296.94764 -22.85406) (xy 296.974936 -22.805425) (xy 297.009022 -22.761282) (xy 297.049171 -22.722573)
			(xy 297.094529 -22.690122) (xy 297.144129 -22.664621) (xy 297.196913 -22.646614) (xy 297.251756 -22.636484)
			(xy 297.30749 -22.634447) (xy 297.362927 -22.640547) (xy 297.416884 -22.654653) (xy 297.468213 -22.676465)
			(xy 297.515819 -22.705519) (xy 297.558687 -22.741194) (xy 297.595904 -22.782731) (xy 297.626677 -22.829244)
			(xy 297.650349 -22.879741) (xy 297.666417 -22.933148) (xy 297.674537 -22.988324) (xy 297.675046 -23.01621)
			(xy 297.674884 -23.0251) (xy 321.56222 -23.0251) (xy 321.566291 -22.969478) (xy 321.578417 -22.915041)
			(xy 321.59834 -22.86295) (xy 321.625636 -22.814315) (xy 321.659722 -22.770172) (xy 321.699871 -22.731463)
			(xy 321.745229 -22.699012) (xy 321.794829 -22.673511) (xy 321.847613 -22.655504) (xy 321.902456 -22.645374)
			(xy 321.95819 -22.643337) (xy 322.013627 -22.649437) (xy 322.067584 -22.663543) (xy 322.118913 -22.685355)
			(xy 322.166519 -22.714409) (xy 322.209387 -22.750084) (xy 322.246604 -22.791621) (xy 322.277377 -22.838134)
			(xy 322.301049 -22.888631) (xy 322.317117 -22.942038) (xy 322.325237 -22.997214) (xy 322.325584 -23.01621)
			(xy 322.911468 -23.01621) (xy 322.915539 -22.960588) (xy 322.927665 -22.906151) (xy 322.947588 -22.85406)
			(xy 322.974884 -22.805425) (xy 323.00897 -22.761282) (xy 323.049119 -22.722573) (xy 323.094477 -22.690122)
			(xy 323.144077 -22.664621) (xy 323.196861 -22.646614) (xy 323.251704 -22.636484) (xy 323.307438 -22.634447)
			(xy 323.362875 -22.640547) (xy 323.416832 -22.654653) (xy 323.468161 -22.676465) (xy 323.515767 -22.705519)
			(xy 323.558635 -22.741194) (xy 323.595852 -22.782731) (xy 323.626625 -22.829244) (xy 323.650297 -22.879741)
			(xy 323.666365 -22.933148) (xy 323.674485 -22.988324) (xy 323.674994 -23.01621) (xy 323.674832 -23.0251)
			(xy 359.662474 -23.0251) (xy 359.666545 -22.969478) (xy 359.678671 -22.915041) (xy 359.698594 -22.86295)
			(xy 359.72589 -22.814315) (xy 359.759976 -22.770172) (xy 359.800125 -22.731463) (xy 359.845483 -22.699012)
			(xy 359.895083 -22.673511) (xy 359.947867 -22.655504) (xy 360.00271 -22.645374) (xy 360.058444 -22.643337)
			(xy 360.113881 -22.649437) (xy 360.167838 -22.663543) (xy 360.219167 -22.685355) (xy 360.266773 -22.714409)
			(xy 360.309641 -22.750084) (xy 360.346858 -22.791621) (xy 360.377631 -22.838134) (xy 360.401303 -22.888631)
			(xy 360.417371 -22.942038) (xy 360.425491 -22.997214) (xy 360.425838 -23.01621) (xy 361.011722 -23.01621)
			(xy 361.015793 -22.960588) (xy 361.027919 -22.906151) (xy 361.047842 -22.85406) (xy 361.075138 -22.805425)
			(xy 361.109224 -22.761282) (xy 361.149373 -22.722573) (xy 361.194731 -22.690122) (xy 361.244331 -22.664621)
			(xy 361.297115 -22.646614) (xy 361.351958 -22.636484) (xy 361.407692 -22.634447) (xy 361.463129 -22.640547)
			(xy 361.517086 -22.654653) (xy 361.568415 -22.676465) (xy 361.616021 -22.705519) (xy 361.658889 -22.741194)
			(xy 361.696106 -22.782731) (xy 361.726879 -22.829244) (xy 361.750551 -22.879741) (xy 361.766619 -22.933148)
			(xy 361.774739 -22.988324) (xy 361.775248 -23.01621) (xy 361.775086 -23.0251) (xy 385.662422 -23.0251)
			(xy 385.666493 -22.969478) (xy 385.678619 -22.915041) (xy 385.698542 -22.86295) (xy 385.725838 -22.814315)
			(xy 385.759924 -22.770172) (xy 385.800073 -22.731463) (xy 385.845431 -22.699012) (xy 385.895031 -22.673511)
			(xy 385.947815 -22.655504) (xy 386.002658 -22.645374) (xy 386.058392 -22.643337) (xy 386.113829 -22.649437)
			(xy 386.167786 -22.663543) (xy 386.219115 -22.685355) (xy 386.266721 -22.714409) (xy 386.309589 -22.750084)
			(xy 386.346806 -22.791621) (xy 386.377579 -22.838134) (xy 386.401251 -22.888631) (xy 386.417319 -22.942038)
			(xy 386.425439 -22.997214) (xy 386.425786 -23.01621) (xy 387.01167 -23.01621) (xy 387.015741 -22.960588)
			(xy 387.027867 -22.906151) (xy 387.04779 -22.85406) (xy 387.075086 -22.805425) (xy 387.109172 -22.761282)
			(xy 387.149321 -22.722573) (xy 387.194679 -22.690122) (xy 387.244279 -22.664621) (xy 387.297063 -22.646614)
			(xy 387.351906 -22.636484) (xy 387.40764 -22.634447) (xy 387.463077 -22.640547) (xy 387.517034 -22.654653)
			(xy 387.568363 -22.676465) (xy 387.615969 -22.705519) (xy 387.658837 -22.741194) (xy 387.696054 -22.782731)
			(xy 387.726827 -22.829244) (xy 387.750499 -22.879741) (xy 387.766567 -22.933148) (xy 387.774687 -22.988324)
			(xy 387.775196 -23.01621) (xy 387.775034 -23.0251) (xy 411.66237 -23.0251) (xy 411.666441 -22.969478)
			(xy 411.678567 -22.915041) (xy 411.69849 -22.86295) (xy 411.725786 -22.814315) (xy 411.759872 -22.770172)
			(xy 411.800021 -22.731463) (xy 411.845379 -22.699012) (xy 411.894979 -22.673511) (xy 411.947763 -22.655504)
			(xy 412.002606 -22.645374) (xy 412.05834 -22.643337) (xy 412.113777 -22.649437) (xy 412.167734 -22.663543)
			(xy 412.219063 -22.685355) (xy 412.266669 -22.714409) (xy 412.309537 -22.750084) (xy 412.346754 -22.791621)
			(xy 412.377527 -22.838134) (xy 412.401199 -22.888631) (xy 412.417267 -22.942038) (xy 412.425387 -22.997214)
			(xy 412.425734 -23.01621) (xy 413.011618 -23.01621) (xy 413.015689 -22.960588) (xy 413.027815 -22.906151)
			(xy 413.047738 -22.85406) (xy 413.075034 -22.805425) (xy 413.10912 -22.761282) (xy 413.149269 -22.722573)
			(xy 413.194627 -22.690122) (xy 413.244227 -22.664621) (xy 413.297011 -22.646614) (xy 413.351854 -22.636484)
			(xy 413.407588 -22.634447) (xy 413.463025 -22.640547) (xy 413.516982 -22.654653) (xy 413.568311 -22.676465)
			(xy 413.615917 -22.705519) (xy 413.658785 -22.741194) (xy 413.696002 -22.782731) (xy 413.726775 -22.829244)
			(xy 413.750447 -22.879741) (xy 413.766515 -22.933148) (xy 413.774635 -22.988324) (xy 413.775144 -23.01621)
			(xy 413.774982 -23.0251) (xy 437.662318 -23.0251) (xy 437.666389 -22.969478) (xy 437.678515 -22.915041)
			(xy 437.698438 -22.86295) (xy 437.725734 -22.814315) (xy 437.75982 -22.770172) (xy 437.799969 -22.731463)
			(xy 437.845327 -22.699012) (xy 437.894927 -22.673511) (xy 437.947711 -22.655504) (xy 438.002554 -22.645374)
			(xy 438.058288 -22.643337) (xy 438.113725 -22.649437) (xy 438.167682 -22.663543) (xy 438.219011 -22.685355)
			(xy 438.266617 -22.714409) (xy 438.309485 -22.750084) (xy 438.346702 -22.791621) (xy 438.377475 -22.838134)
			(xy 438.401147 -22.888631) (xy 438.417215 -22.942038) (xy 438.425335 -22.997214) (xy 438.425682 -23.01621)
			(xy 439.011566 -23.01621) (xy 439.015637 -22.960588) (xy 439.027763 -22.906151) (xy 439.047686 -22.85406)
			(xy 439.074982 -22.805425) (xy 439.109068 -22.761282) (xy 439.149217 -22.722573) (xy 439.194575 -22.690122)
			(xy 439.244175 -22.664621) (xy 439.296959 -22.646614) (xy 439.351802 -22.636484) (xy 439.407536 -22.634447)
			(xy 439.462973 -22.640547) (xy 439.51693 -22.654653) (xy 439.568259 -22.676465) (xy 439.615865 -22.705519)
			(xy 439.658733 -22.741194) (xy 439.69595 -22.782731) (xy 439.726723 -22.829244) (xy 439.750395 -22.879741)
			(xy 439.766463 -22.933148) (xy 439.774583 -22.988324) (xy 439.775092 -23.01621) (xy 439.774583 -23.044096)
			(xy 439.766463 -23.099272) (xy 439.750395 -23.152679) (xy 439.726723 -23.203176) (xy 439.69595 -23.249689)
			(xy 439.658733 -23.291226) (xy 439.615865 -23.326901) (xy 439.568259 -23.355955) (xy 439.51693 -23.377767)
			(xy 439.462973 -23.391873) (xy 439.407536 -23.397973) (xy 439.351802 -23.395936) (xy 439.296959 -23.385806)
			(xy 439.244175 -23.367799) (xy 439.194575 -23.342298) (xy 439.149217 -23.309847) (xy 439.109068 -23.271138)
			(xy 439.074982 -23.226995) (xy 439.047686 -23.17836) (xy 439.027763 -23.126269) (xy 439.015637 -23.071832)
			(xy 439.011566 -23.01621) (xy 438.425682 -23.01621) (xy 438.425844 -23.0251) (xy 438.425335 -23.052986)
			(xy 438.417215 -23.108162) (xy 438.401147 -23.161569) (xy 438.377475 -23.212066) (xy 438.346702 -23.258579)
			(xy 438.309485 -23.300116) (xy 438.266617 -23.335791) (xy 438.219011 -23.364845) (xy 438.167682 -23.386657)
			(xy 438.113725 -23.400763) (xy 438.058288 -23.406863) (xy 438.002554 -23.404826) (xy 437.947711 -23.394696)
			(xy 437.894927 -23.376689) (xy 437.845327 -23.351188) (xy 437.799969 -23.318737) (xy 437.75982 -23.280028)
			(xy 437.725734 -23.235885) (xy 437.698438 -23.18725) (xy 437.678515 -23.135159) (xy 437.666389 -23.080722)
			(xy 437.662318 -23.0251) (xy 413.774982 -23.0251) (xy 413.774635 -23.044096) (xy 413.766515 -23.099272)
			(xy 413.750447 -23.152679) (xy 413.726775 -23.203176) (xy 413.696002 -23.249689) (xy 413.658785 -23.291226)
			(xy 413.615917 -23.326901) (xy 413.568311 -23.355955) (xy 413.516982 -23.377767) (xy 413.463025 -23.391873)
			(xy 413.407588 -23.397973) (xy 413.351854 -23.395936) (xy 413.297011 -23.385806) (xy 413.244227 -23.367799)
			(xy 413.194627 -23.342298) (xy 413.149269 -23.309847) (xy 413.10912 -23.271138) (xy 413.075034 -23.226995)
			(xy 413.047738 -23.17836) (xy 413.027815 -23.126269) (xy 413.015689 -23.071832) (xy 413.011618 -23.01621)
			(xy 412.425734 -23.01621) (xy 412.425896 -23.0251) (xy 412.425387 -23.052986) (xy 412.417267 -23.108162)
			(xy 412.401199 -23.161569) (xy 412.377527 -23.212066) (xy 412.346754 -23.258579) (xy 412.309537 -23.300116)
			(xy 412.266669 -23.335791) (xy 412.219063 -23.364845) (xy 412.167734 -23.386657) (xy 412.113777 -23.400763)
			(xy 412.05834 -23.406863) (xy 412.002606 -23.404826) (xy 411.947763 -23.394696) (xy 411.894979 -23.376689)
			(xy 411.845379 -23.351188) (xy 411.800021 -23.318737) (xy 411.759872 -23.280028) (xy 411.725786 -23.235885)
			(xy 411.69849 -23.18725) (xy 411.678567 -23.135159) (xy 411.666441 -23.080722) (xy 411.66237 -23.0251)
			(xy 387.775034 -23.0251) (xy 387.774687 -23.044096) (xy 387.766567 -23.099272) (xy 387.750499 -23.152679)
			(xy 387.726827 -23.203176) (xy 387.696054 -23.249689) (xy 387.658837 -23.291226) (xy 387.615969 -23.326901)
			(xy 387.568363 -23.355955) (xy 387.517034 -23.377767) (xy 387.463077 -23.391873) (xy 387.40764 -23.397973)
			(xy 387.351906 -23.395936) (xy 387.297063 -23.385806) (xy 387.244279 -23.367799) (xy 387.194679 -23.342298)
			(xy 387.149321 -23.309847) (xy 387.109172 -23.271138) (xy 387.075086 -23.226995) (xy 387.04779 -23.17836)
			(xy 387.027867 -23.126269) (xy 387.015741 -23.071832) (xy 387.01167 -23.01621) (xy 386.425786 -23.01621)
			(xy 386.425948 -23.0251) (xy 386.425439 -23.052986) (xy 386.417319 -23.108162) (xy 386.401251 -23.161569)
			(xy 386.377579 -23.212066) (xy 386.346806 -23.258579) (xy 386.309589 -23.300116) (xy 386.266721 -23.335791)
			(xy 386.219115 -23.364845) (xy 386.167786 -23.386657) (xy 386.113829 -23.400763) (xy 386.058392 -23.406863)
			(xy 386.002658 -23.404826) (xy 385.947815 -23.394696) (xy 385.895031 -23.376689) (xy 385.845431 -23.351188)
			(xy 385.800073 -23.318737) (xy 385.759924 -23.280028) (xy 385.725838 -23.235885) (xy 385.698542 -23.18725)
			(xy 385.678619 -23.135159) (xy 385.666493 -23.080722) (xy 385.662422 -23.0251) (xy 361.775086 -23.0251)
			(xy 361.774739 -23.044096) (xy 361.766619 -23.099272) (xy 361.750551 -23.152679) (xy 361.726879 -23.203176)
			(xy 361.696106 -23.249689) (xy 361.658889 -23.291226) (xy 361.616021 -23.326901) (xy 361.568415 -23.355955)
			(xy 361.517086 -23.377767) (xy 361.463129 -23.391873) (xy 361.407692 -23.397973) (xy 361.351958 -23.395936)
			(xy 361.297115 -23.385806) (xy 361.244331 -23.367799) (xy 361.194731 -23.342298) (xy 361.149373 -23.309847)
			(xy 361.109224 -23.271138) (xy 361.075138 -23.226995) (xy 361.047842 -23.17836) (xy 361.027919 -23.126269)
			(xy 361.015793 -23.071832) (xy 361.011722 -23.01621) (xy 360.425838 -23.01621) (xy 360.426 -23.0251)
			(xy 360.425491 -23.052986) (xy 360.417371 -23.108162) (xy 360.401303 -23.161569) (xy 360.377631 -23.212066)
			(xy 360.346858 -23.258579) (xy 360.309641 -23.300116) (xy 360.266773 -23.335791) (xy 360.219167 -23.364845)
			(xy 360.167838 -23.386657) (xy 360.113881 -23.400763) (xy 360.058444 -23.406863) (xy 360.00271 -23.404826)
			(xy 359.947867 -23.394696) (xy 359.895083 -23.376689) (xy 359.845483 -23.351188) (xy 359.800125 -23.318737)
			(xy 359.759976 -23.280028) (xy 359.72589 -23.235885) (xy 359.698594 -23.18725) (xy 359.678671 -23.135159)
			(xy 359.666545 -23.080722) (xy 359.662474 -23.0251) (xy 323.674832 -23.0251) (xy 323.674485 -23.044096)
			(xy 323.666365 -23.099272) (xy 323.650297 -23.152679) (xy 323.626625 -23.203176) (xy 323.595852 -23.249689)
			(xy 323.558635 -23.291226) (xy 323.515767 -23.326901) (xy 323.468161 -23.355955) (xy 323.416832 -23.377767)
			(xy 323.362875 -23.391873) (xy 323.307438 -23.397973) (xy 323.251704 -23.395936) (xy 323.196861 -23.385806)
			(xy 323.144077 -23.367799) (xy 323.094477 -23.342298) (xy 323.049119 -23.309847) (xy 323.00897 -23.271138)
			(xy 322.974884 -23.226995) (xy 322.947588 -23.17836) (xy 322.927665 -23.126269) (xy 322.915539 -23.071832)
			(xy 322.911468 -23.01621) (xy 322.325584 -23.01621) (xy 322.325746 -23.0251) (xy 322.325237 -23.052986)
			(xy 322.317117 -23.108162) (xy 322.301049 -23.161569) (xy 322.277377 -23.212066) (xy 322.246604 -23.258579)
			(xy 322.209387 -23.300116) (xy 322.166519 -23.335791) (xy 322.118913 -23.364845) (xy 322.067584 -23.386657)
			(xy 322.013627 -23.400763) (xy 321.95819 -23.406863) (xy 321.902456 -23.404826) (xy 321.847613 -23.394696)
			(xy 321.794829 -23.376689) (xy 321.745229 -23.351188) (xy 321.699871 -23.318737) (xy 321.659722 -23.280028)
			(xy 321.625636 -23.235885) (xy 321.59834 -23.18725) (xy 321.578417 -23.135159) (xy 321.566291 -23.080722)
			(xy 321.56222 -23.0251) (xy 297.674884 -23.0251) (xy 297.674537 -23.044096) (xy 297.666417 -23.099272)
			(xy 297.650349 -23.152679) (xy 297.626677 -23.203176) (xy 297.595904 -23.249689) (xy 297.558687 -23.291226)
			(xy 297.515819 -23.326901) (xy 297.468213 -23.355955) (xy 297.416884 -23.377767) (xy 297.362927 -23.391873)
			(xy 297.30749 -23.397973) (xy 297.251756 -23.395936) (xy 297.196913 -23.385806) (xy 297.144129 -23.367799)
			(xy 297.094529 -23.342298) (xy 297.049171 -23.309847) (xy 297.009022 -23.271138) (xy 296.974936 -23.226995)
			(xy 296.94764 -23.17836) (xy 296.927717 -23.126269) (xy 296.915591 -23.071832) (xy 296.91152 -23.01621)
			(xy 296.325636 -23.01621) (xy 296.325798 -23.0251) (xy 296.325289 -23.052986) (xy 296.317169 -23.108162)
			(xy 296.301101 -23.161569) (xy 296.277429 -23.212066) (xy 296.246656 -23.258579) (xy 296.209439 -23.300116)
			(xy 296.166571 -23.335791) (xy 296.118965 -23.364845) (xy 296.067636 -23.386657) (xy 296.013679 -23.400763)
			(xy 295.958242 -23.406863) (xy 295.902508 -23.404826) (xy 295.847665 -23.394696) (xy 295.794881 -23.376689)
			(xy 295.745281 -23.351188) (xy 295.699923 -23.318737) (xy 295.659774 -23.280028) (xy 295.625688 -23.235885)
			(xy 295.598392 -23.18725) (xy 295.578469 -23.135159) (xy 295.566343 -23.080722) (xy 295.562272 -23.0251)
			(xy 271.674936 -23.0251) (xy 271.674589 -23.044096) (xy 271.666469 -23.099272) (xy 271.650401 -23.152679)
			(xy 271.626729 -23.203176) (xy 271.595956 -23.249689) (xy 271.558739 -23.291226) (xy 271.515871 -23.326901)
			(xy 271.468265 -23.355955) (xy 271.416936 -23.377767) (xy 271.362979 -23.391873) (xy 271.307542 -23.397973)
			(xy 271.251808 -23.395936) (xy 271.196965 -23.385806) (xy 271.144181 -23.367799) (xy 271.094581 -23.342298)
			(xy 271.049223 -23.309847) (xy 271.009074 -23.271138) (xy 270.974988 -23.226995) (xy 270.947692 -23.17836)
			(xy 270.927769 -23.126269) (xy 270.915643 -23.071832) (xy 270.911572 -23.01621) (xy 270.325688 -23.01621)
			(xy 270.32585 -23.0251) (xy 270.325341 -23.052986) (xy 270.317221 -23.108162) (xy 270.301153 -23.161569)
			(xy 270.277481 -23.212066) (xy 270.246708 -23.258579) (xy 270.209491 -23.300116) (xy 270.166623 -23.335791)
			(xy 270.119017 -23.364845) (xy 270.067688 -23.386657) (xy 270.013731 -23.400763) (xy 269.958294 -23.406863)
			(xy 269.90256 -23.404826) (xy 269.847717 -23.394696) (xy 269.794933 -23.376689) (xy 269.745333 -23.351188)
			(xy 269.699975 -23.318737) (xy 269.659826 -23.280028) (xy 269.62574 -23.235885) (xy 269.598444 -23.18725)
			(xy 269.578521 -23.135159) (xy 269.566395 -23.080722) (xy 269.562324 -23.0251) (xy 245.674988 -23.0251)
			(xy 245.674641 -23.044096) (xy 245.666521 -23.099272) (xy 245.650453 -23.152679) (xy 245.626781 -23.203176)
			(xy 245.596008 -23.249689) (xy 245.558791 -23.291226) (xy 245.515923 -23.326901) (xy 245.468317 -23.355955)
			(xy 245.416988 -23.377767) (xy 245.363031 -23.391873) (xy 245.307594 -23.397973) (xy 245.25186 -23.395936)
			(xy 245.197017 -23.385806) (xy 245.144233 -23.367799) (xy 245.094633 -23.342298) (xy 245.049275 -23.309847)
			(xy 245.009126 -23.271138) (xy 244.97504 -23.226995) (xy 244.947744 -23.17836) (xy 244.927821 -23.126269)
			(xy 244.915695 -23.071832) (xy 244.911624 -23.01621) (xy 244.32574 -23.01621) (xy 244.325902 -23.0251)
			(xy 244.325393 -23.052986) (xy 244.317273 -23.108162) (xy 244.301205 -23.161569) (xy 244.277533 -23.212066)
			(xy 244.24676 -23.258579) (xy 244.209543 -23.300116) (xy 244.166675 -23.335791) (xy 244.119069 -23.364845)
			(xy 244.06774 -23.386657) (xy 244.013783 -23.400763) (xy 243.958346 -23.406863) (xy 243.902612 -23.404826)
			(xy 243.847769 -23.394696) (xy 243.794985 -23.376689) (xy 243.745385 -23.351188) (xy 243.700027 -23.318737)
			(xy 243.659878 -23.280028) (xy 243.625792 -23.235885) (xy 243.598496 -23.18725) (xy 243.578573 -23.135159)
			(xy 243.566447 -23.080722) (xy 243.562376 -23.0251) (xy 207.574988 -23.0251) (xy 207.574641 -23.044096)
			(xy 207.566521 -23.099272) (xy 207.550453 -23.152679) (xy 207.526781 -23.203176) (xy 207.496008 -23.249689)
			(xy 207.458791 -23.291226) (xy 207.415923 -23.326901) (xy 207.368317 -23.355955) (xy 207.316988 -23.377767)
			(xy 207.263031 -23.391873) (xy 207.207594 -23.397973) (xy 207.15186 -23.395936) (xy 207.097017 -23.385806)
			(xy 207.044233 -23.367799) (xy 206.994633 -23.342298) (xy 206.949275 -23.309847) (xy 206.909126 -23.271138)
			(xy 206.87504 -23.226995) (xy 206.847744 -23.17836) (xy 206.827821 -23.126269) (xy 206.815695 -23.071832)
			(xy 206.811624 -23.01621) (xy 206.22574 -23.01621) (xy 206.225902 -23.0251) (xy 206.225393 -23.052986)
			(xy 206.217273 -23.108162) (xy 206.201205 -23.161569) (xy 206.177533 -23.212066) (xy 206.14676 -23.258579)
			(xy 206.109543 -23.300116) (xy 206.066675 -23.335791) (xy 206.019069 -23.364845) (xy 205.96774 -23.386657)
			(xy 205.913783 -23.400763) (xy 205.858346 -23.406863) (xy 205.802612 -23.404826) (xy 205.747769 -23.394696)
			(xy 205.694985 -23.376689) (xy 205.645385 -23.351188) (xy 205.600027 -23.318737) (xy 205.559878 -23.280028)
			(xy 205.525792 -23.235885) (xy 205.498496 -23.18725) (xy 205.478573 -23.135159) (xy 205.466447 -23.080722)
			(xy 205.462376 -23.0251) (xy 181.57504 -23.0251) (xy 181.574693 -23.044096) (xy 181.566573 -23.099272)
			(xy 181.550505 -23.152679) (xy 181.526833 -23.203176) (xy 181.49606 -23.249689) (xy 181.458843 -23.291226)
			(xy 181.415975 -23.326901) (xy 181.368369 -23.355955) (xy 181.31704 -23.377767) (xy 181.263083 -23.391873)
			(xy 181.207646 -23.397973) (xy 181.151912 -23.395936) (xy 181.097069 -23.385806) (xy 181.044285 -23.367799)
			(xy 180.994685 -23.342298) (xy 180.949327 -23.309847) (xy 180.909178 -23.271138) (xy 180.875092 -23.226995)
			(xy 180.847796 -23.17836) (xy 180.827873 -23.126269) (xy 180.815747 -23.071832) (xy 180.811676 -23.01621)
			(xy 180.225792 -23.01621) (xy 180.225954 -23.0251) (xy 180.225445 -23.052986) (xy 180.217325 -23.108162)
			(xy 180.201257 -23.161569) (xy 180.177585 -23.212066) (xy 180.146812 -23.258579) (xy 180.109595 -23.300116)
			(xy 180.066727 -23.335791) (xy 180.019121 -23.364845) (xy 179.967792 -23.386657) (xy 179.913835 -23.400763)
			(xy 179.858398 -23.406863) (xy 179.802664 -23.404826) (xy 179.747821 -23.394696) (xy 179.695037 -23.376689)
			(xy 179.645437 -23.351188) (xy 179.600079 -23.318737) (xy 179.55993 -23.280028) (xy 179.525844 -23.235885)
			(xy 179.498548 -23.18725) (xy 179.478625 -23.135159) (xy 179.466499 -23.080722) (xy 179.462428 -23.0251)
			(xy 155.575092 -23.0251) (xy 155.574745 -23.044096) (xy 155.566625 -23.099272) (xy 155.550557 -23.152679)
			(xy 155.526885 -23.203176) (xy 155.496112 -23.249689) (xy 155.458895 -23.291226) (xy 155.416027 -23.326901)
			(xy 155.368421 -23.355955) (xy 155.317092 -23.377767) (xy 155.263135 -23.391873) (xy 155.207698 -23.397973)
			(xy 155.151964 -23.395936) (xy 155.097121 -23.385806) (xy 155.044337 -23.367799) (xy 154.994737 -23.342298)
			(xy 154.949379 -23.309847) (xy 154.90923 -23.271138) (xy 154.875144 -23.226995) (xy 154.847848 -23.17836)
			(xy 154.827925 -23.126269) (xy 154.815799 -23.071832) (xy 154.811728 -23.01621) (xy 154.225844 -23.01621)
			(xy 154.226006 -23.0251) (xy 154.225497 -23.052986) (xy 154.217377 -23.108162) (xy 154.201309 -23.161569)
			(xy 154.177637 -23.212066) (xy 154.146864 -23.258579) (xy 154.109647 -23.300116) (xy 154.066779 -23.335791)
			(xy 154.019173 -23.364845) (xy 153.967844 -23.386657) (xy 153.913887 -23.400763) (xy 153.85845 -23.406863)
			(xy 153.802716 -23.404826) (xy 153.747873 -23.394696) (xy 153.695089 -23.376689) (xy 153.645489 -23.351188)
			(xy 153.600131 -23.318737) (xy 153.559982 -23.280028) (xy 153.525896 -23.235885) (xy 153.4986 -23.18725)
			(xy 153.478677 -23.135159) (xy 153.466551 -23.080722) (xy 153.46248 -23.0251) (xy 129.575144 -23.0251)
			(xy 129.574797 -23.044096) (xy 129.566677 -23.099272) (xy 129.550609 -23.152679) (xy 129.526937 -23.203176)
			(xy 129.496164 -23.249689) (xy 129.458947 -23.291226) (xy 129.416079 -23.326901) (xy 129.368473 -23.355955)
			(xy 129.317144 -23.377767) (xy 129.263187 -23.391873) (xy 129.20775 -23.397973) (xy 129.152016 -23.395936)
			(xy 129.097173 -23.385806) (xy 129.044389 -23.367799) (xy 128.994789 -23.342298) (xy 128.949431 -23.309847)
			(xy 128.909282 -23.271138) (xy 128.875196 -23.226995) (xy 128.8479 -23.17836) (xy 128.827977 -23.126269)
			(xy 128.815851 -23.071832) (xy 128.81178 -23.01621) (xy 128.225896 -23.01621) (xy 128.226058 -23.0251)
			(xy 128.225549 -23.052986) (xy 128.217429 -23.108162) (xy 128.201361 -23.161569) (xy 128.177689 -23.212066)
			(xy 128.146916 -23.258579) (xy 128.109699 -23.300116) (xy 128.066831 -23.335791) (xy 128.019225 -23.364845)
			(xy 127.967896 -23.386657) (xy 127.913939 -23.400763) (xy 127.858502 -23.406863) (xy 127.802768 -23.404826)
			(xy 127.747925 -23.394696) (xy 127.695141 -23.376689) (xy 127.645541 -23.351188) (xy 127.600183 -23.318737)
			(xy 127.560034 -23.280028) (xy 127.525948 -23.235885) (xy 127.498652 -23.18725) (xy 127.478729 -23.135159)
			(xy 127.466603 -23.080722) (xy 127.462532 -23.0251) (xy 91.47489 -23.0251) (xy 91.474543 -23.044096)
			(xy 91.466423 -23.099272) (xy 91.450355 -23.152679) (xy 91.426683 -23.203176) (xy 91.39591 -23.249689)
			(xy 91.358693 -23.291226) (xy 91.315825 -23.326901) (xy 91.268219 -23.355955) (xy 91.21689 -23.377767)
			(xy 91.162933 -23.391873) (xy 91.107496 -23.397973) (xy 91.051762 -23.395936) (xy 90.996919 -23.385806)
			(xy 90.944135 -23.367799) (xy 90.894535 -23.342298) (xy 90.849177 -23.309847) (xy 90.809028 -23.271138)
			(xy 90.774942 -23.226995) (xy 90.747646 -23.17836) (xy 90.727723 -23.126269) (xy 90.715597 -23.071832)
			(xy 90.711526 -23.01621) (xy 90.125642 -23.01621) (xy 90.125804 -23.0251) (xy 90.125295 -23.052986)
			(xy 90.117175 -23.108162) (xy 90.101107 -23.161569) (xy 90.077435 -23.212066) (xy 90.046662 -23.258579)
			(xy 90.009445 -23.300116) (xy 89.966577 -23.335791) (xy 89.918971 -23.364845) (xy 89.867642 -23.386657)
			(xy 89.813685 -23.400763) (xy 89.758248 -23.406863) (xy 89.702514 -23.404826) (xy 89.647671 -23.394696)
			(xy 89.594887 -23.376689) (xy 89.545287 -23.351188) (xy 89.499929 -23.318737) (xy 89.45978 -23.280028)
			(xy 89.425694 -23.235885) (xy 89.398398 -23.18725) (xy 89.378475 -23.135159) (xy 89.366349 -23.080722)
			(xy 89.362278 -23.0251) (xy 65.474942 -23.0251) (xy 65.474595 -23.044096) (xy 65.466475 -23.099272)
			(xy 65.450407 -23.152679) (xy 65.426735 -23.203176) (xy 65.395962 -23.249689) (xy 65.358745 -23.291226)
			(xy 65.315877 -23.326901) (xy 65.268271 -23.355955) (xy 65.216942 -23.377767) (xy 65.162985 -23.391873)
			(xy 65.107548 -23.397973) (xy 65.051814 -23.395936) (xy 64.996971 -23.385806) (xy 64.944187 -23.367799)
			(xy 64.894587 -23.342298) (xy 64.849229 -23.309847) (xy 64.80908 -23.271138) (xy 64.774994 -23.226995)
			(xy 64.747698 -23.17836) (xy 64.727775 -23.126269) (xy 64.715649 -23.071832) (xy 64.711578 -23.01621)
			(xy 64.125694 -23.01621) (xy 64.125856 -23.0251) (xy 64.125347 -23.052986) (xy 64.117227 -23.108162)
			(xy 64.101159 -23.161569) (xy 64.077487 -23.212066) (xy 64.046714 -23.258579) (xy 64.009497 -23.300116)
			(xy 63.966629 -23.335791) (xy 63.919023 -23.364845) (xy 63.867694 -23.386657) (xy 63.813737 -23.400763)
			(xy 63.7583 -23.406863) (xy 63.702566 -23.404826) (xy 63.647723 -23.394696) (xy 63.594939 -23.376689)
			(xy 63.545339 -23.351188) (xy 63.499981 -23.318737) (xy 63.459832 -23.280028) (xy 63.425746 -23.235885)
			(xy 63.39845 -23.18725) (xy 63.378527 -23.135159) (xy 63.366401 -23.080722) (xy 63.36233 -23.0251)
			(xy 39.474994 -23.0251) (xy 39.474647 -23.044096) (xy 39.466527 -23.099272) (xy 39.450459 -23.152679)
			(xy 39.426787 -23.203176) (xy 39.396014 -23.249689) (xy 39.358797 -23.291226) (xy 39.315929 -23.326901)
			(xy 39.268323 -23.355955) (xy 39.216994 -23.377767) (xy 39.163037 -23.391873) (xy 39.1076 -23.397973)
			(xy 39.051866 -23.395936) (xy 38.997023 -23.385806) (xy 38.944239 -23.367799) (xy 38.894639 -23.342298)
			(xy 38.849281 -23.309847) (xy 38.809132 -23.271138) (xy 38.775046 -23.226995) (xy 38.74775 -23.17836)
			(xy 38.727827 -23.126269) (xy 38.715701 -23.071832) (xy 38.71163 -23.01621) (xy 38.125746 -23.01621)
			(xy 38.125908 -23.0251) (xy 38.125399 -23.052986) (xy 38.117279 -23.108162) (xy 38.101211 -23.161569)
			(xy 38.077539 -23.212066) (xy 38.046766 -23.258579) (xy 38.009549 -23.300116) (xy 37.966681 -23.335791)
			(xy 37.919075 -23.364845) (xy 37.867746 -23.386657) (xy 37.813789 -23.400763) (xy 37.758352 -23.406863)
			(xy 37.702618 -23.404826) (xy 37.647775 -23.394696) (xy 37.594991 -23.376689) (xy 37.545391 -23.351188)
			(xy 37.500033 -23.318737) (xy 37.459884 -23.280028) (xy 37.425798 -23.235885) (xy 37.398502 -23.18725)
			(xy 37.378579 -23.135159) (xy 37.366453 -23.080722) (xy 37.362382 -23.0251) (xy 13.475046 -23.0251)
			(xy 13.474699 -23.044096) (xy 13.466579 -23.099272) (xy 13.450511 -23.152679) (xy 13.426839 -23.203176)
			(xy 13.396066 -23.249689) (xy 13.358849 -23.291226) (xy 13.315981 -23.326901) (xy 13.268375 -23.355955)
			(xy 13.217046 -23.377767) (xy 13.163089 -23.391873) (xy 13.107652 -23.397973) (xy 13.051918 -23.395936)
			(xy 12.997075 -23.385806) (xy 12.944291 -23.367799) (xy 12.894691 -23.342298) (xy 12.849333 -23.309847)
			(xy 12.809184 -23.271138) (xy 12.775098 -23.226995) (xy 12.747802 -23.17836) (xy 12.727879 -23.126269)
			(xy 12.715753 -23.071832) (xy 12.711682 -23.01621) (xy 12.061982 -23.01621) (xy 12.061951 -23.017934)
			(xy 12.053831 -23.07311) (xy 12.037763 -23.126517) (xy 12.014091 -23.177014) (xy 11.983318 -23.223527)
			(xy 11.946101 -23.265064) (xy 11.903233 -23.300739) (xy 11.855627 -23.329793) (xy 11.804298 -23.351605)
			(xy 11.750341 -23.365711) (xy 11.694904 -23.371811) (xy 11.63917 -23.369774) (xy 11.584327 -23.359644)
			(xy 11.531543 -23.341637) (xy 11.481943 -23.316136) (xy 11.436585 -23.283685) (xy 11.396436 -23.244976)
			(xy 11.36235 -23.200833) (xy 11.335054 -23.152198) (xy 11.315131 -23.100107) (xy 11.303005 -23.04567)
			(xy 11.298934 -22.990048) (xy 4.930743 -22.990048) (xy 4.928811 -22.996469) (xy 4.905139 -23.046966)
			(xy 4.874366 -23.093479) (xy 4.837149 -23.135016) (xy 4.794281 -23.170691) (xy 4.746675 -23.199745)
			(xy 4.695346 -23.221557) (xy 4.641389 -23.235663) (xy 4.585952 -23.241763) (xy 4.530218 -23.239726)
			(xy 4.475375 -23.229596) (xy 4.422591 -23.211589) (xy 4.372991 -23.186088) (xy 4.327633 -23.153637)
			(xy 4.287484 -23.114928) (xy 4.253398 -23.070785) (xy 4.226102 -23.02215) (xy 4.206179 -22.970059)
			(xy 4.194053 -22.915622) (xy 4.189982 -22.86) (xy 1.49987 -22.86) (xy 1.49987 -22.961346) (xy 1.500632 -22.969474)
			(xy 1.500632 -22.969982) (xy 1.502228 -22.977503) (xy 1.509197 -22.991198) (xy 1.514348 -22.996906)
			(xy 1.85293 -23.335488) (xy 1.859786 -23.342882) (xy 1.867536 -23.361481) (xy 1.867916 -23.371556)
			(xy 1.867916 -23.935944) (xy 2.23215 -23.935944) (xy 2.236221 -23.880322) (xy 2.248347 -23.825885)
			(xy 2.26827 -23.773794) (xy 2.295566 -23.725159) (xy 2.329652 -23.681016) (xy 2.369801 -23.642307)
			(xy 2.415159 -23.609856) (xy 2.464759 -23.584355) (xy 2.517543 -23.566348) (xy 2.572386 -23.556218)
			(xy 2.62812 -23.554181) (xy 2.683557 -23.560281) (xy 2.737514 -23.574387) (xy 2.788843 -23.596199)
			(xy 2.836449 -23.625253) (xy 2.879317 -23.660928) (xy 2.916534 -23.702465) (xy 2.947307 -23.748978)
			(xy 2.970979 -23.799475) (xy 2.987047 -23.852882) (xy 2.995167 -23.908058) (xy 2.995676 -23.935944)
			(xy 3.241038 -23.935944) (xy 3.245109 -23.880322) (xy 3.257235 -23.825885) (xy 3.277158 -23.773794)
			(xy 3.304454 -23.725159) (xy 3.33854 -23.681016) (xy 3.378689 -23.642307) (xy 3.424047 -23.609856)
			(xy 3.473647 -23.584355) (xy 3.526431 -23.566348) (xy 3.581274 -23.556218) (xy 3.637008 -23.554181)
			(xy 3.692445 -23.560281) (xy 3.746402 -23.574387) (xy 3.783134 -23.589996) (xy 16.084548 -23.589996)
			(xy 16.088619 -23.534374) (xy 16.100745 -23.479937) (xy 16.120668 -23.427846) (xy 16.147964 -23.379211)
			(xy 16.18205 -23.335068) (xy 16.222199 -23.296359) (xy 16.267557 -23.263908) (xy 16.317157 -23.238407)
			(xy 16.369941 -23.2204) (xy 16.424784 -23.21027) (xy 16.480518 -23.208233) (xy 16.535955 -23.214333)
			(xy 16.589912 -23.228439) (xy 16.641241 -23.250251) (xy 16.688847 -23.279305) (xy 16.731715 -23.31498)
			(xy 16.768932 -23.356517) (xy 16.799705 -23.40303) (xy 16.823377 -23.453527) (xy 16.839445 -23.506934)
			(xy 16.847565 -23.56211) (xy 16.848074 -23.589996) (xy 42.084496 -23.589996) (xy 42.088567 -23.534374)
			(xy 42.100693 -23.479937) (xy 42.120616 -23.427846) (xy 42.147912 -23.379211) (xy 42.181998 -23.335068)
			(xy 42.222147 -23.296359) (xy 42.267505 -23.263908) (xy 42.317105 -23.238407) (xy 42.369889 -23.2204)
			(xy 42.424732 -23.21027) (xy 42.480466 -23.208233) (xy 42.535903 -23.214333) (xy 42.58986 -23.228439)
			(xy 42.641189 -23.250251) (xy 42.688795 -23.279305) (xy 42.731663 -23.31498) (xy 42.76888 -23.356517)
			(xy 42.799653 -23.40303) (xy 42.823325 -23.453527) (xy 42.839393 -23.506934) (xy 42.847513 -23.56211)
			(xy 42.848022 -23.589996) (xy 42.847513 -23.617882) (xy 42.839393 -23.673058) (xy 42.823325 -23.726465)
			(xy 42.799653 -23.776962) (xy 42.76888 -23.823475) (xy 42.731663 -23.865012) (xy 42.688795 -23.900687)
			(xy 42.641189 -23.929741) (xy 42.58986 -23.951553) (xy 42.537835 -23.965154) (xy 52.077364 -23.965154)
			(xy 52.081435 -23.909532) (xy 52.093561 -23.855095) (xy 52.113484 -23.803004) (xy 52.14078 -23.754369)
			(xy 52.174866 -23.710226) (xy 52.215015 -23.671517) (xy 52.260373 -23.639066) (xy 52.309973 -23.613565)
			(xy 52.362757 -23.595558) (xy 52.4176 -23.585428) (xy 52.473334 -23.583391) (xy 52.528771 -23.589491)
			(xy 52.582728 -23.603597) (xy 52.634057 -23.625409) (xy 52.681663 -23.654463) (xy 52.724531 -23.690138)
			(xy 52.761748 -23.731675) (xy 52.792521 -23.778188) (xy 52.816193 -23.828685) (xy 52.832261 -23.882092)
			(xy 52.840381 -23.937268) (xy 52.840556 -23.946866) (xy 53.08041 -23.946866) (xy 53.084481 -23.891244)
			(xy 53.096607 -23.836807) (xy 53.11653 -23.784716) (xy 53.143826 -23.736081) (xy 53.177912 -23.691938)
			(xy 53.218061 -23.653229) (xy 53.263419 -23.620778) (xy 53.313019 -23.595277) (xy 53.365803 -23.57727)
			(xy 53.420646 -23.56714) (xy 53.47638 -23.565103) (xy 53.531817 -23.571203) (xy 53.585774 -23.585309)
			(xy 53.637103 -23.607121) (xy 53.684709 -23.636175) (xy 53.727577 -23.67185) (xy 53.764794 -23.713387)
			(xy 53.795567 -23.7599) (xy 53.819239 -23.810397) (xy 53.835307 -23.863804) (xy 53.843427 -23.91898)
			(xy 53.843936 -23.946866) (xy 53.843496 -23.970996) (xy 54.072788 -23.970996) (xy 54.076859 -23.915374)
			(xy 54.088985 -23.860937) (xy 54.108908 -23.808846) (xy 54.136204 -23.760211) (xy 54.17029 -23.716068)
			(xy 54.210439 -23.677359) (xy 54.255797 -23.644908) (xy 54.305397 -23.619407) (xy 54.358181 -23.6014)
			(xy 54.413024 -23.59127) (xy 54.468758 -23.589233) (xy 54.475692 -23.589996) (xy 68.084444 -23.589996)
			(xy 68.088515 -23.534374) (xy 68.100641 -23.479937) (xy 68.120564 -23.427846) (xy 68.14786 -23.379211)
			(xy 68.181946 -23.335068) (xy 68.222095 -23.296359) (xy 68.267453 -23.263908) (xy 68.317053 -23.238407)
			(xy 68.369837 -23.2204) (xy 68.42468 -23.21027) (xy 68.480414 -23.208233) (xy 68.535851 -23.214333)
			(xy 68.589808 -23.228439) (xy 68.641137 -23.250251) (xy 68.688743 -23.279305) (xy 68.731611 -23.31498)
			(xy 68.768828 -23.356517) (xy 68.799601 -23.40303) (xy 68.823273 -23.453527) (xy 68.839341 -23.506934)
			(xy 68.847461 -23.56211) (xy 68.84797 -23.589996) (xy 68.847461 -23.617882) (xy 68.839341 -23.673058)
			(xy 68.823273 -23.726465) (xy 68.799601 -23.776962) (xy 68.768828 -23.823475) (xy 68.731611 -23.865012)
			(xy 68.688743 -23.900687) (xy 68.641137 -23.929741) (xy 68.589808 -23.951553) (xy 68.537783 -23.965154)
			(xy 78.077312 -23.965154) (xy 78.081383 -23.909532) (xy 78.093509 -23.855095) (xy 78.113432 -23.803004)
			(xy 78.140728 -23.754369) (xy 78.174814 -23.710226) (xy 78.214963 -23.671517) (xy 78.260321 -23.639066)
			(xy 78.309921 -23.613565) (xy 78.362705 -23.595558) (xy 78.417548 -23.585428) (xy 78.473282 -23.583391)
			(xy 78.528719 -23.589491) (xy 78.582676 -23.603597) (xy 78.634005 -23.625409) (xy 78.681611 -23.654463)
			(xy 78.724479 -23.690138) (xy 78.761696 -23.731675) (xy 78.792469 -23.778188) (xy 78.816141 -23.828685)
			(xy 78.832209 -23.882092) (xy 78.840329 -23.937268) (xy 78.840504 -23.946866) (xy 79.080358 -23.946866)
			(xy 79.084429 -23.891244) (xy 79.096555 -23.836807) (xy 79.116478 -23.784716) (xy 79.143774 -23.736081)
			(xy 79.17786 -23.691938) (xy 79.218009 -23.653229) (xy 79.263367 -23.620778) (xy 79.312967 -23.595277)
			(xy 79.365751 -23.57727) (xy 79.420594 -23.56714) (xy 79.476328 -23.565103) (xy 79.531765 -23.571203)
			(xy 79.585722 -23.585309) (xy 79.637051 -23.607121) (xy 79.684657 -23.636175) (xy 79.727525 -23.67185)
			(xy 79.764742 -23.713387) (xy 79.795515 -23.7599) (xy 79.819187 -23.810397) (xy 79.835255 -23.863804)
			(xy 79.843375 -23.91898) (xy 79.843884 -23.946866) (xy 79.843444 -23.970996) (xy 80.072736 -23.970996)
			(xy 80.076807 -23.915374) (xy 80.088933 -23.860937) (xy 80.108856 -23.808846) (xy 80.136152 -23.760211)
			(xy 80.170238 -23.716068) (xy 80.210387 -23.677359) (xy 80.255745 -23.644908) (xy 80.305345 -23.619407)
			(xy 80.358129 -23.6014) (xy 80.412972 -23.59127) (xy 80.468706 -23.589233) (xy 80.47564 -23.589996)
			(xy 94.084392 -23.589996) (xy 94.088463 -23.534374) (xy 94.100589 -23.479937) (xy 94.120512 -23.427846)
			(xy 94.147808 -23.379211) (xy 94.181894 -23.335068) (xy 94.222043 -23.296359) (xy 94.267401 -23.263908)
			(xy 94.317001 -23.238407) (xy 94.369785 -23.2204) (xy 94.424628 -23.21027) (xy 94.480362 -23.208233)
			(xy 94.535799 -23.214333) (xy 94.589756 -23.228439) (xy 94.641085 -23.250251) (xy 94.688691 -23.279305)
			(xy 94.731559 -23.31498) (xy 94.768776 -23.356517) (xy 94.799549 -23.40303) (xy 94.823221 -23.453527)
			(xy 94.839289 -23.506934) (xy 94.847409 -23.56211) (xy 94.847918 -23.589996) (xy 132.184646 -23.589996)
			(xy 132.188717 -23.534374) (xy 132.200843 -23.479937) (xy 132.220766 -23.427846) (xy 132.248062 -23.379211)
			(xy 132.282148 -23.335068) (xy 132.322297 -23.296359) (xy 132.367655 -23.263908) (xy 132.417255 -23.238407)
			(xy 132.470039 -23.2204) (xy 132.524882 -23.21027) (xy 132.580616 -23.208233) (xy 132.636053 -23.214333)
			(xy 132.69001 -23.228439) (xy 132.741339 -23.250251) (xy 132.788945 -23.279305) (xy 132.831813 -23.31498)
			(xy 132.86903 -23.356517) (xy 132.899803 -23.40303) (xy 132.923475 -23.453527) (xy 132.939543 -23.506934)
			(xy 132.947663 -23.56211) (xy 132.948172 -23.589996) (xy 132.947663 -23.617882) (xy 132.939543 -23.673058)
			(xy 132.923475 -23.726465) (xy 132.899803 -23.776962) (xy 132.86903 -23.823475) (xy 132.831813 -23.865012)
			(xy 132.788945 -23.900687) (xy 132.741339 -23.929741) (xy 132.69001 -23.951553) (xy 132.637985 -23.965154)
			(xy 142.177514 -23.965154) (xy 142.181585 -23.909532) (xy 142.193711 -23.855095) (xy 142.213634 -23.803004)
			(xy 142.24093 -23.754369) (xy 142.275016 -23.710226) (xy 142.315165 -23.671517) (xy 142.360523 -23.639066)
			(xy 142.410123 -23.613565) (xy 142.462907 -23.595558) (xy 142.51775 -23.585428) (xy 142.573484 -23.583391)
			(xy 142.628921 -23.589491) (xy 142.682878 -23.603597) (xy 142.734207 -23.625409) (xy 142.781813 -23.654463)
			(xy 142.824681 -23.690138) (xy 142.861898 -23.731675) (xy 142.892671 -23.778188) (xy 142.916343 -23.828685)
			(xy 142.932411 -23.882092) (xy 142.940531 -23.937268) (xy 142.940706 -23.946866) (xy 143.18056 -23.946866)
			(xy 143.184631 -23.891244) (xy 143.196757 -23.836807) (xy 143.21668 -23.784716) (xy 143.243976 -23.736081)
			(xy 143.278062 -23.691938) (xy 143.318211 -23.653229) (xy 143.363569 -23.620778) (xy 143.413169 -23.595277)
			(xy 143.465953 -23.57727) (xy 143.520796 -23.56714) (xy 143.57653 -23.565103) (xy 143.631967 -23.571203)
			(xy 143.685924 -23.585309) (xy 143.737253 -23.607121) (xy 143.784859 -23.636175) (xy 143.827727 -23.67185)
			(xy 143.864944 -23.713387) (xy 143.895717 -23.7599) (xy 143.919389 -23.810397) (xy 143.935457 -23.863804)
			(xy 143.943577 -23.91898) (xy 143.944086 -23.946866) (xy 143.943646 -23.970996) (xy 144.172938 -23.970996)
			(xy 144.177009 -23.915374) (xy 144.189135 -23.860937) (xy 144.209058 -23.808846) (xy 144.236354 -23.760211)
			(xy 144.27044 -23.716068) (xy 144.310589 -23.677359) (xy 144.355947 -23.644908) (xy 144.405547 -23.619407)
			(xy 144.458331 -23.6014) (xy 144.513174 -23.59127) (xy 144.568908 -23.589233) (xy 144.575842 -23.589996)
			(xy 158.184594 -23.589996) (xy 158.188665 -23.534374) (xy 158.200791 -23.479937) (xy 158.220714 -23.427846)
			(xy 158.24801 -23.379211) (xy 158.282096 -23.335068) (xy 158.322245 -23.296359) (xy 158.367603 -23.263908)
			(xy 158.417203 -23.238407) (xy 158.469987 -23.2204) (xy 158.52483 -23.21027) (xy 158.580564 -23.208233)
			(xy 158.636001 -23.214333) (xy 158.689958 -23.228439) (xy 158.741287 -23.250251) (xy 158.788893 -23.279305)
			(xy 158.831761 -23.31498) (xy 158.868978 -23.356517) (xy 158.899751 -23.40303) (xy 158.923423 -23.453527)
			(xy 158.939491 -23.506934) (xy 158.947611 -23.56211) (xy 158.94812 -23.589996) (xy 158.947611 -23.617882)
			(xy 158.939491 -23.673058) (xy 158.923423 -23.726465) (xy 158.899751 -23.776962) (xy 158.868978 -23.823475)
			(xy 158.831761 -23.865012) (xy 158.788893 -23.900687) (xy 158.741287 -23.929741) (xy 158.689958 -23.951553)
			(xy 158.637933 -23.965154) (xy 168.177462 -23.965154) (xy 168.181533 -23.909532) (xy 168.193659 -23.855095)
			(xy 168.213582 -23.803004) (xy 168.240878 -23.754369) (xy 168.274964 -23.710226) (xy 168.315113 -23.671517)
			(xy 168.360471 -23.639066) (xy 168.410071 -23.613565) (xy 168.462855 -23.595558) (xy 168.517698 -23.585428)
			(xy 168.573432 -23.583391) (xy 168.628869 -23.589491) (xy 168.682826 -23.603597) (xy 168.734155 -23.625409)
			(xy 168.781761 -23.654463) (xy 168.824629 -23.690138) (xy 168.861846 -23.731675) (xy 168.892619 -23.778188)
			(xy 168.916291 -23.828685) (xy 168.932359 -23.882092) (xy 168.940479 -23.937268) (xy 168.940654 -23.946866)
			(xy 169.180508 -23.946866) (xy 169.184579 -23.891244) (xy 169.196705 -23.836807) (xy 169.216628 -23.784716)
			(xy 169.243924 -23.736081) (xy 169.27801 -23.691938) (xy 169.318159 -23.653229) (xy 169.363517 -23.620778)
			(xy 169.413117 -23.595277) (xy 169.465901 -23.57727) (xy 169.520744 -23.56714) (xy 169.576478 -23.565103)
			(xy 169.631915 -23.571203) (xy 169.685872 -23.585309) (xy 169.737201 -23.607121) (xy 169.784807 -23.636175)
			(xy 169.827675 -23.67185) (xy 169.864892 -23.713387) (xy 169.895665 -23.7599) (xy 169.919337 -23.810397)
			(xy 169.935405 -23.863804) (xy 169.943525 -23.91898) (xy 169.944034 -23.946866) (xy 169.943594 -23.970996)
			(xy 170.172886 -23.970996) (xy 170.176957 -23.915374) (xy 170.189083 -23.860937) (xy 170.209006 -23.808846)
			(xy 170.236302 -23.760211) (xy 170.270388 -23.716068) (xy 170.310537 -23.677359) (xy 170.355895 -23.644908)
			(xy 170.405495 -23.619407) (xy 170.458279 -23.6014) (xy 170.513122 -23.59127) (xy 170.568856 -23.589233)
			(xy 170.57579 -23.589996) (xy 184.184542 -23.589996) (xy 184.188613 -23.534374) (xy 184.200739 -23.479937)
			(xy 184.220662 -23.427846) (xy 184.247958 -23.379211) (xy 184.282044 -23.335068) (xy 184.322193 -23.296359)
			(xy 184.367551 -23.263908) (xy 184.417151 -23.238407) (xy 184.469935 -23.2204) (xy 184.524778 -23.21027)
			(xy 184.580512 -23.208233) (xy 184.635949 -23.214333) (xy 184.689906 -23.228439) (xy 184.741235 -23.250251)
			(xy 184.788841 -23.279305) (xy 184.831709 -23.31498) (xy 184.868926 -23.356517) (xy 184.899699 -23.40303)
			(xy 184.923371 -23.453527) (xy 184.939439 -23.506934) (xy 184.947559 -23.56211) (xy 184.948068 -23.589996)
			(xy 184.947559 -23.617882) (xy 184.939439 -23.673058) (xy 184.923371 -23.726465) (xy 184.899699 -23.776962)
			(xy 184.868926 -23.823475) (xy 184.831709 -23.865012) (xy 184.788841 -23.900687) (xy 184.741235 -23.929741)
			(xy 184.689906 -23.951553) (xy 184.637881 -23.965154) (xy 194.17741 -23.965154) (xy 194.181481 -23.909532)
			(xy 194.193607 -23.855095) (xy 194.21353 -23.803004) (xy 194.240826 -23.754369) (xy 194.274912 -23.710226)
			(xy 194.315061 -23.671517) (xy 194.360419 -23.639066) (xy 194.410019 -23.613565) (xy 194.462803 -23.595558)
			(xy 194.517646 -23.585428) (xy 194.57338 -23.583391) (xy 194.628817 -23.589491) (xy 194.682774 -23.603597)
			(xy 194.734103 -23.625409) (xy 194.781709 -23.654463) (xy 194.824577 -23.690138) (xy 194.861794 -23.731675)
			(xy 194.892567 -23.778188) (xy 194.916239 -23.828685) (xy 194.932307 -23.882092) (xy 194.940427 -23.937268)
			(xy 194.940602 -23.946866) (xy 195.180456 -23.946866) (xy 195.184527 -23.891244) (xy 195.196653 -23.836807)
			(xy 195.216576 -23.784716) (xy 195.243872 -23.736081) (xy 195.277958 -23.691938) (xy 195.318107 -23.653229)
			(xy 195.363465 -23.620778) (xy 195.413065 -23.595277) (xy 195.465849 -23.57727) (xy 195.520692 -23.56714)
			(xy 195.576426 -23.565103) (xy 195.631863 -23.571203) (xy 195.68582 -23.585309) (xy 195.737149 -23.607121)
			(xy 195.784755 -23.636175) (xy 195.827623 -23.67185) (xy 195.86484 -23.713387) (xy 195.895613 -23.7599)
			(xy 195.919285 -23.810397) (xy 195.935353 -23.863804) (xy 195.943473 -23.91898) (xy 195.943982 -23.946866)
			(xy 195.943542 -23.970996) (xy 196.172834 -23.970996) (xy 196.176905 -23.915374) (xy 196.189031 -23.860937)
			(xy 196.208954 -23.808846) (xy 196.23625 -23.760211) (xy 196.270336 -23.716068) (xy 196.310485 -23.677359)
			(xy 196.355843 -23.644908) (xy 196.405443 -23.619407) (xy 196.458227 -23.6014) (xy 196.51307 -23.59127)
			(xy 196.568804 -23.589233) (xy 196.575738 -23.589996) (xy 210.18449 -23.589996) (xy 210.188561 -23.534374)
			(xy 210.200687 -23.479937) (xy 210.22061 -23.427846) (xy 210.247906 -23.379211) (xy 210.281992 -23.335068)
			(xy 210.322141 -23.296359) (xy 210.367499 -23.263908) (xy 210.417099 -23.238407) (xy 210.469883 -23.2204)
			(xy 210.524726 -23.21027) (xy 210.58046 -23.208233) (xy 210.635897 -23.214333) (xy 210.689854 -23.228439)
			(xy 210.741183 -23.250251) (xy 210.788789 -23.279305) (xy 210.831657 -23.31498) (xy 210.868874 -23.356517)
			(xy 210.899647 -23.40303) (xy 210.923319 -23.453527) (xy 210.939387 -23.506934) (xy 210.947507 -23.56211)
			(xy 210.948016 -23.589996) (xy 210.947507 -23.617882) (xy 210.939387 -23.673058) (xy 210.923319 -23.726465)
			(xy 210.899647 -23.776962) (xy 210.868874 -23.823475) (xy 210.831657 -23.865012) (xy 210.788789 -23.900687)
			(xy 210.741183 -23.929741) (xy 210.689854 -23.951553) (xy 210.637829 -23.965154) (xy 220.177358 -23.965154)
			(xy 220.181429 -23.909532) (xy 220.193555 -23.855095) (xy 220.213478 -23.803004) (xy 220.240774 -23.754369)
			(xy 220.27486 -23.710226) (xy 220.315009 -23.671517) (xy 220.360367 -23.639066) (xy 220.409967 -23.613565)
			(xy 220.462751 -23.595558) (xy 220.517594 -23.585428) (xy 220.573328 -23.583391) (xy 220.628765 -23.589491)
			(xy 220.682722 -23.603597) (xy 220.734051 -23.625409) (xy 220.781657 -23.654463) (xy 220.824525 -23.690138)
			(xy 220.861742 -23.731675) (xy 220.892515 -23.778188) (xy 220.916187 -23.828685) (xy 220.932255 -23.882092)
			(xy 220.940375 -23.937268) (xy 220.94055 -23.946866) (xy 221.180404 -23.946866) (xy 221.184475 -23.891244)
			(xy 221.196601 -23.836807) (xy 221.216524 -23.784716) (xy 221.24382 -23.736081) (xy 221.277906 -23.691938)
			(xy 221.318055 -23.653229) (xy 221.363413 -23.620778) (xy 221.413013 -23.595277) (xy 221.465797 -23.57727)
			(xy 221.52064 -23.56714) (xy 221.576374 -23.565103) (xy 221.631811 -23.571203) (xy 221.685768 -23.585309)
			(xy 221.737097 -23.607121) (xy 221.784703 -23.636175) (xy 221.827571 -23.67185) (xy 221.864788 -23.713387)
			(xy 221.895561 -23.7599) (xy 221.919233 -23.810397) (xy 221.935301 -23.863804) (xy 221.943421 -23.91898)
			(xy 221.94393 -23.946866) (xy 221.94349 -23.970996) (xy 222.172782 -23.970996) (xy 222.176853 -23.915374)
			(xy 222.188979 -23.860937) (xy 222.208902 -23.808846) (xy 222.236198 -23.760211) (xy 222.270284 -23.716068)
			(xy 222.310433 -23.677359) (xy 222.355791 -23.644908) (xy 222.405391 -23.619407) (xy 222.458175 -23.6014)
			(xy 222.513018 -23.59127) (xy 222.568752 -23.589233) (xy 222.575686 -23.589996) (xy 248.28449 -23.589996)
			(xy 248.288561 -23.534374) (xy 248.300687 -23.479937) (xy 248.32061 -23.427846) (xy 248.347906 -23.379211)
			(xy 248.381992 -23.335068) (xy 248.422141 -23.296359) (xy 248.467499 -23.263908) (xy 248.517099 -23.238407)
			(xy 248.569883 -23.2204) (xy 248.624726 -23.21027) (xy 248.68046 -23.208233) (xy 248.735897 -23.214333)
			(xy 248.789854 -23.228439) (xy 248.841183 -23.250251) (xy 248.888789 -23.279305) (xy 248.931657 -23.31498)
			(xy 248.968874 -23.356517) (xy 248.999647 -23.40303) (xy 249.023319 -23.453527) (xy 249.039387 -23.506934)
			(xy 249.047507 -23.56211) (xy 249.048016 -23.589996) (xy 249.047507 -23.617882) (xy 249.039387 -23.673058)
			(xy 249.023319 -23.726465) (xy 248.999647 -23.776962) (xy 248.968874 -23.823475) (xy 248.931657 -23.865012)
			(xy 248.888789 -23.900687) (xy 248.841183 -23.929741) (xy 248.789854 -23.951553) (xy 248.737829 -23.965154)
			(xy 258.277358 -23.965154) (xy 258.281429 -23.909532) (xy 258.293555 -23.855095) (xy 258.313478 -23.803004)
			(xy 258.340774 -23.754369) (xy 258.37486 -23.710226) (xy 258.415009 -23.671517) (xy 258.460367 -23.639066)
			(xy 258.509967 -23.613565) (xy 258.562751 -23.595558) (xy 258.617594 -23.585428) (xy 258.673328 -23.583391)
			(xy 258.728765 -23.589491) (xy 258.782722 -23.603597) (xy 258.834051 -23.625409) (xy 258.881657 -23.654463)
			(xy 258.924525 -23.690138) (xy 258.961742 -23.731675) (xy 258.992515 -23.778188) (xy 259.016187 -23.828685)
			(xy 259.032255 -23.882092) (xy 259.040375 -23.937268) (xy 259.04055 -23.946866) (xy 259.280404 -23.946866)
			(xy 259.284475 -23.891244) (xy 259.296601 -23.836807) (xy 259.316524 -23.784716) (xy 259.34382 -23.736081)
			(xy 259.377906 -23.691938) (xy 259.418055 -23.653229) (xy 259.463413 -23.620778) (xy 259.513013 -23.595277)
			(xy 259.565797 -23.57727) (xy 259.62064 -23.56714) (xy 259.676374 -23.565103) (xy 259.731811 -23.571203)
			(xy 259.785768 -23.585309) (xy 259.837097 -23.607121) (xy 259.884703 -23.636175) (xy 259.927571 -23.67185)
			(xy 259.964788 -23.713387) (xy 259.995561 -23.7599) (xy 260.019233 -23.810397) (xy 260.035301 -23.863804)
			(xy 260.043421 -23.91898) (xy 260.04393 -23.946866) (xy 260.04349 -23.970996) (xy 260.272782 -23.970996)
			(xy 260.276853 -23.915374) (xy 260.288979 -23.860937) (xy 260.308902 -23.808846) (xy 260.336198 -23.760211)
			(xy 260.370284 -23.716068) (xy 260.410433 -23.677359) (xy 260.455791 -23.644908) (xy 260.505391 -23.619407)
			(xy 260.558175 -23.6014) (xy 260.613018 -23.59127) (xy 260.668752 -23.589233) (xy 260.675686 -23.589996)
			(xy 274.284438 -23.589996) (xy 274.288509 -23.534374) (xy 274.300635 -23.479937) (xy 274.320558 -23.427846)
			(xy 274.347854 -23.379211) (xy 274.38194 -23.335068) (xy 274.422089 -23.296359) (xy 274.467447 -23.263908)
			(xy 274.517047 -23.238407) (xy 274.569831 -23.2204) (xy 274.624674 -23.21027) (xy 274.680408 -23.208233)
			(xy 274.735845 -23.214333) (xy 274.789802 -23.228439) (xy 274.841131 -23.250251) (xy 274.888737 -23.279305)
			(xy 274.931605 -23.31498) (xy 274.968822 -23.356517) (xy 274.999595 -23.40303) (xy 275.023267 -23.453527)
			(xy 275.039335 -23.506934) (xy 275.047455 -23.56211) (xy 275.047964 -23.589996) (xy 275.047455 -23.617882)
			(xy 275.039335 -23.673058) (xy 275.023267 -23.726465) (xy 274.999595 -23.776962) (xy 274.968822 -23.823475)
			(xy 274.931605 -23.865012) (xy 274.888737 -23.900687) (xy 274.841131 -23.929741) (xy 274.789802 -23.951553)
			(xy 274.737777 -23.965154) (xy 284.277306 -23.965154) (xy 284.281377 -23.909532) (xy 284.293503 -23.855095)
			(xy 284.313426 -23.803004) (xy 284.340722 -23.754369) (xy 284.374808 -23.710226) (xy 284.414957 -23.671517)
			(xy 284.460315 -23.639066) (xy 284.509915 -23.613565) (xy 284.562699 -23.595558) (xy 284.617542 -23.585428)
			(xy 284.673276 -23.583391) (xy 284.728713 -23.589491) (xy 284.78267 -23.603597) (xy 284.833999 -23.625409)
			(xy 284.881605 -23.654463) (xy 284.924473 -23.690138) (xy 284.96169 -23.731675) (xy 284.992463 -23.778188)
			(xy 285.016135 -23.828685) (xy 285.032203 -23.882092) (xy 285.040323 -23.937268) (xy 285.040498 -23.946866)
			(xy 285.280352 -23.946866) (xy 285.284423 -23.891244) (xy 285.296549 -23.836807) (xy 285.316472 -23.784716)
			(xy 285.343768 -23.736081) (xy 285.377854 -23.691938) (xy 285.418003 -23.653229) (xy 285.463361 -23.620778)
			(xy 285.512961 -23.595277) (xy 285.565745 -23.57727) (xy 285.620588 -23.56714) (xy 285.676322 -23.565103)
			(xy 285.731759 -23.571203) (xy 285.785716 -23.585309) (xy 285.837045 -23.607121) (xy 285.884651 -23.636175)
			(xy 285.927519 -23.67185) (xy 285.964736 -23.713387) (xy 285.995509 -23.7599) (xy 286.019181 -23.810397)
			(xy 286.035249 -23.863804) (xy 286.043369 -23.91898) (xy 286.043878 -23.946866) (xy 286.043438 -23.970996)
			(xy 286.27273 -23.970996) (xy 286.276801 -23.915374) (xy 286.288927 -23.860937) (xy 286.30885 -23.808846)
			(xy 286.336146 -23.760211) (xy 286.370232 -23.716068) (xy 286.410381 -23.677359) (xy 286.455739 -23.644908)
			(xy 286.505339 -23.619407) (xy 286.558123 -23.6014) (xy 286.612966 -23.59127) (xy 286.6687 -23.589233)
			(xy 286.675634 -23.589996) (xy 300.284386 -23.589996) (xy 300.288457 -23.534374) (xy 300.300583 -23.479937)
			(xy 300.320506 -23.427846) (xy 300.347802 -23.379211) (xy 300.381888 -23.335068) (xy 300.422037 -23.296359)
			(xy 300.467395 -23.263908) (xy 300.516995 -23.238407) (xy 300.569779 -23.2204) (xy 300.624622 -23.21027)
			(xy 300.680356 -23.208233) (xy 300.735793 -23.214333) (xy 300.78975 -23.228439) (xy 300.841079 -23.250251)
			(xy 300.888685 -23.279305) (xy 300.931553 -23.31498) (xy 300.96877 -23.356517) (xy 300.999543 -23.40303)
			(xy 301.023215 -23.453527) (xy 301.039283 -23.506934) (xy 301.047403 -23.56211) (xy 301.047912 -23.589996)
			(xy 301.047403 -23.617882) (xy 301.039283 -23.673058) (xy 301.023215 -23.726465) (xy 300.999543 -23.776962)
			(xy 300.96877 -23.823475) (xy 300.931553 -23.865012) (xy 300.888685 -23.900687) (xy 300.841079 -23.929741)
			(xy 300.78975 -23.951553) (xy 300.737725 -23.965154) (xy 310.277254 -23.965154) (xy 310.281325 -23.909532)
			(xy 310.293451 -23.855095) (xy 310.313374 -23.803004) (xy 310.34067 -23.754369) (xy 310.374756 -23.710226)
			(xy 310.414905 -23.671517) (xy 310.460263 -23.639066) (xy 310.509863 -23.613565) (xy 310.562647 -23.595558)
			(xy 310.61749 -23.585428) (xy 310.673224 -23.583391) (xy 310.728661 -23.589491) (xy 310.782618 -23.603597)
			(xy 310.833947 -23.625409) (xy 310.881553 -23.654463) (xy 310.924421 -23.690138) (xy 310.961638 -23.731675)
			(xy 310.992411 -23.778188) (xy 311.016083 -23.828685) (xy 311.032151 -23.882092) (xy 311.040271 -23.937268)
			(xy 311.040446 -23.946866) (xy 311.2803 -23.946866) (xy 311.284371 -23.891244) (xy 311.296497 -23.836807)
			(xy 311.31642 -23.784716) (xy 311.343716 -23.736081) (xy 311.377802 -23.691938) (xy 311.417951 -23.653229)
			(xy 311.463309 -23.620778) (xy 311.512909 -23.595277) (xy 311.565693 -23.57727) (xy 311.620536 -23.56714)
			(xy 311.67627 -23.565103) (xy 311.731707 -23.571203) (xy 311.785664 -23.585309) (xy 311.836993 -23.607121)
			(xy 311.884599 -23.636175) (xy 311.927467 -23.67185) (xy 311.964684 -23.713387) (xy 311.995457 -23.7599)
			(xy 312.019129 -23.810397) (xy 312.035197 -23.863804) (xy 312.043317 -23.91898) (xy 312.043826 -23.946866)
			(xy 312.043386 -23.970996) (xy 312.272678 -23.970996) (xy 312.276749 -23.915374) (xy 312.288875 -23.860937)
			(xy 312.308798 -23.808846) (xy 312.336094 -23.760211) (xy 312.37018 -23.716068) (xy 312.410329 -23.677359)
			(xy 312.455687 -23.644908) (xy 312.505287 -23.619407) (xy 312.558071 -23.6014) (xy 312.612914 -23.59127)
			(xy 312.668648 -23.589233) (xy 312.675582 -23.589996) (xy 326.284334 -23.589996) (xy 326.288405 -23.534374)
			(xy 326.300531 -23.479937) (xy 326.320454 -23.427846) (xy 326.34775 -23.379211) (xy 326.381836 -23.335068)
			(xy 326.421985 -23.296359) (xy 326.467343 -23.263908) (xy 326.516943 -23.238407) (xy 326.569727 -23.2204)
			(xy 326.62457 -23.21027) (xy 326.680304 -23.208233) (xy 326.735741 -23.214333) (xy 326.789698 -23.228439)
			(xy 326.841027 -23.250251) (xy 326.888633 -23.279305) (xy 326.931501 -23.31498) (xy 326.968718 -23.356517)
			(xy 326.999491 -23.40303) (xy 327.023163 -23.453527) (xy 327.039231 -23.506934) (xy 327.047351 -23.56211)
			(xy 327.04786 -23.589996) (xy 364.384588 -23.589996) (xy 364.388659 -23.534374) (xy 364.400785 -23.479937)
			(xy 364.420708 -23.427846) (xy 364.448004 -23.379211) (xy 364.48209 -23.335068) (xy 364.522239 -23.296359)
			(xy 364.567597 -23.263908) (xy 364.617197 -23.238407) (xy 364.669981 -23.2204) (xy 364.724824 -23.21027)
			(xy 364.780558 -23.208233) (xy 364.835995 -23.214333) (xy 364.889952 -23.228439) (xy 364.941281 -23.250251)
			(xy 364.988887 -23.279305) (xy 365.031755 -23.31498) (xy 365.068972 -23.356517) (xy 365.099745 -23.40303)
			(xy 365.123417 -23.453527) (xy 365.139485 -23.506934) (xy 365.147605 -23.56211) (xy 365.148114 -23.589996)
			(xy 365.147605 -23.617882) (xy 365.139485 -23.673058) (xy 365.123417 -23.726465) (xy 365.099745 -23.776962)
			(xy 365.068972 -23.823475) (xy 365.031755 -23.865012) (xy 364.988887 -23.900687) (xy 364.941281 -23.929741)
			(xy 364.889952 -23.951553) (xy 364.837927 -23.965154) (xy 374.377456 -23.965154) (xy 374.381527 -23.909532)
			(xy 374.393653 -23.855095) (xy 374.413576 -23.803004) (xy 374.440872 -23.754369) (xy 374.474958 -23.710226)
			(xy 374.515107 -23.671517) (xy 374.560465 -23.639066) (xy 374.610065 -23.613565) (xy 374.662849 -23.595558)
			(xy 374.717692 -23.585428) (xy 374.773426 -23.583391) (xy 374.828863 -23.589491) (xy 374.88282 -23.603597)
			(xy 374.934149 -23.625409) (xy 374.981755 -23.654463) (xy 375.024623 -23.690138) (xy 375.06184 -23.731675)
			(xy 375.092613 -23.778188) (xy 375.116285 -23.828685) (xy 375.132353 -23.882092) (xy 375.140473 -23.937268)
			(xy 375.140648 -23.946866) (xy 375.380502 -23.946866) (xy 375.384573 -23.891244) (xy 375.396699 -23.836807)
			(xy 375.416622 -23.784716) (xy 375.443918 -23.736081) (xy 375.478004 -23.691938) (xy 375.518153 -23.653229)
			(xy 375.563511 -23.620778) (xy 375.613111 -23.595277) (xy 375.665895 -23.57727) (xy 375.720738 -23.56714)
			(xy 375.776472 -23.565103) (xy 375.831909 -23.571203) (xy 375.885866 -23.585309) (xy 375.937195 -23.607121)
			(xy 375.984801 -23.636175) (xy 376.027669 -23.67185) (xy 376.064886 -23.713387) (xy 376.095659 -23.7599)
			(xy 376.119331 -23.810397) (xy 376.135399 -23.863804) (xy 376.143519 -23.91898) (xy 376.144028 -23.946866)
			(xy 376.143588 -23.970996) (xy 376.37288 -23.970996) (xy 376.376951 -23.915374) (xy 376.389077 -23.860937)
			(xy 376.409 -23.808846) (xy 376.436296 -23.760211) (xy 376.470382 -23.716068) (xy 376.510531 -23.677359)
			(xy 376.555889 -23.644908) (xy 376.605489 -23.619407) (xy 376.658273 -23.6014) (xy 376.713116 -23.59127)
			(xy 376.76885 -23.589233) (xy 376.775784 -23.589996) (xy 390.384536 -23.589996) (xy 390.388607 -23.534374)
			(xy 390.400733 -23.479937) (xy 390.420656 -23.427846) (xy 390.447952 -23.379211) (xy 390.482038 -23.335068)
			(xy 390.522187 -23.296359) (xy 390.567545 -23.263908) (xy 390.617145 -23.238407) (xy 390.669929 -23.2204)
			(xy 390.724772 -23.21027) (xy 390.780506 -23.208233) (xy 390.835943 -23.214333) (xy 390.8899 -23.228439)
			(xy 390.941229 -23.250251) (xy 390.988835 -23.279305) (xy 391.031703 -23.31498) (xy 391.06892 -23.356517)
			(xy 391.099693 -23.40303) (xy 391.123365 -23.453527) (xy 391.139433 -23.506934) (xy 391.147553 -23.56211)
			(xy 391.148062 -23.589996) (xy 391.147553 -23.617882) (xy 391.139433 -23.673058) (xy 391.123365 -23.726465)
			(xy 391.099693 -23.776962) (xy 391.06892 -23.823475) (xy 391.031703 -23.865012) (xy 390.988835 -23.900687)
			(xy 390.941229 -23.929741) (xy 390.8899 -23.951553) (xy 390.837875 -23.965154) (xy 400.377404 -23.965154)
			(xy 400.381475 -23.909532) (xy 400.393601 -23.855095) (xy 400.413524 -23.803004) (xy 400.44082 -23.754369)
			(xy 400.474906 -23.710226) (xy 400.515055 -23.671517) (xy 400.560413 -23.639066) (xy 400.610013 -23.613565)
			(xy 400.662797 -23.595558) (xy 400.71764 -23.585428) (xy 400.773374 -23.583391) (xy 400.828811 -23.589491)
			(xy 400.882768 -23.603597) (xy 400.934097 -23.625409) (xy 400.981703 -23.654463) (xy 401.024571 -23.690138)
			(xy 401.061788 -23.731675) (xy 401.092561 -23.778188) (xy 401.116233 -23.828685) (xy 401.132301 -23.882092)
			(xy 401.140421 -23.937268) (xy 401.140596 -23.946866) (xy 401.38045 -23.946866) (xy 401.384521 -23.891244)
			(xy 401.396647 -23.836807) (xy 401.41657 -23.784716) (xy 401.443866 -23.736081) (xy 401.477952 -23.691938)
			(xy 401.518101 -23.653229) (xy 401.563459 -23.620778) (xy 401.613059 -23.595277) (xy 401.665843 -23.57727)
			(xy 401.720686 -23.56714) (xy 401.77642 -23.565103) (xy 401.831857 -23.571203) (xy 401.885814 -23.585309)
			(xy 401.937143 -23.607121) (xy 401.984749 -23.636175) (xy 402.027617 -23.67185) (xy 402.064834 -23.713387)
			(xy 402.095607 -23.7599) (xy 402.119279 -23.810397) (xy 402.135347 -23.863804) (xy 402.143467 -23.91898)
			(xy 402.143976 -23.946866) (xy 402.143536 -23.970996) (xy 402.372828 -23.970996) (xy 402.376899 -23.915374)
			(xy 402.389025 -23.860937) (xy 402.408948 -23.808846) (xy 402.436244 -23.760211) (xy 402.47033 -23.716068)
			(xy 402.510479 -23.677359) (xy 402.555837 -23.644908) (xy 402.605437 -23.619407) (xy 402.658221 -23.6014)
			(xy 402.713064 -23.59127) (xy 402.768798 -23.589233) (xy 402.775732 -23.589996) (xy 416.384484 -23.589996)
			(xy 416.388555 -23.534374) (xy 416.400681 -23.479937) (xy 416.420604 -23.427846) (xy 416.4479 -23.379211)
			(xy 416.481986 -23.335068) (xy 416.522135 -23.296359) (xy 416.567493 -23.263908) (xy 416.617093 -23.238407)
			(xy 416.669877 -23.2204) (xy 416.72472 -23.21027) (xy 416.780454 -23.208233) (xy 416.835891 -23.214333)
			(xy 416.889848 -23.228439) (xy 416.941177 -23.250251) (xy 416.988783 -23.279305) (xy 417.031651 -23.31498)
			(xy 417.068868 -23.356517) (xy 417.099641 -23.40303) (xy 417.123313 -23.453527) (xy 417.139381 -23.506934)
			(xy 417.147501 -23.56211) (xy 417.14801 -23.589996) (xy 417.147501 -23.617882) (xy 417.139381 -23.673058)
			(xy 417.123313 -23.726465) (xy 417.099641 -23.776962) (xy 417.068868 -23.823475) (xy 417.031651 -23.865012)
			(xy 416.988783 -23.900687) (xy 416.941177 -23.929741) (xy 416.889848 -23.951553) (xy 416.837823 -23.965154)
			(xy 426.377352 -23.965154) (xy 426.381423 -23.909532) (xy 426.393549 -23.855095) (xy 426.413472 -23.803004)
			(xy 426.440768 -23.754369) (xy 426.474854 -23.710226) (xy 426.515003 -23.671517) (xy 426.560361 -23.639066)
			(xy 426.609961 -23.613565) (xy 426.662745 -23.595558) (xy 426.717588 -23.585428) (xy 426.773322 -23.583391)
			(xy 426.828759 -23.589491) (xy 426.882716 -23.603597) (xy 426.934045 -23.625409) (xy 426.981651 -23.654463)
			(xy 427.024519 -23.690138) (xy 427.061736 -23.731675) (xy 427.092509 -23.778188) (xy 427.116181 -23.828685)
			(xy 427.132249 -23.882092) (xy 427.140369 -23.937268) (xy 427.140544 -23.946866) (xy 427.380398 -23.946866)
			(xy 427.384469 -23.891244) (xy 427.396595 -23.836807) (xy 427.416518 -23.784716) (xy 427.443814 -23.736081)
			(xy 427.4779 -23.691938) (xy 427.518049 -23.653229) (xy 427.563407 -23.620778) (xy 427.613007 -23.595277)
			(xy 427.665791 -23.57727) (xy 427.720634 -23.56714) (xy 427.776368 -23.565103) (xy 427.831805 -23.571203)
			(xy 427.885762 -23.585309) (xy 427.937091 -23.607121) (xy 427.984697 -23.636175) (xy 428.027565 -23.67185)
			(xy 428.064782 -23.713387) (xy 428.095555 -23.7599) (xy 428.119227 -23.810397) (xy 428.135295 -23.863804)
			(xy 428.143415 -23.91898) (xy 428.143924 -23.946866) (xy 428.143484 -23.970996) (xy 428.372776 -23.970996)
			(xy 428.376847 -23.915374) (xy 428.388973 -23.860937) (xy 428.408896 -23.808846) (xy 428.436192 -23.760211)
			(xy 428.470278 -23.716068) (xy 428.510427 -23.677359) (xy 428.555785 -23.644908) (xy 428.605385 -23.619407)
			(xy 428.658169 -23.6014) (xy 428.713012 -23.59127) (xy 428.768746 -23.589233) (xy 428.77568 -23.589996)
			(xy 442.384432 -23.589996) (xy 442.388503 -23.534374) (xy 442.400629 -23.479937) (xy 442.420552 -23.427846)
			(xy 442.447848 -23.379211) (xy 442.481934 -23.335068) (xy 442.522083 -23.296359) (xy 442.567441 -23.263908)
			(xy 442.617041 -23.238407) (xy 442.669825 -23.2204) (xy 442.724668 -23.21027) (xy 442.780402 -23.208233)
			(xy 442.835839 -23.214333) (xy 442.889796 -23.228439) (xy 442.941125 -23.250251) (xy 442.988731 -23.279305)
			(xy 443.031599 -23.31498) (xy 443.068816 -23.356517) (xy 443.099589 -23.40303) (xy 443.123261 -23.453527)
			(xy 443.139329 -23.506934) (xy 443.147449 -23.56211) (xy 443.147958 -23.589996) (xy 443.147449 -23.617882)
			(xy 443.139329 -23.673058) (xy 443.123261 -23.726465) (xy 443.099589 -23.776962) (xy 443.068816 -23.823475)
			(xy 443.031599 -23.865012) (xy 442.988731 -23.900687) (xy 442.941125 -23.929741) (xy 442.889796 -23.951553)
			(xy 442.837771 -23.965154) (xy 452.3773 -23.965154) (xy 452.381371 -23.909532) (xy 452.393497 -23.855095)
			(xy 452.41342 -23.803004) (xy 452.440716 -23.754369) (xy 452.474802 -23.710226) (xy 452.514951 -23.671517)
			(xy 452.560309 -23.639066) (xy 452.609909 -23.613565) (xy 452.662693 -23.595558) (xy 452.717536 -23.585428)
			(xy 452.77327 -23.583391) (xy 452.828707 -23.589491) (xy 452.882664 -23.603597) (xy 452.933993 -23.625409)
			(xy 452.981599 -23.654463) (xy 453.024467 -23.690138) (xy 453.061684 -23.731675) (xy 453.092457 -23.778188)
			(xy 453.116129 -23.828685) (xy 453.132197 -23.882092) (xy 453.140317 -23.937268) (xy 453.140492 -23.946866)
			(xy 453.380346 -23.946866) (xy 453.384417 -23.891244) (xy 453.396543 -23.836807) (xy 453.416466 -23.784716)
			(xy 453.443762 -23.736081) (xy 453.477848 -23.691938) (xy 453.517997 -23.653229) (xy 453.563355 -23.620778)
			(xy 453.612955 -23.595277) (xy 453.665739 -23.57727) (xy 453.720582 -23.56714) (xy 453.776316 -23.565103)
			(xy 453.831753 -23.571203) (xy 453.88571 -23.585309) (xy 453.937039 -23.607121) (xy 453.984645 -23.636175)
			(xy 454.027513 -23.67185) (xy 454.06473 -23.713387) (xy 454.095503 -23.7599) (xy 454.119175 -23.810397)
			(xy 454.135243 -23.863804) (xy 454.143363 -23.91898) (xy 454.143872 -23.946866) (xy 454.143363 -23.974752)
			(xy 454.135243 -24.029928) (xy 454.130888 -24.044402) (xy 454.372724 -24.044402) (xy 454.376795 -23.98878)
			(xy 454.388921 -23.934343) (xy 454.408844 -23.882252) (xy 454.43614 -23.833617) (xy 454.470226 -23.789474)
			(xy 454.510375 -23.750765) (xy 454.555733 -23.718314) (xy 454.605333 -23.692813) (xy 454.658117 -23.674806)
			(xy 454.71296 -23.664676) (xy 454.768694 -23.662639) (xy 454.824131 -23.668739) (xy 454.878088 -23.682845)
			(xy 454.929417 -23.704657) (xy 454.977023 -23.733711) (xy 455.019891 -23.769386) (xy 455.057108 -23.810923)
			(xy 455.087881 -23.857436) (xy 455.111553 -23.907933) (xy 455.127621 -23.96134) (xy 455.135741 -24.016516)
			(xy 455.13625 -24.044402) (xy 455.135741 -24.072288) (xy 455.127621 -24.127464) (xy 455.111553 -24.180871)
			(xy 455.087881 -24.231368) (xy 455.057108 -24.277881) (xy 455.019891 -24.319418) (xy 454.977023 -24.355093)
			(xy 454.929417 -24.384147) (xy 454.878088 -24.405959) (xy 454.824131 -24.420065) (xy 454.768694 -24.426165)
			(xy 454.71296 -24.424128) (xy 454.658117 -24.413998) (xy 454.605333 -24.395991) (xy 454.555733 -24.37049)
			(xy 454.510375 -24.338039) (xy 454.470226 -24.29933) (xy 454.43614 -24.255187) (xy 454.408844 -24.206552)
			(xy 454.388921 -24.154461) (xy 454.376795 -24.100024) (xy 454.372724 -24.044402) (xy 454.130888 -24.044402)
			(xy 454.119175 -24.083335) (xy 454.095503 -24.133832) (xy 454.06473 -24.180345) (xy 454.027513 -24.221882)
			(xy 453.984645 -24.257557) (xy 453.937039 -24.286611) (xy 453.88571 -24.308423) (xy 453.831753 -24.322529)
			(xy 453.776316 -24.328629) (xy 453.720582 -24.326592) (xy 453.665739 -24.316462) (xy 453.612955 -24.298455)
			(xy 453.563355 -24.272954) (xy 453.517997 -24.240503) (xy 453.477848 -24.201794) (xy 453.443762 -24.157651)
			(xy 453.416466 -24.109016) (xy 453.396543 -24.056925) (xy 453.384417 -24.002488) (xy 453.380346 -23.946866)
			(xy 453.140492 -23.946866) (xy 453.140826 -23.965154) (xy 453.140317 -23.99304) (xy 453.132197 -24.048216)
			(xy 453.116129 -24.101623) (xy 453.092457 -24.15212) (xy 453.061684 -24.198633) (xy 453.024467 -24.24017)
			(xy 452.981599 -24.275845) (xy 452.933993 -24.304899) (xy 452.882664 -24.326711) (xy 452.828707 -24.340817)
			(xy 452.77327 -24.346917) (xy 452.717536 -24.34488) (xy 452.662693 -24.33475) (xy 452.609909 -24.316743)
			(xy 452.560309 -24.291242) (xy 452.514951 -24.258791) (xy 452.474802 -24.220082) (xy 452.440716 -24.175939)
			(xy 452.41342 -24.127304) (xy 452.393497 -24.075213) (xy 452.381371 -24.020776) (xy 452.3773 -23.965154)
			(xy 442.837771 -23.965154) (xy 442.835839 -23.965659) (xy 442.780402 -23.971759) (xy 442.724668 -23.969722)
			(xy 442.669825 -23.959592) (xy 442.617041 -23.941585) (xy 442.567441 -23.916084) (xy 442.522083 -23.883633)
			(xy 442.481934 -23.844924) (xy 442.447848 -23.800781) (xy 442.420552 -23.752146) (xy 442.400629 -23.700055)
			(xy 442.388503 -23.645618) (xy 442.384432 -23.589996) (xy 428.77568 -23.589996) (xy 428.824183 -23.595333)
			(xy 428.87814 -23.609439) (xy 428.929469 -23.631251) (xy 428.977075 -23.660305) (xy 429.019943 -23.69598)
			(xy 429.05716 -23.737517) (xy 429.087933 -23.78403) (xy 429.111605 -23.834527) (xy 429.127673 -23.887934)
			(xy 429.135793 -23.94311) (xy 429.136302 -23.970996) (xy 429.135793 -23.998882) (xy 429.127673 -24.054058)
			(xy 429.111605 -24.107465) (xy 429.087933 -24.157962) (xy 429.08778 -24.158194) (xy 433.750718 -24.158194)
			(xy 433.754789 -24.102572) (xy 433.766915 -24.048135) (xy 433.786838 -23.996044) (xy 433.814134 -23.947409)
			(xy 433.84822 -23.903266) (xy 433.888369 -23.864557) (xy 433.933727 -23.832106) (xy 433.983327 -23.806605)
			(xy 434.036111 -23.788598) (xy 434.090954 -23.778468) (xy 434.146688 -23.776431) (xy 434.202125 -23.782531)
			(xy 434.256082 -23.796637) (xy 434.307411 -23.818449) (xy 434.355017 -23.847503) (xy 434.397885 -23.883178)
			(xy 434.435102 -23.924715) (xy 434.465875 -23.971228) (xy 434.489547 -24.021725) (xy 434.505615 -24.075132)
			(xy 434.513735 -24.130308) (xy 434.514244 -24.158194) (xy 434.513735 -24.18608) (xy 434.513166 -24.189944)
			(xy 437.598818 -24.189944) (xy 437.602889 -24.134322) (xy 437.615015 -24.079885) (xy 437.634938 -24.027794)
			(xy 437.662234 -23.979159) (xy 437.69632 -23.935016) (xy 437.736469 -23.896307) (xy 437.781827 -23.863856)
			(xy 437.831427 -23.838355) (xy 437.884211 -23.820348) (xy 437.939054 -23.810218) (xy 437.994788 -23.808181)
			(xy 438.050225 -23.814281) (xy 438.104182 -23.828387) (xy 438.155511 -23.850199) (xy 438.203117 -23.879253)
			(xy 438.245985 -23.914928) (xy 438.283202 -23.956465) (xy 438.313975 -24.002978) (xy 438.337647 -24.053475)
			(xy 438.353715 -24.106882) (xy 438.361835 -24.162058) (xy 438.362344 -24.189944) (xy 440.1218 -24.189944)
			(xy 440.125871 -24.134322) (xy 440.137997 -24.079885) (xy 440.15792 -24.027794) (xy 440.185216 -23.979159)
			(xy 440.219302 -23.935016) (xy 440.259451 -23.896307) (xy 440.304809 -23.863856) (xy 440.354409 -23.838355)
			(xy 440.407193 -23.820348) (xy 440.462036 -23.810218) (xy 440.51777 -23.808181) (xy 440.573207 -23.814281)
			(xy 440.627164 -23.828387) (xy 440.678493 -23.850199) (xy 440.726099 -23.879253) (xy 440.768967 -23.914928)
			(xy 440.806184 -23.956465) (xy 440.836957 -24.002978) (xy 440.860629 -24.053475) (xy 440.876697 -24.106882)
			(xy 440.884817 -24.162058) (xy 440.885326 -24.189944) (xy 440.884817 -24.21783) (xy 440.876697 -24.273006)
			(xy 440.860629 -24.326413) (xy 440.836957 -24.37691) (xy 440.806184 -24.423423) (xy 440.768967 -24.46496)
			(xy 440.726099 -24.500635) (xy 440.678493 -24.529689) (xy 440.627164 -24.551501) (xy 440.573207 -24.565607)
			(xy 440.51777 -24.571707) (xy 440.462036 -24.56967) (xy 440.407193 -24.55954) (xy 440.354409 -24.541533)
			(xy 440.304809 -24.516032) (xy 440.259451 -24.483581) (xy 440.219302 -24.444872) (xy 440.185216 -24.400729)
			(xy 440.15792 -24.352094) (xy 440.137997 -24.300003) (xy 440.125871 -24.245566) (xy 440.1218 -24.189944)
			(xy 438.362344 -24.189944) (xy 438.361835 -24.21783) (xy 438.353715 -24.273006) (xy 438.337647 -24.326413)
			(xy 438.313975 -24.37691) (xy 438.283202 -24.423423) (xy 438.245985 -24.46496) (xy 438.203117 -24.500635)
			(xy 438.155511 -24.529689) (xy 438.104182 -24.551501) (xy 438.050225 -24.565607) (xy 437.994788 -24.571707)
			(xy 437.939054 -24.56967) (xy 437.884211 -24.55954) (xy 437.831427 -24.541533) (xy 437.781827 -24.516032)
			(xy 437.736469 -24.483581) (xy 437.69632 -24.444872) (xy 437.662234 -24.400729) (xy 437.634938 -24.352094)
			(xy 437.615015 -24.300003) (xy 437.602889 -24.245566) (xy 437.598818 -24.189944) (xy 434.513166 -24.189944)
			(xy 434.505615 -24.241256) (xy 434.489547 -24.294663) (xy 434.465875 -24.34516) (xy 434.435102 -24.391673)
			(xy 434.397885 -24.43321) (xy 434.355017 -24.468885) (xy 434.307411 -24.497939) (xy 434.256082 -24.519751)
			(xy 434.202125 -24.533857) (xy 434.146688 -24.539957) (xy 434.090954 -24.53792) (xy 434.036111 -24.52779)
			(xy 433.983327 -24.509783) (xy 433.933727 -24.484282) (xy 433.888369 -24.451831) (xy 433.84822 -24.413122)
			(xy 433.814134 -24.368979) (xy 433.786838 -24.320344) (xy 433.766915 -24.268253) (xy 433.754789 -24.213816)
			(xy 433.750718 -24.158194) (xy 429.08778 -24.158194) (xy 429.05716 -24.204475) (xy 429.019943 -24.246012)
			(xy 428.977075 -24.281687) (xy 428.929469 -24.310741) (xy 428.87814 -24.332553) (xy 428.824183 -24.346659)
			(xy 428.768746 -24.352759) (xy 428.713012 -24.350722) (xy 428.658169 -24.340592) (xy 428.605385 -24.322585)
			(xy 428.555785 -24.297084) (xy 428.510427 -24.264633) (xy 428.470278 -24.225924) (xy 428.436192 -24.181781)
			(xy 428.408896 -24.133146) (xy 428.388973 -24.081055) (xy 428.376847 -24.026618) (xy 428.372776 -23.970996)
			(xy 428.143484 -23.970996) (xy 428.143415 -23.974752) (xy 428.135295 -24.029928) (xy 428.119227 -24.083335)
			(xy 428.095555 -24.133832) (xy 428.064782 -24.180345) (xy 428.027565 -24.221882) (xy 427.984697 -24.257557)
			(xy 427.937091 -24.286611) (xy 427.885762 -24.308423) (xy 427.831805 -24.322529) (xy 427.776368 -24.328629)
			(xy 427.720634 -24.326592) (xy 427.665791 -24.316462) (xy 427.613007 -24.298455) (xy 427.563407 -24.272954)
			(xy 427.518049 -24.240503) (xy 427.4779 -24.201794) (xy 427.443814 -24.157651) (xy 427.416518 -24.109016)
			(xy 427.396595 -24.056925) (xy 427.384469 -24.002488) (xy 427.380398 -23.946866) (xy 427.140544 -23.946866)
			(xy 427.140878 -23.965154) (xy 427.140369 -23.99304) (xy 427.132249 -24.048216) (xy 427.116181 -24.101623)
			(xy 427.092509 -24.15212) (xy 427.061736 -24.198633) (xy 427.024519 -24.24017) (xy 426.981651 -24.275845)
			(xy 426.934045 -24.304899) (xy 426.882716 -24.326711) (xy 426.828759 -24.340817) (xy 426.773322 -24.346917)
			(xy 426.717588 -24.34488) (xy 426.662745 -24.33475) (xy 426.609961 -24.316743) (xy 426.560361 -24.291242)
			(xy 426.515003 -24.258791) (xy 426.474854 -24.220082) (xy 426.440768 -24.175939) (xy 426.413472 -24.127304)
			(xy 426.393549 -24.075213) (xy 426.381423 -24.020776) (xy 426.377352 -23.965154) (xy 416.837823 -23.965154)
			(xy 416.835891 -23.965659) (xy 416.780454 -23.971759) (xy 416.72472 -23.969722) (xy 416.669877 -23.959592)
			(xy 416.617093 -23.941585) (xy 416.567493 -23.916084) (xy 416.522135 -23.883633) (xy 416.481986 -23.844924)
			(xy 416.4479 -23.800781) (xy 416.420604 -23.752146) (xy 416.400681 -23.700055) (xy 416.388555 -23.645618)
			(xy 416.384484 -23.589996) (xy 402.775732 -23.589996) (xy 402.824235 -23.595333) (xy 402.878192 -23.609439)
			(xy 402.929521 -23.631251) (xy 402.977127 -23.660305) (xy 403.019995 -23.69598) (xy 403.057212 -23.737517)
			(xy 403.087985 -23.78403) (xy 403.111657 -23.834527) (xy 403.127725 -23.887934) (xy 403.135845 -23.94311)
			(xy 403.136354 -23.970996) (xy 403.135845 -23.998882) (xy 403.127725 -24.054058) (xy 403.111657 -24.107465)
			(xy 403.087985 -24.157962) (xy 403.087832 -24.158194) (xy 407.75077 -24.158194) (xy 407.754841 -24.102572)
			(xy 407.766967 -24.048135) (xy 407.78689 -23.996044) (xy 407.814186 -23.947409) (xy 407.848272 -23.903266)
			(xy 407.888421 -23.864557) (xy 407.933779 -23.832106) (xy 407.983379 -23.806605) (xy 408.036163 -23.788598)
			(xy 408.091006 -23.778468) (xy 408.14674 -23.776431) (xy 408.202177 -23.782531) (xy 408.256134 -23.796637)
			(xy 408.307463 -23.818449) (xy 408.355069 -23.847503) (xy 408.397937 -23.883178) (xy 408.435154 -23.924715)
			(xy 408.465927 -23.971228) (xy 408.489599 -24.021725) (xy 408.505667 -24.075132) (xy 408.513787 -24.130308)
			(xy 408.514296 -24.158194) (xy 408.513787 -24.18608) (xy 408.513218 -24.189944) (xy 411.59887 -24.189944)
			(xy 411.602941 -24.134322) (xy 411.615067 -24.079885) (xy 411.63499 -24.027794) (xy 411.662286 -23.979159)
			(xy 411.696372 -23.935016) (xy 411.736521 -23.896307) (xy 411.781879 -23.863856) (xy 411.831479 -23.838355)
			(xy 411.884263 -23.820348) (xy 411.939106 -23.810218) (xy 411.99484 -23.808181) (xy 412.050277 -23.814281)
			(xy 412.104234 -23.828387) (xy 412.155563 -23.850199) (xy 412.203169 -23.879253) (xy 412.246037 -23.914928)
			(xy 412.283254 -23.956465) (xy 412.314027 -24.002978) (xy 412.337699 -24.053475) (xy 412.353767 -24.106882)
			(xy 412.361887 -24.162058) (xy 412.362396 -24.189944) (xy 414.121852 -24.189944) (xy 414.125923 -24.134322)
			(xy 414.138049 -24.079885) (xy 414.157972 -24.027794) (xy 414.185268 -23.979159) (xy 414.219354 -23.935016)
			(xy 414.259503 -23.896307) (xy 414.304861 -23.863856) (xy 414.354461 -23.838355) (xy 414.407245 -23.820348)
			(xy 414.462088 -23.810218) (xy 414.517822 -23.808181) (xy 414.573259 -23.814281) (xy 414.627216 -23.828387)
			(xy 414.678545 -23.850199) (xy 414.726151 -23.879253) (xy 414.769019 -23.914928) (xy 414.806236 -23.956465)
			(xy 414.837009 -24.002978) (xy 414.860681 -24.053475) (xy 414.876749 -24.106882) (xy 414.884869 -24.162058)
			(xy 414.885378 -24.189944) (xy 414.884869 -24.21783) (xy 414.876749 -24.273006) (xy 414.860681 -24.326413)
			(xy 414.837009 -24.37691) (xy 414.806236 -24.423423) (xy 414.769019 -24.46496) (xy 414.726151 -24.500635)
			(xy 414.678545 -24.529689) (xy 414.627216 -24.551501) (xy 414.573259 -24.565607) (xy 414.517822 -24.571707)
			(xy 414.462088 -24.56967) (xy 414.407245 -24.55954) (xy 414.354461 -24.541533) (xy 414.304861 -24.516032)
			(xy 414.259503 -24.483581) (xy 414.219354 -24.444872) (xy 414.185268 -24.400729) (xy 414.157972 -24.352094)
			(xy 414.138049 -24.300003) (xy 414.125923 -24.245566) (xy 414.121852 -24.189944) (xy 412.362396 -24.189944)
			(xy 412.361887 -24.21783) (xy 412.353767 -24.273006) (xy 412.337699 -24.326413) (xy 412.314027 -24.37691)
			(xy 412.283254 -24.423423) (xy 412.246037 -24.46496) (xy 412.203169 -24.500635) (xy 412.155563 -24.529689)
			(xy 412.104234 -24.551501) (xy 412.050277 -24.565607) (xy 411.99484 -24.571707) (xy 411.939106 -24.56967)
			(xy 411.884263 -24.55954) (xy 411.831479 -24.541533) (xy 411.781879 -24.516032) (xy 411.736521 -24.483581)
			(xy 411.696372 -24.444872) (xy 411.662286 -24.400729) (xy 411.63499 -24.352094) (xy 411.615067 -24.300003)
			(xy 411.602941 -24.245566) (xy 411.59887 -24.189944) (xy 408.513218 -24.189944) (xy 408.505667 -24.241256)
			(xy 408.489599 -24.294663) (xy 408.465927 -24.34516) (xy 408.435154 -24.391673) (xy 408.397937 -24.43321)
			(xy 408.355069 -24.468885) (xy 408.307463 -24.497939) (xy 408.256134 -24.519751) (xy 408.202177 -24.533857)
			(xy 408.14674 -24.539957) (xy 408.091006 -24.53792) (xy 408.036163 -24.52779) (xy 407.983379 -24.509783)
			(xy 407.933779 -24.484282) (xy 407.888421 -24.451831) (xy 407.848272 -24.413122) (xy 407.814186 -24.368979)
			(xy 407.78689 -24.320344) (xy 407.766967 -24.268253) (xy 407.754841 -24.213816) (xy 407.75077 -24.158194)
			(xy 403.087832 -24.158194) (xy 403.057212 -24.204475) (xy 403.019995 -24.246012) (xy 402.977127 -24.281687)
			(xy 402.929521 -24.310741) (xy 402.878192 -24.332553) (xy 402.824235 -24.346659) (xy 402.768798 -24.352759)
			(xy 402.713064 -24.350722) (xy 402.658221 -24.340592) (xy 402.605437 -24.322585) (xy 402.555837 -24.297084)
			(xy 402.510479 -24.264633) (xy 402.47033 -24.225924) (xy 402.436244 -24.181781) (xy 402.408948 -24.133146)
			(xy 402.389025 -24.081055) (xy 402.376899 -24.026618) (xy 402.372828 -23.970996) (xy 402.143536 -23.970996)
			(xy 402.143467 -23.974752) (xy 402.135347 -24.029928) (xy 402.119279 -24.083335) (xy 402.095607 -24.133832)
			(xy 402.064834 -24.180345) (xy 402.027617 -24.221882) (xy 401.984749 -24.257557) (xy 401.937143 -24.286611)
			(xy 401.885814 -24.308423) (xy 401.831857 -24.322529) (xy 401.77642 -24.328629) (xy 401.720686 -24.326592)
			(xy 401.665843 -24.316462) (xy 401.613059 -24.298455) (xy 401.563459 -24.272954) (xy 401.518101 -24.240503)
			(xy 401.477952 -24.201794) (xy 401.443866 -24.157651) (xy 401.41657 -24.109016) (xy 401.396647 -24.056925)
			(xy 401.384521 -24.002488) (xy 401.38045 -23.946866) (xy 401.140596 -23.946866) (xy 401.14093 -23.965154)
			(xy 401.140421 -23.99304) (xy 401.132301 -24.048216) (xy 401.116233 -24.101623) (xy 401.092561 -24.15212)
			(xy 401.061788 -24.198633) (xy 401.024571 -24.24017) (xy 400.981703 -24.275845) (xy 400.934097 -24.304899)
			(xy 400.882768 -24.326711) (xy 400.828811 -24.340817) (xy 400.773374 -24.346917) (xy 400.71764 -24.34488)
			(xy 400.662797 -24.33475) (xy 400.610013 -24.316743) (xy 400.560413 -24.291242) (xy 400.515055 -24.258791)
			(xy 400.474906 -24.220082) (xy 400.44082 -24.175939) (xy 400.413524 -24.127304) (xy 400.393601 -24.075213)
			(xy 400.381475 -24.020776) (xy 400.377404 -23.965154) (xy 390.837875 -23.965154) (xy 390.835943 -23.965659)
			(xy 390.780506 -23.971759) (xy 390.724772 -23.969722) (xy 390.669929 -23.959592) (xy 390.617145 -23.941585)
			(xy 390.567545 -23.916084) (xy 390.522187 -23.883633) (xy 390.482038 -23.844924) (xy 390.447952 -23.800781)
			(xy 390.420656 -23.752146) (xy 390.400733 -23.700055) (xy 390.388607 -23.645618) (xy 390.384536 -23.589996)
			(xy 376.775784 -23.589996) (xy 376.824287 -23.595333) (xy 376.878244 -23.609439) (xy 376.929573 -23.631251)
			(xy 376.977179 -23.660305) (xy 377.020047 -23.69598) (xy 377.057264 -23.737517) (xy 377.088037 -23.78403)
			(xy 377.111709 -23.834527) (xy 377.127777 -23.887934) (xy 377.135897 -23.94311) (xy 377.136406 -23.970996)
			(xy 377.135897 -23.998882) (xy 377.127777 -24.054058) (xy 377.111709 -24.107465) (xy 377.088037 -24.157962)
			(xy 377.087884 -24.158194) (xy 381.750822 -24.158194) (xy 381.754893 -24.102572) (xy 381.767019 -24.048135)
			(xy 381.786942 -23.996044) (xy 381.814238 -23.947409) (xy 381.848324 -23.903266) (xy 381.888473 -23.864557)
			(xy 381.933831 -23.832106) (xy 381.983431 -23.806605) (xy 382.036215 -23.788598) (xy 382.091058 -23.778468)
			(xy 382.146792 -23.776431) (xy 382.202229 -23.782531) (xy 382.256186 -23.796637) (xy 382.307515 -23.818449)
			(xy 382.355121 -23.847503) (xy 382.397989 -23.883178) (xy 382.435206 -23.924715) (xy 382.465979 -23.971228)
			(xy 382.489651 -24.021725) (xy 382.505719 -24.075132) (xy 382.513839 -24.130308) (xy 382.514348 -24.158194)
			(xy 382.513839 -24.18608) (xy 382.51327 -24.189944) (xy 385.598922 -24.189944) (xy 385.602993 -24.134322)
			(xy 385.615119 -24.079885) (xy 385.635042 -24.027794) (xy 385.662338 -23.979159) (xy 385.696424 -23.935016)
			(xy 385.736573 -23.896307) (xy 385.781931 -23.863856) (xy 385.831531 -23.838355) (xy 385.884315 -23.820348)
			(xy 385.939158 -23.810218) (xy 385.994892 -23.808181) (xy 386.050329 -23.814281) (xy 386.104286 -23.828387)
			(xy 386.155615 -23.850199) (xy 386.203221 -23.879253) (xy 386.246089 -23.914928) (xy 386.283306 -23.956465)
			(xy 386.314079 -24.002978) (xy 386.337751 -24.053475) (xy 386.353819 -24.106882) (xy 386.361939 -24.162058)
			(xy 386.362448 -24.189944) (xy 388.121904 -24.189944) (xy 388.125975 -24.134322) (xy 388.138101 -24.079885)
			(xy 388.158024 -24.027794) (xy 388.18532 -23.979159) (xy 388.219406 -23.935016) (xy 388.259555 -23.896307)
			(xy 388.304913 -23.863856) (xy 388.354513 -23.838355) (xy 388.407297 -23.820348) (xy 388.46214 -23.810218)
			(xy 388.517874 -23.808181) (xy 388.573311 -23.814281) (xy 388.627268 -23.828387) (xy 388.678597 -23.850199)
			(xy 388.726203 -23.879253) (xy 388.769071 -23.914928) (xy 388.806288 -23.956465) (xy 388.837061 -24.002978)
			(xy 388.860733 -24.053475) (xy 388.876801 -24.106882) (xy 388.884921 -24.162058) (xy 388.88543 -24.189944)
			(xy 388.884921 -24.21783) (xy 388.876801 -24.273006) (xy 388.860733 -24.326413) (xy 388.837061 -24.37691)
			(xy 388.806288 -24.423423) (xy 388.769071 -24.46496) (xy 388.726203 -24.500635) (xy 388.678597 -24.529689)
			(xy 388.627268 -24.551501) (xy 388.573311 -24.565607) (xy 388.517874 -24.571707) (xy 388.46214 -24.56967)
			(xy 388.407297 -24.55954) (xy 388.354513 -24.541533) (xy 388.304913 -24.516032) (xy 388.259555 -24.483581)
			(xy 388.219406 -24.444872) (xy 388.18532 -24.400729) (xy 388.158024 -24.352094) (xy 388.138101 -24.300003)
			(xy 388.125975 -24.245566) (xy 388.121904 -24.189944) (xy 386.362448 -24.189944) (xy 386.361939 -24.21783)
			(xy 386.353819 -24.273006) (xy 386.337751 -24.326413) (xy 386.314079 -24.37691) (xy 386.283306 -24.423423)
			(xy 386.246089 -24.46496) (xy 386.203221 -24.500635) (xy 386.155615 -24.529689) (xy 386.104286 -24.551501)
			(xy 386.050329 -24.565607) (xy 385.994892 -24.571707) (xy 385.939158 -24.56967) (xy 385.884315 -24.55954)
			(xy 385.831531 -24.541533) (xy 385.781931 -24.516032) (xy 385.736573 -24.483581) (xy 385.696424 -24.444872)
			(xy 385.662338 -24.400729) (xy 385.635042 -24.352094) (xy 385.615119 -24.300003) (xy 385.602993 -24.245566)
			(xy 385.598922 -24.189944) (xy 382.51327 -24.189944) (xy 382.505719 -24.241256) (xy 382.489651 -24.294663)
			(xy 382.465979 -24.34516) (xy 382.435206 -24.391673) (xy 382.397989 -24.43321) (xy 382.355121 -24.468885)
			(xy 382.307515 -24.497939) (xy 382.256186 -24.519751) (xy 382.202229 -24.533857) (xy 382.146792 -24.539957)
			(xy 382.091058 -24.53792) (xy 382.036215 -24.52779) (xy 381.983431 -24.509783) (xy 381.933831 -24.484282)
			(xy 381.888473 -24.451831) (xy 381.848324 -24.413122) (xy 381.814238 -24.368979) (xy 381.786942 -24.320344)
			(xy 381.767019 -24.268253) (xy 381.754893 -24.213816) (xy 381.750822 -24.158194) (xy 377.087884 -24.158194)
			(xy 377.057264 -24.204475) (xy 377.020047 -24.246012) (xy 376.977179 -24.281687) (xy 376.929573 -24.310741)
			(xy 376.878244 -24.332553) (xy 376.824287 -24.346659) (xy 376.76885 -24.352759) (xy 376.713116 -24.350722)
			(xy 376.658273 -24.340592) (xy 376.605489 -24.322585) (xy 376.555889 -24.297084) (xy 376.510531 -24.264633)
			(xy 376.470382 -24.225924) (xy 376.436296 -24.181781) (xy 376.409 -24.133146) (xy 376.389077 -24.081055)
			(xy 376.376951 -24.026618) (xy 376.37288 -23.970996) (xy 376.143588 -23.970996) (xy 376.143519 -23.974752)
			(xy 376.135399 -24.029928) (xy 376.119331 -24.083335) (xy 376.095659 -24.133832) (xy 376.064886 -24.180345)
			(xy 376.027669 -24.221882) (xy 375.984801 -24.257557) (xy 375.937195 -24.286611) (xy 375.885866 -24.308423)
			(xy 375.831909 -24.322529) (xy 375.776472 -24.328629) (xy 375.720738 -24.326592) (xy 375.665895 -24.316462)
			(xy 375.613111 -24.298455) (xy 375.563511 -24.272954) (xy 375.518153 -24.240503) (xy 375.478004 -24.201794)
			(xy 375.443918 -24.157651) (xy 375.416622 -24.109016) (xy 375.396699 -24.056925) (xy 375.384573 -24.002488)
			(xy 375.380502 -23.946866) (xy 375.140648 -23.946866) (xy 375.140982 -23.965154) (xy 375.140473 -23.99304)
			(xy 375.132353 -24.048216) (xy 375.116285 -24.101623) (xy 375.092613 -24.15212) (xy 375.06184 -24.198633)
			(xy 375.024623 -24.24017) (xy 374.981755 -24.275845) (xy 374.934149 -24.304899) (xy 374.88282 -24.326711)
			(xy 374.828863 -24.340817) (xy 374.773426 -24.346917) (xy 374.717692 -24.34488) (xy 374.662849 -24.33475)
			(xy 374.610065 -24.316743) (xy 374.560465 -24.291242) (xy 374.515107 -24.258791) (xy 374.474958 -24.220082)
			(xy 374.440872 -24.175939) (xy 374.413576 -24.127304) (xy 374.393653 -24.075213) (xy 374.381527 -24.020776)
			(xy 374.377456 -23.965154) (xy 364.837927 -23.965154) (xy 364.835995 -23.965659) (xy 364.780558 -23.971759)
			(xy 364.724824 -23.969722) (xy 364.669981 -23.959592) (xy 364.617197 -23.941585) (xy 364.567597 -23.916084)
			(xy 364.522239 -23.883633) (xy 364.48209 -23.844924) (xy 364.448004 -23.800781) (xy 364.420708 -23.752146)
			(xy 364.400785 -23.700055) (xy 364.388659 -23.645618) (xy 364.384588 -23.589996) (xy 327.04786 -23.589996)
			(xy 327.047351 -23.617882) (xy 327.039231 -23.673058) (xy 327.023163 -23.726465) (xy 326.999491 -23.776962)
			(xy 326.968718 -23.823475) (xy 326.931501 -23.865012) (xy 326.888633 -23.900687) (xy 326.841027 -23.929741)
			(xy 326.789698 -23.951553) (xy 326.735741 -23.965659) (xy 326.680304 -23.971759) (xy 326.62457 -23.969722)
			(xy 326.569727 -23.959592) (xy 326.516943 -23.941585) (xy 326.467343 -23.916084) (xy 326.421985 -23.883633)
			(xy 326.381836 -23.844924) (xy 326.34775 -23.800781) (xy 326.320454 -23.752146) (xy 326.300531 -23.700055)
			(xy 326.288405 -23.645618) (xy 326.284334 -23.589996) (xy 312.675582 -23.589996) (xy 312.724085 -23.595333)
			(xy 312.778042 -23.609439) (xy 312.829371 -23.631251) (xy 312.876977 -23.660305) (xy 312.919845 -23.69598)
			(xy 312.957062 -23.737517) (xy 312.987835 -23.78403) (xy 313.011507 -23.834527) (xy 313.027575 -23.887934)
			(xy 313.035695 -23.94311) (xy 313.036204 -23.970996) (xy 313.035695 -23.998882) (xy 313.027575 -24.054058)
			(xy 313.011507 -24.107465) (xy 312.987835 -24.157962) (xy 312.987682 -24.158194) (xy 317.65062 -24.158194)
			(xy 317.654691 -24.102572) (xy 317.666817 -24.048135) (xy 317.68674 -23.996044) (xy 317.714036 -23.947409)
			(xy 317.748122 -23.903266) (xy 317.788271 -23.864557) (xy 317.833629 -23.832106) (xy 317.883229 -23.806605)
			(xy 317.936013 -23.788598) (xy 317.990856 -23.778468) (xy 318.04659 -23.776431) (xy 318.102027 -23.782531)
			(xy 318.155984 -23.796637) (xy 318.207313 -23.818449) (xy 318.254919 -23.847503) (xy 318.297787 -23.883178)
			(xy 318.335004 -23.924715) (xy 318.365777 -23.971228) (xy 318.389449 -24.021725) (xy 318.405517 -24.075132)
			(xy 318.413637 -24.130308) (xy 318.414146 -24.158194) (xy 318.413637 -24.18608) (xy 318.413068 -24.189944)
			(xy 321.49872 -24.189944) (xy 321.502791 -24.134322) (xy 321.514917 -24.079885) (xy 321.53484 -24.027794)
			(xy 321.562136 -23.979159) (xy 321.596222 -23.935016) (xy 321.636371 -23.896307) (xy 321.681729 -23.863856)
			(xy 321.731329 -23.838355) (xy 321.784113 -23.820348) (xy 321.838956 -23.810218) (xy 321.89469 -23.808181)
			(xy 321.950127 -23.814281) (xy 322.004084 -23.828387) (xy 322.055413 -23.850199) (xy 322.103019 -23.879253)
			(xy 322.145887 -23.914928) (xy 322.183104 -23.956465) (xy 322.213877 -24.002978) (xy 322.237549 -24.053475)
			(xy 322.253617 -24.106882) (xy 322.261737 -24.162058) (xy 322.262246 -24.189944) (xy 324.021702 -24.189944)
			(xy 324.025773 -24.134322) (xy 324.037899 -24.079885) (xy 324.057822 -24.027794) (xy 324.085118 -23.979159)
			(xy 324.119204 -23.935016) (xy 324.159353 -23.896307) (xy 324.204711 -23.863856) (xy 324.254311 -23.838355)
			(xy 324.307095 -23.820348) (xy 324.361938 -23.810218) (xy 324.417672 -23.808181) (xy 324.473109 -23.814281)
			(xy 324.527066 -23.828387) (xy 324.578395 -23.850199) (xy 324.626001 -23.879253) (xy 324.668869 -23.914928)
			(xy 324.706086 -23.956465) (xy 324.736859 -24.002978) (xy 324.760531 -24.053475) (xy 324.776599 -24.106882)
			(xy 324.78415 -24.158194) (xy 355.750874 -24.158194) (xy 355.754945 -24.102572) (xy 355.767071 -24.048135)
			(xy 355.786994 -23.996044) (xy 355.81429 -23.947409) (xy 355.848376 -23.903266) (xy 355.888525 -23.864557)
			(xy 355.933883 -23.832106) (xy 355.983483 -23.806605) (xy 356.036267 -23.788598) (xy 356.09111 -23.778468)
			(xy 356.146844 -23.776431) (xy 356.202281 -23.782531) (xy 356.256238 -23.796637) (xy 356.307567 -23.818449)
			(xy 356.355173 -23.847503) (xy 356.398041 -23.883178) (xy 356.435258 -23.924715) (xy 356.466031 -23.971228)
			(xy 356.489703 -24.021725) (xy 356.505771 -24.075132) (xy 356.513891 -24.130308) (xy 356.5144 -24.158194)
			(xy 356.513891 -24.18608) (xy 356.513322 -24.189944) (xy 359.598974 -24.189944) (xy 359.603045 -24.134322)
			(xy 359.615171 -24.079885) (xy 359.635094 -24.027794) (xy 359.66239 -23.979159) (xy 359.696476 -23.935016)
			(xy 359.736625 -23.896307) (xy 359.781983 -23.863856) (xy 359.831583 -23.838355) (xy 359.884367 -23.820348)
			(xy 359.93921 -23.810218) (xy 359.994944 -23.808181) (xy 360.050381 -23.814281) (xy 360.104338 -23.828387)
			(xy 360.155667 -23.850199) (xy 360.203273 -23.879253) (xy 360.246141 -23.914928) (xy 360.283358 -23.956465)
			(xy 360.314131 -24.002978) (xy 360.337803 -24.053475) (xy 360.353871 -24.106882) (xy 360.361991 -24.162058)
			(xy 360.3625 -24.189944) (xy 362.121956 -24.189944) (xy 362.126027 -24.134322) (xy 362.138153 -24.079885)
			(xy 362.158076 -24.027794) (xy 362.185372 -23.979159) (xy 362.219458 -23.935016) (xy 362.259607 -23.896307)
			(xy 362.304965 -23.863856) (xy 362.354565 -23.838355) (xy 362.407349 -23.820348) (xy 362.462192 -23.810218)
			(xy 362.517926 -23.808181) (xy 362.573363 -23.814281) (xy 362.62732 -23.828387) (xy 362.678649 -23.850199)
			(xy 362.726255 -23.879253) (xy 362.769123 -23.914928) (xy 362.80634 -23.956465) (xy 362.837113 -24.002978)
			(xy 362.860785 -24.053475) (xy 362.876853 -24.106882) (xy 362.884973 -24.162058) (xy 362.885482 -24.189944)
			(xy 362.884973 -24.21783) (xy 362.876853 -24.273006) (xy 362.860785 -24.326413) (xy 362.837113 -24.37691)
			(xy 362.80634 -24.423423) (xy 362.769123 -24.46496) (xy 362.726255 -24.500635) (xy 362.678649 -24.529689)
			(xy 362.62732 -24.551501) (xy 362.573363 -24.565607) (xy 362.517926 -24.571707) (xy 362.462192 -24.56967)
			(xy 362.407349 -24.55954) (xy 362.354565 -24.541533) (xy 362.304965 -24.516032) (xy 362.259607 -24.483581)
			(xy 362.219458 -24.444872) (xy 362.185372 -24.400729) (xy 362.158076 -24.352094) (xy 362.138153 -24.300003)
			(xy 362.126027 -24.245566) (xy 362.121956 -24.189944) (xy 360.3625 -24.189944) (xy 360.361991 -24.21783)
			(xy 360.353871 -24.273006) (xy 360.337803 -24.326413) (xy 360.314131 -24.37691) (xy 360.283358 -24.423423)
			(xy 360.246141 -24.46496) (xy 360.203273 -24.500635) (xy 360.155667 -24.529689) (xy 360.104338 -24.551501)
			(xy 360.050381 -24.565607) (xy 359.994944 -24.571707) (xy 359.93921 -24.56967) (xy 359.884367 -24.55954)
			(xy 359.831583 -24.541533) (xy 359.781983 -24.516032) (xy 359.736625 -24.483581) (xy 359.696476 -24.444872)
			(xy 359.66239 -24.400729) (xy 359.635094 -24.352094) (xy 359.615171 -24.300003) (xy 359.603045 -24.245566)
			(xy 359.598974 -24.189944) (xy 356.513322 -24.189944) (xy 356.505771 -24.241256) (xy 356.489703 -24.294663)
			(xy 356.466031 -24.34516) (xy 356.435258 -24.391673) (xy 356.398041 -24.43321) (xy 356.355173 -24.468885)
			(xy 356.307567 -24.497939) (xy 356.256238 -24.519751) (xy 356.202281 -24.533857) (xy 356.146844 -24.539957)
			(xy 356.09111 -24.53792) (xy 356.036267 -24.52779) (xy 355.983483 -24.509783) (xy 355.933883 -24.484282)
			(xy 355.888525 -24.451831) (xy 355.848376 -24.413122) (xy 355.81429 -24.368979) (xy 355.786994 -24.320344)
			(xy 355.767071 -24.268253) (xy 355.754945 -24.213816) (xy 355.750874 -24.158194) (xy 324.78415 -24.158194)
			(xy 324.784719 -24.162058) (xy 324.785228 -24.189944) (xy 324.784719 -24.21783) (xy 324.776599 -24.273006)
			(xy 324.760531 -24.326413) (xy 324.736859 -24.37691) (xy 324.706086 -24.423423) (xy 324.668869 -24.46496)
			(xy 324.626001 -24.500635) (xy 324.578395 -24.529689) (xy 324.527066 -24.551501) (xy 324.473109 -24.565607)
			(xy 324.417672 -24.571707) (xy 324.361938 -24.56967) (xy 324.307095 -24.55954) (xy 324.254311 -24.541533)
			(xy 324.204711 -24.516032) (xy 324.159353 -24.483581) (xy 324.119204 -24.444872) (xy 324.085118 -24.400729)
			(xy 324.057822 -24.352094) (xy 324.037899 -24.300003) (xy 324.025773 -24.245566) (xy 324.021702 -24.189944)
			(xy 322.262246 -24.189944) (xy 322.261737 -24.21783) (xy 322.253617 -24.273006) (xy 322.237549 -24.326413)
			(xy 322.213877 -24.37691) (xy 322.183104 -24.423423) (xy 322.145887 -24.46496) (xy 322.103019 -24.500635)
			(xy 322.055413 -24.529689) (xy 322.004084 -24.551501) (xy 321.950127 -24.565607) (xy 321.89469 -24.571707)
			(xy 321.838956 -24.56967) (xy 321.784113 -24.55954) (xy 321.731329 -24.541533) (xy 321.681729 -24.516032)
			(xy 321.636371 -24.483581) (xy 321.596222 -24.444872) (xy 321.562136 -24.400729) (xy 321.53484 -24.352094)
			(xy 321.514917 -24.300003) (xy 321.502791 -24.245566) (xy 321.49872 -24.189944) (xy 318.413068 -24.189944)
			(xy 318.405517 -24.241256) (xy 318.389449 -24.294663) (xy 318.365777 -24.34516) (xy 318.335004 -24.391673)
			(xy 318.297787 -24.43321) (xy 318.254919 -24.468885) (xy 318.207313 -24.497939) (xy 318.155984 -24.519751)
			(xy 318.102027 -24.533857) (xy 318.04659 -24.539957) (xy 317.990856 -24.53792) (xy 317.936013 -24.52779)
			(xy 317.883229 -24.509783) (xy 317.833629 -24.484282) (xy 317.788271 -24.451831) (xy 317.748122 -24.413122)
			(xy 317.714036 -24.368979) (xy 317.68674 -24.320344) (xy 317.666817 -24.268253) (xy 317.654691 -24.213816)
			(xy 317.65062 -24.158194) (xy 312.987682 -24.158194) (xy 312.957062 -24.204475) (xy 312.919845 -24.246012)
			(xy 312.876977 -24.281687) (xy 312.829371 -24.310741) (xy 312.778042 -24.332553) (xy 312.724085 -24.346659)
			(xy 312.668648 -24.352759) (xy 312.612914 -24.350722) (xy 312.558071 -24.340592) (xy 312.505287 -24.322585)
			(xy 312.455687 -24.297084) (xy 312.410329 -24.264633) (xy 312.37018 -24.225924) (xy 312.336094 -24.181781)
			(xy 312.308798 -24.133146) (xy 312.288875 -24.081055) (xy 312.276749 -24.026618) (xy 312.272678 -23.970996)
			(xy 312.043386 -23.970996) (xy 312.043317 -23.974752) (xy 312.035197 -24.029928) (xy 312.019129 -24.083335)
			(xy 311.995457 -24.133832) (xy 311.964684 -24.180345) (xy 311.927467 -24.221882) (xy 311.884599 -24.257557)
			(xy 311.836993 -24.286611) (xy 311.785664 -24.308423) (xy 311.731707 -24.322529) (xy 311.67627 -24.328629)
			(xy 311.620536 -24.326592) (xy 311.565693 -24.316462) (xy 311.512909 -24.298455) (xy 311.463309 -24.272954)
			(xy 311.417951 -24.240503) (xy 311.377802 -24.201794) (xy 311.343716 -24.157651) (xy 311.31642 -24.109016)
			(xy 311.296497 -24.056925) (xy 311.284371 -24.002488) (xy 311.2803 -23.946866) (xy 311.040446 -23.946866)
			(xy 311.04078 -23.965154) (xy 311.040271 -23.99304) (xy 311.032151 -24.048216) (xy 311.016083 -24.101623)
			(xy 310.992411 -24.15212) (xy 310.961638 -24.198633) (xy 310.924421 -24.24017) (xy 310.881553 -24.275845)
			(xy 310.833947 -24.304899) (xy 310.782618 -24.326711) (xy 310.728661 -24.340817) (xy 310.673224 -24.346917)
			(xy 310.61749 -24.34488) (xy 310.562647 -24.33475) (xy 310.509863 -24.316743) (xy 310.460263 -24.291242)
			(xy 310.414905 -24.258791) (xy 310.374756 -24.220082) (xy 310.34067 -24.175939) (xy 310.313374 -24.127304)
			(xy 310.293451 -24.075213) (xy 310.281325 -24.020776) (xy 310.277254 -23.965154) (xy 300.737725 -23.965154)
			(xy 300.735793 -23.965659) (xy 300.680356 -23.971759) (xy 300.624622 -23.969722) (xy 300.569779 -23.959592)
			(xy 300.516995 -23.941585) (xy 300.467395 -23.916084) (xy 300.422037 -23.883633) (xy 300.381888 -23.844924)
			(xy 300.347802 -23.800781) (xy 300.320506 -23.752146) (xy 300.300583 -23.700055) (xy 300.288457 -23.645618)
			(xy 300.284386 -23.589996) (xy 286.675634 -23.589996) (xy 286.724137 -23.595333) (xy 286.778094 -23.609439)
			(xy 286.829423 -23.631251) (xy 286.877029 -23.660305) (xy 286.919897 -23.69598) (xy 286.957114 -23.737517)
			(xy 286.987887 -23.78403) (xy 287.011559 -23.834527) (xy 287.027627 -23.887934) (xy 287.035747 -23.94311)
			(xy 287.036256 -23.970996) (xy 287.035747 -23.998882) (xy 287.027627 -24.054058) (xy 287.011559 -24.107465)
			(xy 286.987887 -24.157962) (xy 286.987734 -24.158194) (xy 291.650672 -24.158194) (xy 291.654743 -24.102572)
			(xy 291.666869 -24.048135) (xy 291.686792 -23.996044) (xy 291.714088 -23.947409) (xy 291.748174 -23.903266)
			(xy 291.788323 -23.864557) (xy 291.833681 -23.832106) (xy 291.883281 -23.806605) (xy 291.936065 -23.788598)
			(xy 291.990908 -23.778468) (xy 292.046642 -23.776431) (xy 292.102079 -23.782531) (xy 292.156036 -23.796637)
			(xy 292.207365 -23.818449) (xy 292.254971 -23.847503) (xy 292.297839 -23.883178) (xy 292.335056 -23.924715)
			(xy 292.365829 -23.971228) (xy 292.389501 -24.021725) (xy 292.405569 -24.075132) (xy 292.413689 -24.130308)
			(xy 292.414198 -24.158194) (xy 292.413689 -24.18608) (xy 292.41312 -24.189944) (xy 295.498772 -24.189944)
			(xy 295.502843 -24.134322) (xy 295.514969 -24.079885) (xy 295.534892 -24.027794) (xy 295.562188 -23.979159)
			(xy 295.596274 -23.935016) (xy 295.636423 -23.896307) (xy 295.681781 -23.863856) (xy 295.731381 -23.838355)
			(xy 295.784165 -23.820348) (xy 295.839008 -23.810218) (xy 295.894742 -23.808181) (xy 295.950179 -23.814281)
			(xy 296.004136 -23.828387) (xy 296.055465 -23.850199) (xy 296.103071 -23.879253) (xy 296.145939 -23.914928)
			(xy 296.183156 -23.956465) (xy 296.213929 -24.002978) (xy 296.237601 -24.053475) (xy 296.253669 -24.106882)
			(xy 296.261789 -24.162058) (xy 296.262298 -24.189944) (xy 298.021754 -24.189944) (xy 298.025825 -24.134322)
			(xy 298.037951 -24.079885) (xy 298.057874 -24.027794) (xy 298.08517 -23.979159) (xy 298.119256 -23.935016)
			(xy 298.159405 -23.896307) (xy 298.204763 -23.863856) (xy 298.254363 -23.838355) (xy 298.307147 -23.820348)
			(xy 298.36199 -23.810218) (xy 298.417724 -23.808181) (xy 298.473161 -23.814281) (xy 298.527118 -23.828387)
			(xy 298.578447 -23.850199) (xy 298.626053 -23.879253) (xy 298.668921 -23.914928) (xy 298.706138 -23.956465)
			(xy 298.736911 -24.002978) (xy 298.760583 -24.053475) (xy 298.776651 -24.106882) (xy 298.784771 -24.162058)
			(xy 298.78528 -24.189944) (xy 298.784771 -24.21783) (xy 298.776651 -24.273006) (xy 298.760583 -24.326413)
			(xy 298.736911 -24.37691) (xy 298.706138 -24.423423) (xy 298.668921 -24.46496) (xy 298.626053 -24.500635)
			(xy 298.578447 -24.529689) (xy 298.527118 -24.551501) (xy 298.473161 -24.565607) (xy 298.417724 -24.571707)
			(xy 298.36199 -24.56967) (xy 298.307147 -24.55954) (xy 298.254363 -24.541533) (xy 298.204763 -24.516032)
			(xy 298.159405 -24.483581) (xy 298.119256 -24.444872) (xy 298.08517 -24.400729) (xy 298.057874 -24.352094)
			(xy 298.037951 -24.300003) (xy 298.025825 -24.245566) (xy 298.021754 -24.189944) (xy 296.262298 -24.189944)
			(xy 296.261789 -24.21783) (xy 296.253669 -24.273006) (xy 296.237601 -24.326413) (xy 296.213929 -24.37691)
			(xy 296.183156 -24.423423) (xy 296.145939 -24.46496) (xy 296.103071 -24.500635) (xy 296.055465 -24.529689)
			(xy 296.004136 -24.551501) (xy 295.950179 -24.565607) (xy 295.894742 -24.571707) (xy 295.839008 -24.56967)
			(xy 295.784165 -24.55954) (xy 295.731381 -24.541533) (xy 295.681781 -24.516032) (xy 295.636423 -24.483581)
			(xy 295.596274 -24.444872) (xy 295.562188 -24.400729) (xy 295.534892 -24.352094) (xy 295.514969 -24.300003)
			(xy 295.502843 -24.245566) (xy 295.498772 -24.189944) (xy 292.41312 -24.189944) (xy 292.405569 -24.241256)
			(xy 292.389501 -24.294663) (xy 292.365829 -24.34516) (xy 292.335056 -24.391673) (xy 292.297839 -24.43321)
			(xy 292.254971 -24.468885) (xy 292.207365 -24.497939) (xy 292.156036 -24.519751) (xy 292.102079 -24.533857)
			(xy 292.046642 -24.539957) (xy 291.990908 -24.53792) (xy 291.936065 -24.52779) (xy 291.883281 -24.509783)
			(xy 291.833681 -24.484282) (xy 291.788323 -24.451831) (xy 291.748174 -24.413122) (xy 291.714088 -24.368979)
			(xy 291.686792 -24.320344) (xy 291.666869 -24.268253) (xy 291.654743 -24.213816) (xy 291.650672 -24.158194)
			(xy 286.987734 -24.158194) (xy 286.957114 -24.204475) (xy 286.919897 -24.246012) (xy 286.877029 -24.281687)
			(xy 286.829423 -24.310741) (xy 286.778094 -24.332553) (xy 286.724137 -24.346659) (xy 286.6687 -24.352759)
			(xy 286.612966 -24.350722) (xy 286.558123 -24.340592) (xy 286.505339 -24.322585) (xy 286.455739 -24.297084)
			(xy 286.410381 -24.264633) (xy 286.370232 -24.225924) (xy 286.336146 -24.181781) (xy 286.30885 -24.133146)
			(xy 286.288927 -24.081055) (xy 286.276801 -24.026618) (xy 286.27273 -23.970996) (xy 286.043438 -23.970996)
			(xy 286.043369 -23.974752) (xy 286.035249 -24.029928) (xy 286.019181 -24.083335) (xy 285.995509 -24.133832)
			(xy 285.964736 -24.180345) (xy 285.927519 -24.221882) (xy 285.884651 -24.257557) (xy 285.837045 -24.286611)
			(xy 285.785716 -24.308423) (xy 285.731759 -24.322529) (xy 285.676322 -24.328629) (xy 285.620588 -24.326592)
			(xy 285.565745 -24.316462) (xy 285.512961 -24.298455) (xy 285.463361 -24.272954) (xy 285.418003 -24.240503)
			(xy 285.377854 -24.201794) (xy 285.343768 -24.157651) (xy 285.316472 -24.109016) (xy 285.296549 -24.056925)
			(xy 285.284423 -24.002488) (xy 285.280352 -23.946866) (xy 285.040498 -23.946866) (xy 285.040832 -23.965154)
			(xy 285.040323 -23.99304) (xy 285.032203 -24.048216) (xy 285.016135 -24.101623) (xy 284.992463 -24.15212)
			(xy 284.96169 -24.198633) (xy 284.924473 -24.24017) (xy 284.881605 -24.275845) (xy 284.833999 -24.304899)
			(xy 284.78267 -24.326711) (xy 284.728713 -24.340817) (xy 284.673276 -24.346917) (xy 284.617542 -24.34488)
			(xy 284.562699 -24.33475) (xy 284.509915 -24.316743) (xy 284.460315 -24.291242) (xy 284.414957 -24.258791)
			(xy 284.374808 -24.220082) (xy 284.340722 -24.175939) (xy 284.313426 -24.127304) (xy 284.293503 -24.075213)
			(xy 284.281377 -24.020776) (xy 284.277306 -23.965154) (xy 274.737777 -23.965154) (xy 274.735845 -23.965659)
			(xy 274.680408 -23.971759) (xy 274.624674 -23.969722) (xy 274.569831 -23.959592) (xy 274.517047 -23.941585)
			(xy 274.467447 -23.916084) (xy 274.422089 -23.883633) (xy 274.38194 -23.844924) (xy 274.347854 -23.800781)
			(xy 274.320558 -23.752146) (xy 274.300635 -23.700055) (xy 274.288509 -23.645618) (xy 274.284438 -23.589996)
			(xy 260.675686 -23.589996) (xy 260.724189 -23.595333) (xy 260.778146 -23.609439) (xy 260.829475 -23.631251)
			(xy 260.877081 -23.660305) (xy 260.919949 -23.69598) (xy 260.957166 -23.737517) (xy 260.987939 -23.78403)
			(xy 261.011611 -23.834527) (xy 261.027679 -23.887934) (xy 261.035799 -23.94311) (xy 261.036308 -23.970996)
			(xy 261.035799 -23.998882) (xy 261.027679 -24.054058) (xy 261.011611 -24.107465) (xy 260.987939 -24.157962)
			(xy 260.987786 -24.158194) (xy 265.650724 -24.158194) (xy 265.654795 -24.102572) (xy 265.666921 -24.048135)
			(xy 265.686844 -23.996044) (xy 265.71414 -23.947409) (xy 265.748226 -23.903266) (xy 265.788375 -23.864557)
			(xy 265.833733 -23.832106) (xy 265.883333 -23.806605) (xy 265.936117 -23.788598) (xy 265.99096 -23.778468)
			(xy 266.046694 -23.776431) (xy 266.102131 -23.782531) (xy 266.156088 -23.796637) (xy 266.207417 -23.818449)
			(xy 266.255023 -23.847503) (xy 266.297891 -23.883178) (xy 266.335108 -23.924715) (xy 266.365881 -23.971228)
			(xy 266.389553 -24.021725) (xy 266.405621 -24.075132) (xy 266.413741 -24.130308) (xy 266.41425 -24.158194)
			(xy 266.413741 -24.18608) (xy 266.413172 -24.189944) (xy 269.498824 -24.189944) (xy 269.502895 -24.134322)
			(xy 269.515021 -24.079885) (xy 269.534944 -24.027794) (xy 269.56224 -23.979159) (xy 269.596326 -23.935016)
			(xy 269.636475 -23.896307) (xy 269.681833 -23.863856) (xy 269.731433 -23.838355) (xy 269.784217 -23.820348)
			(xy 269.83906 -23.810218) (xy 269.894794 -23.808181) (xy 269.950231 -23.814281) (xy 270.004188 -23.828387)
			(xy 270.055517 -23.850199) (xy 270.103123 -23.879253) (xy 270.145991 -23.914928) (xy 270.183208 -23.956465)
			(xy 270.213981 -24.002978) (xy 270.237653 -24.053475) (xy 270.253721 -24.106882) (xy 270.261841 -24.162058)
			(xy 270.26235 -24.189944) (xy 272.021806 -24.189944) (xy 272.025877 -24.134322) (xy 272.038003 -24.079885)
			(xy 272.057926 -24.027794) (xy 272.085222 -23.979159) (xy 272.119308 -23.935016) (xy 272.159457 -23.896307)
			(xy 272.204815 -23.863856) (xy 272.254415 -23.838355) (xy 272.307199 -23.820348) (xy 272.362042 -23.810218)
			(xy 272.417776 -23.808181) (xy 272.473213 -23.814281) (xy 272.52717 -23.828387) (xy 272.578499 -23.850199)
			(xy 272.626105 -23.879253) (xy 272.668973 -23.914928) (xy 272.70619 -23.956465) (xy 272.736963 -24.002978)
			(xy 272.760635 -24.053475) (xy 272.776703 -24.106882) (xy 272.784823 -24.162058) (xy 272.785332 -24.189944)
			(xy 272.784823 -24.21783) (xy 272.776703 -24.273006) (xy 272.760635 -24.326413) (xy 272.736963 -24.37691)
			(xy 272.70619 -24.423423) (xy 272.668973 -24.46496) (xy 272.626105 -24.500635) (xy 272.578499 -24.529689)
			(xy 272.52717 -24.551501) (xy 272.473213 -24.565607) (xy 272.417776 -24.571707) (xy 272.362042 -24.56967)
			(xy 272.307199 -24.55954) (xy 272.254415 -24.541533) (xy 272.204815 -24.516032) (xy 272.159457 -24.483581)
			(xy 272.119308 -24.444872) (xy 272.085222 -24.400729) (xy 272.057926 -24.352094) (xy 272.038003 -24.300003)
			(xy 272.025877 -24.245566) (xy 272.021806 -24.189944) (xy 270.26235 -24.189944) (xy 270.261841 -24.21783)
			(xy 270.253721 -24.273006) (xy 270.237653 -24.326413) (xy 270.213981 -24.37691) (xy 270.183208 -24.423423)
			(xy 270.145991 -24.46496) (xy 270.103123 -24.500635) (xy 270.055517 -24.529689) (xy 270.004188 -24.551501)
			(xy 269.950231 -24.565607) (xy 269.894794 -24.571707) (xy 269.83906 -24.56967) (xy 269.784217 -24.55954)
			(xy 269.731433 -24.541533) (xy 269.681833 -24.516032) (xy 269.636475 -24.483581) (xy 269.596326 -24.444872)
			(xy 269.56224 -24.400729) (xy 269.534944 -24.352094) (xy 269.515021 -24.300003) (xy 269.502895 -24.245566)
			(xy 269.498824 -24.189944) (xy 266.413172 -24.189944) (xy 266.405621 -24.241256) (xy 266.389553 -24.294663)
			(xy 266.365881 -24.34516) (xy 266.335108 -24.391673) (xy 266.297891 -24.43321) (xy 266.255023 -24.468885)
			(xy 266.207417 -24.497939) (xy 266.156088 -24.519751) (xy 266.102131 -24.533857) (xy 266.046694 -24.539957)
			(xy 265.99096 -24.53792) (xy 265.936117 -24.52779) (xy 265.883333 -24.509783) (xy 265.833733 -24.484282)
			(xy 265.788375 -24.451831) (xy 265.748226 -24.413122) (xy 265.71414 -24.368979) (xy 265.686844 -24.320344)
			(xy 265.666921 -24.268253) (xy 265.654795 -24.213816) (xy 265.650724 -24.158194) (xy 260.987786 -24.158194)
			(xy 260.957166 -24.204475) (xy 260.919949 -24.246012) (xy 260.877081 -24.281687) (xy 260.829475 -24.310741)
			(xy 260.778146 -24.332553) (xy 260.724189 -24.346659) (xy 260.668752 -24.352759) (xy 260.613018 -24.350722)
			(xy 260.558175 -24.340592) (xy 260.505391 -24.322585) (xy 260.455791 -24.297084) (xy 260.410433 -24.264633)
			(xy 260.370284 -24.225924) (xy 260.336198 -24.181781) (xy 260.308902 -24.133146) (xy 260.288979 -24.081055)
			(xy 260.276853 -24.026618) (xy 260.272782 -23.970996) (xy 260.04349 -23.970996) (xy 260.043421 -23.974752)
			(xy 260.035301 -24.029928) (xy 260.019233 -24.083335) (xy 259.995561 -24.133832) (xy 259.964788 -24.180345)
			(xy 259.927571 -24.221882) (xy 259.884703 -24.257557) (xy 259.837097 -24.286611) (xy 259.785768 -24.308423)
			(xy 259.731811 -24.322529) (xy 259.676374 -24.328629) (xy 259.62064 -24.326592) (xy 259.565797 -24.316462)
			(xy 259.513013 -24.298455) (xy 259.463413 -24.272954) (xy 259.418055 -24.240503) (xy 259.377906 -24.201794)
			(xy 259.34382 -24.157651) (xy 259.316524 -24.109016) (xy 259.296601 -24.056925) (xy 259.284475 -24.002488)
			(xy 259.280404 -23.946866) (xy 259.04055 -23.946866) (xy 259.040884 -23.965154) (xy 259.040375 -23.99304)
			(xy 259.032255 -24.048216) (xy 259.016187 -24.101623) (xy 258.992515 -24.15212) (xy 258.961742 -24.198633)
			(xy 258.924525 -24.24017) (xy 258.881657 -24.275845) (xy 258.834051 -24.304899) (xy 258.782722 -24.326711)
			(xy 258.728765 -24.340817) (xy 258.673328 -24.346917) (xy 258.617594 -24.34488) (xy 258.562751 -24.33475)
			(xy 258.509967 -24.316743) (xy 258.460367 -24.291242) (xy 258.415009 -24.258791) (xy 258.37486 -24.220082)
			(xy 258.340774 -24.175939) (xy 258.313478 -24.127304) (xy 258.293555 -24.075213) (xy 258.281429 -24.020776)
			(xy 258.277358 -23.965154) (xy 248.737829 -23.965154) (xy 248.735897 -23.965659) (xy 248.68046 -23.971759)
			(xy 248.624726 -23.969722) (xy 248.569883 -23.959592) (xy 248.517099 -23.941585) (xy 248.467499 -23.916084)
			(xy 248.422141 -23.883633) (xy 248.381992 -23.844924) (xy 248.347906 -23.800781) (xy 248.32061 -23.752146)
			(xy 248.300687 -23.700055) (xy 248.288561 -23.645618) (xy 248.28449 -23.589996) (xy 222.575686 -23.589996)
			(xy 222.624189 -23.595333) (xy 222.678146 -23.609439) (xy 222.729475 -23.631251) (xy 222.777081 -23.660305)
			(xy 222.819949 -23.69598) (xy 222.857166 -23.737517) (xy 222.887939 -23.78403) (xy 222.911611 -23.834527)
			(xy 222.927679 -23.887934) (xy 222.935799 -23.94311) (xy 222.936308 -23.970996) (xy 222.935799 -23.998882)
			(xy 222.927679 -24.054058) (xy 222.911611 -24.107465) (xy 222.887939 -24.157962) (xy 222.887786 -24.158194)
			(xy 239.650776 -24.158194) (xy 239.654847 -24.102572) (xy 239.666973 -24.048135) (xy 239.686896 -23.996044)
			(xy 239.714192 -23.947409) (xy 239.748278 -23.903266) (xy 239.788427 -23.864557) (xy 239.833785 -23.832106)
			(xy 239.883385 -23.806605) (xy 239.936169 -23.788598) (xy 239.991012 -23.778468) (xy 240.046746 -23.776431)
			(xy 240.102183 -23.782531) (xy 240.15614 -23.796637) (xy 240.207469 -23.818449) (xy 240.255075 -23.847503)
			(xy 240.297943 -23.883178) (xy 240.33516 -23.924715) (xy 240.365933 -23.971228) (xy 240.389605 -24.021725)
			(xy 240.405673 -24.075132) (xy 240.413793 -24.130308) (xy 240.414302 -24.158194) (xy 240.413793 -24.18608)
			(xy 240.413224 -24.189944) (xy 243.498876 -24.189944) (xy 243.502947 -24.134322) (xy 243.515073 -24.079885)
			(xy 243.534996 -24.027794) (xy 243.562292 -23.979159) (xy 243.596378 -23.935016) (xy 243.636527 -23.896307)
			(xy 243.681885 -23.863856) (xy 243.731485 -23.838355) (xy 243.784269 -23.820348) (xy 243.839112 -23.810218)
			(xy 243.894846 -23.808181) (xy 243.950283 -23.814281) (xy 244.00424 -23.828387) (xy 244.055569 -23.850199)
			(xy 244.103175 -23.879253) (xy 244.146043 -23.914928) (xy 244.18326 -23.956465) (xy 244.214033 -24.002978)
			(xy 244.237705 -24.053475) (xy 244.253773 -24.106882) (xy 244.261893 -24.162058) (xy 244.262402 -24.189944)
			(xy 246.021858 -24.189944) (xy 246.025929 -24.134322) (xy 246.038055 -24.079885) (xy 246.057978 -24.027794)
			(xy 246.085274 -23.979159) (xy 246.11936 -23.935016) (xy 246.159509 -23.896307) (xy 246.204867 -23.863856)
			(xy 246.254467 -23.838355) (xy 246.307251 -23.820348) (xy 246.362094 -23.810218) (xy 246.417828 -23.808181)
			(xy 246.473265 -23.814281) (xy 246.527222 -23.828387) (xy 246.578551 -23.850199) (xy 246.626157 -23.879253)
			(xy 246.669025 -23.914928) (xy 246.706242 -23.956465) (xy 246.737015 -24.002978) (xy 246.760687 -24.053475)
			(xy 246.776755 -24.106882) (xy 246.784875 -24.162058) (xy 246.785384 -24.189944) (xy 246.784875 -24.21783)
			(xy 246.776755 -24.273006) (xy 246.760687 -24.326413) (xy 246.737015 -24.37691) (xy 246.706242 -24.423423)
			(xy 246.669025 -24.46496) (xy 246.626157 -24.500635) (xy 246.578551 -24.529689) (xy 246.527222 -24.551501)
			(xy 246.473265 -24.565607) (xy 246.417828 -24.571707) (xy 246.362094 -24.56967) (xy 246.307251 -24.55954)
			(xy 246.254467 -24.541533) (xy 246.204867 -24.516032) (xy 246.159509 -24.483581) (xy 246.11936 -24.444872)
			(xy 246.085274 -24.400729) (xy 246.057978 -24.352094) (xy 246.038055 -24.300003) (xy 246.025929 -24.245566)
			(xy 246.021858 -24.189944) (xy 244.262402 -24.189944) (xy 244.261893 -24.21783) (xy 244.253773 -24.273006)
			(xy 244.237705 -24.326413) (xy 244.214033 -24.37691) (xy 244.18326 -24.423423) (xy 244.146043 -24.46496)
			(xy 244.103175 -24.500635) (xy 244.055569 -24.529689) (xy 244.00424 -24.551501) (xy 243.950283 -24.565607)
			(xy 243.894846 -24.571707) (xy 243.839112 -24.56967) (xy 243.784269 -24.55954) (xy 243.731485 -24.541533)
			(xy 243.681885 -24.516032) (xy 243.636527 -24.483581) (xy 243.596378 -24.444872) (xy 243.562292 -24.400729)
			(xy 243.534996 -24.352094) (xy 243.515073 -24.300003) (xy 243.502947 -24.245566) (xy 243.498876 -24.189944)
			(xy 240.413224 -24.189944) (xy 240.405673 -24.241256) (xy 240.389605 -24.294663) (xy 240.365933 -24.34516)
			(xy 240.33516 -24.391673) (xy 240.297943 -24.43321) (xy 240.255075 -24.468885) (xy 240.207469 -24.497939)
			(xy 240.15614 -24.519751) (xy 240.102183 -24.533857) (xy 240.046746 -24.539957) (xy 239.991012 -24.53792)
			(xy 239.936169 -24.52779) (xy 239.883385 -24.509783) (xy 239.833785 -24.484282) (xy 239.788427 -24.451831)
			(xy 239.748278 -24.413122) (xy 239.714192 -24.368979) (xy 239.686896 -24.320344) (xy 239.666973 -24.268253)
			(xy 239.654847 -24.213816) (xy 239.650776 -24.158194) (xy 222.887786 -24.158194) (xy 222.857166 -24.204475)
			(xy 222.819949 -24.246012) (xy 222.777081 -24.281687) (xy 222.729475 -24.310741) (xy 222.678146 -24.332553)
			(xy 222.624189 -24.346659) (xy 222.568752 -24.352759) (xy 222.513018 -24.350722) (xy 222.458175 -24.340592)
			(xy 222.405391 -24.322585) (xy 222.355791 -24.297084) (xy 222.310433 -24.264633) (xy 222.270284 -24.225924)
			(xy 222.236198 -24.181781) (xy 222.208902 -24.133146) (xy 222.188979 -24.081055) (xy 222.176853 -24.026618)
			(xy 222.172782 -23.970996) (xy 221.94349 -23.970996) (xy 221.943421 -23.974752) (xy 221.935301 -24.029928)
			(xy 221.919233 -24.083335) (xy 221.895561 -24.133832) (xy 221.864788 -24.180345) (xy 221.827571 -24.221882)
			(xy 221.784703 -24.257557) (xy 221.737097 -24.286611) (xy 221.685768 -24.308423) (xy 221.631811 -24.322529)
			(xy 221.576374 -24.328629) (xy 221.52064 -24.326592) (xy 221.465797 -24.316462) (xy 221.413013 -24.298455)
			(xy 221.363413 -24.272954) (xy 221.318055 -24.240503) (xy 221.277906 -24.201794) (xy 221.24382 -24.157651)
			(xy 221.216524 -24.109016) (xy 221.196601 -24.056925) (xy 221.184475 -24.002488) (xy 221.180404 -23.946866)
			(xy 220.94055 -23.946866) (xy 220.940884 -23.965154) (xy 220.940375 -23.99304) (xy 220.932255 -24.048216)
			(xy 220.916187 -24.101623) (xy 220.892515 -24.15212) (xy 220.861742 -24.198633) (xy 220.824525 -24.24017)
			(xy 220.781657 -24.275845) (xy 220.734051 -24.304899) (xy 220.682722 -24.326711) (xy 220.628765 -24.340817)
			(xy 220.573328 -24.346917) (xy 220.517594 -24.34488) (xy 220.462751 -24.33475) (xy 220.409967 -24.316743)
			(xy 220.360367 -24.291242) (xy 220.315009 -24.258791) (xy 220.27486 -24.220082) (xy 220.240774 -24.175939)
			(xy 220.213478 -24.127304) (xy 220.193555 -24.075213) (xy 220.181429 -24.020776) (xy 220.177358 -23.965154)
			(xy 210.637829 -23.965154) (xy 210.635897 -23.965659) (xy 210.58046 -23.971759) (xy 210.524726 -23.969722)
			(xy 210.469883 -23.959592) (xy 210.417099 -23.941585) (xy 210.367499 -23.916084) (xy 210.322141 -23.883633)
			(xy 210.281992 -23.844924) (xy 210.247906 -23.800781) (xy 210.22061 -23.752146) (xy 210.200687 -23.700055)
			(xy 210.188561 -23.645618) (xy 210.18449 -23.589996) (xy 196.575738 -23.589996) (xy 196.624241 -23.595333)
			(xy 196.678198 -23.609439) (xy 196.729527 -23.631251) (xy 196.777133 -23.660305) (xy 196.820001 -23.69598)
			(xy 196.857218 -23.737517) (xy 196.887991 -23.78403) (xy 196.911663 -23.834527) (xy 196.927731 -23.887934)
			(xy 196.935851 -23.94311) (xy 196.93636 -23.970996) (xy 196.935851 -23.998882) (xy 196.927731 -24.054058)
			(xy 196.911663 -24.107465) (xy 196.887991 -24.157962) (xy 196.887838 -24.158194) (xy 201.550776 -24.158194)
			(xy 201.554847 -24.102572) (xy 201.566973 -24.048135) (xy 201.586896 -23.996044) (xy 201.614192 -23.947409)
			(xy 201.648278 -23.903266) (xy 201.688427 -23.864557) (xy 201.733785 -23.832106) (xy 201.783385 -23.806605)
			(xy 201.836169 -23.788598) (xy 201.891012 -23.778468) (xy 201.946746 -23.776431) (xy 202.002183 -23.782531)
			(xy 202.05614 -23.796637) (xy 202.107469 -23.818449) (xy 202.155075 -23.847503) (xy 202.197943 -23.883178)
			(xy 202.23516 -23.924715) (xy 202.265933 -23.971228) (xy 202.289605 -24.021725) (xy 202.305673 -24.075132)
			(xy 202.313793 -24.130308) (xy 202.314302 -24.158194) (xy 202.313793 -24.18608) (xy 202.313224 -24.189944)
			(xy 205.398876 -24.189944) (xy 205.402947 -24.134322) (xy 205.415073 -24.079885) (xy 205.434996 -24.027794)
			(xy 205.462292 -23.979159) (xy 205.496378 -23.935016) (xy 205.536527 -23.896307) (xy 205.581885 -23.863856)
			(xy 205.631485 -23.838355) (xy 205.684269 -23.820348) (xy 205.739112 -23.810218) (xy 205.794846 -23.808181)
			(xy 205.850283 -23.814281) (xy 205.90424 -23.828387) (xy 205.955569 -23.850199) (xy 206.003175 -23.879253)
			(xy 206.046043 -23.914928) (xy 206.08326 -23.956465) (xy 206.114033 -24.002978) (xy 206.137705 -24.053475)
			(xy 206.153773 -24.106882) (xy 206.161893 -24.162058) (xy 206.162402 -24.189944) (xy 207.921858 -24.189944)
			(xy 207.925929 -24.134322) (xy 207.938055 -24.079885) (xy 207.957978 -24.027794) (xy 207.985274 -23.979159)
			(xy 208.01936 -23.935016) (xy 208.059509 -23.896307) (xy 208.104867 -23.863856) (xy 208.154467 -23.838355)
			(xy 208.207251 -23.820348) (xy 208.262094 -23.810218) (xy 208.317828 -23.808181) (xy 208.373265 -23.814281)
			(xy 208.427222 -23.828387) (xy 208.478551 -23.850199) (xy 208.526157 -23.879253) (xy 208.569025 -23.914928)
			(xy 208.606242 -23.956465) (xy 208.637015 -24.002978) (xy 208.660687 -24.053475) (xy 208.676755 -24.106882)
			(xy 208.684875 -24.162058) (xy 208.685384 -24.189944) (xy 208.684875 -24.21783) (xy 208.676755 -24.273006)
			(xy 208.660687 -24.326413) (xy 208.637015 -24.37691) (xy 208.606242 -24.423423) (xy 208.569025 -24.46496)
			(xy 208.526157 -24.500635) (xy 208.478551 -24.529689) (xy 208.427222 -24.551501) (xy 208.373265 -24.565607)
			(xy 208.317828 -24.571707) (xy 208.262094 -24.56967) (xy 208.207251 -24.55954) (xy 208.154467 -24.541533)
			(xy 208.104867 -24.516032) (xy 208.059509 -24.483581) (xy 208.01936 -24.444872) (xy 207.985274 -24.400729)
			(xy 207.957978 -24.352094) (xy 207.938055 -24.300003) (xy 207.925929 -24.245566) (xy 207.921858 -24.189944)
			(xy 206.162402 -24.189944) (xy 206.161893 -24.21783) (xy 206.153773 -24.273006) (xy 206.137705 -24.326413)
			(xy 206.114033 -24.37691) (xy 206.08326 -24.423423) (xy 206.046043 -24.46496) (xy 206.003175 -24.500635)
			(xy 205.955569 -24.529689) (xy 205.90424 -24.551501) (xy 205.850283 -24.565607) (xy 205.794846 -24.571707)
			(xy 205.739112 -24.56967) (xy 205.684269 -24.55954) (xy 205.631485 -24.541533) (xy 205.581885 -24.516032)
			(xy 205.536527 -24.483581) (xy 205.496378 -24.444872) (xy 205.462292 -24.400729) (xy 205.434996 -24.352094)
			(xy 205.415073 -24.300003) (xy 205.402947 -24.245566) (xy 205.398876 -24.189944) (xy 202.313224 -24.189944)
			(xy 202.305673 -24.241256) (xy 202.289605 -24.294663) (xy 202.265933 -24.34516) (xy 202.23516 -24.391673)
			(xy 202.197943 -24.43321) (xy 202.155075 -24.468885) (xy 202.107469 -24.497939) (xy 202.05614 -24.519751)
			(xy 202.002183 -24.533857) (xy 201.946746 -24.539957) (xy 201.891012 -24.53792) (xy 201.836169 -24.52779)
			(xy 201.783385 -24.509783) (xy 201.733785 -24.484282) (xy 201.688427 -24.451831) (xy 201.648278 -24.413122)
			(xy 201.614192 -24.368979) (xy 201.586896 -24.320344) (xy 201.566973 -24.268253) (xy 201.554847 -24.213816)
			(xy 201.550776 -24.158194) (xy 196.887838 -24.158194) (xy 196.857218 -24.204475) (xy 196.820001 -24.246012)
			(xy 196.777133 -24.281687) (xy 196.729527 -24.310741) (xy 196.678198 -24.332553) (xy 196.624241 -24.346659)
			(xy 196.568804 -24.352759) (xy 196.51307 -24.350722) (xy 196.458227 -24.340592) (xy 196.405443 -24.322585)
			(xy 196.355843 -24.297084) (xy 196.310485 -24.264633) (xy 196.270336 -24.225924) (xy 196.23625 -24.181781)
			(xy 196.208954 -24.133146) (xy 196.189031 -24.081055) (xy 196.176905 -24.026618) (xy 196.172834 -23.970996)
			(xy 195.943542 -23.970996) (xy 195.943473 -23.974752) (xy 195.935353 -24.029928) (xy 195.919285 -24.083335)
			(xy 195.895613 -24.133832) (xy 195.86484 -24.180345) (xy 195.827623 -24.221882) (xy 195.784755 -24.257557)
			(xy 195.737149 -24.286611) (xy 195.68582 -24.308423) (xy 195.631863 -24.322529) (xy 195.576426 -24.328629)
			(xy 195.520692 -24.326592) (xy 195.465849 -24.316462) (xy 195.413065 -24.298455) (xy 195.363465 -24.272954)
			(xy 195.318107 -24.240503) (xy 195.277958 -24.201794) (xy 195.243872 -24.157651) (xy 195.216576 -24.109016)
			(xy 195.196653 -24.056925) (xy 195.184527 -24.002488) (xy 195.180456 -23.946866) (xy 194.940602 -23.946866)
			(xy 194.940936 -23.965154) (xy 194.940427 -23.99304) (xy 194.932307 -24.048216) (xy 194.916239 -24.101623)
			(xy 194.892567 -24.15212) (xy 194.861794 -24.198633) (xy 194.824577 -24.24017) (xy 194.781709 -24.275845)
			(xy 194.734103 -24.304899) (xy 194.682774 -24.326711) (xy 194.628817 -24.340817) (xy 194.57338 -24.346917)
			(xy 194.517646 -24.34488) (xy 194.462803 -24.33475) (xy 194.410019 -24.316743) (xy 194.360419 -24.291242)
			(xy 194.315061 -24.258791) (xy 194.274912 -24.220082) (xy 194.240826 -24.175939) (xy 194.21353 -24.127304)
			(xy 194.193607 -24.075213) (xy 194.181481 -24.020776) (xy 194.17741 -23.965154) (xy 184.637881 -23.965154)
			(xy 184.635949 -23.965659) (xy 184.580512 -23.971759) (xy 184.524778 -23.969722) (xy 184.469935 -23.959592)
			(xy 184.417151 -23.941585) (xy 184.367551 -23.916084) (xy 184.322193 -23.883633) (xy 184.282044 -23.844924)
			(xy 184.247958 -23.800781) (xy 184.220662 -23.752146) (xy 184.200739 -23.700055) (xy 184.188613 -23.645618)
			(xy 184.184542 -23.589996) (xy 170.57579 -23.589996) (xy 170.624293 -23.595333) (xy 170.67825 -23.609439)
			(xy 170.729579 -23.631251) (xy 170.777185 -23.660305) (xy 170.820053 -23.69598) (xy 170.85727 -23.737517)
			(xy 170.888043 -23.78403) (xy 170.911715 -23.834527) (xy 170.927783 -23.887934) (xy 170.935903 -23.94311)
			(xy 170.936412 -23.970996) (xy 170.935903 -23.998882) (xy 170.927783 -24.054058) (xy 170.911715 -24.107465)
			(xy 170.888043 -24.157962) (xy 170.88789 -24.158194) (xy 175.550828 -24.158194) (xy 175.554899 -24.102572)
			(xy 175.567025 -24.048135) (xy 175.586948 -23.996044) (xy 175.614244 -23.947409) (xy 175.64833 -23.903266)
			(xy 175.688479 -23.864557) (xy 175.733837 -23.832106) (xy 175.783437 -23.806605) (xy 175.836221 -23.788598)
			(xy 175.891064 -23.778468) (xy 175.946798 -23.776431) (xy 176.002235 -23.782531) (xy 176.056192 -23.796637)
			(xy 176.107521 -23.818449) (xy 176.155127 -23.847503) (xy 176.197995 -23.883178) (xy 176.235212 -23.924715)
			(xy 176.265985 -23.971228) (xy 176.289657 -24.021725) (xy 176.305725 -24.075132) (xy 176.313845 -24.130308)
			(xy 176.314354 -24.158194) (xy 176.313845 -24.18608) (xy 176.313276 -24.189944) (xy 179.398928 -24.189944)
			(xy 179.402999 -24.134322) (xy 179.415125 -24.079885) (xy 179.435048 -24.027794) (xy 179.462344 -23.979159)
			(xy 179.49643 -23.935016) (xy 179.536579 -23.896307) (xy 179.581937 -23.863856) (xy 179.631537 -23.838355)
			(xy 179.684321 -23.820348) (xy 179.739164 -23.810218) (xy 179.794898 -23.808181) (xy 179.850335 -23.814281)
			(xy 179.904292 -23.828387) (xy 179.955621 -23.850199) (xy 180.003227 -23.879253) (xy 180.046095 -23.914928)
			(xy 180.083312 -23.956465) (xy 180.114085 -24.002978) (xy 180.137757 -24.053475) (xy 180.153825 -24.106882)
			(xy 180.161945 -24.162058) (xy 180.162454 -24.189944) (xy 181.92191 -24.189944) (xy 181.925981 -24.134322)
			(xy 181.938107 -24.079885) (xy 181.95803 -24.027794) (xy 181.985326 -23.979159) (xy 182.019412 -23.935016)
			(xy 182.059561 -23.896307) (xy 182.104919 -23.863856) (xy 182.154519 -23.838355) (xy 182.207303 -23.820348)
			(xy 182.262146 -23.810218) (xy 182.31788 -23.808181) (xy 182.373317 -23.814281) (xy 182.427274 -23.828387)
			(xy 182.478603 -23.850199) (xy 182.526209 -23.879253) (xy 182.569077 -23.914928) (xy 182.606294 -23.956465)
			(xy 182.637067 -24.002978) (xy 182.660739 -24.053475) (xy 182.676807 -24.106882) (xy 182.684927 -24.162058)
			(xy 182.685436 -24.189944) (xy 182.684927 -24.21783) (xy 182.676807 -24.273006) (xy 182.660739 -24.326413)
			(xy 182.637067 -24.37691) (xy 182.606294 -24.423423) (xy 182.569077 -24.46496) (xy 182.526209 -24.500635)
			(xy 182.478603 -24.529689) (xy 182.427274 -24.551501) (xy 182.373317 -24.565607) (xy 182.31788 -24.571707)
			(xy 182.262146 -24.56967) (xy 182.207303 -24.55954) (xy 182.154519 -24.541533) (xy 182.104919 -24.516032)
			(xy 182.059561 -24.483581) (xy 182.019412 -24.444872) (xy 181.985326 -24.400729) (xy 181.95803 -24.352094)
			(xy 181.938107 -24.300003) (xy 181.925981 -24.245566) (xy 181.92191 -24.189944) (xy 180.162454 -24.189944)
			(xy 180.161945 -24.21783) (xy 180.153825 -24.273006) (xy 180.137757 -24.326413) (xy 180.114085 -24.37691)
			(xy 180.083312 -24.423423) (xy 180.046095 -24.46496) (xy 180.003227 -24.500635) (xy 179.955621 -24.529689)
			(xy 179.904292 -24.551501) (xy 179.850335 -24.565607) (xy 179.794898 -24.571707) (xy 179.739164 -24.56967)
			(xy 179.684321 -24.55954) (xy 179.631537 -24.541533) (xy 179.581937 -24.516032) (xy 179.536579 -24.483581)
			(xy 179.49643 -24.444872) (xy 179.462344 -24.400729) (xy 179.435048 -24.352094) (xy 179.415125 -24.300003)
			(xy 179.402999 -24.245566) (xy 179.398928 -24.189944) (xy 176.313276 -24.189944) (xy 176.305725 -24.241256)
			(xy 176.289657 -24.294663) (xy 176.265985 -24.34516) (xy 176.235212 -24.391673) (xy 176.197995 -24.43321)
			(xy 176.155127 -24.468885) (xy 176.107521 -24.497939) (xy 176.056192 -24.519751) (xy 176.002235 -24.533857)
			(xy 175.946798 -24.539957) (xy 175.891064 -24.53792) (xy 175.836221 -24.52779) (xy 175.783437 -24.509783)
			(xy 175.733837 -24.484282) (xy 175.688479 -24.451831) (xy 175.64833 -24.413122) (xy 175.614244 -24.368979)
			(xy 175.586948 -24.320344) (xy 175.567025 -24.268253) (xy 175.554899 -24.213816) (xy 175.550828 -24.158194)
			(xy 170.88789 -24.158194) (xy 170.85727 -24.204475) (xy 170.820053 -24.246012) (xy 170.777185 -24.281687)
			(xy 170.729579 -24.310741) (xy 170.67825 -24.332553) (xy 170.624293 -24.346659) (xy 170.568856 -24.352759)
			(xy 170.513122 -24.350722) (xy 170.458279 -24.340592) (xy 170.405495 -24.322585) (xy 170.355895 -24.297084)
			(xy 170.310537 -24.264633) (xy 170.270388 -24.225924) (xy 170.236302 -24.181781) (xy 170.209006 -24.133146)
			(xy 170.189083 -24.081055) (xy 170.176957 -24.026618) (xy 170.172886 -23.970996) (xy 169.943594 -23.970996)
			(xy 169.943525 -23.974752) (xy 169.935405 -24.029928) (xy 169.919337 -24.083335) (xy 169.895665 -24.133832)
			(xy 169.864892 -24.180345) (xy 169.827675 -24.221882) (xy 169.784807 -24.257557) (xy 169.737201 -24.286611)
			(xy 169.685872 -24.308423) (xy 169.631915 -24.322529) (xy 169.576478 -24.328629) (xy 169.520744 -24.326592)
			(xy 169.465901 -24.316462) (xy 169.413117 -24.298455) (xy 169.363517 -24.272954) (xy 169.318159 -24.240503)
			(xy 169.27801 -24.201794) (xy 169.243924 -24.157651) (xy 169.216628 -24.109016) (xy 169.196705 -24.056925)
			(xy 169.184579 -24.002488) (xy 169.180508 -23.946866) (xy 168.940654 -23.946866) (xy 168.940988 -23.965154)
			(xy 168.940479 -23.99304) (xy 168.932359 -24.048216) (xy 168.916291 -24.101623) (xy 168.892619 -24.15212)
			(xy 168.861846 -24.198633) (xy 168.824629 -24.24017) (xy 168.781761 -24.275845) (xy 168.734155 -24.304899)
			(xy 168.682826 -24.326711) (xy 168.628869 -24.340817) (xy 168.573432 -24.346917) (xy 168.517698 -24.34488)
			(xy 168.462855 -24.33475) (xy 168.410071 -24.316743) (xy 168.360471 -24.291242) (xy 168.315113 -24.258791)
			(xy 168.274964 -24.220082) (xy 168.240878 -24.175939) (xy 168.213582 -24.127304) (xy 168.193659 -24.075213)
			(xy 168.181533 -24.020776) (xy 168.177462 -23.965154) (xy 158.637933 -23.965154) (xy 158.636001 -23.965659)
			(xy 158.580564 -23.971759) (xy 158.52483 -23.969722) (xy 158.469987 -23.959592) (xy 158.417203 -23.941585)
			(xy 158.367603 -23.916084) (xy 158.322245 -23.883633) (xy 158.282096 -23.844924) (xy 158.24801 -23.800781)
			(xy 158.220714 -23.752146) (xy 158.200791 -23.700055) (xy 158.188665 -23.645618) (xy 158.184594 -23.589996)
			(xy 144.575842 -23.589996) (xy 144.624345 -23.595333) (xy 144.678302 -23.609439) (xy 144.729631 -23.631251)
			(xy 144.777237 -23.660305) (xy 144.820105 -23.69598) (xy 144.857322 -23.737517) (xy 144.888095 -23.78403)
			(xy 144.911767 -23.834527) (xy 144.927835 -23.887934) (xy 144.935955 -23.94311) (xy 144.936464 -23.970996)
			(xy 144.935955 -23.998882) (xy 144.927835 -24.054058) (xy 144.911767 -24.107465) (xy 144.888095 -24.157962)
			(xy 144.887942 -24.158194) (xy 149.55088 -24.158194) (xy 149.554951 -24.102572) (xy 149.567077 -24.048135)
			(xy 149.587 -23.996044) (xy 149.614296 -23.947409) (xy 149.648382 -23.903266) (xy 149.688531 -23.864557)
			(xy 149.733889 -23.832106) (xy 149.783489 -23.806605) (xy 149.836273 -23.788598) (xy 149.891116 -23.778468)
			(xy 149.94685 -23.776431) (xy 150.002287 -23.782531) (xy 150.056244 -23.796637) (xy 150.107573 -23.818449)
			(xy 150.155179 -23.847503) (xy 150.198047 -23.883178) (xy 150.235264 -23.924715) (xy 150.266037 -23.971228)
			(xy 150.289709 -24.021725) (xy 150.305777 -24.075132) (xy 150.313897 -24.130308) (xy 150.314406 -24.158194)
			(xy 150.313897 -24.18608) (xy 150.313328 -24.189944) (xy 153.39898 -24.189944) (xy 153.403051 -24.134322)
			(xy 153.415177 -24.079885) (xy 153.4351 -24.027794) (xy 153.462396 -23.979159) (xy 153.496482 -23.935016)
			(xy 153.536631 -23.896307) (xy 153.581989 -23.863856) (xy 153.631589 -23.838355) (xy 153.684373 -23.820348)
			(xy 153.739216 -23.810218) (xy 153.79495 -23.808181) (xy 153.850387 -23.814281) (xy 153.904344 -23.828387)
			(xy 153.955673 -23.850199) (xy 154.003279 -23.879253) (xy 154.046147 -23.914928) (xy 154.083364 -23.956465)
			(xy 154.114137 -24.002978) (xy 154.137809 -24.053475) (xy 154.153877 -24.106882) (xy 154.161997 -24.162058)
			(xy 154.162506 -24.189944) (xy 155.921962 -24.189944) (xy 155.926033 -24.134322) (xy 155.938159 -24.079885)
			(xy 155.958082 -24.027794) (xy 155.985378 -23.979159) (xy 156.019464 -23.935016) (xy 156.059613 -23.896307)
			(xy 156.104971 -23.863856) (xy 156.154571 -23.838355) (xy 156.207355 -23.820348) (xy 156.262198 -23.810218)
			(xy 156.317932 -23.808181) (xy 156.373369 -23.814281) (xy 156.427326 -23.828387) (xy 156.478655 -23.850199)
			(xy 156.526261 -23.879253) (xy 156.569129 -23.914928) (xy 156.606346 -23.956465) (xy 156.637119 -24.002978)
			(xy 156.660791 -24.053475) (xy 156.676859 -24.106882) (xy 156.684979 -24.162058) (xy 156.685488 -24.189944)
			(xy 156.684979 -24.21783) (xy 156.676859 -24.273006) (xy 156.660791 -24.326413) (xy 156.637119 -24.37691)
			(xy 156.606346 -24.423423) (xy 156.569129 -24.46496) (xy 156.526261 -24.500635) (xy 156.478655 -24.529689)
			(xy 156.427326 -24.551501) (xy 156.373369 -24.565607) (xy 156.317932 -24.571707) (xy 156.262198 -24.56967)
			(xy 156.207355 -24.55954) (xy 156.154571 -24.541533) (xy 156.104971 -24.516032) (xy 156.059613 -24.483581)
			(xy 156.019464 -24.444872) (xy 155.985378 -24.400729) (xy 155.958082 -24.352094) (xy 155.938159 -24.300003)
			(xy 155.926033 -24.245566) (xy 155.921962 -24.189944) (xy 154.162506 -24.189944) (xy 154.161997 -24.21783)
			(xy 154.153877 -24.273006) (xy 154.137809 -24.326413) (xy 154.114137 -24.37691) (xy 154.083364 -24.423423)
			(xy 154.046147 -24.46496) (xy 154.003279 -24.500635) (xy 153.955673 -24.529689) (xy 153.904344 -24.551501)
			(xy 153.850387 -24.565607) (xy 153.79495 -24.571707) (xy 153.739216 -24.56967) (xy 153.684373 -24.55954)
			(xy 153.631589 -24.541533) (xy 153.581989 -24.516032) (xy 153.536631 -24.483581) (xy 153.496482 -24.444872)
			(xy 153.462396 -24.400729) (xy 153.4351 -24.352094) (xy 153.415177 -24.300003) (xy 153.403051 -24.245566)
			(xy 153.39898 -24.189944) (xy 150.313328 -24.189944) (xy 150.305777 -24.241256) (xy 150.289709 -24.294663)
			(xy 150.266037 -24.34516) (xy 150.235264 -24.391673) (xy 150.198047 -24.43321) (xy 150.155179 -24.468885)
			(xy 150.107573 -24.497939) (xy 150.056244 -24.519751) (xy 150.002287 -24.533857) (xy 149.94685 -24.539957)
			(xy 149.891116 -24.53792) (xy 149.836273 -24.52779) (xy 149.783489 -24.509783) (xy 149.733889 -24.484282)
			(xy 149.688531 -24.451831) (xy 149.648382 -24.413122) (xy 149.614296 -24.368979) (xy 149.587 -24.320344)
			(xy 149.567077 -24.268253) (xy 149.554951 -24.213816) (xy 149.55088 -24.158194) (xy 144.887942 -24.158194)
			(xy 144.857322 -24.204475) (xy 144.820105 -24.246012) (xy 144.777237 -24.281687) (xy 144.729631 -24.310741)
			(xy 144.678302 -24.332553) (xy 144.624345 -24.346659) (xy 144.568908 -24.352759) (xy 144.513174 -24.350722)
			(xy 144.458331 -24.340592) (xy 144.405547 -24.322585) (xy 144.355947 -24.297084) (xy 144.310589 -24.264633)
			(xy 144.27044 -24.225924) (xy 144.236354 -24.181781) (xy 144.209058 -24.133146) (xy 144.189135 -24.081055)
			(xy 144.177009 -24.026618) (xy 144.172938 -23.970996) (xy 143.943646 -23.970996) (xy 143.943577 -23.974752)
			(xy 143.935457 -24.029928) (xy 143.919389 -24.083335) (xy 143.895717 -24.133832) (xy 143.864944 -24.180345)
			(xy 143.827727 -24.221882) (xy 143.784859 -24.257557) (xy 143.737253 -24.286611) (xy 143.685924 -24.308423)
			(xy 143.631967 -24.322529) (xy 143.57653 -24.328629) (xy 143.520796 -24.326592) (xy 143.465953 -24.316462)
			(xy 143.413169 -24.298455) (xy 143.363569 -24.272954) (xy 143.318211 -24.240503) (xy 143.278062 -24.201794)
			(xy 143.243976 -24.157651) (xy 143.21668 -24.109016) (xy 143.196757 -24.056925) (xy 143.184631 -24.002488)
			(xy 143.18056 -23.946866) (xy 142.940706 -23.946866) (xy 142.94104 -23.965154) (xy 142.940531 -23.99304)
			(xy 142.932411 -24.048216) (xy 142.916343 -24.101623) (xy 142.892671 -24.15212) (xy 142.861898 -24.198633)
			(xy 142.824681 -24.24017) (xy 142.781813 -24.275845) (xy 142.734207 -24.304899) (xy 142.682878 -24.326711)
			(xy 142.628921 -24.340817) (xy 142.573484 -24.346917) (xy 142.51775 -24.34488) (xy 142.462907 -24.33475)
			(xy 142.410123 -24.316743) (xy 142.360523 -24.291242) (xy 142.315165 -24.258791) (xy 142.275016 -24.220082)
			(xy 142.24093 -24.175939) (xy 142.213634 -24.127304) (xy 142.193711 -24.075213) (xy 142.181585 -24.020776)
			(xy 142.177514 -23.965154) (xy 132.637985 -23.965154) (xy 132.636053 -23.965659) (xy 132.580616 -23.971759)
			(xy 132.524882 -23.969722) (xy 132.470039 -23.959592) (xy 132.417255 -23.941585) (xy 132.367655 -23.916084)
			(xy 132.322297 -23.883633) (xy 132.282148 -23.844924) (xy 132.248062 -23.800781) (xy 132.220766 -23.752146)
			(xy 132.200843 -23.700055) (xy 132.188717 -23.645618) (xy 132.184646 -23.589996) (xy 94.847918 -23.589996)
			(xy 94.847409 -23.617882) (xy 94.839289 -23.673058) (xy 94.823221 -23.726465) (xy 94.799549 -23.776962)
			(xy 94.768776 -23.823475) (xy 94.731559 -23.865012) (xy 94.688691 -23.900687) (xy 94.641085 -23.929741)
			(xy 94.589756 -23.951553) (xy 94.535799 -23.965659) (xy 94.480362 -23.971759) (xy 94.424628 -23.969722)
			(xy 94.369785 -23.959592) (xy 94.317001 -23.941585) (xy 94.267401 -23.916084) (xy 94.222043 -23.883633)
			(xy 94.181894 -23.844924) (xy 94.147808 -23.800781) (xy 94.120512 -23.752146) (xy 94.100589 -23.700055)
			(xy 94.088463 -23.645618) (xy 94.084392 -23.589996) (xy 80.47564 -23.589996) (xy 80.524143 -23.595333)
			(xy 80.5781 -23.609439) (xy 80.629429 -23.631251) (xy 80.677035 -23.660305) (xy 80.719903 -23.69598)
			(xy 80.75712 -23.737517) (xy 80.787893 -23.78403) (xy 80.811565 -23.834527) (xy 80.827633 -23.887934)
			(xy 80.835753 -23.94311) (xy 80.836262 -23.970996) (xy 80.835753 -23.998882) (xy 80.827633 -24.054058)
			(xy 80.811565 -24.107465) (xy 80.787893 -24.157962) (xy 80.78774 -24.158194) (xy 85.450678 -24.158194)
			(xy 85.454749 -24.102572) (xy 85.466875 -24.048135) (xy 85.486798 -23.996044) (xy 85.514094 -23.947409)
			(xy 85.54818 -23.903266) (xy 85.588329 -23.864557) (xy 85.633687 -23.832106) (xy 85.683287 -23.806605)
			(xy 85.736071 -23.788598) (xy 85.790914 -23.778468) (xy 85.846648 -23.776431) (xy 85.902085 -23.782531)
			(xy 85.956042 -23.796637) (xy 86.007371 -23.818449) (xy 86.054977 -23.847503) (xy 86.097845 -23.883178)
			(xy 86.135062 -23.924715) (xy 86.165835 -23.971228) (xy 86.189507 -24.021725) (xy 86.205575 -24.075132)
			(xy 86.213695 -24.130308) (xy 86.214204 -24.158194) (xy 86.213695 -24.18608) (xy 86.213126 -24.189944)
			(xy 89.298778 -24.189944) (xy 89.302849 -24.134322) (xy 89.314975 -24.079885) (xy 89.334898 -24.027794)
			(xy 89.362194 -23.979159) (xy 89.39628 -23.935016) (xy 89.436429 -23.896307) (xy 89.481787 -23.863856)
			(xy 89.531387 -23.838355) (xy 89.584171 -23.820348) (xy 89.639014 -23.810218) (xy 89.694748 -23.808181)
			(xy 89.750185 -23.814281) (xy 89.804142 -23.828387) (xy 89.855471 -23.850199) (xy 89.903077 -23.879253)
			(xy 89.945945 -23.914928) (xy 89.983162 -23.956465) (xy 90.013935 -24.002978) (xy 90.037607 -24.053475)
			(xy 90.053675 -24.106882) (xy 90.061795 -24.162058) (xy 90.062304 -24.189944) (xy 91.82176 -24.189944)
			(xy 91.825831 -24.134322) (xy 91.837957 -24.079885) (xy 91.85788 -24.027794) (xy 91.885176 -23.979159)
			(xy 91.919262 -23.935016) (xy 91.959411 -23.896307) (xy 92.004769 -23.863856) (xy 92.054369 -23.838355)
			(xy 92.107153 -23.820348) (xy 92.161996 -23.810218) (xy 92.21773 -23.808181) (xy 92.273167 -23.814281)
			(xy 92.327124 -23.828387) (xy 92.378453 -23.850199) (xy 92.426059 -23.879253) (xy 92.468927 -23.914928)
			(xy 92.506144 -23.956465) (xy 92.536917 -24.002978) (xy 92.560589 -24.053475) (xy 92.576657 -24.106882)
			(xy 92.584208 -24.158194) (xy 123.550932 -24.158194) (xy 123.555003 -24.102572) (xy 123.567129 -24.048135)
			(xy 123.587052 -23.996044) (xy 123.614348 -23.947409) (xy 123.648434 -23.903266) (xy 123.688583 -23.864557)
			(xy 123.733941 -23.832106) (xy 123.783541 -23.806605) (xy 123.836325 -23.788598) (xy 123.891168 -23.778468)
			(xy 123.946902 -23.776431) (xy 124.002339 -23.782531) (xy 124.056296 -23.796637) (xy 124.107625 -23.818449)
			(xy 124.155231 -23.847503) (xy 124.198099 -23.883178) (xy 124.235316 -23.924715) (xy 124.266089 -23.971228)
			(xy 124.289761 -24.021725) (xy 124.305829 -24.075132) (xy 124.313949 -24.130308) (xy 124.314458 -24.158194)
			(xy 124.313949 -24.18608) (xy 124.31338 -24.189944) (xy 127.399032 -24.189944) (xy 127.403103 -24.134322)
			(xy 127.415229 -24.079885) (xy 127.435152 -24.027794) (xy 127.462448 -23.979159) (xy 127.496534 -23.935016)
			(xy 127.536683 -23.896307) (xy 127.582041 -23.863856) (xy 127.631641 -23.838355) (xy 127.684425 -23.820348)
			(xy 127.739268 -23.810218) (xy 127.795002 -23.808181) (xy 127.850439 -23.814281) (xy 127.904396 -23.828387)
			(xy 127.955725 -23.850199) (xy 128.003331 -23.879253) (xy 128.046199 -23.914928) (xy 128.083416 -23.956465)
			(xy 128.114189 -24.002978) (xy 128.137861 -24.053475) (xy 128.153929 -24.106882) (xy 128.162049 -24.162058)
			(xy 128.162558 -24.189944) (xy 129.922014 -24.189944) (xy 129.926085 -24.134322) (xy 129.938211 -24.079885)
			(xy 129.958134 -24.027794) (xy 129.98543 -23.979159) (xy 130.019516 -23.935016) (xy 130.059665 -23.896307)
			(xy 130.105023 -23.863856) (xy 130.154623 -23.838355) (xy 130.207407 -23.820348) (xy 130.26225 -23.810218)
			(xy 130.317984 -23.808181) (xy 130.373421 -23.814281) (xy 130.427378 -23.828387) (xy 130.478707 -23.850199)
			(xy 130.526313 -23.879253) (xy 130.569181 -23.914928) (xy 130.606398 -23.956465) (xy 130.637171 -24.002978)
			(xy 130.660843 -24.053475) (xy 130.676911 -24.106882) (xy 130.685031 -24.162058) (xy 130.68554 -24.189944)
			(xy 130.685031 -24.21783) (xy 130.676911 -24.273006) (xy 130.660843 -24.326413) (xy 130.637171 -24.37691)
			(xy 130.606398 -24.423423) (xy 130.569181 -24.46496) (xy 130.526313 -24.500635) (xy 130.478707 -24.529689)
			(xy 130.427378 -24.551501) (xy 130.373421 -24.565607) (xy 130.317984 -24.571707) (xy 130.26225 -24.56967)
			(xy 130.207407 -24.55954) (xy 130.154623 -24.541533) (xy 130.105023 -24.516032) (xy 130.059665 -24.483581)
			(xy 130.019516 -24.444872) (xy 129.98543 -24.400729) (xy 129.958134 -24.352094) (xy 129.938211 -24.300003)
			(xy 129.926085 -24.245566) (xy 129.922014 -24.189944) (xy 128.162558 -24.189944) (xy 128.162049 -24.21783)
			(xy 128.153929 -24.273006) (xy 128.137861 -24.326413) (xy 128.114189 -24.37691) (xy 128.083416 -24.423423)
			(xy 128.046199 -24.46496) (xy 128.003331 -24.500635) (xy 127.955725 -24.529689) (xy 127.904396 -24.551501)
			(xy 127.850439 -24.565607) (xy 127.795002 -24.571707) (xy 127.739268 -24.56967) (xy 127.684425 -24.55954)
			(xy 127.631641 -24.541533) (xy 127.582041 -24.516032) (xy 127.536683 -24.483581) (xy 127.496534 -24.444872)
			(xy 127.462448 -24.400729) (xy 127.435152 -24.352094) (xy 127.415229 -24.300003) (xy 127.403103 -24.245566)
			(xy 127.399032 -24.189944) (xy 124.31338 -24.189944) (xy 124.305829 -24.241256) (xy 124.289761 -24.294663)
			(xy 124.266089 -24.34516) (xy 124.235316 -24.391673) (xy 124.198099 -24.43321) (xy 124.155231 -24.468885)
			(xy 124.107625 -24.497939) (xy 124.056296 -24.519751) (xy 124.002339 -24.533857) (xy 123.946902 -24.539957)
			(xy 123.891168 -24.53792) (xy 123.836325 -24.52779) (xy 123.783541 -24.509783) (xy 123.733941 -24.484282)
			(xy 123.688583 -24.451831) (xy 123.648434 -24.413122) (xy 123.614348 -24.368979) (xy 123.587052 -24.320344)
			(xy 123.567129 -24.268253) (xy 123.555003 -24.213816) (xy 123.550932 -24.158194) (xy 92.584208 -24.158194)
			(xy 92.584777 -24.162058) (xy 92.585286 -24.189944) (xy 92.584777 -24.21783) (xy 92.576657 -24.273006)
			(xy 92.560589 -24.326413) (xy 92.536917 -24.37691) (xy 92.506144 -24.423423) (xy 92.468927 -24.46496)
			(xy 92.426059 -24.500635) (xy 92.378453 -24.529689) (xy 92.327124 -24.551501) (xy 92.273167 -24.565607)
			(xy 92.21773 -24.571707) (xy 92.161996 -24.56967) (xy 92.107153 -24.55954) (xy 92.054369 -24.541533)
			(xy 92.004769 -24.516032) (xy 91.959411 -24.483581) (xy 91.919262 -24.444872) (xy 91.885176 -24.400729)
			(xy 91.85788 -24.352094) (xy 91.837957 -24.300003) (xy 91.825831 -24.245566) (xy 91.82176 -24.189944)
			(xy 90.062304 -24.189944) (xy 90.061795 -24.21783) (xy 90.053675 -24.273006) (xy 90.037607 -24.326413)
			(xy 90.013935 -24.37691) (xy 89.983162 -24.423423) (xy 89.945945 -24.46496) (xy 89.903077 -24.500635)
			(xy 89.855471 -24.529689) (xy 89.804142 -24.551501) (xy 89.750185 -24.565607) (xy 89.694748 -24.571707)
			(xy 89.639014 -24.56967) (xy 89.584171 -24.55954) (xy 89.531387 -24.541533) (xy 89.481787 -24.516032)
			(xy 89.436429 -24.483581) (xy 89.39628 -24.444872) (xy 89.362194 -24.400729) (xy 89.334898 -24.352094)
			(xy 89.314975 -24.300003) (xy 89.302849 -24.245566) (xy 89.298778 -24.189944) (xy 86.213126 -24.189944)
			(xy 86.205575 -24.241256) (xy 86.189507 -24.294663) (xy 86.165835 -24.34516) (xy 86.135062 -24.391673)
			(xy 86.097845 -24.43321) (xy 86.054977 -24.468885) (xy 86.007371 -24.497939) (xy 85.956042 -24.519751)
			(xy 85.902085 -24.533857) (xy 85.846648 -24.539957) (xy 85.790914 -24.53792) (xy 85.736071 -24.52779)
			(xy 85.683287 -24.509783) (xy 85.633687 -24.484282) (xy 85.588329 -24.451831) (xy 85.54818 -24.413122)
			(xy 85.514094 -24.368979) (xy 85.486798 -24.320344) (xy 85.466875 -24.268253) (xy 85.454749 -24.213816)
			(xy 85.450678 -24.158194) (xy 80.78774 -24.158194) (xy 80.75712 -24.204475) (xy 80.719903 -24.246012)
			(xy 80.677035 -24.281687) (xy 80.629429 -24.310741) (xy 80.5781 -24.332553) (xy 80.524143 -24.346659)
			(xy 80.468706 -24.352759) (xy 80.412972 -24.350722) (xy 80.358129 -24.340592) (xy 80.305345 -24.322585)
			(xy 80.255745 -24.297084) (xy 80.210387 -24.264633) (xy 80.170238 -24.225924) (xy 80.136152 -24.181781)
			(xy 80.108856 -24.133146) (xy 80.088933 -24.081055) (xy 80.076807 -24.026618) (xy 80.072736 -23.970996)
			(xy 79.843444 -23.970996) (xy 79.843375 -23.974752) (xy 79.835255 -24.029928) (xy 79.819187 -24.083335)
			(xy 79.795515 -24.133832) (xy 79.764742 -24.180345) (xy 79.727525 -24.221882) (xy 79.684657 -24.257557)
			(xy 79.637051 -24.286611) (xy 79.585722 -24.308423) (xy 79.531765 -24.322529) (xy 79.476328 -24.328629)
			(xy 79.420594 -24.326592) (xy 79.365751 -24.316462) (xy 79.312967 -24.298455) (xy 79.263367 -24.272954)
			(xy 79.218009 -24.240503) (xy 79.17786 -24.201794) (xy 79.143774 -24.157651) (xy 79.116478 -24.109016)
			(xy 79.096555 -24.056925) (xy 79.084429 -24.002488) (xy 79.080358 -23.946866) (xy 78.840504 -23.946866)
			(xy 78.840838 -23.965154) (xy 78.840329 -23.99304) (xy 78.832209 -24.048216) (xy 78.816141 -24.101623)
			(xy 78.792469 -24.15212) (xy 78.761696 -24.198633) (xy 78.724479 -24.24017) (xy 78.681611 -24.275845)
			(xy 78.634005 -24.304899) (xy 78.582676 -24.326711) (xy 78.528719 -24.340817) (xy 78.473282 -24.346917)
			(xy 78.417548 -24.34488) (xy 78.362705 -24.33475) (xy 78.309921 -24.316743) (xy 78.260321 -24.291242)
			(xy 78.214963 -24.258791) (xy 78.174814 -24.220082) (xy 78.140728 -24.175939) (xy 78.113432 -24.127304)
			(xy 78.093509 -24.075213) (xy 78.081383 -24.020776) (xy 78.077312 -23.965154) (xy 68.537783 -23.965154)
			(xy 68.535851 -23.965659) (xy 68.480414 -23.971759) (xy 68.42468 -23.969722) (xy 68.369837 -23.959592)
			(xy 68.317053 -23.941585) (xy 68.267453 -23.916084) (xy 68.222095 -23.883633) (xy 68.181946 -23.844924)
			(xy 68.14786 -23.800781) (xy 68.120564 -23.752146) (xy 68.100641 -23.700055) (xy 68.088515 -23.645618)
			(xy 68.084444 -23.589996) (xy 54.475692 -23.589996) (xy 54.524195 -23.595333) (xy 54.578152 -23.609439)
			(xy 54.629481 -23.631251) (xy 54.677087 -23.660305) (xy 54.719955 -23.69598) (xy 54.757172 -23.737517)
			(xy 54.787945 -23.78403) (xy 54.811617 -23.834527) (xy 54.827685 -23.887934) (xy 54.835805 -23.94311)
			(xy 54.836314 -23.970996) (xy 54.835805 -23.998882) (xy 54.827685 -24.054058) (xy 54.811617 -24.107465)
			(xy 54.787945 -24.157962) (xy 54.787792 -24.158194) (xy 59.45073 -24.158194) (xy 59.454801 -24.102572)
			(xy 59.466927 -24.048135) (xy 59.48685 -23.996044) (xy 59.514146 -23.947409) (xy 59.548232 -23.903266)
			(xy 59.588381 -23.864557) (xy 59.633739 -23.832106) (xy 59.683339 -23.806605) (xy 59.736123 -23.788598)
			(xy 59.790966 -23.778468) (xy 59.8467 -23.776431) (xy 59.902137 -23.782531) (xy 59.956094 -23.796637)
			(xy 60.007423 -23.818449) (xy 60.055029 -23.847503) (xy 60.097897 -23.883178) (xy 60.135114 -23.924715)
			(xy 60.165887 -23.971228) (xy 60.189559 -24.021725) (xy 60.205627 -24.075132) (xy 60.213747 -24.130308)
			(xy 60.214256 -24.158194) (xy 60.213747 -24.18608) (xy 60.213178 -24.189944) (xy 63.29883 -24.189944)
			(xy 63.302901 -24.134322) (xy 63.315027 -24.079885) (xy 63.33495 -24.027794) (xy 63.362246 -23.979159)
			(xy 63.396332 -23.935016) (xy 63.436481 -23.896307) (xy 63.481839 -23.863856) (xy 63.531439 -23.838355)
			(xy 63.584223 -23.820348) (xy 63.639066 -23.810218) (xy 63.6948 -23.808181) (xy 63.750237 -23.814281)
			(xy 63.804194 -23.828387) (xy 63.855523 -23.850199) (xy 63.903129 -23.879253) (xy 63.945997 -23.914928)
			(xy 63.983214 -23.956465) (xy 64.013987 -24.002978) (xy 64.037659 -24.053475) (xy 64.053727 -24.106882)
			(xy 64.061847 -24.162058) (xy 64.062356 -24.189944) (xy 65.821812 -24.189944) (xy 65.825883 -24.134322)
			(xy 65.838009 -24.079885) (xy 65.857932 -24.027794) (xy 65.885228 -23.979159) (xy 65.919314 -23.935016)
			(xy 65.959463 -23.896307) (xy 66.004821 -23.863856) (xy 66.054421 -23.838355) (xy 66.107205 -23.820348)
			(xy 66.162048 -23.810218) (xy 66.217782 -23.808181) (xy 66.273219 -23.814281) (xy 66.327176 -23.828387)
			(xy 66.378505 -23.850199) (xy 66.426111 -23.879253) (xy 66.468979 -23.914928) (xy 66.506196 -23.956465)
			(xy 66.536969 -24.002978) (xy 66.560641 -24.053475) (xy 66.576709 -24.106882) (xy 66.584829 -24.162058)
			(xy 66.585338 -24.189944) (xy 66.584829 -24.21783) (xy 66.576709 -24.273006) (xy 66.560641 -24.326413)
			(xy 66.536969 -24.37691) (xy 66.506196 -24.423423) (xy 66.468979 -24.46496) (xy 66.426111 -24.500635)
			(xy 66.378505 -24.529689) (xy 66.327176 -24.551501) (xy 66.273219 -24.565607) (xy 66.217782 -24.571707)
			(xy 66.162048 -24.56967) (xy 66.107205 -24.55954) (xy 66.054421 -24.541533) (xy 66.004821 -24.516032)
			(xy 65.959463 -24.483581) (xy 65.919314 -24.444872) (xy 65.885228 -24.400729) (xy 65.857932 -24.352094)
			(xy 65.838009 -24.300003) (xy 65.825883 -24.245566) (xy 65.821812 -24.189944) (xy 64.062356 -24.189944)
			(xy 64.061847 -24.21783) (xy 64.053727 -24.273006) (xy 64.037659 -24.326413) (xy 64.013987 -24.37691)
			(xy 63.983214 -24.423423) (xy 63.945997 -24.46496) (xy 63.903129 -24.500635) (xy 63.855523 -24.529689)
			(xy 63.804194 -24.551501) (xy 63.750237 -24.565607) (xy 63.6948 -24.571707) (xy 63.639066 -24.56967)
			(xy 63.584223 -24.55954) (xy 63.531439 -24.541533) (xy 63.481839 -24.516032) (xy 63.436481 -24.483581)
			(xy 63.396332 -24.444872) (xy 63.362246 -24.400729) (xy 63.33495 -24.352094) (xy 63.315027 -24.300003)
			(xy 63.302901 -24.245566) (xy 63.29883 -24.189944) (xy 60.213178 -24.189944) (xy 60.205627 -24.241256)
			(xy 60.189559 -24.294663) (xy 60.165887 -24.34516) (xy 60.135114 -24.391673) (xy 60.097897 -24.43321)
			(xy 60.055029 -24.468885) (xy 60.007423 -24.497939) (xy 59.956094 -24.519751) (xy 59.902137 -24.533857)
			(xy 59.8467 -24.539957) (xy 59.790966 -24.53792) (xy 59.736123 -24.52779) (xy 59.683339 -24.509783)
			(xy 59.633739 -24.484282) (xy 59.588381 -24.451831) (xy 59.548232 -24.413122) (xy 59.514146 -24.368979)
			(xy 59.48685 -24.320344) (xy 59.466927 -24.268253) (xy 59.454801 -24.213816) (xy 59.45073 -24.158194)
			(xy 54.787792 -24.158194) (xy 54.757172 -24.204475) (xy 54.719955 -24.246012) (xy 54.677087 -24.281687)
			(xy 54.629481 -24.310741) (xy 54.578152 -24.332553) (xy 54.524195 -24.346659) (xy 54.468758 -24.352759)
			(xy 54.413024 -24.350722) (xy 54.358181 -24.340592) (xy 54.305397 -24.322585) (xy 54.255797 -24.297084)
			(xy 54.210439 -24.264633) (xy 54.17029 -24.225924) (xy 54.136204 -24.181781) (xy 54.108908 -24.133146)
			(xy 54.088985 -24.081055) (xy 54.076859 -24.026618) (xy 54.072788 -23.970996) (xy 53.843496 -23.970996)
			(xy 53.843427 -23.974752) (xy 53.835307 -24.029928) (xy 53.819239 -24.083335) (xy 53.795567 -24.133832)
			(xy 53.764794 -24.180345) (xy 53.727577 -24.221882) (xy 53.684709 -24.257557) (xy 53.637103 -24.286611)
			(xy 53.585774 -24.308423) (xy 53.531817 -24.322529) (xy 53.47638 -24.328629) (xy 53.420646 -24.326592)
			(xy 53.365803 -24.316462) (xy 53.313019 -24.298455) (xy 53.263419 -24.272954) (xy 53.218061 -24.240503)
			(xy 53.177912 -24.201794) (xy 53.143826 -24.157651) (xy 53.11653 -24.109016) (xy 53.096607 -24.056925)
			(xy 53.084481 -24.002488) (xy 53.08041 -23.946866) (xy 52.840556 -23.946866) (xy 52.84089 -23.965154)
			(xy 52.840381 -23.99304) (xy 52.832261 -24.048216) (xy 52.816193 -24.101623) (xy 52.792521 -24.15212)
			(xy 52.761748 -24.198633) (xy 52.724531 -24.24017) (xy 52.681663 -24.275845) (xy 52.634057 -24.304899)
			(xy 52.582728 -24.326711) (xy 52.528771 -24.340817) (xy 52.473334 -24.346917) (xy 52.4176 -24.34488)
			(xy 52.362757 -24.33475) (xy 52.309973 -24.316743) (xy 52.260373 -24.291242) (xy 52.215015 -24.258791)
			(xy 52.174866 -24.220082) (xy 52.14078 -24.175939) (xy 52.113484 -24.127304) (xy 52.093561 -24.075213)
			(xy 52.081435 -24.020776) (xy 52.077364 -23.965154) (xy 42.537835 -23.965154) (xy 42.535903 -23.965659)
			(xy 42.480466 -23.971759) (xy 42.424732 -23.969722) (xy 42.369889 -23.959592) (xy 42.317105 -23.941585)
			(xy 42.267505 -23.916084) (xy 42.222147 -23.883633) (xy 42.181998 -23.844924) (xy 42.147912 -23.800781)
			(xy 42.120616 -23.752146) (xy 42.100693 -23.700055) (xy 42.088567 -23.645618) (xy 42.084496 -23.589996)
			(xy 16.848074 -23.589996) (xy 16.847565 -23.617882) (xy 16.839445 -23.673058) (xy 16.823377 -23.726465)
			(xy 16.799705 -23.776962) (xy 16.768932 -23.823475) (xy 16.731715 -23.865012) (xy 16.688847 -23.900687)
			(xy 16.641241 -23.929741) (xy 16.589912 -23.951553) (xy 16.535955 -23.965659) (xy 16.480518 -23.971759)
			(xy 16.424784 -23.969722) (xy 16.369941 -23.959592) (xy 16.317157 -23.941585) (xy 16.267557 -23.916084)
			(xy 16.222199 -23.883633) (xy 16.18205 -23.844924) (xy 16.147964 -23.800781) (xy 16.120668 -23.752146)
			(xy 16.100745 -23.700055) (xy 16.088619 -23.645618) (xy 16.084548 -23.589996) (xy 3.783134 -23.589996)
			(xy 3.797731 -23.596199) (xy 3.845337 -23.625253) (xy 3.888205 -23.660928) (xy 3.925422 -23.702465)
			(xy 3.956195 -23.748978) (xy 3.979867 -23.799475) (xy 3.995935 -23.852882) (xy 4.004055 -23.908058)
			(xy 4.004564 -23.935944) (xy 4.004055 -23.96383) (xy 3.995935 -24.019006) (xy 3.979867 -24.072413)
			(xy 3.956195 -24.12291) (xy 3.925422 -24.169423) (xy 3.907035 -24.189944) (xy 13.821916 -24.189944)
			(xy 13.825987 -24.134322) (xy 13.838113 -24.079885) (xy 13.858036 -24.027794) (xy 13.885332 -23.979159)
			(xy 13.919418 -23.935016) (xy 13.959567 -23.896307) (xy 14.004925 -23.863856) (xy 14.054525 -23.838355)
			(xy 14.107309 -23.820348) (xy 14.162152 -23.810218) (xy 14.217886 -23.808181) (xy 14.273323 -23.814281)
			(xy 14.32728 -23.828387) (xy 14.378609 -23.850199) (xy 14.426215 -23.879253) (xy 14.469083 -23.914928)
			(xy 14.5063 -23.956465) (xy 14.537073 -24.002978) (xy 14.560745 -24.053475) (xy 14.576813 -24.106882)
			(xy 14.584933 -24.162058) (xy 14.585442 -24.189944) (xy 14.584933 -24.21783) (xy 14.576813 -24.273006)
			(xy 14.560745 -24.326413) (xy 14.548157 -24.353266) (xy 19.380198 -24.353266) (xy 19.384269 -24.297644)
			(xy 19.396395 -24.243207) (xy 19.416318 -24.191116) (xy 19.443614 -24.142481) (xy 19.4777 -24.098338)
			(xy 19.517849 -24.059629) (xy 19.563207 -24.027178) (xy 19.612807 -24.001677) (xy 19.665591 -23.98367)
			(xy 19.720434 -23.97354) (xy 19.776168 -23.971503) (xy 19.831605 -23.977603) (xy 19.885562 -23.991709)
			(xy 19.936891 -24.013521) (xy 19.984497 -24.042575) (xy 20.027365 -24.07825) (xy 20.064582 -24.119787)
			(xy 20.089992 -24.158194) (xy 33.450782 -24.158194) (xy 33.454853 -24.102572) (xy 33.466979 -24.048135)
			(xy 33.486902 -23.996044) (xy 33.514198 -23.947409) (xy 33.548284 -23.903266) (xy 33.588433 -23.864557)
			(xy 33.633791 -23.832106) (xy 33.683391 -23.806605) (xy 33.736175 -23.788598) (xy 33.791018 -23.778468)
			(xy 33.846752 -23.776431) (xy 33.902189 -23.782531) (xy 33.956146 -23.796637) (xy 34.007475 -23.818449)
			(xy 34.055081 -23.847503) (xy 34.097949 -23.883178) (xy 34.135166 -23.924715) (xy 34.165939 -23.971228)
			(xy 34.189611 -24.021725) (xy 34.205679 -24.075132) (xy 34.213799 -24.130308) (xy 34.214308 -24.158194)
			(xy 34.213799 -24.18608) (xy 34.21323 -24.189944) (xy 37.298882 -24.189944) (xy 37.302953 -24.134322)
			(xy 37.315079 -24.079885) (xy 37.335002 -24.027794) (xy 37.362298 -23.979159) (xy 37.396384 -23.935016)
			(xy 37.436533 -23.896307) (xy 37.481891 -23.863856) (xy 37.531491 -23.838355) (xy 37.584275 -23.820348)
			(xy 37.639118 -23.810218) (xy 37.694852 -23.808181) (xy 37.750289 -23.814281) (xy 37.804246 -23.828387)
			(xy 37.855575 -23.850199) (xy 37.903181 -23.879253) (xy 37.946049 -23.914928) (xy 37.983266 -23.956465)
			(xy 38.014039 -24.002978) (xy 38.037711 -24.053475) (xy 38.053779 -24.106882) (xy 38.061899 -24.162058)
			(xy 38.062408 -24.189944) (xy 39.821864 -24.189944) (xy 39.825935 -24.134322) (xy 39.838061 -24.079885)
			(xy 39.857984 -24.027794) (xy 39.88528 -23.979159) (xy 39.919366 -23.935016) (xy 39.959515 -23.896307)
			(xy 40.004873 -23.863856) (xy 40.054473 -23.838355) (xy 40.107257 -23.820348) (xy 40.1621 -23.810218)
			(xy 40.217834 -23.808181) (xy 40.273271 -23.814281) (xy 40.327228 -23.828387) (xy 40.378557 -23.850199)
			(xy 40.426163 -23.879253) (xy 40.469031 -23.914928) (xy 40.506248 -23.956465) (xy 40.537021 -24.002978)
			(xy 40.560693 -24.053475) (xy 40.576761 -24.106882) (xy 40.584881 -24.162058) (xy 40.58539 -24.189944)
			(xy 40.584881 -24.21783) (xy 40.576761 -24.273006) (xy 40.560693 -24.326413) (xy 40.537021 -24.37691)
			(xy 40.506248 -24.423423) (xy 40.469031 -24.46496) (xy 40.426163 -24.500635) (xy 40.378557 -24.529689)
			(xy 40.327228 -24.551501) (xy 40.273271 -24.565607) (xy 40.217834 -24.571707) (xy 40.1621 -24.56967)
			(xy 40.107257 -24.55954) (xy 40.054473 -24.541533) (xy 40.004873 -24.516032) (xy 39.959515 -24.483581)
			(xy 39.919366 -24.444872) (xy 39.88528 -24.400729) (xy 39.857984 -24.352094) (xy 39.838061 -24.300003)
			(xy 39.825935 -24.245566) (xy 39.821864 -24.189944) (xy 38.062408 -24.189944) (xy 38.061899 -24.21783)
			(xy 38.053779 -24.273006) (xy 38.037711 -24.326413) (xy 38.014039 -24.37691) (xy 37.983266 -24.423423)
			(xy 37.946049 -24.46496) (xy 37.903181 -24.500635) (xy 37.855575 -24.529689) (xy 37.804246 -24.551501)
			(xy 37.750289 -24.565607) (xy 37.694852 -24.571707) (xy 37.639118 -24.56967) (xy 37.584275 -24.55954)
			(xy 37.531491 -24.541533) (xy 37.481891 -24.516032) (xy 37.436533 -24.483581) (xy 37.396384 -24.444872)
			(xy 37.362298 -24.400729) (xy 37.335002 -24.352094) (xy 37.315079 -24.300003) (xy 37.302953 -24.245566)
			(xy 37.298882 -24.189944) (xy 34.21323 -24.189944) (xy 34.205679 -24.241256) (xy 34.189611 -24.294663)
			(xy 34.165939 -24.34516) (xy 34.135166 -24.391673) (xy 34.097949 -24.43321) (xy 34.055081 -24.468885)
			(xy 34.007475 -24.497939) (xy 33.956146 -24.519751) (xy 33.902189 -24.533857) (xy 33.846752 -24.539957)
			(xy 33.791018 -24.53792) (xy 33.736175 -24.52779) (xy 33.683391 -24.509783) (xy 33.633791 -24.484282)
			(xy 33.588433 -24.451831) (xy 33.548284 -24.413122) (xy 33.514198 -24.368979) (xy 33.486902 -24.320344)
			(xy 33.466979 -24.268253) (xy 33.454853 -24.213816) (xy 33.450782 -24.158194) (xy 20.089992 -24.158194)
			(xy 20.095355 -24.1663) (xy 20.119027 -24.216797) (xy 20.135095 -24.270204) (xy 20.143215 -24.32538)
			(xy 20.143724 -24.353266) (xy 20.143215 -24.381152) (xy 20.135095 -24.436328) (xy 20.119027 -24.489735)
			(xy 20.095355 -24.540232) (xy 20.064582 -24.586745) (xy 20.027365 -24.628282) (xy 19.984497 -24.663957)
			(xy 19.936891 -24.693011) (xy 19.885562 -24.714823) (xy 19.831605 -24.728929) (xy 19.776168 -24.735029)
			(xy 19.720434 -24.732992) (xy 19.665591 -24.722862) (xy 19.612807 -24.704855) (xy 19.563207 -24.679354)
			(xy 19.517849 -24.646903) (xy 19.4777 -24.608194) (xy 19.443614 -24.564051) (xy 19.416318 -24.515416)
			(xy 19.396395 -24.463325) (xy 19.384269 -24.408888) (xy 19.380198 -24.353266) (xy 14.548157 -24.353266)
			(xy 14.537073 -24.37691) (xy 14.5063 -24.423423) (xy 14.469083 -24.46496) (xy 14.426215 -24.500635)
			(xy 14.378609 -24.529689) (xy 14.32728 -24.551501) (xy 14.273323 -24.565607) (xy 14.217886 -24.571707)
			(xy 14.162152 -24.56967) (xy 14.107309 -24.55954) (xy 14.054525 -24.541533) (xy 14.004925 -24.516032)
			(xy 13.959567 -24.483581) (xy 13.919418 -24.444872) (xy 13.885332 -24.400729) (xy 13.858036 -24.352094)
			(xy 13.838113 -24.300003) (xy 13.825987 -24.245566) (xy 13.821916 -24.189944) (xy 3.907035 -24.189944)
			(xy 3.888205 -24.21096) (xy 3.845337 -24.246635) (xy 3.797731 -24.275689) (xy 3.746402 -24.297501)
			(xy 3.692445 -24.311607) (xy 3.637008 -24.317707) (xy 3.581274 -24.31567) (xy 3.526431 -24.30554)
			(xy 3.473647 -24.287533) (xy 3.424047 -24.262032) (xy 3.378689 -24.229581) (xy 3.33854 -24.190872)
			(xy 3.304454 -24.146729) (xy 3.277158 -24.098094) (xy 3.257235 -24.046003) (xy 3.245109 -23.991566)
			(xy 3.241038 -23.935944) (xy 2.995676 -23.935944) (xy 2.995167 -23.96383) (xy 2.987047 -24.019006)
			(xy 2.970979 -24.072413) (xy 2.947307 -24.12291) (xy 2.916534 -24.169423) (xy 2.879317 -24.21096)
			(xy 2.836449 -24.246635) (xy 2.788843 -24.275689) (xy 2.737514 -24.297501) (xy 2.683557 -24.311607)
			(xy 2.62812 -24.317707) (xy 2.572386 -24.31567) (xy 2.517543 -24.30554) (xy 2.464759 -24.287533)
			(xy 2.415159 -24.262032) (xy 2.369801 -24.229581) (xy 2.329652 -24.190872) (xy 2.295566 -24.146729)
			(xy 2.26827 -24.098094) (xy 2.248347 -24.046003) (xy 2.236221 -23.991566) (xy 2.23215 -23.935944)
			(xy 1.867916 -23.935944) (xy 1.867916 -24.807418) (xy 6.371334 -24.807418) (xy 6.375405 -24.751796)
			(xy 6.387531 -24.697359) (xy 6.407454 -24.645268) (xy 6.43475 -24.596633) (xy 6.468836 -24.55249)
			(xy 6.508985 -24.513781) (xy 6.554343 -24.48133) (xy 6.603943 -24.455829) (xy 6.656727 -24.437822)
			(xy 6.71157 -24.427692) (xy 6.767304 -24.425655) (xy 6.822741 -24.431755) (xy 6.876698 -24.445861)
			(xy 6.928027 -24.467673) (xy 6.975633 -24.496727) (xy 7.018501 -24.532402) (xy 7.055718 -24.573939)
			(xy 7.086491 -24.620452) (xy 7.110163 -24.670949) (xy 7.126231 -24.724356) (xy 7.134351 -24.779532)
			(xy 7.13486 -24.807418) (xy 8.62025 -24.807418) (xy 8.624321 -24.751796) (xy 8.636447 -24.697359)
			(xy 8.65637 -24.645268) (xy 8.683666 -24.596633) (xy 8.717752 -24.55249) (xy 8.757901 -24.513781)
			(xy 8.803259 -24.48133) (xy 8.852859 -24.455829) (xy 8.905643 -24.437822) (xy 8.960486 -24.427692)
			(xy 9.01622 -24.425655) (xy 9.071657 -24.431755) (xy 9.125614 -24.445861) (xy 9.176943 -24.467673)
			(xy 9.224549 -24.496727) (xy 9.267417 -24.532402) (xy 9.304634 -24.573939) (xy 9.335407 -24.620452)
			(xy 9.359079 -24.670949) (xy 9.375147 -24.724356) (xy 9.383267 -24.779532) (xy 9.383776 -24.807418)
			(xy 9.383267 -24.835304) (xy 9.375147 -24.89048) (xy 9.359079 -24.943887) (xy 9.335407 -24.994384)
			(xy 9.304634 -25.040897) (xy 9.267417 -25.082434) (xy 9.224549 -25.118109) (xy 9.176943 -25.147163)
			(xy 9.125614 -25.168975) (xy 9.071657 -25.183081) (xy 9.01622 -25.189181) (xy 8.960486 -25.187144)
			(xy 8.905643 -25.177014) (xy 8.852859 -25.159007) (xy 8.803259 -25.133506) (xy 8.757901 -25.101055)
			(xy 8.717752 -25.062346) (xy 8.683666 -25.018203) (xy 8.65637 -24.969568) (xy 8.636447 -24.917477)
			(xy 8.624321 -24.86304) (xy 8.62025 -24.807418) (xy 7.13486 -24.807418) (xy 7.134351 -24.835304)
			(xy 7.126231 -24.89048) (xy 7.110163 -24.943887) (xy 7.086491 -24.994384) (xy 7.055718 -25.040897)
			(xy 7.018501 -25.082434) (xy 6.975633 -25.118109) (xy 6.928027 -25.147163) (xy 6.876698 -25.168975)
			(xy 6.822741 -25.183081) (xy 6.767304 -25.189181) (xy 6.71157 -25.187144) (xy 6.656727 -25.177014)
			(xy 6.603943 -25.159007) (xy 6.554343 -25.133506) (xy 6.508985 -25.101055) (xy 6.468836 -25.062346)
			(xy 6.43475 -25.018203) (xy 6.407454 -24.969568) (xy 6.387531 -24.917477) (xy 6.375405 -24.86304)
			(xy 6.371334 -24.807418) (xy 1.867916 -24.807418) (xy 1.867916 -25.390094) (xy 13.809216 -25.390094)
			(xy 13.813287 -25.334472) (xy 13.825413 -25.280035) (xy 13.845336 -25.227944) (xy 13.872632 -25.179309)
			(xy 13.906718 -25.135166) (xy 13.946867 -25.096457) (xy 13.992225 -25.064006) (xy 14.041825 -25.038505)
			(xy 14.094609 -25.020498) (xy 14.149452 -25.010368) (xy 14.205186 -25.008331) (xy 14.260623 -25.014431)
			(xy 14.31458 -25.028537) (xy 14.322621 -25.031954) (xy 18.187922 -25.031954) (xy 18.191993 -24.976332)
			(xy 18.204119 -24.921895) (xy 18.224042 -24.869804) (xy 18.251338 -24.821169) (xy 18.285424 -24.777026)
			(xy 18.325573 -24.738317) (xy 18.370931 -24.705866) (xy 18.420531 -24.680365) (xy 18.473315 -24.662358)
			(xy 18.528158 -24.652228) (xy 18.583892 -24.650191) (xy 18.639329 -24.656291) (xy 18.693286 -24.670397)
			(xy 18.744615 -24.692209) (xy 18.792221 -24.721263) (xy 18.835089 -24.756938) (xy 18.872306 -24.798475)
			(xy 18.878223 -24.807418) (xy 32.371282 -24.807418) (xy 32.375353 -24.751796) (xy 32.387479 -24.697359)
			(xy 32.407402 -24.645268) (xy 32.434698 -24.596633) (xy 32.468784 -24.55249) (xy 32.508933 -24.513781)
			(xy 32.554291 -24.48133) (xy 32.603891 -24.455829) (xy 32.656675 -24.437822) (xy 32.711518 -24.427692)
			(xy 32.767252 -24.425655) (xy 32.822689 -24.431755) (xy 32.876646 -24.445861) (xy 32.927975 -24.467673)
			(xy 32.975581 -24.496727) (xy 33.018449 -24.532402) (xy 33.055666 -24.573939) (xy 33.086439 -24.620452)
			(xy 33.110111 -24.670949) (xy 33.126179 -24.724356) (xy 33.134299 -24.779532) (xy 33.134808 -24.807418)
			(xy 34.620198 -24.807418) (xy 34.624269 -24.751796) (xy 34.636395 -24.697359) (xy 34.656318 -24.645268)
			(xy 34.683614 -24.596633) (xy 34.7177 -24.55249) (xy 34.757849 -24.513781) (xy 34.803207 -24.48133)
			(xy 34.852807 -24.455829) (xy 34.905591 -24.437822) (xy 34.960434 -24.427692) (xy 35.016168 -24.425655)
			(xy 35.071605 -24.431755) (xy 35.125562 -24.445861) (xy 35.176891 -24.467673) (xy 35.224497 -24.496727)
			(xy 35.267365 -24.532402) (xy 35.304582 -24.573939) (xy 35.335355 -24.620452) (xy 35.359027 -24.670949)
			(xy 35.375095 -24.724356) (xy 35.383215 -24.779532) (xy 35.383724 -24.807418) (xy 35.383215 -24.835304)
			(xy 35.375095 -24.89048) (xy 35.359027 -24.943887) (xy 35.335355 -24.994384) (xy 35.304582 -25.040897)
			(xy 35.267365 -25.082434) (xy 35.224497 -25.118109) (xy 35.176891 -25.147163) (xy 35.125562 -25.168975)
			(xy 35.071605 -25.183081) (xy 35.016168 -25.189181) (xy 34.960434 -25.187144) (xy 34.905591 -25.177014)
			(xy 34.852807 -25.159007) (xy 34.803207 -25.133506) (xy 34.757849 -25.101055) (xy 34.7177 -25.062346)
			(xy 34.683614 -25.018203) (xy 34.656318 -24.969568) (xy 34.636395 -24.917477) (xy 34.624269 -24.86304)
			(xy 34.620198 -24.807418) (xy 33.134808 -24.807418) (xy 33.134299 -24.835304) (xy 33.126179 -24.89048)
			(xy 33.110111 -24.943887) (xy 33.086439 -24.994384) (xy 33.055666 -25.040897) (xy 33.018449 -25.082434)
			(xy 32.975581 -25.118109) (xy 32.927975 -25.147163) (xy 32.876646 -25.168975) (xy 32.822689 -25.183081)
			(xy 32.767252 -25.189181) (xy 32.711518 -25.187144) (xy 32.656675 -25.177014) (xy 32.603891 -25.159007)
			(xy 32.554291 -25.133506) (xy 32.508933 -25.101055) (xy 32.468784 -25.062346) (xy 32.434698 -25.018203)
			(xy 32.407402 -24.969568) (xy 32.387479 -24.917477) (xy 32.375353 -24.86304) (xy 32.371282 -24.807418)
			(xy 18.878223 -24.807418) (xy 18.903079 -24.844988) (xy 18.926751 -24.895485) (xy 18.942819 -24.948892)
			(xy 18.950939 -25.004068) (xy 18.951448 -25.031954) (xy 18.950939 -25.05984) (xy 18.942819 -25.115016)
			(xy 18.926751 -25.168423) (xy 18.903079 -25.21892) (xy 18.872306 -25.265433) (xy 18.835089 -25.30697)
			(xy 18.792221 -25.342645) (xy 18.744615 -25.371699) (xy 18.701327 -25.390094) (xy 39.809164 -25.390094)
			(xy 39.813235 -25.334472) (xy 39.825361 -25.280035) (xy 39.845284 -25.227944) (xy 39.87258 -25.179309)
			(xy 39.906666 -25.135166) (xy 39.946815 -25.096457) (xy 39.992173 -25.064006) (xy 40.041773 -25.038505)
			(xy 40.094557 -25.020498) (xy 40.1494 -25.010368) (xy 40.205134 -25.008331) (xy 40.260571 -25.014431)
			(xy 40.314528 -25.028537) (xy 40.322569 -25.031954) (xy 44.18787 -25.031954) (xy 44.191941 -24.976332)
			(xy 44.204067 -24.921895) (xy 44.22399 -24.869804) (xy 44.251286 -24.821169) (xy 44.285372 -24.777026)
			(xy 44.325521 -24.738317) (xy 44.370879 -24.705866) (xy 44.420479 -24.680365) (xy 44.473263 -24.662358)
			(xy 44.528106 -24.652228) (xy 44.58384 -24.650191) (xy 44.639277 -24.656291) (xy 44.693234 -24.670397)
			(xy 44.744563 -24.692209) (xy 44.792169 -24.721263) (xy 44.835037 -24.756938) (xy 44.836571 -24.75865)
			(xy 46.868586 -24.75865) (xy 46.872657 -24.703028) (xy 46.884783 -24.648591) (xy 46.904706 -24.5965)
			(xy 46.932002 -24.547865) (xy 46.966088 -24.503722) (xy 47.006237 -24.465013) (xy 47.051595 -24.432562)
			(xy 47.101195 -24.407061) (xy 47.153979 -24.389054) (xy 47.208822 -24.378924) (xy 47.264556 -24.376887)
			(xy 47.319993 -24.382987) (xy 47.37395 -24.397093) (xy 47.425279 -24.418905) (xy 47.472885 -24.447959)
			(xy 47.515753 -24.483634) (xy 47.55297 -24.525171) (xy 47.583743 -24.571684) (xy 47.607415 -24.622181)
			(xy 47.623483 -24.675588) (xy 47.631603 -24.730764) (xy 47.632112 -24.75865) (xy 47.631603 -24.786536)
			(xy 47.62853 -24.807418) (xy 58.37123 -24.807418) (xy 58.375301 -24.751796) (xy 58.387427 -24.697359)
			(xy 58.40735 -24.645268) (xy 58.434646 -24.596633) (xy 58.468732 -24.55249) (xy 58.508881 -24.513781)
			(xy 58.554239 -24.48133) (xy 58.603839 -24.455829) (xy 58.656623 -24.437822) (xy 58.711466 -24.427692)
			(xy 58.7672 -24.425655) (xy 58.822637 -24.431755) (xy 58.876594 -24.445861) (xy 58.927923 -24.467673)
			(xy 58.975529 -24.496727) (xy 59.018397 -24.532402) (xy 59.055614 -24.573939) (xy 59.086387 -24.620452)
			(xy 59.110059 -24.670949) (xy 59.126127 -24.724356) (xy 59.134247 -24.779532) (xy 59.134756 -24.807418)
			(xy 60.620146 -24.807418) (xy 60.624217 -24.751796) (xy 60.636343 -24.697359) (xy 60.656266 -24.645268)
			(xy 60.683562 -24.596633) (xy 60.717648 -24.55249) (xy 60.757797 -24.513781) (xy 60.803155 -24.48133)
			(xy 60.852755 -24.455829) (xy 60.905539 -24.437822) (xy 60.960382 -24.427692) (xy 61.016116 -24.425655)
			(xy 61.071553 -24.431755) (xy 61.12551 -24.445861) (xy 61.176839 -24.467673) (xy 61.224445 -24.496727)
			(xy 61.267313 -24.532402) (xy 61.30453 -24.573939) (xy 61.335303 -24.620452) (xy 61.358975 -24.670949)
			(xy 61.375043 -24.724356) (xy 61.383163 -24.779532) (xy 61.383672 -24.807418) (xy 61.383163 -24.835304)
			(xy 61.375043 -24.89048) (xy 61.358975 -24.943887) (xy 61.335303 -24.994384) (xy 61.30453 -25.040897)
			(xy 61.267313 -25.082434) (xy 61.224445 -25.118109) (xy 61.176839 -25.147163) (xy 61.12551 -25.168975)
			(xy 61.071553 -25.183081) (xy 61.016116 -25.189181) (xy 60.960382 -25.187144) (xy 60.905539 -25.177014)
			(xy 60.852755 -25.159007) (xy 60.803155 -25.133506) (xy 60.757797 -25.101055) (xy 60.717648 -25.062346)
			(xy 60.683562 -25.018203) (xy 60.656266 -24.969568) (xy 60.636343 -24.917477) (xy 60.624217 -24.86304)
			(xy 60.620146 -24.807418) (xy 59.134756 -24.807418) (xy 59.134247 -24.835304) (xy 59.126127 -24.89048)
			(xy 59.110059 -24.943887) (xy 59.086387 -24.994384) (xy 59.055614 -25.040897) (xy 59.018397 -25.082434)
			(xy 58.975529 -25.118109) (xy 58.927923 -25.147163) (xy 58.876594 -25.168975) (xy 58.822637 -25.183081)
			(xy 58.7672 -25.189181) (xy 58.711466 -25.187144) (xy 58.656623 -25.177014) (xy 58.603839 -25.159007)
			(xy 58.554239 -25.133506) (xy 58.508881 -25.101055) (xy 58.468732 -25.062346) (xy 58.434646 -25.018203)
			(xy 58.40735 -24.969568) (xy 58.387427 -24.917477) (xy 58.375301 -24.86304) (xy 58.37123 -24.807418)
			(xy 47.62853 -24.807418) (xy 47.623483 -24.841712) (xy 47.607415 -24.895119) (xy 47.583743 -24.945616)
			(xy 47.55297 -24.992129) (xy 47.515753 -25.033666) (xy 47.472885 -25.069341) (xy 47.425279 -25.098395)
			(xy 47.37395 -25.120207) (xy 47.319993 -25.134313) (xy 47.264556 -25.140413) (xy 47.208822 -25.138376)
			(xy 47.153979 -25.128246) (xy 47.101195 -25.110239) (xy 47.051595 -25.084738) (xy 47.006237 -25.052287)
			(xy 46.966088 -25.013578) (xy 46.932002 -24.969435) (xy 46.904706 -24.9208) (xy 46.884783 -24.868709)
			(xy 46.872657 -24.814272) (xy 46.868586 -24.75865) (xy 44.836571 -24.75865) (xy 44.872254 -24.798475)
			(xy 44.903027 -24.844988) (xy 44.926699 -24.895485) (xy 44.942767 -24.948892) (xy 44.950887 -25.004068)
			(xy 44.951396 -25.031954) (xy 44.950887 -25.05984) (xy 44.942767 -25.115016) (xy 44.926699 -25.168423)
			(xy 44.903027 -25.21892) (xy 44.872254 -25.265433) (xy 44.835037 -25.30697) (xy 44.792169 -25.342645)
			(xy 44.744563 -25.371699) (xy 44.693234 -25.393511) (xy 44.639277 -25.407617) (xy 44.58384 -25.413717)
			(xy 44.528106 -25.41168) (xy 44.473263 -25.40155) (xy 44.420479 -25.383543) (xy 44.370879 -25.358042)
			(xy 44.325521 -25.325591) (xy 44.285372 -25.286882) (xy 44.251286 -25.242739) (xy 44.22399 -25.194104)
			(xy 44.204067 -25.142013) (xy 44.191941 -25.087576) (xy 44.18787 -25.031954) (xy 40.322569 -25.031954)
			(xy 40.365857 -25.050349) (xy 40.413463 -25.079403) (xy 40.456331 -25.115078) (xy 40.493548 -25.156615)
			(xy 40.524321 -25.203128) (xy 40.547993 -25.253625) (xy 40.564061 -25.307032) (xy 40.572181 -25.362208)
			(xy 40.57269 -25.390094) (xy 40.572181 -25.41798) (xy 40.564061 -25.473156) (xy 40.547993 -25.526563)
			(xy 40.532904 -25.55875) (xy 48.64176 -25.55875) (xy 48.645831 -25.503128) (xy 48.657957 -25.448691)
			(xy 48.67788 -25.3966) (xy 48.705176 -25.347965) (xy 48.739262 -25.303822) (xy 48.779411 -25.265113)
			(xy 48.824769 -25.232662) (xy 48.874369 -25.207161) (xy 48.927153 -25.189154) (xy 48.981996 -25.179024)
			(xy 49.03773 -25.176987) (xy 49.093167 -25.183087) (xy 49.147124 -25.197193) (xy 49.198453 -25.219005)
			(xy 49.246059 -25.248059) (xy 49.288927 -25.283734) (xy 49.326144 -25.325271) (xy 49.356917 -25.371784)
			(xy 49.3655 -25.390094) (xy 65.809112 -25.390094) (xy 65.813183 -25.334472) (xy 65.825309 -25.280035)
			(xy 65.845232 -25.227944) (xy 65.872528 -25.179309) (xy 65.906614 -25.135166) (xy 65.946763 -25.096457)
			(xy 65.992121 -25.064006) (xy 66.041721 -25.038505) (xy 66.094505 -25.020498) (xy 66.149348 -25.010368)
			(xy 66.205082 -25.008331) (xy 66.260519 -25.014431) (xy 66.314476 -25.028537) (xy 66.322517 -25.031954)
			(xy 70.187818 -25.031954) (xy 70.191889 -24.976332) (xy 70.204015 -24.921895) (xy 70.223938 -24.869804)
			(xy 70.251234 -24.821169) (xy 70.28532 -24.777026) (xy 70.325469 -24.738317) (xy 70.370827 -24.705866)
			(xy 70.420427 -24.680365) (xy 70.473211 -24.662358) (xy 70.528054 -24.652228) (xy 70.583788 -24.650191)
			(xy 70.639225 -24.656291) (xy 70.693182 -24.670397) (xy 70.744511 -24.692209) (xy 70.792117 -24.721263)
			(xy 70.834985 -24.756938) (xy 70.836519 -24.75865) (xy 72.868534 -24.75865) (xy 72.872605 -24.703028)
			(xy 72.884731 -24.648591) (xy 72.904654 -24.5965) (xy 72.93195 -24.547865) (xy 72.966036 -24.503722)
			(xy 73.006185 -24.465013) (xy 73.051543 -24.432562) (xy 73.101143 -24.407061) (xy 73.153927 -24.389054)
			(xy 73.20877 -24.378924) (xy 73.264504 -24.376887) (xy 73.319941 -24.382987) (xy 73.373898 -24.397093)
			(xy 73.425227 -24.418905) (xy 73.472833 -24.447959) (xy 73.515701 -24.483634) (xy 73.552918 -24.525171)
			(xy 73.583691 -24.571684) (xy 73.607363 -24.622181) (xy 73.623431 -24.675588) (xy 73.631551 -24.730764)
			(xy 73.63206 -24.75865) (xy 73.631551 -24.786536) (xy 73.628478 -24.807418) (xy 84.371178 -24.807418)
			(xy 84.375249 -24.751796) (xy 84.387375 -24.697359) (xy 84.407298 -24.645268) (xy 84.434594 -24.596633)
			(xy 84.46868 -24.55249) (xy 84.508829 -24.513781) (xy 84.554187 -24.48133) (xy 84.603787 -24.455829)
			(xy 84.656571 -24.437822) (xy 84.711414 -24.427692) (xy 84.767148 -24.425655) (xy 84.822585 -24.431755)
			(xy 84.876542 -24.445861) (xy 84.927871 -24.467673) (xy 84.975477 -24.496727) (xy 85.018345 -24.532402)
			(xy 85.055562 -24.573939) (xy 85.086335 -24.620452) (xy 85.110007 -24.670949) (xy 85.126075 -24.724356)
			(xy 85.134195 -24.779532) (xy 85.134704 -24.807418) (xy 86.620094 -24.807418) (xy 86.624165 -24.751796)
			(xy 86.636291 -24.697359) (xy 86.656214 -24.645268) (xy 86.68351 -24.596633) (xy 86.717596 -24.55249)
			(xy 86.757745 -24.513781) (xy 86.803103 -24.48133) (xy 86.852703 -24.455829) (xy 86.905487 -24.437822)
			(xy 86.96033 -24.427692) (xy 87.016064 -24.425655) (xy 87.071501 -24.431755) (xy 87.125458 -24.445861)
			(xy 87.176787 -24.467673) (xy 87.224393 -24.496727) (xy 87.267261 -24.532402) (xy 87.304478 -24.573939)
			(xy 87.335251 -24.620452) (xy 87.358923 -24.670949) (xy 87.374991 -24.724356) (xy 87.383111 -24.779532)
			(xy 87.38362 -24.807418) (xy 87.383111 -24.835304) (xy 87.374991 -24.89048) (xy 87.358923 -24.943887)
			(xy 87.335251 -24.994384) (xy 87.304478 -25.040897) (xy 87.267261 -25.082434) (xy 87.224393 -25.118109)
			(xy 87.176787 -25.147163) (xy 87.125458 -25.168975) (xy 87.071501 -25.183081) (xy 87.016064 -25.189181)
			(xy 86.96033 -25.187144) (xy 86.905487 -25.177014) (xy 86.852703 -25.159007) (xy 86.803103 -25.133506)
			(xy 86.757745 -25.101055) (xy 86.717596 -25.062346) (xy 86.68351 -25.018203) (xy 86.656214 -24.969568)
			(xy 86.636291 -24.917477) (xy 86.624165 -24.86304) (xy 86.620094 -24.807418) (xy 85.134704 -24.807418)
			(xy 85.134195 -24.835304) (xy 85.126075 -24.89048) (xy 85.110007 -24.943887) (xy 85.086335 -24.994384)
			(xy 85.055562 -25.040897) (xy 85.018345 -25.082434) (xy 84.975477 -25.118109) (xy 84.927871 -25.147163)
			(xy 84.876542 -25.168975) (xy 84.822585 -25.183081) (xy 84.767148 -25.189181) (xy 84.711414 -25.187144)
			(xy 84.656571 -25.177014) (xy 84.603787 -25.159007) (xy 84.554187 -25.133506) (xy 84.508829 -25.101055)
			(xy 84.46868 -25.062346) (xy 84.434594 -25.018203) (xy 84.407298 -24.969568) (xy 84.387375 -24.917477)
			(xy 84.375249 -24.86304) (xy 84.371178 -24.807418) (xy 73.628478 -24.807418) (xy 73.623431 -24.841712)
			(xy 73.607363 -24.895119) (xy 73.583691 -24.945616) (xy 73.552918 -24.992129) (xy 73.515701 -25.033666)
			(xy 73.472833 -25.069341) (xy 73.425227 -25.098395) (xy 73.373898 -25.120207) (xy 73.319941 -25.134313)
			(xy 73.264504 -25.140413) (xy 73.20877 -25.138376) (xy 73.153927 -25.128246) (xy 73.101143 -25.110239)
			(xy 73.051543 -25.084738) (xy 73.006185 -25.052287) (xy 72.966036 -25.013578) (xy 72.93195 -24.969435)
			(xy 72.904654 -24.9208) (xy 72.884731 -24.868709) (xy 72.872605 -24.814272) (xy 72.868534 -24.75865)
			(xy 70.836519 -24.75865) (xy 70.872202 -24.798475) (xy 70.902975 -24.844988) (xy 70.926647 -24.895485)
			(xy 70.942715 -24.948892) (xy 70.950835 -25.004068) (xy 70.951344 -25.031954) (xy 70.950835 -25.05984)
			(xy 70.942715 -25.115016) (xy 70.926647 -25.168423) (xy 70.902975 -25.21892) (xy 70.872202 -25.265433)
			(xy 70.834985 -25.30697) (xy 70.792117 -25.342645) (xy 70.744511 -25.371699) (xy 70.693182 -25.393511)
			(xy 70.639225 -25.407617) (xy 70.583788 -25.413717) (xy 70.528054 -25.41168) (xy 70.473211 -25.40155)
			(xy 70.420427 -25.383543) (xy 70.370827 -25.358042) (xy 70.325469 -25.325591) (xy 70.28532 -25.286882)
			(xy 70.251234 -25.242739) (xy 70.223938 -25.194104) (xy 70.204015 -25.142013) (xy 70.191889 -25.087576)
			(xy 70.187818 -25.031954) (xy 66.322517 -25.031954) (xy 66.365805 -25.050349) (xy 66.413411 -25.079403)
			(xy 66.456279 -25.115078) (xy 66.493496 -25.156615) (xy 66.524269 -25.203128) (xy 66.547941 -25.253625)
			(xy 66.564009 -25.307032) (xy 66.572129 -25.362208) (xy 66.572638 -25.390094) (xy 66.572129 -25.41798)
			(xy 66.564009 -25.473156) (xy 66.547941 -25.526563) (xy 66.532852 -25.55875) (xy 74.641708 -25.55875)
			(xy 74.645779 -25.503128) (xy 74.657905 -25.448691) (xy 74.677828 -25.3966) (xy 74.705124 -25.347965)
			(xy 74.73921 -25.303822) (xy 74.779359 -25.265113) (xy 74.824717 -25.232662) (xy 74.874317 -25.207161)
			(xy 74.927101 -25.189154) (xy 74.981944 -25.179024) (xy 75.037678 -25.176987) (xy 75.093115 -25.183087)
			(xy 75.147072 -25.197193) (xy 75.198401 -25.219005) (xy 75.246007 -25.248059) (xy 75.288875 -25.283734)
			(xy 75.326092 -25.325271) (xy 75.356865 -25.371784) (xy 75.365448 -25.390094) (xy 91.80906 -25.390094)
			(xy 91.813131 -25.334472) (xy 91.825257 -25.280035) (xy 91.84518 -25.227944) (xy 91.872476 -25.179309)
			(xy 91.906562 -25.135166) (xy 91.946711 -25.096457) (xy 91.992069 -25.064006) (xy 92.041669 -25.038505)
			(xy 92.094453 -25.020498) (xy 92.149296 -25.010368) (xy 92.20503 -25.008331) (xy 92.260467 -25.014431)
			(xy 92.314424 -25.028537) (xy 92.322465 -25.031954) (xy 96.187766 -25.031954) (xy 96.191837 -24.976332)
			(xy 96.203963 -24.921895) (xy 96.223886 -24.869804) (xy 96.251182 -24.821169) (xy 96.285268 -24.777026)
			(xy 96.325417 -24.738317) (xy 96.370775 -24.705866) (xy 96.420375 -24.680365) (xy 96.473159 -24.662358)
			(xy 96.528002 -24.652228) (xy 96.583736 -24.650191) (xy 96.639173 -24.656291) (xy 96.69313 -24.670397)
			(xy 96.744459 -24.692209) (xy 96.792065 -24.721263) (xy 96.834933 -24.756938) (xy 96.836467 -24.75865)
			(xy 98.868482 -24.75865) (xy 98.872553 -24.703028) (xy 98.884679 -24.648591) (xy 98.904602 -24.5965)
			(xy 98.931898 -24.547865) (xy 98.965984 -24.503722) (xy 99.006133 -24.465013) (xy 99.051491 -24.432562)
			(xy 99.101091 -24.407061) (xy 99.153875 -24.389054) (xy 99.208718 -24.378924) (xy 99.264452 -24.376887)
			(xy 99.319889 -24.382987) (xy 99.373846 -24.397093) (xy 99.425175 -24.418905) (xy 99.472781 -24.447959)
			(xy 99.515649 -24.483634) (xy 99.552866 -24.525171) (xy 99.583639 -24.571684) (xy 99.607311 -24.622181)
			(xy 99.623379 -24.675588) (xy 99.631499 -24.730764) (xy 99.632008 -24.75865) (xy 99.631499 -24.786536)
			(xy 99.628426 -24.807418) (xy 122.471432 -24.807418) (xy 122.475503 -24.751796) (xy 122.487629 -24.697359)
			(xy 122.507552 -24.645268) (xy 122.534848 -24.596633) (xy 122.568934 -24.55249) (xy 122.609083 -24.513781)
			(xy 122.654441 -24.48133) (xy 122.704041 -24.455829) (xy 122.756825 -24.437822) (xy 122.811668 -24.427692)
			(xy 122.867402 -24.425655) (xy 122.922839 -24.431755) (xy 122.976796 -24.445861) (xy 123.028125 -24.467673)
			(xy 123.075731 -24.496727) (xy 123.118599 -24.532402) (xy 123.155816 -24.573939) (xy 123.186589 -24.620452)
			(xy 123.210261 -24.670949) (xy 123.226329 -24.724356) (xy 123.234449 -24.779532) (xy 123.234958 -24.807418)
			(xy 124.720348 -24.807418) (xy 124.724419 -24.751796) (xy 124.736545 -24.697359) (xy 124.756468 -24.645268)
			(xy 124.783764 -24.596633) (xy 124.81785 -24.55249) (xy 124.857999 -24.513781) (xy 124.903357 -24.48133)
			(xy 124.952957 -24.455829) (xy 125.005741 -24.437822) (xy 125.060584 -24.427692) (xy 125.116318 -24.425655)
			(xy 125.171755 -24.431755) (xy 125.225712 -24.445861) (xy 125.277041 -24.467673) (xy 125.324647 -24.496727)
			(xy 125.367515 -24.532402) (xy 125.404732 -24.573939) (xy 125.435505 -24.620452) (xy 125.459177 -24.670949)
			(xy 125.475245 -24.724356) (xy 125.483365 -24.779532) (xy 125.483874 -24.807418) (xy 125.483365 -24.835304)
			(xy 125.475245 -24.89048) (xy 125.459177 -24.943887) (xy 125.435505 -24.994384) (xy 125.404732 -25.040897)
			(xy 125.367515 -25.082434) (xy 125.324647 -25.118109) (xy 125.277041 -25.147163) (xy 125.225712 -25.168975)
			(xy 125.171755 -25.183081) (xy 125.116318 -25.189181) (xy 125.060584 -25.187144) (xy 125.005741 -25.177014)
			(xy 124.952957 -25.159007) (xy 124.903357 -25.133506) (xy 124.857999 -25.101055) (xy 124.81785 -25.062346)
			(xy 124.783764 -25.018203) (xy 124.756468 -24.969568) (xy 124.736545 -24.917477) (xy 124.724419 -24.86304)
			(xy 124.720348 -24.807418) (xy 123.234958 -24.807418) (xy 123.234449 -24.835304) (xy 123.226329 -24.89048)
			(xy 123.210261 -24.943887) (xy 123.186589 -24.994384) (xy 123.155816 -25.040897) (xy 123.118599 -25.082434)
			(xy 123.075731 -25.118109) (xy 123.028125 -25.147163) (xy 122.976796 -25.168975) (xy 122.922839 -25.183081)
			(xy 122.867402 -25.189181) (xy 122.811668 -25.187144) (xy 122.756825 -25.177014) (xy 122.704041 -25.159007)
			(xy 122.654441 -25.133506) (xy 122.609083 -25.101055) (xy 122.568934 -25.062346) (xy 122.534848 -25.018203)
			(xy 122.507552 -24.969568) (xy 122.487629 -24.917477) (xy 122.475503 -24.86304) (xy 122.471432 -24.807418)
			(xy 99.628426 -24.807418) (xy 99.623379 -24.841712) (xy 99.607311 -24.895119) (xy 99.583639 -24.945616)
			(xy 99.552866 -24.992129) (xy 99.515649 -25.033666) (xy 99.472781 -25.069341) (xy 99.425175 -25.098395)
			(xy 99.373846 -25.120207) (xy 99.319889 -25.134313) (xy 99.264452 -25.140413) (xy 99.208718 -25.138376)
			(xy 99.153875 -25.128246) (xy 99.101091 -25.110239) (xy 99.051491 -25.084738) (xy 99.006133 -25.052287)
			(xy 98.965984 -25.013578) (xy 98.931898 -24.969435) (xy 98.904602 -24.9208) (xy 98.884679 -24.868709)
			(xy 98.872553 -24.814272) (xy 98.868482 -24.75865) (xy 96.836467 -24.75865) (xy 96.87215 -24.798475)
			(xy 96.902923 -24.844988) (xy 96.926595 -24.895485) (xy 96.942663 -24.948892) (xy 96.950783 -25.004068)
			(xy 96.951292 -25.031954) (xy 96.950783 -25.05984) (xy 96.942663 -25.115016) (xy 96.926595 -25.168423)
			(xy 96.902923 -25.21892) (xy 96.87215 -25.265433) (xy 96.834933 -25.30697) (xy 96.792065 -25.342645)
			(xy 96.744459 -25.371699) (xy 96.69313 -25.393511) (xy 96.639173 -25.407617) (xy 96.583736 -25.413717)
			(xy 96.528002 -25.41168) (xy 96.473159 -25.40155) (xy 96.420375 -25.383543) (xy 96.370775 -25.358042)
			(xy 96.325417 -25.325591) (xy 96.285268 -25.286882) (xy 96.251182 -25.242739) (xy 96.223886 -25.194104)
			(xy 96.203963 -25.142013) (xy 96.191837 -25.087576) (xy 96.187766 -25.031954) (xy 92.322465 -25.031954)
			(xy 92.365753 -25.050349) (xy 92.413359 -25.079403) (xy 92.456227 -25.115078) (xy 92.493444 -25.156615)
			(xy 92.524217 -25.203128) (xy 92.547889 -25.253625) (xy 92.563957 -25.307032) (xy 92.572077 -25.362208)
			(xy 92.572586 -25.390094) (xy 92.572077 -25.41798) (xy 92.563957 -25.473156) (xy 92.547889 -25.526563)
			(xy 92.5328 -25.55875) (xy 100.641656 -25.55875) (xy 100.645727 -25.503128) (xy 100.657853 -25.448691)
			(xy 100.677776 -25.3966) (xy 100.705072 -25.347965) (xy 100.739158 -25.303822) (xy 100.779307 -25.265113)
			(xy 100.824665 -25.232662) (xy 100.874265 -25.207161) (xy 100.927049 -25.189154) (xy 100.981892 -25.179024)
			(xy 101.037626 -25.176987) (xy 101.093063 -25.183087) (xy 101.14702 -25.197193) (xy 101.198349 -25.219005)
			(xy 101.245955 -25.248059) (xy 101.288823 -25.283734) (xy 101.32604 -25.325271) (xy 101.356813 -25.371784)
			(xy 101.365396 -25.390094) (xy 129.909314 -25.390094) (xy 129.913385 -25.334472) (xy 129.925511 -25.280035)
			(xy 129.945434 -25.227944) (xy 129.97273 -25.179309) (xy 130.006816 -25.135166) (xy 130.046965 -25.096457)
			(xy 130.092323 -25.064006) (xy 130.141923 -25.038505) (xy 130.194707 -25.020498) (xy 130.24955 -25.010368)
			(xy 130.305284 -25.008331) (xy 130.360721 -25.014431) (xy 130.414678 -25.028537) (xy 130.422719 -25.031954)
			(xy 134.28802 -25.031954) (xy 134.292091 -24.976332) (xy 134.304217 -24.921895) (xy 134.32414 -24.869804)
			(xy 134.351436 -24.821169) (xy 134.385522 -24.777026) (xy 134.425671 -24.738317) (xy 134.471029 -24.705866)
			(xy 134.520629 -24.680365) (xy 134.573413 -24.662358) (xy 134.628256 -24.652228) (xy 134.68399 -24.650191)
			(xy 134.739427 -24.656291) (xy 134.793384 -24.670397) (xy 134.844713 -24.692209) (xy 134.892319 -24.721263)
			(xy 134.935187 -24.756938) (xy 134.936721 -24.75865) (xy 136.968736 -24.75865) (xy 136.972807 -24.703028)
			(xy 136.984933 -24.648591) (xy 137.004856 -24.5965) (xy 137.032152 -24.547865) (xy 137.066238 -24.503722)
			(xy 137.106387 -24.465013) (xy 137.151745 -24.432562) (xy 137.201345 -24.407061) (xy 137.254129 -24.389054)
			(xy 137.308972 -24.378924) (xy 137.364706 -24.376887) (xy 137.420143 -24.382987) (xy 137.4741 -24.397093)
			(xy 137.525429 -24.418905) (xy 137.573035 -24.447959) (xy 137.615903 -24.483634) (xy 137.65312 -24.525171)
			(xy 137.683893 -24.571684) (xy 137.707565 -24.622181) (xy 137.723633 -24.675588) (xy 137.731753 -24.730764)
			(xy 137.732262 -24.75865) (xy 137.731753 -24.786536) (xy 137.72868 -24.807418) (xy 148.47138 -24.807418)
			(xy 148.475451 -24.751796) (xy 148.487577 -24.697359) (xy 148.5075 -24.645268) (xy 148.534796 -24.596633)
			(xy 148.568882 -24.55249) (xy 148.609031 -24.513781) (xy 148.654389 -24.48133) (xy 148.703989 -24.455829)
			(xy 148.756773 -24.437822) (xy 148.811616 -24.427692) (xy 148.86735 -24.425655) (xy 148.922787 -24.431755)
			(xy 148.976744 -24.445861) (xy 149.028073 -24.467673) (xy 149.075679 -24.496727) (xy 149.118547 -24.532402)
			(xy 149.155764 -24.573939) (xy 149.186537 -24.620452) (xy 149.210209 -24.670949) (xy 149.226277 -24.724356)
			(xy 149.234397 -24.779532) (xy 149.234906 -24.807418) (xy 150.720296 -24.807418) (xy 150.724367 -24.751796)
			(xy 150.736493 -24.697359) (xy 150.756416 -24.645268) (xy 150.783712 -24.596633) (xy 150.817798 -24.55249)
			(xy 150.857947 -24.513781) (xy 150.903305 -24.48133) (xy 150.952905 -24.455829) (xy 151.005689 -24.437822)
			(xy 151.060532 -24.427692) (xy 151.116266 -24.425655) (xy 151.171703 -24.431755) (xy 151.22566 -24.445861)
			(xy 151.276989 -24.467673) (xy 151.324595 -24.496727) (xy 151.367463 -24.532402) (xy 151.40468 -24.573939)
			(xy 151.435453 -24.620452) (xy 151.459125 -24.670949) (xy 151.475193 -24.724356) (xy 151.483313 -24.779532)
			(xy 151.483822 -24.807418) (xy 151.483313 -24.835304) (xy 151.475193 -24.89048) (xy 151.459125 -24.943887)
			(xy 151.435453 -24.994384) (xy 151.40468 -25.040897) (xy 151.367463 -25.082434) (xy 151.324595 -25.118109)
			(xy 151.276989 -25.147163) (xy 151.22566 -25.168975) (xy 151.171703 -25.183081) (xy 151.116266 -25.189181)
			(xy 151.060532 -25.187144) (xy 151.005689 -25.177014) (xy 150.952905 -25.159007) (xy 150.903305 -25.133506)
			(xy 150.857947 -25.101055) (xy 150.817798 -25.062346) (xy 150.783712 -25.018203) (xy 150.756416 -24.969568)
			(xy 150.736493 -24.917477) (xy 150.724367 -24.86304) (xy 150.720296 -24.807418) (xy 149.234906 -24.807418)
			(xy 149.234397 -24.835304) (xy 149.226277 -24.89048) (xy 149.210209 -24.943887) (xy 149.186537 -24.994384)
			(xy 149.155764 -25.040897) (xy 149.118547 -25.082434) (xy 149.075679 -25.118109) (xy 149.028073 -25.147163)
			(xy 148.976744 -25.168975) (xy 148.922787 -25.183081) (xy 148.86735 -25.189181) (xy 148.811616 -25.187144)
			(xy 148.756773 -25.177014) (xy 148.703989 -25.159007) (xy 148.654389 -25.133506) (xy 148.609031 -25.101055)
			(xy 148.568882 -25.062346) (xy 148.534796 -25.018203) (xy 148.5075 -24.969568) (xy 148.487577 -24.917477)
			(xy 148.475451 -24.86304) (xy 148.47138 -24.807418) (xy 137.72868 -24.807418) (xy 137.723633 -24.841712)
			(xy 137.707565 -24.895119) (xy 137.683893 -24.945616) (xy 137.65312 -24.992129) (xy 137.615903 -25.033666)
			(xy 137.573035 -25.069341) (xy 137.525429 -25.098395) (xy 137.4741 -25.120207) (xy 137.420143 -25.134313)
			(xy 137.364706 -25.140413) (xy 137.308972 -25.138376) (xy 137.254129 -25.128246) (xy 137.201345 -25.110239)
			(xy 137.151745 -25.084738) (xy 137.106387 -25.052287) (xy 137.066238 -25.013578) (xy 137.032152 -24.969435)
			(xy 137.004856 -24.9208) (xy 136.984933 -24.868709) (xy 136.972807 -24.814272) (xy 136.968736 -24.75865)
			(xy 134.936721 -24.75865) (xy 134.972404 -24.798475) (xy 135.003177 -24.844988) (xy 135.026849 -24.895485)
			(xy 135.042917 -24.948892) (xy 135.051037 -25.004068) (xy 135.051546 -25.031954) (xy 135.051037 -25.05984)
			(xy 135.042917 -25.115016) (xy 135.026849 -25.168423) (xy 135.003177 -25.21892) (xy 134.972404 -25.265433)
			(xy 134.935187 -25.30697) (xy 134.892319 -25.342645) (xy 134.844713 -25.371699) (xy 134.793384 -25.393511)
			(xy 134.739427 -25.407617) (xy 134.68399 -25.413717) (xy 134.628256 -25.41168) (xy 134.573413 -25.40155)
			(xy 134.520629 -25.383543) (xy 134.471029 -25.358042) (xy 134.425671 -25.325591) (xy 134.385522 -25.286882)
			(xy 134.351436 -25.242739) (xy 134.32414 -25.194104) (xy 134.304217 -25.142013) (xy 134.292091 -25.087576)
			(xy 134.28802 -25.031954) (xy 130.422719 -25.031954) (xy 130.466007 -25.050349) (xy 130.513613 -25.079403)
			(xy 130.556481 -25.115078) (xy 130.593698 -25.156615) (xy 130.624471 -25.203128) (xy 130.648143 -25.253625)
			(xy 130.664211 -25.307032) (xy 130.672331 -25.362208) (xy 130.67284 -25.390094) (xy 130.672331 -25.41798)
			(xy 130.664211 -25.473156) (xy 130.648143 -25.526563) (xy 130.633054 -25.55875) (xy 138.74191 -25.55875)
			(xy 138.745981 -25.503128) (xy 138.758107 -25.448691) (xy 138.77803 -25.3966) (xy 138.805326 -25.347965)
			(xy 138.839412 -25.303822) (xy 138.879561 -25.265113) (xy 138.924919 -25.232662) (xy 138.974519 -25.207161)
			(xy 139.027303 -25.189154) (xy 139.082146 -25.179024) (xy 139.13788 -25.176987) (xy 139.193317 -25.183087)
			(xy 139.247274 -25.197193) (xy 139.298603 -25.219005) (xy 139.346209 -25.248059) (xy 139.389077 -25.283734)
			(xy 139.426294 -25.325271) (xy 139.457067 -25.371784) (xy 139.46565 -25.390094) (xy 155.909262 -25.390094)
			(xy 155.913333 -25.334472) (xy 155.925459 -25.280035) (xy 155.945382 -25.227944) (xy 155.972678 -25.179309)
			(xy 156.006764 -25.135166) (xy 156.046913 -25.096457) (xy 156.092271 -25.064006) (xy 156.141871 -25.038505)
			(xy 156.194655 -25.020498) (xy 156.249498 -25.010368) (xy 156.305232 -25.008331) (xy 156.360669 -25.014431)
			(xy 156.414626 -25.028537) (xy 156.422667 -25.031954) (xy 160.287968 -25.031954) (xy 160.292039 -24.976332)
			(xy 160.304165 -24.921895) (xy 160.324088 -24.869804) (xy 160.351384 -24.821169) (xy 160.38547 -24.777026)
			(xy 160.425619 -24.738317) (xy 160.470977 -24.705866) (xy 160.520577 -24.680365) (xy 160.573361 -24.662358)
			(xy 160.628204 -24.652228) (xy 160.683938 -24.650191) (xy 160.739375 -24.656291) (xy 160.793332 -24.670397)
			(xy 160.844661 -24.692209) (xy 160.892267 -24.721263) (xy 160.935135 -24.756938) (xy 160.936669 -24.75865)
			(xy 162.968684 -24.75865) (xy 162.972755 -24.703028) (xy 162.984881 -24.648591) (xy 163.004804 -24.5965)
			(xy 163.0321 -24.547865) (xy 163.066186 -24.503722) (xy 163.106335 -24.465013) (xy 163.151693 -24.432562)
			(xy 163.201293 -24.407061) (xy 163.254077 -24.389054) (xy 163.30892 -24.378924) (xy 163.364654 -24.376887)
			(xy 163.420091 -24.382987) (xy 163.474048 -24.397093) (xy 163.525377 -24.418905) (xy 163.572983 -24.447959)
			(xy 163.615851 -24.483634) (xy 163.653068 -24.525171) (xy 163.683841 -24.571684) (xy 163.707513 -24.622181)
			(xy 163.723581 -24.675588) (xy 163.731701 -24.730764) (xy 163.73221 -24.75865) (xy 163.731701 -24.786536)
			(xy 163.728628 -24.807418) (xy 174.471328 -24.807418) (xy 174.475399 -24.751796) (xy 174.487525 -24.697359)
			(xy 174.507448 -24.645268) (xy 174.534744 -24.596633) (xy 174.56883 -24.55249) (xy 174.608979 -24.513781)
			(xy 174.654337 -24.48133) (xy 174.703937 -24.455829) (xy 174.756721 -24.437822) (xy 174.811564 -24.427692)
			(xy 174.867298 -24.425655) (xy 174.922735 -24.431755) (xy 174.976692 -24.445861) (xy 175.028021 -24.467673)
			(xy 175.075627 -24.496727) (xy 175.118495 -24.532402) (xy 175.155712 -24.573939) (xy 175.186485 -24.620452)
			(xy 175.210157 -24.670949) (xy 175.226225 -24.724356) (xy 175.234345 -24.779532) (xy 175.234854 -24.807418)
			(xy 176.720244 -24.807418) (xy 176.724315 -24.751796) (xy 176.736441 -24.697359) (xy 176.756364 -24.645268)
			(xy 176.78366 -24.596633) (xy 176.817746 -24.55249) (xy 176.857895 -24.513781) (xy 176.903253 -24.48133)
			(xy 176.952853 -24.455829) (xy 177.005637 -24.437822) (xy 177.06048 -24.427692) (xy 177.116214 -24.425655)
			(xy 177.171651 -24.431755) (xy 177.225608 -24.445861) (xy 177.276937 -24.467673) (xy 177.324543 -24.496727)
			(xy 177.367411 -24.532402) (xy 177.404628 -24.573939) (xy 177.435401 -24.620452) (xy 177.459073 -24.670949)
			(xy 177.475141 -24.724356) (xy 177.483261 -24.779532) (xy 177.48377 -24.807418) (xy 177.483261 -24.835304)
			(xy 177.475141 -24.89048) (xy 177.459073 -24.943887) (xy 177.435401 -24.994384) (xy 177.404628 -25.040897)
			(xy 177.367411 -25.082434) (xy 177.324543 -25.118109) (xy 177.276937 -25.147163) (xy 177.225608 -25.168975)
			(xy 177.171651 -25.183081) (xy 177.116214 -25.189181) (xy 177.06048 -25.187144) (xy 177.005637 -25.177014)
			(xy 176.952853 -25.159007) (xy 176.903253 -25.133506) (xy 176.857895 -25.101055) (xy 176.817746 -25.062346)
			(xy 176.78366 -25.018203) (xy 176.756364 -24.969568) (xy 176.736441 -24.917477) (xy 176.724315 -24.86304)
			(xy 176.720244 -24.807418) (xy 175.234854 -24.807418) (xy 175.234345 -24.835304) (xy 175.226225 -24.89048)
			(xy 175.210157 -24.943887) (xy 175.186485 -24.994384) (xy 175.155712 -25.040897) (xy 175.118495 -25.082434)
			(xy 175.075627 -25.118109) (xy 175.028021 -25.147163) (xy 174.976692 -25.168975) (xy 174.922735 -25.183081)
			(xy 174.867298 -25.189181) (xy 174.811564 -25.187144) (xy 174.756721 -25.177014) (xy 174.703937 -25.159007)
			(xy 174.654337 -25.133506) (xy 174.608979 -25.101055) (xy 174.56883 -25.062346) (xy 174.534744 -25.018203)
			(xy 174.507448 -24.969568) (xy 174.487525 -24.917477) (xy 174.475399 -24.86304) (xy 174.471328 -24.807418)
			(xy 163.728628 -24.807418) (xy 163.723581 -24.841712) (xy 163.707513 -24.895119) (xy 163.683841 -24.945616)
			(xy 163.653068 -24.992129) (xy 163.615851 -25.033666) (xy 163.572983 -25.069341) (xy 163.525377 -25.098395)
			(xy 163.474048 -25.120207) (xy 163.420091 -25.134313) (xy 163.364654 -25.140413) (xy 163.30892 -25.138376)
			(xy 163.254077 -25.128246) (xy 163.201293 -25.110239) (xy 163.151693 -25.084738) (xy 163.106335 -25.052287)
			(xy 163.066186 -25.013578) (xy 163.0321 -24.969435) (xy 163.004804 -24.9208) (xy 162.984881 -24.868709)
			(xy 162.972755 -24.814272) (xy 162.968684 -24.75865) (xy 160.936669 -24.75865) (xy 160.972352 -24.798475)
			(xy 161.003125 -24.844988) (xy 161.026797 -24.895485) (xy 161.042865 -24.948892) (xy 161.050985 -25.004068)
			(xy 161.051494 -25.031954) (xy 161.050985 -25.05984) (xy 161.042865 -25.115016) (xy 161.026797 -25.168423)
			(xy 161.003125 -25.21892) (xy 160.972352 -25.265433) (xy 160.935135 -25.30697) (xy 160.892267 -25.342645)
			(xy 160.844661 -25.371699) (xy 160.793332 -25.393511) (xy 160.739375 -25.407617) (xy 160.683938 -25.413717)
			(xy 160.628204 -25.41168) (xy 160.573361 -25.40155) (xy 160.520577 -25.383543) (xy 160.470977 -25.358042)
			(xy 160.425619 -25.325591) (xy 160.38547 -25.286882) (xy 160.351384 -25.242739) (xy 160.324088 -25.194104)
			(xy 160.304165 -25.142013) (xy 160.292039 -25.087576) (xy 160.287968 -25.031954) (xy 156.422667 -25.031954)
			(xy 156.465955 -25.050349) (xy 156.513561 -25.079403) (xy 156.556429 -25.115078) (xy 156.593646 -25.156615)
			(xy 156.624419 -25.203128) (xy 156.648091 -25.253625) (xy 156.664159 -25.307032) (xy 156.672279 -25.362208)
			(xy 156.672788 -25.390094) (xy 156.672279 -25.41798) (xy 156.664159 -25.473156) (xy 156.648091 -25.526563)
			(xy 156.633002 -25.55875) (xy 164.741858 -25.55875) (xy 164.745929 -25.503128) (xy 164.758055 -25.448691)
			(xy 164.777978 -25.3966) (xy 164.805274 -25.347965) (xy 164.83936 -25.303822) (xy 164.879509 -25.265113)
			(xy 164.924867 -25.232662) (xy 164.974467 -25.207161) (xy 165.027251 -25.189154) (xy 165.082094 -25.179024)
			(xy 165.137828 -25.176987) (xy 165.193265 -25.183087) (xy 165.247222 -25.197193) (xy 165.298551 -25.219005)
			(xy 165.346157 -25.248059) (xy 165.389025 -25.283734) (xy 165.426242 -25.325271) (xy 165.457015 -25.371784)
			(xy 165.465598 -25.390094) (xy 181.90921 -25.390094) (xy 181.913281 -25.334472) (xy 181.925407 -25.280035)
			(xy 181.94533 -25.227944) (xy 181.972626 -25.179309) (xy 182.006712 -25.135166) (xy 182.046861 -25.096457)
			(xy 182.092219 -25.064006) (xy 182.141819 -25.038505) (xy 182.194603 -25.020498) (xy 182.249446 -25.010368)
			(xy 182.30518 -25.008331) (xy 182.360617 -25.014431) (xy 182.414574 -25.028537) (xy 182.422615 -25.031954)
			(xy 186.287916 -25.031954) (xy 186.291987 -24.976332) (xy 186.304113 -24.921895) (xy 186.324036 -24.869804)
			(xy 186.351332 -24.821169) (xy 186.385418 -24.777026) (xy 186.425567 -24.738317) (xy 186.470925 -24.705866)
			(xy 186.520525 -24.680365) (xy 186.573309 -24.662358) (xy 186.628152 -24.652228) (xy 186.683886 -24.650191)
			(xy 186.739323 -24.656291) (xy 186.79328 -24.670397) (xy 186.844609 -24.692209) (xy 186.892215 -24.721263)
			(xy 186.935083 -24.756938) (xy 186.936617 -24.75865) (xy 188.968632 -24.75865) (xy 188.972703 -24.703028)
			(xy 188.984829 -24.648591) (xy 189.004752 -24.5965) (xy 189.032048 -24.547865) (xy 189.066134 -24.503722)
			(xy 189.106283 -24.465013) (xy 189.151641 -24.432562) (xy 189.201241 -24.407061) (xy 189.254025 -24.389054)
			(xy 189.308868 -24.378924) (xy 189.364602 -24.376887) (xy 189.420039 -24.382987) (xy 189.473996 -24.397093)
			(xy 189.525325 -24.418905) (xy 189.572931 -24.447959) (xy 189.615799 -24.483634) (xy 189.653016 -24.525171)
			(xy 189.683789 -24.571684) (xy 189.707461 -24.622181) (xy 189.723529 -24.675588) (xy 189.731649 -24.730764)
			(xy 189.732158 -24.75865) (xy 189.731649 -24.786536) (xy 189.728576 -24.807418) (xy 200.471276 -24.807418)
			(xy 200.475347 -24.751796) (xy 200.487473 -24.697359) (xy 200.507396 -24.645268) (xy 200.534692 -24.596633)
			(xy 200.568778 -24.55249) (xy 200.608927 -24.513781) (xy 200.654285 -24.48133) (xy 200.703885 -24.455829)
			(xy 200.756669 -24.437822) (xy 200.811512 -24.427692) (xy 200.867246 -24.425655) (xy 200.922683 -24.431755)
			(xy 200.97664 -24.445861) (xy 201.027969 -24.467673) (xy 201.075575 -24.496727) (xy 201.118443 -24.532402)
			(xy 201.15566 -24.573939) (xy 201.186433 -24.620452) (xy 201.210105 -24.670949) (xy 201.226173 -24.724356)
			(xy 201.234293 -24.779532) (xy 201.234802 -24.807418) (xy 202.720192 -24.807418) (xy 202.724263 -24.751796)
			(xy 202.736389 -24.697359) (xy 202.756312 -24.645268) (xy 202.783608 -24.596633) (xy 202.817694 -24.55249)
			(xy 202.857843 -24.513781) (xy 202.903201 -24.48133) (xy 202.952801 -24.455829) (xy 203.005585 -24.437822)
			(xy 203.060428 -24.427692) (xy 203.116162 -24.425655) (xy 203.171599 -24.431755) (xy 203.225556 -24.445861)
			(xy 203.276885 -24.467673) (xy 203.324491 -24.496727) (xy 203.367359 -24.532402) (xy 203.404576 -24.573939)
			(xy 203.435349 -24.620452) (xy 203.459021 -24.670949) (xy 203.475089 -24.724356) (xy 203.483209 -24.779532)
			(xy 203.483718 -24.807418) (xy 203.483209 -24.835304) (xy 203.475089 -24.89048) (xy 203.459021 -24.943887)
			(xy 203.435349 -24.994384) (xy 203.404576 -25.040897) (xy 203.367359 -25.082434) (xy 203.324491 -25.118109)
			(xy 203.276885 -25.147163) (xy 203.225556 -25.168975) (xy 203.171599 -25.183081) (xy 203.116162 -25.189181)
			(xy 203.060428 -25.187144) (xy 203.005585 -25.177014) (xy 202.952801 -25.159007) (xy 202.903201 -25.133506)
			(xy 202.857843 -25.101055) (xy 202.817694 -25.062346) (xy 202.783608 -25.018203) (xy 202.756312 -24.969568)
			(xy 202.736389 -24.917477) (xy 202.724263 -24.86304) (xy 202.720192 -24.807418) (xy 201.234802 -24.807418)
			(xy 201.234293 -24.835304) (xy 201.226173 -24.89048) (xy 201.210105 -24.943887) (xy 201.186433 -24.994384)
			(xy 201.15566 -25.040897) (xy 201.118443 -25.082434) (xy 201.075575 -25.118109) (xy 201.027969 -25.147163)
			(xy 200.97664 -25.168975) (xy 200.922683 -25.183081) (xy 200.867246 -25.189181) (xy 200.811512 -25.187144)
			(xy 200.756669 -25.177014) (xy 200.703885 -25.159007) (xy 200.654285 -25.133506) (xy 200.608927 -25.101055)
			(xy 200.568778 -25.062346) (xy 200.534692 -25.018203) (xy 200.507396 -24.969568) (xy 200.487473 -24.917477)
			(xy 200.475347 -24.86304) (xy 200.471276 -24.807418) (xy 189.728576 -24.807418) (xy 189.723529 -24.841712)
			(xy 189.707461 -24.895119) (xy 189.683789 -24.945616) (xy 189.653016 -24.992129) (xy 189.615799 -25.033666)
			(xy 189.572931 -25.069341) (xy 189.525325 -25.098395) (xy 189.473996 -25.120207) (xy 189.420039 -25.134313)
			(xy 189.364602 -25.140413) (xy 189.308868 -25.138376) (xy 189.254025 -25.128246) (xy 189.201241 -25.110239)
			(xy 189.151641 -25.084738) (xy 189.106283 -25.052287) (xy 189.066134 -25.013578) (xy 189.032048 -24.969435)
			(xy 189.004752 -24.9208) (xy 188.984829 -24.868709) (xy 188.972703 -24.814272) (xy 188.968632 -24.75865)
			(xy 186.936617 -24.75865) (xy 186.9723 -24.798475) (xy 187.003073 -24.844988) (xy 187.026745 -24.895485)
			(xy 187.042813 -24.948892) (xy 187.050933 -25.004068) (xy 187.051442 -25.031954) (xy 187.050933 -25.05984)
			(xy 187.042813 -25.115016) (xy 187.026745 -25.168423) (xy 187.003073 -25.21892) (xy 186.9723 -25.265433)
			(xy 186.935083 -25.30697) (xy 186.892215 -25.342645) (xy 186.844609 -25.371699) (xy 186.79328 -25.393511)
			(xy 186.739323 -25.407617) (xy 186.683886 -25.413717) (xy 186.628152 -25.41168) (xy 186.573309 -25.40155)
			(xy 186.520525 -25.383543) (xy 186.470925 -25.358042) (xy 186.425567 -25.325591) (xy 186.385418 -25.286882)
			(xy 186.351332 -25.242739) (xy 186.324036 -25.194104) (xy 186.304113 -25.142013) (xy 186.291987 -25.087576)
			(xy 186.287916 -25.031954) (xy 182.422615 -25.031954) (xy 182.465903 -25.050349) (xy 182.513509 -25.079403)
			(xy 182.556377 -25.115078) (xy 182.593594 -25.156615) (xy 182.624367 -25.203128) (xy 182.648039 -25.253625)
			(xy 182.664107 -25.307032) (xy 182.672227 -25.362208) (xy 182.672736 -25.390094) (xy 182.672227 -25.41798)
			(xy 182.664107 -25.473156) (xy 182.648039 -25.526563) (xy 182.63295 -25.55875) (xy 190.741806 -25.55875)
			(xy 190.745877 -25.503128) (xy 190.758003 -25.448691) (xy 190.777926 -25.3966) (xy 190.805222 -25.347965)
			(xy 190.839308 -25.303822) (xy 190.879457 -25.265113) (xy 190.924815 -25.232662) (xy 190.974415 -25.207161)
			(xy 191.027199 -25.189154) (xy 191.082042 -25.179024) (xy 191.137776 -25.176987) (xy 191.193213 -25.183087)
			(xy 191.24717 -25.197193) (xy 191.298499 -25.219005) (xy 191.346105 -25.248059) (xy 191.388973 -25.283734)
			(xy 191.42619 -25.325271) (xy 191.456963 -25.371784) (xy 191.465546 -25.390094) (xy 207.909158 -25.390094)
			(xy 207.913229 -25.334472) (xy 207.925355 -25.280035) (xy 207.945278 -25.227944) (xy 207.972574 -25.179309)
			(xy 208.00666 -25.135166) (xy 208.046809 -25.096457) (xy 208.092167 -25.064006) (xy 208.141767 -25.038505)
			(xy 208.194551 -25.020498) (xy 208.249394 -25.010368) (xy 208.305128 -25.008331) (xy 208.360565 -25.014431)
			(xy 208.414522 -25.028537) (xy 208.422563 -25.031954) (xy 212.287864 -25.031954) (xy 212.291935 -24.976332)
			(xy 212.304061 -24.921895) (xy 212.323984 -24.869804) (xy 212.35128 -24.821169) (xy 212.385366 -24.777026)
			(xy 212.425515 -24.738317) (xy 212.470873 -24.705866) (xy 212.520473 -24.680365) (xy 212.573257 -24.662358)
			(xy 212.6281 -24.652228) (xy 212.683834 -24.650191) (xy 212.739271 -24.656291) (xy 212.793228 -24.670397)
			(xy 212.844557 -24.692209) (xy 212.892163 -24.721263) (xy 212.935031 -24.756938) (xy 212.936565 -24.75865)
			(xy 214.96858 -24.75865) (xy 214.972651 -24.703028) (xy 214.984777 -24.648591) (xy 215.0047 -24.5965)
			(xy 215.031996 -24.547865) (xy 215.066082 -24.503722) (xy 215.106231 -24.465013) (xy 215.151589 -24.432562)
			(xy 215.201189 -24.407061) (xy 215.253973 -24.389054) (xy 215.308816 -24.378924) (xy 215.36455 -24.376887)
			(xy 215.419987 -24.382987) (xy 215.473944 -24.397093) (xy 215.525273 -24.418905) (xy 215.572879 -24.447959)
			(xy 215.615747 -24.483634) (xy 215.652964 -24.525171) (xy 215.683737 -24.571684) (xy 215.707409 -24.622181)
			(xy 215.723477 -24.675588) (xy 215.731597 -24.730764) (xy 215.732106 -24.75865) (xy 215.731597 -24.786536)
			(xy 215.728524 -24.807418) (xy 238.571276 -24.807418) (xy 238.575347 -24.751796) (xy 238.587473 -24.697359)
			(xy 238.607396 -24.645268) (xy 238.634692 -24.596633) (xy 238.668778 -24.55249) (xy 238.708927 -24.513781)
			(xy 238.754285 -24.48133) (xy 238.803885 -24.455829) (xy 238.856669 -24.437822) (xy 238.911512 -24.427692)
			(xy 238.967246 -24.425655) (xy 239.022683 -24.431755) (xy 239.07664 -24.445861) (xy 239.127969 -24.467673)
			(xy 239.175575 -24.496727) (xy 239.218443 -24.532402) (xy 239.25566 -24.573939) (xy 239.286433 -24.620452)
			(xy 239.310105 -24.670949) (xy 239.326173 -24.724356) (xy 239.334293 -24.779532) (xy 239.334802 -24.807418)
			(xy 240.820192 -24.807418) (xy 240.824263 -24.751796) (xy 240.836389 -24.697359) (xy 240.856312 -24.645268)
			(xy 240.883608 -24.596633) (xy 240.917694 -24.55249) (xy 240.957843 -24.513781) (xy 241.003201 -24.48133)
			(xy 241.052801 -24.455829) (xy 241.105585 -24.437822) (xy 241.160428 -24.427692) (xy 241.216162 -24.425655)
			(xy 241.271599 -24.431755) (xy 241.325556 -24.445861) (xy 241.376885 -24.467673) (xy 241.424491 -24.496727)
			(xy 241.467359 -24.532402) (xy 241.504576 -24.573939) (xy 241.535349 -24.620452) (xy 241.559021 -24.670949)
			(xy 241.575089 -24.724356) (xy 241.583209 -24.779532) (xy 241.583718 -24.807418) (xy 241.583209 -24.835304)
			(xy 241.575089 -24.89048) (xy 241.559021 -24.943887) (xy 241.535349 -24.994384) (xy 241.504576 -25.040897)
			(xy 241.467359 -25.082434) (xy 241.424491 -25.118109) (xy 241.376885 -25.147163) (xy 241.325556 -25.168975)
			(xy 241.271599 -25.183081) (xy 241.216162 -25.189181) (xy 241.160428 -25.187144) (xy 241.105585 -25.177014)
			(xy 241.052801 -25.159007) (xy 241.003201 -25.133506) (xy 240.957843 -25.101055) (xy 240.917694 -25.062346)
			(xy 240.883608 -25.018203) (xy 240.856312 -24.969568) (xy 240.836389 -24.917477) (xy 240.824263 -24.86304)
			(xy 240.820192 -24.807418) (xy 239.334802 -24.807418) (xy 239.334293 -24.835304) (xy 239.326173 -24.89048)
			(xy 239.310105 -24.943887) (xy 239.286433 -24.994384) (xy 239.25566 -25.040897) (xy 239.218443 -25.082434)
			(xy 239.175575 -25.118109) (xy 239.127969 -25.147163) (xy 239.07664 -25.168975) (xy 239.022683 -25.183081)
			(xy 238.967246 -25.189181) (xy 238.911512 -25.187144) (xy 238.856669 -25.177014) (xy 238.803885 -25.159007)
			(xy 238.754285 -25.133506) (xy 238.708927 -25.101055) (xy 238.668778 -25.062346) (xy 238.634692 -25.018203)
			(xy 238.607396 -24.969568) (xy 238.587473 -24.917477) (xy 238.575347 -24.86304) (xy 238.571276 -24.807418)
			(xy 215.728524 -24.807418) (xy 215.723477 -24.841712) (xy 215.707409 -24.895119) (xy 215.683737 -24.945616)
			(xy 215.652964 -24.992129) (xy 215.615747 -25.033666) (xy 215.572879 -25.069341) (xy 215.525273 -25.098395)
			(xy 215.473944 -25.120207) (xy 215.419987 -25.134313) (xy 215.36455 -25.140413) (xy 215.308816 -25.138376)
			(xy 215.253973 -25.128246) (xy 215.201189 -25.110239) (xy 215.151589 -25.084738) (xy 215.106231 -25.052287)
			(xy 215.066082 -25.013578) (xy 215.031996 -24.969435) (xy 215.0047 -24.9208) (xy 214.984777 -24.868709)
			(xy 214.972651 -24.814272) (xy 214.96858 -24.75865) (xy 212.936565 -24.75865) (xy 212.972248 -24.798475)
			(xy 213.003021 -24.844988) (xy 213.026693 -24.895485) (xy 213.042761 -24.948892) (xy 213.050881 -25.004068)
			(xy 213.05139 -25.031954) (xy 213.050881 -25.05984) (xy 213.042761 -25.115016) (xy 213.026693 -25.168423)
			(xy 213.003021 -25.21892) (xy 212.972248 -25.265433) (xy 212.935031 -25.30697) (xy 212.892163 -25.342645)
			(xy 212.844557 -25.371699) (xy 212.793228 -25.393511) (xy 212.739271 -25.407617) (xy 212.683834 -25.413717)
			(xy 212.6281 -25.41168) (xy 212.573257 -25.40155) (xy 212.520473 -25.383543) (xy 212.470873 -25.358042)
			(xy 212.425515 -25.325591) (xy 212.385366 -25.286882) (xy 212.35128 -25.242739) (xy 212.323984 -25.194104)
			(xy 212.304061 -25.142013) (xy 212.291935 -25.087576) (xy 212.287864 -25.031954) (xy 208.422563 -25.031954)
			(xy 208.465851 -25.050349) (xy 208.513457 -25.079403) (xy 208.556325 -25.115078) (xy 208.593542 -25.156615)
			(xy 208.624315 -25.203128) (xy 208.647987 -25.253625) (xy 208.664055 -25.307032) (xy 208.672175 -25.362208)
			(xy 208.672684 -25.390094) (xy 208.672175 -25.41798) (xy 208.664055 -25.473156) (xy 208.647987 -25.526563)
			(xy 208.632898 -25.55875) (xy 216.741754 -25.55875) (xy 216.745825 -25.503128) (xy 216.757951 -25.448691)
			(xy 216.777874 -25.3966) (xy 216.80517 -25.347965) (xy 216.839256 -25.303822) (xy 216.879405 -25.265113)
			(xy 216.924763 -25.232662) (xy 216.974363 -25.207161) (xy 217.027147 -25.189154) (xy 217.08199 -25.179024)
			(xy 217.137724 -25.176987) (xy 217.193161 -25.183087) (xy 217.247118 -25.197193) (xy 217.298447 -25.219005)
			(xy 217.346053 -25.248059) (xy 217.388921 -25.283734) (xy 217.426138 -25.325271) (xy 217.456911 -25.371784)
			(xy 217.465494 -25.390094) (xy 246.009158 -25.390094) (xy 246.013229 -25.334472) (xy 246.025355 -25.280035)
			(xy 246.045278 -25.227944) (xy 246.072574 -25.179309) (xy 246.10666 -25.135166) (xy 246.146809 -25.096457)
			(xy 246.192167 -25.064006) (xy 246.241767 -25.038505) (xy 246.294551 -25.020498) (xy 246.349394 -25.010368)
			(xy 246.405128 -25.008331) (xy 246.460565 -25.014431) (xy 246.514522 -25.028537) (xy 246.522563 -25.031954)
			(xy 250.387864 -25.031954) (xy 250.391935 -24.976332) (xy 250.404061 -24.921895) (xy 250.423984 -24.869804)
			(xy 250.45128 -24.821169) (xy 250.485366 -24.777026) (xy 250.525515 -24.738317) (xy 250.570873 -24.705866)
			(xy 250.620473 -24.680365) (xy 250.673257 -24.662358) (xy 250.7281 -24.652228) (xy 250.783834 -24.650191)
			(xy 250.839271 -24.656291) (xy 250.893228 -24.670397) (xy 250.944557 -24.692209) (xy 250.992163 -24.721263)
			(xy 251.035031 -24.756938) (xy 251.036565 -24.75865) (xy 253.06858 -24.75865) (xy 253.072651 -24.703028)
			(xy 253.084777 -24.648591) (xy 253.1047 -24.5965) (xy 253.131996 -24.547865) (xy 253.166082 -24.503722)
			(xy 253.206231 -24.465013) (xy 253.251589 -24.432562) (xy 253.301189 -24.407061) (xy 253.353973 -24.389054)
			(xy 253.408816 -24.378924) (xy 253.46455 -24.376887) (xy 253.519987 -24.382987) (xy 253.573944 -24.397093)
			(xy 253.625273 -24.418905) (xy 253.672879 -24.447959) (xy 253.715747 -24.483634) (xy 253.752964 -24.525171)
			(xy 253.783737 -24.571684) (xy 253.807409 -24.622181) (xy 253.823477 -24.675588) (xy 253.831597 -24.730764)
			(xy 253.832106 -24.75865) (xy 253.831597 -24.786536) (xy 253.828524 -24.807418) (xy 264.571224 -24.807418)
			(xy 264.575295 -24.751796) (xy 264.587421 -24.697359) (xy 264.607344 -24.645268) (xy 264.63464 -24.596633)
			(xy 264.668726 -24.55249) (xy 264.708875 -24.513781) (xy 264.754233 -24.48133) (xy 264.803833 -24.455829)
			(xy 264.856617 -24.437822) (xy 264.91146 -24.427692) (xy 264.967194 -24.425655) (xy 265.022631 -24.431755)
			(xy 265.076588 -24.445861) (xy 265.127917 -24.467673) (xy 265.175523 -24.496727) (xy 265.218391 -24.532402)
			(xy 265.255608 -24.573939) (xy 265.286381 -24.620452) (xy 265.310053 -24.670949) (xy 265.326121 -24.724356)
			(xy 265.334241 -24.779532) (xy 265.33475 -24.807418) (xy 266.82014 -24.807418) (xy 266.824211 -24.751796)
			(xy 266.836337 -24.697359) (xy 266.85626 -24.645268) (xy 266.883556 -24.596633) (xy 266.917642 -24.55249)
			(xy 266.957791 -24.513781) (xy 267.003149 -24.48133) (xy 267.052749 -24.455829) (xy 267.105533 -24.437822)
			(xy 267.160376 -24.427692) (xy 267.21611 -24.425655) (xy 267.271547 -24.431755) (xy 267.325504 -24.445861)
			(xy 267.376833 -24.467673) (xy 267.424439 -24.496727) (xy 267.467307 -24.532402) (xy 267.504524 -24.573939)
			(xy 267.535297 -24.620452) (xy 267.558969 -24.670949) (xy 267.575037 -24.724356) (xy 267.583157 -24.779532)
			(xy 267.583666 -24.807418) (xy 267.583157 -24.835304) (xy 267.575037 -24.89048) (xy 267.558969 -24.943887)
			(xy 267.535297 -24.994384) (xy 267.504524 -25.040897) (xy 267.467307 -25.082434) (xy 267.424439 -25.118109)
			(xy 267.376833 -25.147163) (xy 267.325504 -25.168975) (xy 267.271547 -25.183081) (xy 267.21611 -25.189181)
			(xy 267.160376 -25.187144) (xy 267.105533 -25.177014) (xy 267.052749 -25.159007) (xy 267.003149 -25.133506)
			(xy 266.957791 -25.101055) (xy 266.917642 -25.062346) (xy 266.883556 -25.018203) (xy 266.85626 -24.969568)
			(xy 266.836337 -24.917477) (xy 266.824211 -24.86304) (xy 266.82014 -24.807418) (xy 265.33475 -24.807418)
			(xy 265.334241 -24.835304) (xy 265.326121 -24.89048) (xy 265.310053 -24.943887) (xy 265.286381 -24.994384)
			(xy 265.255608 -25.040897) (xy 265.218391 -25.082434) (xy 265.175523 -25.118109) (xy 265.127917 -25.147163)
			(xy 265.076588 -25.168975) (xy 265.022631 -25.183081) (xy 264.967194 -25.189181) (xy 264.91146 -25.187144)
			(xy 264.856617 -25.177014) (xy 264.803833 -25.159007) (xy 264.754233 -25.133506) (xy 264.708875 -25.101055)
			(xy 264.668726 -25.062346) (xy 264.63464 -25.018203) (xy 264.607344 -24.969568) (xy 264.587421 -24.917477)
			(xy 264.575295 -24.86304) (xy 264.571224 -24.807418) (xy 253.828524 -24.807418) (xy 253.823477 -24.841712)
			(xy 253.807409 -24.895119) (xy 253.783737 -24.945616) (xy 253.752964 -24.992129) (xy 253.715747 -25.033666)
			(xy 253.672879 -25.069341) (xy 253.625273 -25.098395) (xy 253.573944 -25.120207) (xy 253.519987 -25.134313)
			(xy 253.46455 -25.140413) (xy 253.408816 -25.138376) (xy 253.353973 -25.128246) (xy 253.301189 -25.110239)
			(xy 253.251589 -25.084738) (xy 253.206231 -25.052287) (xy 253.166082 -25.013578) (xy 253.131996 -24.969435)
			(xy 253.1047 -24.9208) (xy 253.084777 -24.868709) (xy 253.072651 -24.814272) (xy 253.06858 -24.75865)
			(xy 251.036565 -24.75865) (xy 251.072248 -24.798475) (xy 251.103021 -24.844988) (xy 251.126693 -24.895485)
			(xy 251.142761 -24.948892) (xy 251.150881 -25.004068) (xy 251.15139 -25.031954) (xy 251.150881 -25.05984)
			(xy 251.142761 -25.115016) (xy 251.126693 -25.168423) (xy 251.103021 -25.21892) (xy 251.072248 -25.265433)
			(xy 251.035031 -25.30697) (xy 250.992163 -25.342645) (xy 250.944557 -25.371699) (xy 250.893228 -25.393511)
			(xy 250.839271 -25.407617) (xy 250.783834 -25.413717) (xy 250.7281 -25.41168) (xy 250.673257 -25.40155)
			(xy 250.620473 -25.383543) (xy 250.570873 -25.358042) (xy 250.525515 -25.325591) (xy 250.485366 -25.286882)
			(xy 250.45128 -25.242739) (xy 250.423984 -25.194104) (xy 250.404061 -25.142013) (xy 250.391935 -25.087576)
			(xy 250.387864 -25.031954) (xy 246.522563 -25.031954) (xy 246.565851 -25.050349) (xy 246.613457 -25.079403)
			(xy 246.656325 -25.115078) (xy 246.693542 -25.156615) (xy 246.724315 -25.203128) (xy 246.747987 -25.253625)
			(xy 246.764055 -25.307032) (xy 246.772175 -25.362208) (xy 246.772684 -25.390094) (xy 246.772175 -25.41798)
			(xy 246.764055 -25.473156) (xy 246.747987 -25.526563) (xy 246.732898 -25.55875) (xy 254.841754 -25.55875)
			(xy 254.845825 -25.503128) (xy 254.857951 -25.448691) (xy 254.877874 -25.3966) (xy 254.90517 -25.347965)
			(xy 254.939256 -25.303822) (xy 254.979405 -25.265113) (xy 255.024763 -25.232662) (xy 255.074363 -25.207161)
			(xy 255.127147 -25.189154) (xy 255.18199 -25.179024) (xy 255.237724 -25.176987) (xy 255.293161 -25.183087)
			(xy 255.347118 -25.197193) (xy 255.398447 -25.219005) (xy 255.446053 -25.248059) (xy 255.488921 -25.283734)
			(xy 255.526138 -25.325271) (xy 255.556911 -25.371784) (xy 255.565494 -25.390094) (xy 272.009106 -25.390094)
			(xy 272.013177 -25.334472) (xy 272.025303 -25.280035) (xy 272.045226 -25.227944) (xy 272.072522 -25.179309)
			(xy 272.106608 -25.135166) (xy 272.146757 -25.096457) (xy 272.192115 -25.064006) (xy 272.241715 -25.038505)
			(xy 272.294499 -25.020498) (xy 272.349342 -25.010368) (xy 272.405076 -25.008331) (xy 272.460513 -25.014431)
			(xy 272.51447 -25.028537) (xy 272.522511 -25.031954) (xy 276.387812 -25.031954) (xy 276.391883 -24.976332)
			(xy 276.404009 -24.921895) (xy 276.423932 -24.869804) (xy 276.451228 -24.821169) (xy 276.485314 -24.777026)
			(xy 276.525463 -24.738317) (xy 276.570821 -24.705866) (xy 276.620421 -24.680365) (xy 276.673205 -24.662358)
			(xy 276.728048 -24.652228) (xy 276.783782 -24.650191) (xy 276.839219 -24.656291) (xy 276.893176 -24.670397)
			(xy 276.944505 -24.692209) (xy 276.992111 -24.721263) (xy 277.034979 -24.756938) (xy 277.036513 -24.75865)
			(xy 279.068528 -24.75865) (xy 279.072599 -24.703028) (xy 279.084725 -24.648591) (xy 279.104648 -24.5965)
			(xy 279.131944 -24.547865) (xy 279.16603 -24.503722) (xy 279.206179 -24.465013) (xy 279.251537 -24.432562)
			(xy 279.301137 -24.407061) (xy 279.353921 -24.389054) (xy 279.408764 -24.378924) (xy 279.464498 -24.376887)
			(xy 279.519935 -24.382987) (xy 279.573892 -24.397093) (xy 279.625221 -24.418905) (xy 279.672827 -24.447959)
			(xy 279.715695 -24.483634) (xy 279.752912 -24.525171) (xy 279.783685 -24.571684) (xy 279.807357 -24.622181)
			(xy 279.823425 -24.675588) (xy 279.831545 -24.730764) (xy 279.832054 -24.75865) (xy 279.831545 -24.786536)
			(xy 279.828472 -24.807418) (xy 290.571172 -24.807418) (xy 290.575243 -24.751796) (xy 290.587369 -24.697359)
			(xy 290.607292 -24.645268) (xy 290.634588 -24.596633) (xy 290.668674 -24.55249) (xy 290.708823 -24.513781)
			(xy 290.754181 -24.48133) (xy 290.803781 -24.455829) (xy 290.856565 -24.437822) (xy 290.911408 -24.427692)
			(xy 290.967142 -24.425655) (xy 291.022579 -24.431755) (xy 291.076536 -24.445861) (xy 291.127865 -24.467673)
			(xy 291.175471 -24.496727) (xy 291.218339 -24.532402) (xy 291.255556 -24.573939) (xy 291.286329 -24.620452)
			(xy 291.310001 -24.670949) (xy 291.326069 -24.724356) (xy 291.334189 -24.779532) (xy 291.334698 -24.807418)
			(xy 292.820088 -24.807418) (xy 292.824159 -24.751796) (xy 292.836285 -24.697359) (xy 292.856208 -24.645268)
			(xy 292.883504 -24.596633) (xy 292.91759 -24.55249) (xy 292.957739 -24.513781) (xy 293.003097 -24.48133)
			(xy 293.052697 -24.455829) (xy 293.105481 -24.437822) (xy 293.160324 -24.427692) (xy 293.216058 -24.425655)
			(xy 293.271495 -24.431755) (xy 293.325452 -24.445861) (xy 293.376781 -24.467673) (xy 293.424387 -24.496727)
			(xy 293.467255 -24.532402) (xy 293.504472 -24.573939) (xy 293.535245 -24.620452) (xy 293.558917 -24.670949)
			(xy 293.574985 -24.724356) (xy 293.583105 -24.779532) (xy 293.583614 -24.807418) (xy 293.583105 -24.835304)
			(xy 293.574985 -24.89048) (xy 293.558917 -24.943887) (xy 293.535245 -24.994384) (xy 293.504472 -25.040897)
			(xy 293.467255 -25.082434) (xy 293.424387 -25.118109) (xy 293.376781 -25.147163) (xy 293.325452 -25.168975)
			(xy 293.271495 -25.183081) (xy 293.216058 -25.189181) (xy 293.160324 -25.187144) (xy 293.105481 -25.177014)
			(xy 293.052697 -25.159007) (xy 293.003097 -25.133506) (xy 292.957739 -25.101055) (xy 292.91759 -25.062346)
			(xy 292.883504 -25.018203) (xy 292.856208 -24.969568) (xy 292.836285 -24.917477) (xy 292.824159 -24.86304)
			(xy 292.820088 -24.807418) (xy 291.334698 -24.807418) (xy 291.334189 -24.835304) (xy 291.326069 -24.89048)
			(xy 291.310001 -24.943887) (xy 291.286329 -24.994384) (xy 291.255556 -25.040897) (xy 291.218339 -25.082434)
			(xy 291.175471 -25.118109) (xy 291.127865 -25.147163) (xy 291.076536 -25.168975) (xy 291.022579 -25.183081)
			(xy 290.967142 -25.189181) (xy 290.911408 -25.187144) (xy 290.856565 -25.177014) (xy 290.803781 -25.159007)
			(xy 290.754181 -25.133506) (xy 290.708823 -25.101055) (xy 290.668674 -25.062346) (xy 290.634588 -25.018203)
			(xy 290.607292 -24.969568) (xy 290.587369 -24.917477) (xy 290.575243 -24.86304) (xy 290.571172 -24.807418)
			(xy 279.828472 -24.807418) (xy 279.823425 -24.841712) (xy 279.807357 -24.895119) (xy 279.783685 -24.945616)
			(xy 279.752912 -24.992129) (xy 279.715695 -25.033666) (xy 279.672827 -25.069341) (xy 279.625221 -25.098395)
			(xy 279.573892 -25.120207) (xy 279.519935 -25.134313) (xy 279.464498 -25.140413) (xy 279.408764 -25.138376)
			(xy 279.353921 -25.128246) (xy 279.301137 -25.110239) (xy 279.251537 -25.084738) (xy 279.206179 -25.052287)
			(xy 279.16603 -25.013578) (xy 279.131944 -24.969435) (xy 279.104648 -24.9208) (xy 279.084725 -24.868709)
			(xy 279.072599 -24.814272) (xy 279.068528 -24.75865) (xy 277.036513 -24.75865) (xy 277.072196 -24.798475)
			(xy 277.102969 -24.844988) (xy 277.126641 -24.895485) (xy 277.142709 -24.948892) (xy 277.150829 -25.004068)
			(xy 277.151338 -25.031954) (xy 277.150829 -25.05984) (xy 277.142709 -25.115016) (xy 277.126641 -25.168423)
			(xy 277.102969 -25.21892) (xy 277.072196 -25.265433) (xy 277.034979 -25.30697) (xy 276.992111 -25.342645)
			(xy 276.944505 -25.371699) (xy 276.893176 -25.393511) (xy 276.839219 -25.407617) (xy 276.783782 -25.413717)
			(xy 276.728048 -25.41168) (xy 276.673205 -25.40155) (xy 276.620421 -25.383543) (xy 276.570821 -25.358042)
			(xy 276.525463 -25.325591) (xy 276.485314 -25.286882) (xy 276.451228 -25.242739) (xy 276.423932 -25.194104)
			(xy 276.404009 -25.142013) (xy 276.391883 -25.087576) (xy 276.387812 -25.031954) (xy 272.522511 -25.031954)
			(xy 272.565799 -25.050349) (xy 272.613405 -25.079403) (xy 272.656273 -25.115078) (xy 272.69349 -25.156615)
			(xy 272.724263 -25.203128) (xy 272.747935 -25.253625) (xy 272.764003 -25.307032) (xy 272.772123 -25.362208)
			(xy 272.772632 -25.390094) (xy 272.772123 -25.41798) (xy 272.764003 -25.473156) (xy 272.747935 -25.526563)
			(xy 272.732846 -25.55875) (xy 280.841702 -25.55875) (xy 280.845773 -25.503128) (xy 280.857899 -25.448691)
			(xy 280.877822 -25.3966) (xy 280.905118 -25.347965) (xy 280.939204 -25.303822) (xy 280.979353 -25.265113)
			(xy 281.024711 -25.232662) (xy 281.074311 -25.207161) (xy 281.127095 -25.189154) (xy 281.181938 -25.179024)
			(xy 281.237672 -25.176987) (xy 281.293109 -25.183087) (xy 281.347066 -25.197193) (xy 281.398395 -25.219005)
			(xy 281.446001 -25.248059) (xy 281.488869 -25.283734) (xy 281.526086 -25.325271) (xy 281.556859 -25.371784)
			(xy 281.565442 -25.390094) (xy 298.009054 -25.390094) (xy 298.013125 -25.334472) (xy 298.025251 -25.280035)
			(xy 298.045174 -25.227944) (xy 298.07247 -25.179309) (xy 298.106556 -25.135166) (xy 298.146705 -25.096457)
			(xy 298.192063 -25.064006) (xy 298.241663 -25.038505) (xy 298.294447 -25.020498) (xy 298.34929 -25.010368)
			(xy 298.405024 -25.008331) (xy 298.460461 -25.014431) (xy 298.514418 -25.028537) (xy 298.522459 -25.031954)
			(xy 302.38776 -25.031954) (xy 302.391831 -24.976332) (xy 302.403957 -24.921895) (xy 302.42388 -24.869804)
			(xy 302.451176 -24.821169) (xy 302.485262 -24.777026) (xy 302.525411 -24.738317) (xy 302.570769 -24.705866)
			(xy 302.620369 -24.680365) (xy 302.673153 -24.662358) (xy 302.727996 -24.652228) (xy 302.78373 -24.650191)
			(xy 302.839167 -24.656291) (xy 302.893124 -24.670397) (xy 302.944453 -24.692209) (xy 302.992059 -24.721263)
			(xy 303.034927 -24.756938) (xy 303.036461 -24.75865) (xy 305.068476 -24.75865) (xy 305.072547 -24.703028)
			(xy 305.084673 -24.648591) (xy 305.104596 -24.5965) (xy 305.131892 -24.547865) (xy 305.165978 -24.503722)
			(xy 305.206127 -24.465013) (xy 305.251485 -24.432562) (xy 305.301085 -24.407061) (xy 305.353869 -24.389054)
			(xy 305.408712 -24.378924) (xy 305.464446 -24.376887) (xy 305.519883 -24.382987) (xy 305.57384 -24.397093)
			(xy 305.625169 -24.418905) (xy 305.672775 -24.447959) (xy 305.715643 -24.483634) (xy 305.75286 -24.525171)
			(xy 305.783633 -24.571684) (xy 305.807305 -24.622181) (xy 305.823373 -24.675588) (xy 305.831493 -24.730764)
			(xy 305.832002 -24.75865) (xy 305.831493 -24.786536) (xy 305.82842 -24.807418) (xy 316.57112 -24.807418)
			(xy 316.575191 -24.751796) (xy 316.587317 -24.697359) (xy 316.60724 -24.645268) (xy 316.634536 -24.596633)
			(xy 316.668622 -24.55249) (xy 316.708771 -24.513781) (xy 316.754129 -24.48133) (xy 316.803729 -24.455829)
			(xy 316.856513 -24.437822) (xy 316.911356 -24.427692) (xy 316.96709 -24.425655) (xy 317.022527 -24.431755)
			(xy 317.076484 -24.445861) (xy 317.127813 -24.467673) (xy 317.175419 -24.496727) (xy 317.218287 -24.532402)
			(xy 317.255504 -24.573939) (xy 317.286277 -24.620452) (xy 317.309949 -24.670949) (xy 317.326017 -24.724356)
			(xy 317.334137 -24.779532) (xy 317.334646 -24.807418) (xy 318.820036 -24.807418) (xy 318.824107 -24.751796)
			(xy 318.836233 -24.697359) (xy 318.856156 -24.645268) (xy 318.883452 -24.596633) (xy 318.917538 -24.55249)
			(xy 318.957687 -24.513781) (xy 319.003045 -24.48133) (xy 319.052645 -24.455829) (xy 319.105429 -24.437822)
			(xy 319.160272 -24.427692) (xy 319.216006 -24.425655) (xy 319.271443 -24.431755) (xy 319.3254 -24.445861)
			(xy 319.376729 -24.467673) (xy 319.424335 -24.496727) (xy 319.467203 -24.532402) (xy 319.50442 -24.573939)
			(xy 319.535193 -24.620452) (xy 319.558865 -24.670949) (xy 319.574933 -24.724356) (xy 319.583053 -24.779532)
			(xy 319.583562 -24.807418) (xy 319.583053 -24.835304) (xy 319.574933 -24.89048) (xy 319.558865 -24.943887)
			(xy 319.535193 -24.994384) (xy 319.50442 -25.040897) (xy 319.467203 -25.082434) (xy 319.424335 -25.118109)
			(xy 319.376729 -25.147163) (xy 319.3254 -25.168975) (xy 319.271443 -25.183081) (xy 319.216006 -25.189181)
			(xy 319.160272 -25.187144) (xy 319.105429 -25.177014) (xy 319.052645 -25.159007) (xy 319.003045 -25.133506)
			(xy 318.957687 -25.101055) (xy 318.917538 -25.062346) (xy 318.883452 -25.018203) (xy 318.856156 -24.969568)
			(xy 318.836233 -24.917477) (xy 318.824107 -24.86304) (xy 318.820036 -24.807418) (xy 317.334646 -24.807418)
			(xy 317.334137 -24.835304) (xy 317.326017 -24.89048) (xy 317.309949 -24.943887) (xy 317.286277 -24.994384)
			(xy 317.255504 -25.040897) (xy 317.218287 -25.082434) (xy 317.175419 -25.118109) (xy 317.127813 -25.147163)
			(xy 317.076484 -25.168975) (xy 317.022527 -25.183081) (xy 316.96709 -25.189181) (xy 316.911356 -25.187144)
			(xy 316.856513 -25.177014) (xy 316.803729 -25.159007) (xy 316.754129 -25.133506) (xy 316.708771 -25.101055)
			(xy 316.668622 -25.062346) (xy 316.634536 -25.018203) (xy 316.60724 -24.969568) (xy 316.587317 -24.917477)
			(xy 316.575191 -24.86304) (xy 316.57112 -24.807418) (xy 305.82842 -24.807418) (xy 305.823373 -24.841712)
			(xy 305.807305 -24.895119) (xy 305.783633 -24.945616) (xy 305.75286 -24.992129) (xy 305.715643 -25.033666)
			(xy 305.672775 -25.069341) (xy 305.625169 -25.098395) (xy 305.57384 -25.120207) (xy 305.519883 -25.134313)
			(xy 305.464446 -25.140413) (xy 305.408712 -25.138376) (xy 305.353869 -25.128246) (xy 305.301085 -25.110239)
			(xy 305.251485 -25.084738) (xy 305.206127 -25.052287) (xy 305.165978 -25.013578) (xy 305.131892 -24.969435)
			(xy 305.104596 -24.9208) (xy 305.084673 -24.868709) (xy 305.072547 -24.814272) (xy 305.068476 -24.75865)
			(xy 303.036461 -24.75865) (xy 303.072144 -24.798475) (xy 303.102917 -24.844988) (xy 303.126589 -24.895485)
			(xy 303.142657 -24.948892) (xy 303.150777 -25.004068) (xy 303.151286 -25.031954) (xy 303.150777 -25.05984)
			(xy 303.142657 -25.115016) (xy 303.126589 -25.168423) (xy 303.102917 -25.21892) (xy 303.072144 -25.265433)
			(xy 303.034927 -25.30697) (xy 302.992059 -25.342645) (xy 302.944453 -25.371699) (xy 302.893124 -25.393511)
			(xy 302.839167 -25.407617) (xy 302.78373 -25.413717) (xy 302.727996 -25.41168) (xy 302.673153 -25.40155)
			(xy 302.620369 -25.383543) (xy 302.570769 -25.358042) (xy 302.525411 -25.325591) (xy 302.485262 -25.286882)
			(xy 302.451176 -25.242739) (xy 302.42388 -25.194104) (xy 302.403957 -25.142013) (xy 302.391831 -25.087576)
			(xy 302.38776 -25.031954) (xy 298.522459 -25.031954) (xy 298.565747 -25.050349) (xy 298.613353 -25.079403)
			(xy 298.656221 -25.115078) (xy 298.693438 -25.156615) (xy 298.724211 -25.203128) (xy 298.747883 -25.253625)
			(xy 298.763951 -25.307032) (xy 298.772071 -25.362208) (xy 298.77258 -25.390094) (xy 298.772071 -25.41798)
			(xy 298.763951 -25.473156) (xy 298.747883 -25.526563) (xy 298.732794 -25.55875) (xy 306.84165 -25.55875)
			(xy 306.845721 -25.503128) (xy 306.857847 -25.448691) (xy 306.87777 -25.3966) (xy 306.905066 -25.347965)
			(xy 306.939152 -25.303822) (xy 306.979301 -25.265113) (xy 307.024659 -25.232662) (xy 307.074259 -25.207161)
			(xy 307.127043 -25.189154) (xy 307.181886 -25.179024) (xy 307.23762 -25.176987) (xy 307.293057 -25.183087)
			(xy 307.347014 -25.197193) (xy 307.398343 -25.219005) (xy 307.445949 -25.248059) (xy 307.488817 -25.283734)
			(xy 307.526034 -25.325271) (xy 307.556807 -25.371784) (xy 307.56539 -25.390094) (xy 324.009002 -25.390094)
			(xy 324.013073 -25.334472) (xy 324.025199 -25.280035) (xy 324.045122 -25.227944) (xy 324.072418 -25.179309)
			(xy 324.106504 -25.135166) (xy 324.146653 -25.096457) (xy 324.192011 -25.064006) (xy 324.241611 -25.038505)
			(xy 324.294395 -25.020498) (xy 324.349238 -25.010368) (xy 324.404972 -25.008331) (xy 324.460409 -25.014431)
			(xy 324.514366 -25.028537) (xy 324.522407 -25.031954) (xy 328.387708 -25.031954) (xy 328.391779 -24.976332)
			(xy 328.403905 -24.921895) (xy 328.423828 -24.869804) (xy 328.451124 -24.821169) (xy 328.48521 -24.777026)
			(xy 328.525359 -24.738317) (xy 328.570717 -24.705866) (xy 328.620317 -24.680365) (xy 328.673101 -24.662358)
			(xy 328.727944 -24.652228) (xy 328.783678 -24.650191) (xy 328.839115 -24.656291) (xy 328.893072 -24.670397)
			(xy 328.944401 -24.692209) (xy 328.992007 -24.721263) (xy 329.034875 -24.756938) (xy 329.036409 -24.75865)
			(xy 331.068424 -24.75865) (xy 331.072495 -24.703028) (xy 331.084621 -24.648591) (xy 331.104544 -24.5965)
			(xy 331.13184 -24.547865) (xy 331.165926 -24.503722) (xy 331.206075 -24.465013) (xy 331.251433 -24.432562)
			(xy 331.301033 -24.407061) (xy 331.353817 -24.389054) (xy 331.40866 -24.378924) (xy 331.464394 -24.376887)
			(xy 331.519831 -24.382987) (xy 331.573788 -24.397093) (xy 331.625117 -24.418905) (xy 331.672723 -24.447959)
			(xy 331.715591 -24.483634) (xy 331.752808 -24.525171) (xy 331.783581 -24.571684) (xy 331.807253 -24.622181)
			(xy 331.823321 -24.675588) (xy 331.831441 -24.730764) (xy 331.83195 -24.75865) (xy 331.831441 -24.786536)
			(xy 331.828368 -24.807418) (xy 354.671374 -24.807418) (xy 354.675445 -24.751796) (xy 354.687571 -24.697359)
			(xy 354.707494 -24.645268) (xy 354.73479 -24.596633) (xy 354.768876 -24.55249) (xy 354.809025 -24.513781)
			(xy 354.854383 -24.48133) (xy 354.903983 -24.455829) (xy 354.956767 -24.437822) (xy 355.01161 -24.427692)
			(xy 355.067344 -24.425655) (xy 355.122781 -24.431755) (xy 355.176738 -24.445861) (xy 355.228067 -24.467673)
			(xy 355.275673 -24.496727) (xy 355.318541 -24.532402) (xy 355.355758 -24.573939) (xy 355.386531 -24.620452)
			(xy 355.410203 -24.670949) (xy 355.426271 -24.724356) (xy 355.434391 -24.779532) (xy 355.4349 -24.807418)
			(xy 356.92029 -24.807418) (xy 356.924361 -24.751796) (xy 356.936487 -24.697359) (xy 356.95641 -24.645268)
			(xy 356.983706 -24.596633) (xy 357.017792 -24.55249) (xy 357.057941 -24.513781) (xy 357.103299 -24.48133)
			(xy 357.152899 -24.455829) (xy 357.205683 -24.437822) (xy 357.260526 -24.427692) (xy 357.31626 -24.425655)
			(xy 357.371697 -24.431755) (xy 357.425654 -24.445861) (xy 357.476983 -24.467673) (xy 357.524589 -24.496727)
			(xy 357.567457 -24.532402) (xy 357.604674 -24.573939) (xy 357.635447 -24.620452) (xy 357.659119 -24.670949)
			(xy 357.675187 -24.724356) (xy 357.683307 -24.779532) (xy 357.683816 -24.807418) (xy 357.683307 -24.835304)
			(xy 357.675187 -24.89048) (xy 357.659119 -24.943887) (xy 357.635447 -24.994384) (xy 357.604674 -25.040897)
			(xy 357.567457 -25.082434) (xy 357.524589 -25.118109) (xy 357.476983 -25.147163) (xy 357.425654 -25.168975)
			(xy 357.371697 -25.183081) (xy 357.31626 -25.189181) (xy 357.260526 -25.187144) (xy 357.205683 -25.177014)
			(xy 357.152899 -25.159007) (xy 357.103299 -25.133506) (xy 357.057941 -25.101055) (xy 357.017792 -25.062346)
			(xy 356.983706 -25.018203) (xy 356.95641 -24.969568) (xy 356.936487 -24.917477) (xy 356.924361 -24.86304)
			(xy 356.92029 -24.807418) (xy 355.4349 -24.807418) (xy 355.434391 -24.835304) (xy 355.426271 -24.89048)
			(xy 355.410203 -24.943887) (xy 355.386531 -24.994384) (xy 355.355758 -25.040897) (xy 355.318541 -25.082434)
			(xy 355.275673 -25.118109) (xy 355.228067 -25.147163) (xy 355.176738 -25.168975) (xy 355.122781 -25.183081)
			(xy 355.067344 -25.189181) (xy 355.01161 -25.187144) (xy 354.956767 -25.177014) (xy 354.903983 -25.159007)
			(xy 354.854383 -25.133506) (xy 354.809025 -25.101055) (xy 354.768876 -25.062346) (xy 354.73479 -25.018203)
			(xy 354.707494 -24.969568) (xy 354.687571 -24.917477) (xy 354.675445 -24.86304) (xy 354.671374 -24.807418)
			(xy 331.828368 -24.807418) (xy 331.823321 -24.841712) (xy 331.807253 -24.895119) (xy 331.783581 -24.945616)
			(xy 331.752808 -24.992129) (xy 331.715591 -25.033666) (xy 331.672723 -25.069341) (xy 331.625117 -25.098395)
			(xy 331.573788 -25.120207) (xy 331.519831 -25.134313) (xy 331.464394 -25.140413) (xy 331.40866 -25.138376)
			(xy 331.353817 -25.128246) (xy 331.301033 -25.110239) (xy 331.251433 -25.084738) (xy 331.206075 -25.052287)
			(xy 331.165926 -25.013578) (xy 331.13184 -24.969435) (xy 331.104544 -24.9208) (xy 331.084621 -24.868709)
			(xy 331.072495 -24.814272) (xy 331.068424 -24.75865) (xy 329.036409 -24.75865) (xy 329.072092 -24.798475)
			(xy 329.102865 -24.844988) (xy 329.126537 -24.895485) (xy 329.142605 -24.948892) (xy 329.150725 -25.004068)
			(xy 329.151234 -25.031954) (xy 329.150725 -25.05984) (xy 329.142605 -25.115016) (xy 329.126537 -25.168423)
			(xy 329.102865 -25.21892) (xy 329.072092 -25.265433) (xy 329.034875 -25.30697) (xy 328.992007 -25.342645)
			(xy 328.944401 -25.371699) (xy 328.893072 -25.393511) (xy 328.839115 -25.407617) (xy 328.783678 -25.413717)
			(xy 328.727944 -25.41168) (xy 328.673101 -25.40155) (xy 328.620317 -25.383543) (xy 328.570717 -25.358042)
			(xy 328.525359 -25.325591) (xy 328.48521 -25.286882) (xy 328.451124 -25.242739) (xy 328.423828 -25.194104)
			(xy 328.403905 -25.142013) (xy 328.391779 -25.087576) (xy 328.387708 -25.031954) (xy 324.522407 -25.031954)
			(xy 324.565695 -25.050349) (xy 324.613301 -25.079403) (xy 324.656169 -25.115078) (xy 324.693386 -25.156615)
			(xy 324.724159 -25.203128) (xy 324.747831 -25.253625) (xy 324.763899 -25.307032) (xy 324.772019 -25.362208)
			(xy 324.772528 -25.390094) (xy 324.772019 -25.41798) (xy 324.763899 -25.473156) (xy 324.747831 -25.526563)
			(xy 324.732742 -25.55875) (xy 332.841598 -25.55875) (xy 332.845669 -25.503128) (xy 332.857795 -25.448691)
			(xy 332.877718 -25.3966) (xy 332.905014 -25.347965) (xy 332.9391 -25.303822) (xy 332.979249 -25.265113)
			(xy 333.024607 -25.232662) (xy 333.074207 -25.207161) (xy 333.126991 -25.189154) (xy 333.181834 -25.179024)
			(xy 333.237568 -25.176987) (xy 333.293005 -25.183087) (xy 333.346962 -25.197193) (xy 333.398291 -25.219005)
			(xy 333.445897 -25.248059) (xy 333.488765 -25.283734) (xy 333.525982 -25.325271) (xy 333.556755 -25.371784)
			(xy 333.565338 -25.390094) (xy 362.109256 -25.390094) (xy 362.113327 -25.334472) (xy 362.125453 -25.280035)
			(xy 362.145376 -25.227944) (xy 362.172672 -25.179309) (xy 362.206758 -25.135166) (xy 362.246907 -25.096457)
			(xy 362.292265 -25.064006) (xy 362.341865 -25.038505) (xy 362.394649 -25.020498) (xy 362.449492 -25.010368)
			(xy 362.505226 -25.008331) (xy 362.560663 -25.014431) (xy 362.61462 -25.028537) (xy 362.622661 -25.031954)
			(xy 366.487962 -25.031954) (xy 366.492033 -24.976332) (xy 366.504159 -24.921895) (xy 366.524082 -24.869804)
			(xy 366.551378 -24.821169) (xy 366.585464 -24.777026) (xy 366.625613 -24.738317) (xy 366.670971 -24.705866)
			(xy 366.720571 -24.680365) (xy 366.773355 -24.662358) (xy 366.828198 -24.652228) (xy 366.883932 -24.650191)
			(xy 366.939369 -24.656291) (xy 366.993326 -24.670397) (xy 367.044655 -24.692209) (xy 367.092261 -24.721263)
			(xy 367.135129 -24.756938) (xy 367.136663 -24.75865) (xy 369.168678 -24.75865) (xy 369.172749 -24.703028)
			(xy 369.184875 -24.648591) (xy 369.204798 -24.5965) (xy 369.232094 -24.547865) (xy 369.26618 -24.503722)
			(xy 369.306329 -24.465013) (xy 369.351687 -24.432562) (xy 369.401287 -24.407061) (xy 369.454071 -24.389054)
			(xy 369.508914 -24.378924) (xy 369.564648 -24.376887) (xy 369.620085 -24.382987) (xy 369.674042 -24.397093)
			(xy 369.725371 -24.418905) (xy 369.772977 -24.447959) (xy 369.815845 -24.483634) (xy 369.853062 -24.525171)
			(xy 369.883835 -24.571684) (xy 369.907507 -24.622181) (xy 369.923575 -24.675588) (xy 369.931695 -24.730764)
			(xy 369.932204 -24.75865) (xy 369.931695 -24.786536) (xy 369.928622 -24.807418) (xy 380.671322 -24.807418)
			(xy 380.675393 -24.751796) (xy 380.687519 -24.697359) (xy 380.707442 -24.645268) (xy 380.734738 -24.596633)
			(xy 380.768824 -24.55249) (xy 380.808973 -24.513781) (xy 380.854331 -24.48133) (xy 380.903931 -24.455829)
			(xy 380.956715 -24.437822) (xy 381.011558 -24.427692) (xy 381.067292 -24.425655) (xy 381.122729 -24.431755)
			(xy 381.176686 -24.445861) (xy 381.228015 -24.467673) (xy 381.275621 -24.496727) (xy 381.318489 -24.532402)
			(xy 381.355706 -24.573939) (xy 381.386479 -24.620452) (xy 381.410151 -24.670949) (xy 381.426219 -24.724356)
			(xy 381.434339 -24.779532) (xy 381.434848 -24.807418) (xy 382.920238 -24.807418) (xy 382.924309 -24.751796)
			(xy 382.936435 -24.697359) (xy 382.956358 -24.645268) (xy 382.983654 -24.596633) (xy 383.01774 -24.55249)
			(xy 383.057889 -24.513781) (xy 383.103247 -24.48133) (xy 383.152847 -24.455829) (xy 383.205631 -24.437822)
			(xy 383.260474 -24.427692) (xy 383.316208 -24.425655) (xy 383.371645 -24.431755) (xy 383.425602 -24.445861)
			(xy 383.476931 -24.467673) (xy 383.524537 -24.496727) (xy 383.567405 -24.532402) (xy 383.604622 -24.573939)
			(xy 383.635395 -24.620452) (xy 383.659067 -24.670949) (xy 383.675135 -24.724356) (xy 383.683255 -24.779532)
			(xy 383.683764 -24.807418) (xy 383.683255 -24.835304) (xy 383.675135 -24.89048) (xy 383.659067 -24.943887)
			(xy 383.635395 -24.994384) (xy 383.604622 -25.040897) (xy 383.567405 -25.082434) (xy 383.524537 -25.118109)
			(xy 383.476931 -25.147163) (xy 383.425602 -25.168975) (xy 383.371645 -25.183081) (xy 383.316208 -25.189181)
			(xy 383.260474 -25.187144) (xy 383.205631 -25.177014) (xy 383.152847 -25.159007) (xy 383.103247 -25.133506)
			(xy 383.057889 -25.101055) (xy 383.01774 -25.062346) (xy 382.983654 -25.018203) (xy 382.956358 -24.969568)
			(xy 382.936435 -24.917477) (xy 382.924309 -24.86304) (xy 382.920238 -24.807418) (xy 381.434848 -24.807418)
			(xy 381.434339 -24.835304) (xy 381.426219 -24.89048) (xy 381.410151 -24.943887) (xy 381.386479 -24.994384)
			(xy 381.355706 -25.040897) (xy 381.318489 -25.082434) (xy 381.275621 -25.118109) (xy 381.228015 -25.147163)
			(xy 381.176686 -25.168975) (xy 381.122729 -25.183081) (xy 381.067292 -25.189181) (xy 381.011558 -25.187144)
			(xy 380.956715 -25.177014) (xy 380.903931 -25.159007) (xy 380.854331 -25.133506) (xy 380.808973 -25.101055)
			(xy 380.768824 -25.062346) (xy 380.734738 -25.018203) (xy 380.707442 -24.969568) (xy 380.687519 -24.917477)
			(xy 380.675393 -24.86304) (xy 380.671322 -24.807418) (xy 369.928622 -24.807418) (xy 369.923575 -24.841712)
			(xy 369.907507 -24.895119) (xy 369.883835 -24.945616) (xy 369.853062 -24.992129) (xy 369.815845 -25.033666)
			(xy 369.772977 -25.069341) (xy 369.725371 -25.098395) (xy 369.674042 -25.120207) (xy 369.620085 -25.134313)
			(xy 369.564648 -25.140413) (xy 369.508914 -25.138376) (xy 369.454071 -25.128246) (xy 369.401287 -25.110239)
			(xy 369.351687 -25.084738) (xy 369.306329 -25.052287) (xy 369.26618 -25.013578) (xy 369.232094 -24.969435)
			(xy 369.204798 -24.9208) (xy 369.184875 -24.868709) (xy 369.172749 -24.814272) (xy 369.168678 -24.75865)
			(xy 367.136663 -24.75865) (xy 367.172346 -24.798475) (xy 367.203119 -24.844988) (xy 367.226791 -24.895485)
			(xy 367.242859 -24.948892) (xy 367.250979 -25.004068) (xy 367.251488 -25.031954) (xy 367.250979 -25.05984)
			(xy 367.242859 -25.115016) (xy 367.226791 -25.168423) (xy 367.203119 -25.21892) (xy 367.172346 -25.265433)
			(xy 367.135129 -25.30697) (xy 367.092261 -25.342645) (xy 367.044655 -25.371699) (xy 366.993326 -25.393511)
			(xy 366.939369 -25.407617) (xy 366.883932 -25.413717) (xy 366.828198 -25.41168) (xy 366.773355 -25.40155)
			(xy 366.720571 -25.383543) (xy 366.670971 -25.358042) (xy 366.625613 -25.325591) (xy 366.585464 -25.286882)
			(xy 366.551378 -25.242739) (xy 366.524082 -25.194104) (xy 366.504159 -25.142013) (xy 366.492033 -25.087576)
			(xy 366.487962 -25.031954) (xy 362.622661 -25.031954) (xy 362.665949 -25.050349) (xy 362.713555 -25.079403)
			(xy 362.756423 -25.115078) (xy 362.79364 -25.156615) (xy 362.824413 -25.203128) (xy 362.848085 -25.253625)
			(xy 362.864153 -25.307032) (xy 362.872273 -25.362208) (xy 362.872782 -25.390094) (xy 362.872273 -25.41798)
			(xy 362.864153 -25.473156) (xy 362.848085 -25.526563) (xy 362.832996 -25.55875) (xy 370.941852 -25.55875)
			(xy 370.945923 -25.503128) (xy 370.958049 -25.448691) (xy 370.977972 -25.3966) (xy 371.005268 -25.347965)
			(xy 371.039354 -25.303822) (xy 371.079503 -25.265113) (xy 371.124861 -25.232662) (xy 371.174461 -25.207161)
			(xy 371.227245 -25.189154) (xy 371.282088 -25.179024) (xy 371.337822 -25.176987) (xy 371.393259 -25.183087)
			(xy 371.447216 -25.197193) (xy 371.498545 -25.219005) (xy 371.546151 -25.248059) (xy 371.589019 -25.283734)
			(xy 371.626236 -25.325271) (xy 371.657009 -25.371784) (xy 371.665592 -25.390094) (xy 388.109204 -25.390094)
			(xy 388.113275 -25.334472) (xy 388.125401 -25.280035) (xy 388.145324 -25.227944) (xy 388.17262 -25.179309)
			(xy 388.206706 -25.135166) (xy 388.246855 -25.096457) (xy 388.292213 -25.064006) (xy 388.341813 -25.038505)
			(xy 388.394597 -25.020498) (xy 388.44944 -25.010368) (xy 388.505174 -25.008331) (xy 388.560611 -25.014431)
			(xy 388.614568 -25.028537) (xy 388.622609 -25.031954) (xy 392.48791 -25.031954) (xy 392.491981 -24.976332)
			(xy 392.504107 -24.921895) (xy 392.52403 -24.869804) (xy 392.551326 -24.821169) (xy 392.585412 -24.777026)
			(xy 392.625561 -24.738317) (xy 392.670919 -24.705866) (xy 392.720519 -24.680365) (xy 392.773303 -24.662358)
			(xy 392.828146 -24.652228) (xy 392.88388 -24.650191) (xy 392.939317 -24.656291) (xy 392.993274 -24.670397)
			(xy 393.044603 -24.692209) (xy 393.092209 -24.721263) (xy 393.135077 -24.756938) (xy 393.136611 -24.75865)
			(xy 395.168626 -24.75865) (xy 395.172697 -24.703028) (xy 395.184823 -24.648591) (xy 395.204746 -24.5965)
			(xy 395.232042 -24.547865) (xy 395.266128 -24.503722) (xy 395.306277 -24.465013) (xy 395.351635 -24.432562)
			(xy 395.401235 -24.407061) (xy 395.454019 -24.389054) (xy 395.508862 -24.378924) (xy 395.564596 -24.376887)
			(xy 395.620033 -24.382987) (xy 395.67399 -24.397093) (xy 395.725319 -24.418905) (xy 395.772925 -24.447959)
			(xy 395.815793 -24.483634) (xy 395.85301 -24.525171) (xy 395.883783 -24.571684) (xy 395.907455 -24.622181)
			(xy 395.923523 -24.675588) (xy 395.931643 -24.730764) (xy 395.932152 -24.75865) (xy 395.931643 -24.786536)
			(xy 395.92857 -24.807418) (xy 406.67127 -24.807418) (xy 406.675341 -24.751796) (xy 406.687467 -24.697359)
			(xy 406.70739 -24.645268) (xy 406.734686 -24.596633) (xy 406.768772 -24.55249) (xy 406.808921 -24.513781)
			(xy 406.854279 -24.48133) (xy 406.903879 -24.455829) (xy 406.956663 -24.437822) (xy 407.011506 -24.427692)
			(xy 407.06724 -24.425655) (xy 407.122677 -24.431755) (xy 407.176634 -24.445861) (xy 407.227963 -24.467673)
			(xy 407.275569 -24.496727) (xy 407.318437 -24.532402) (xy 407.355654 -24.573939) (xy 407.386427 -24.620452)
			(xy 407.410099 -24.670949) (xy 407.426167 -24.724356) (xy 407.434287 -24.779532) (xy 407.434796 -24.807418)
			(xy 408.920186 -24.807418) (xy 408.924257 -24.751796) (xy 408.936383 -24.697359) (xy 408.956306 -24.645268)
			(xy 408.983602 -24.596633) (xy 409.017688 -24.55249) (xy 409.057837 -24.513781) (xy 409.103195 -24.48133)
			(xy 409.152795 -24.455829) (xy 409.205579 -24.437822) (xy 409.260422 -24.427692) (xy 409.316156 -24.425655)
			(xy 409.371593 -24.431755) (xy 409.42555 -24.445861) (xy 409.476879 -24.467673) (xy 409.524485 -24.496727)
			(xy 409.567353 -24.532402) (xy 409.60457 -24.573939) (xy 409.635343 -24.620452) (xy 409.659015 -24.670949)
			(xy 409.675083 -24.724356) (xy 409.683203 -24.779532) (xy 409.683712 -24.807418) (xy 409.683203 -24.835304)
			(xy 409.675083 -24.89048) (xy 409.659015 -24.943887) (xy 409.635343 -24.994384) (xy 409.60457 -25.040897)
			(xy 409.567353 -25.082434) (xy 409.524485 -25.118109) (xy 409.476879 -25.147163) (xy 409.42555 -25.168975)
			(xy 409.371593 -25.183081) (xy 409.316156 -25.189181) (xy 409.260422 -25.187144) (xy 409.205579 -25.177014)
			(xy 409.152795 -25.159007) (xy 409.103195 -25.133506) (xy 409.057837 -25.101055) (xy 409.017688 -25.062346)
			(xy 408.983602 -25.018203) (xy 408.956306 -24.969568) (xy 408.936383 -24.917477) (xy 408.924257 -24.86304)
			(xy 408.920186 -24.807418) (xy 407.434796 -24.807418) (xy 407.434287 -24.835304) (xy 407.426167 -24.89048)
			(xy 407.410099 -24.943887) (xy 407.386427 -24.994384) (xy 407.355654 -25.040897) (xy 407.318437 -25.082434)
			(xy 407.275569 -25.118109) (xy 407.227963 -25.147163) (xy 407.176634 -25.168975) (xy 407.122677 -25.183081)
			(xy 407.06724 -25.189181) (xy 407.011506 -25.187144) (xy 406.956663 -25.177014) (xy 406.903879 -25.159007)
			(xy 406.854279 -25.133506) (xy 406.808921 -25.101055) (xy 406.768772 -25.062346) (xy 406.734686 -25.018203)
			(xy 406.70739 -24.969568) (xy 406.687467 -24.917477) (xy 406.675341 -24.86304) (xy 406.67127 -24.807418)
			(xy 395.92857 -24.807418) (xy 395.923523 -24.841712) (xy 395.907455 -24.895119) (xy 395.883783 -24.945616)
			(xy 395.85301 -24.992129) (xy 395.815793 -25.033666) (xy 395.772925 -25.069341) (xy 395.725319 -25.098395)
			(xy 395.67399 -25.120207) (xy 395.620033 -25.134313) (xy 395.564596 -25.140413) (xy 395.508862 -25.138376)
			(xy 395.454019 -25.128246) (xy 395.401235 -25.110239) (xy 395.351635 -25.084738) (xy 395.306277 -25.052287)
			(xy 395.266128 -25.013578) (xy 395.232042 -24.969435) (xy 395.204746 -24.9208) (xy 395.184823 -24.868709)
			(xy 395.172697 -24.814272) (xy 395.168626 -24.75865) (xy 393.136611 -24.75865) (xy 393.172294 -24.798475)
			(xy 393.203067 -24.844988) (xy 393.226739 -24.895485) (xy 393.242807 -24.948892) (xy 393.250927 -25.004068)
			(xy 393.251436 -25.031954) (xy 393.250927 -25.05984) (xy 393.242807 -25.115016) (xy 393.226739 -25.168423)
			(xy 393.203067 -25.21892) (xy 393.172294 -25.265433) (xy 393.135077 -25.30697) (xy 393.092209 -25.342645)
			(xy 393.044603 -25.371699) (xy 392.993274 -25.393511) (xy 392.939317 -25.407617) (xy 392.88388 -25.413717)
			(xy 392.828146 -25.41168) (xy 392.773303 -25.40155) (xy 392.720519 -25.383543) (xy 392.670919 -25.358042)
			(xy 392.625561 -25.325591) (xy 392.585412 -25.286882) (xy 392.551326 -25.242739) (xy 392.52403 -25.194104)
			(xy 392.504107 -25.142013) (xy 392.491981 -25.087576) (xy 392.48791 -25.031954) (xy 388.622609 -25.031954)
			(xy 388.665897 -25.050349) (xy 388.713503 -25.079403) (xy 388.756371 -25.115078) (xy 388.793588 -25.156615)
			(xy 388.824361 -25.203128) (xy 388.848033 -25.253625) (xy 388.864101 -25.307032) (xy 388.872221 -25.362208)
			(xy 388.87273 -25.390094) (xy 388.872221 -25.41798) (xy 388.864101 -25.473156) (xy 388.848033 -25.526563)
			(xy 388.832944 -25.55875) (xy 396.9418 -25.55875) (xy 396.945871 -25.503128) (xy 396.957997 -25.448691)
			(xy 396.97792 -25.3966) (xy 397.005216 -25.347965) (xy 397.039302 -25.303822) (xy 397.079451 -25.265113)
			(xy 397.124809 -25.232662) (xy 397.174409 -25.207161) (xy 397.227193 -25.189154) (xy 397.282036 -25.179024)
			(xy 397.33777 -25.176987) (xy 397.393207 -25.183087) (xy 397.447164 -25.197193) (xy 397.498493 -25.219005)
			(xy 397.546099 -25.248059) (xy 397.588967 -25.283734) (xy 397.626184 -25.325271) (xy 397.656957 -25.371784)
			(xy 397.66554 -25.390094) (xy 414.109152 -25.390094) (xy 414.113223 -25.334472) (xy 414.125349 -25.280035)
			(xy 414.145272 -25.227944) (xy 414.172568 -25.179309) (xy 414.206654 -25.135166) (xy 414.246803 -25.096457)
			(xy 414.292161 -25.064006) (xy 414.341761 -25.038505) (xy 414.394545 -25.020498) (xy 414.449388 -25.010368)
			(xy 414.505122 -25.008331) (xy 414.560559 -25.014431) (xy 414.614516 -25.028537) (xy 414.622557 -25.031954)
			(xy 418.487858 -25.031954) (xy 418.491929 -24.976332) (xy 418.504055 -24.921895) (xy 418.523978 -24.869804)
			(xy 418.551274 -24.821169) (xy 418.58536 -24.777026) (xy 418.625509 -24.738317) (xy 418.670867 -24.705866)
			(xy 418.720467 -24.680365) (xy 418.773251 -24.662358) (xy 418.828094 -24.652228) (xy 418.883828 -24.650191)
			(xy 418.939265 -24.656291) (xy 418.993222 -24.670397) (xy 419.044551 -24.692209) (xy 419.092157 -24.721263)
			(xy 419.135025 -24.756938) (xy 419.136559 -24.75865) (xy 421.168574 -24.75865) (xy 421.172645 -24.703028)
			(xy 421.184771 -24.648591) (xy 421.204694 -24.5965) (xy 421.23199 -24.547865) (xy 421.266076 -24.503722)
			(xy 421.306225 -24.465013) (xy 421.351583 -24.432562) (xy 421.401183 -24.407061) (xy 421.453967 -24.389054)
			(xy 421.50881 -24.378924) (xy 421.564544 -24.376887) (xy 421.619981 -24.382987) (xy 421.673938 -24.397093)
			(xy 421.725267 -24.418905) (xy 421.772873 -24.447959) (xy 421.815741 -24.483634) (xy 421.852958 -24.525171)
			(xy 421.883731 -24.571684) (xy 421.907403 -24.622181) (xy 421.923471 -24.675588) (xy 421.931591 -24.730764)
			(xy 421.9321 -24.75865) (xy 421.931591 -24.786536) (xy 421.928518 -24.807418) (xy 432.671218 -24.807418)
			(xy 432.675289 -24.751796) (xy 432.687415 -24.697359) (xy 432.707338 -24.645268) (xy 432.734634 -24.596633)
			(xy 432.76872 -24.55249) (xy 432.808869 -24.513781) (xy 432.854227 -24.48133) (xy 432.903827 -24.455829)
			(xy 432.956611 -24.437822) (xy 433.011454 -24.427692) (xy 433.067188 -24.425655) (xy 433.122625 -24.431755)
			(xy 433.176582 -24.445861) (xy 433.227911 -24.467673) (xy 433.275517 -24.496727) (xy 433.318385 -24.532402)
			(xy 433.355602 -24.573939) (xy 433.386375 -24.620452) (xy 433.410047 -24.670949) (xy 433.426115 -24.724356)
			(xy 433.434235 -24.779532) (xy 433.434744 -24.807418) (xy 434.920134 -24.807418) (xy 434.924205 -24.751796)
			(xy 434.936331 -24.697359) (xy 434.956254 -24.645268) (xy 434.98355 -24.596633) (xy 435.017636 -24.55249)
			(xy 435.057785 -24.513781) (xy 435.103143 -24.48133) (xy 435.152743 -24.455829) (xy 435.205527 -24.437822)
			(xy 435.26037 -24.427692) (xy 435.316104 -24.425655) (xy 435.371541 -24.431755) (xy 435.425498 -24.445861)
			(xy 435.476827 -24.467673) (xy 435.524433 -24.496727) (xy 435.567301 -24.532402) (xy 435.604518 -24.573939)
			(xy 435.635291 -24.620452) (xy 435.658963 -24.670949) (xy 435.675031 -24.724356) (xy 435.683151 -24.779532)
			(xy 435.68366 -24.807418) (xy 435.683151 -24.835304) (xy 435.675031 -24.89048) (xy 435.658963 -24.943887)
			(xy 435.635291 -24.994384) (xy 435.604518 -25.040897) (xy 435.567301 -25.082434) (xy 435.524433 -25.118109)
			(xy 435.476827 -25.147163) (xy 435.425498 -25.168975) (xy 435.371541 -25.183081) (xy 435.316104 -25.189181)
			(xy 435.26037 -25.187144) (xy 435.205527 -25.177014) (xy 435.152743 -25.159007) (xy 435.103143 -25.133506)
			(xy 435.057785 -25.101055) (xy 435.017636 -25.062346) (xy 434.98355 -25.018203) (xy 434.956254 -24.969568)
			(xy 434.936331 -24.917477) (xy 434.924205 -24.86304) (xy 434.920134 -24.807418) (xy 433.434744 -24.807418)
			(xy 433.434235 -24.835304) (xy 433.426115 -24.89048) (xy 433.410047 -24.943887) (xy 433.386375 -24.994384)
			(xy 433.355602 -25.040897) (xy 433.318385 -25.082434) (xy 433.275517 -25.118109) (xy 433.227911 -25.147163)
			(xy 433.176582 -25.168975) (xy 433.122625 -25.183081) (xy 433.067188 -25.189181) (xy 433.011454 -25.187144)
			(xy 432.956611 -25.177014) (xy 432.903827 -25.159007) (xy 432.854227 -25.133506) (xy 432.808869 -25.101055)
			(xy 432.76872 -25.062346) (xy 432.734634 -25.018203) (xy 432.707338 -24.969568) (xy 432.687415 -24.917477)
			(xy 432.675289 -24.86304) (xy 432.671218 -24.807418) (xy 421.928518 -24.807418) (xy 421.923471 -24.841712)
			(xy 421.907403 -24.895119) (xy 421.883731 -24.945616) (xy 421.852958 -24.992129) (xy 421.815741 -25.033666)
			(xy 421.772873 -25.069341) (xy 421.725267 -25.098395) (xy 421.673938 -25.120207) (xy 421.619981 -25.134313)
			(xy 421.564544 -25.140413) (xy 421.50881 -25.138376) (xy 421.453967 -25.128246) (xy 421.401183 -25.110239)
			(xy 421.351583 -25.084738) (xy 421.306225 -25.052287) (xy 421.266076 -25.013578) (xy 421.23199 -24.969435)
			(xy 421.204694 -24.9208) (xy 421.184771 -24.868709) (xy 421.172645 -24.814272) (xy 421.168574 -24.75865)
			(xy 419.136559 -24.75865) (xy 419.172242 -24.798475) (xy 419.203015 -24.844988) (xy 419.226687 -24.895485)
			(xy 419.242755 -24.948892) (xy 419.250875 -25.004068) (xy 419.251384 -25.031954) (xy 419.250875 -25.05984)
			(xy 419.242755 -25.115016) (xy 419.226687 -25.168423) (xy 419.203015 -25.21892) (xy 419.172242 -25.265433)
			(xy 419.135025 -25.30697) (xy 419.092157 -25.342645) (xy 419.044551 -25.371699) (xy 418.993222 -25.393511)
			(xy 418.939265 -25.407617) (xy 418.883828 -25.413717) (xy 418.828094 -25.41168) (xy 418.773251 -25.40155)
			(xy 418.720467 -25.383543) (xy 418.670867 -25.358042) (xy 418.625509 -25.325591) (xy 418.58536 -25.286882)
			(xy 418.551274 -25.242739) (xy 418.523978 -25.194104) (xy 418.504055 -25.142013) (xy 418.491929 -25.087576)
			(xy 418.487858 -25.031954) (xy 414.622557 -25.031954) (xy 414.665845 -25.050349) (xy 414.713451 -25.079403)
			(xy 414.756319 -25.115078) (xy 414.793536 -25.156615) (xy 414.824309 -25.203128) (xy 414.847981 -25.253625)
			(xy 414.864049 -25.307032) (xy 414.872169 -25.362208) (xy 414.872678 -25.390094) (xy 414.872169 -25.41798)
			(xy 414.864049 -25.473156) (xy 414.847981 -25.526563) (xy 414.832892 -25.55875) (xy 422.941748 -25.55875)
			(xy 422.945819 -25.503128) (xy 422.957945 -25.448691) (xy 422.977868 -25.3966) (xy 423.005164 -25.347965)
			(xy 423.03925 -25.303822) (xy 423.079399 -25.265113) (xy 423.124757 -25.232662) (xy 423.174357 -25.207161)
			(xy 423.227141 -25.189154) (xy 423.281984 -25.179024) (xy 423.337718 -25.176987) (xy 423.393155 -25.183087)
			(xy 423.447112 -25.197193) (xy 423.498441 -25.219005) (xy 423.546047 -25.248059) (xy 423.588915 -25.283734)
			(xy 423.626132 -25.325271) (xy 423.656905 -25.371784) (xy 423.665488 -25.390094) (xy 440.1091 -25.390094)
			(xy 440.113171 -25.334472) (xy 440.125297 -25.280035) (xy 440.14522 -25.227944) (xy 440.172516 -25.179309)
			(xy 440.206602 -25.135166) (xy 440.246751 -25.096457) (xy 440.292109 -25.064006) (xy 440.341709 -25.038505)
			(xy 440.394493 -25.020498) (xy 440.449336 -25.010368) (xy 440.50507 -25.008331) (xy 440.560507 -25.014431)
			(xy 440.614464 -25.028537) (xy 440.622505 -25.031954) (xy 444.487806 -25.031954) (xy 444.491877 -24.976332)
			(xy 444.504003 -24.921895) (xy 444.523926 -24.869804) (xy 444.551222 -24.821169) (xy 444.585308 -24.777026)
			(xy 444.625457 -24.738317) (xy 444.670815 -24.705866) (xy 444.720415 -24.680365) (xy 444.773199 -24.662358)
			(xy 444.828042 -24.652228) (xy 444.883776 -24.650191) (xy 444.939213 -24.656291) (xy 444.99317 -24.670397)
			(xy 445.044499 -24.692209) (xy 445.092105 -24.721263) (xy 445.134973 -24.756938) (xy 445.136507 -24.75865)
			(xy 447.168522 -24.75865) (xy 447.172593 -24.703028) (xy 447.184719 -24.648591) (xy 447.204642 -24.5965)
			(xy 447.231938 -24.547865) (xy 447.266024 -24.503722) (xy 447.306173 -24.465013) (xy 447.351531 -24.432562)
			(xy 447.401131 -24.407061) (xy 447.453915 -24.389054) (xy 447.508758 -24.378924) (xy 447.564492 -24.376887)
			(xy 447.619929 -24.382987) (xy 447.673886 -24.397093) (xy 447.725215 -24.418905) (xy 447.772821 -24.447959)
			(xy 447.815689 -24.483634) (xy 447.852906 -24.525171) (xy 447.883679 -24.571684) (xy 447.907351 -24.622181)
			(xy 447.923419 -24.675588) (xy 447.931539 -24.730764) (xy 447.932048 -24.75865) (xy 447.931539 -24.786536)
			(xy 447.923419 -24.841712) (xy 447.907351 -24.895119) (xy 447.883679 -24.945616) (xy 447.852906 -24.992129)
			(xy 447.815689 -25.033666) (xy 447.772821 -25.069341) (xy 447.725215 -25.098395) (xy 447.673886 -25.120207)
			(xy 447.619929 -25.134313) (xy 447.564492 -25.140413) (xy 447.508758 -25.138376) (xy 447.453915 -25.128246)
			(xy 447.401131 -25.110239) (xy 447.351531 -25.084738) (xy 447.306173 -25.052287) (xy 447.266024 -25.013578)
			(xy 447.231938 -24.969435) (xy 447.204642 -24.9208) (xy 447.184719 -24.868709) (xy 447.172593 -24.814272)
			(xy 447.168522 -24.75865) (xy 445.136507 -24.75865) (xy 445.17219 -24.798475) (xy 445.202963 -24.844988)
			(xy 445.226635 -24.895485) (xy 445.242703 -24.948892) (xy 445.250823 -25.004068) (xy 445.251332 -25.031954)
			(xy 445.250823 -25.05984) (xy 445.242703 -25.115016) (xy 445.226635 -25.168423) (xy 445.202963 -25.21892)
			(xy 445.17219 -25.265433) (xy 445.134973 -25.30697) (xy 445.092105 -25.342645) (xy 445.044499 -25.371699)
			(xy 444.99317 -25.393511) (xy 444.939213 -25.407617) (xy 444.883776 -25.413717) (xy 444.828042 -25.41168)
			(xy 444.773199 -25.40155) (xy 444.720415 -25.383543) (xy 444.670815 -25.358042) (xy 444.625457 -25.325591)
			(xy 444.585308 -25.286882) (xy 444.551222 -25.242739) (xy 444.523926 -25.194104) (xy 444.504003 -25.142013)
			(xy 444.491877 -25.087576) (xy 444.487806 -25.031954) (xy 440.622505 -25.031954) (xy 440.665793 -25.050349)
			(xy 440.713399 -25.079403) (xy 440.756267 -25.115078) (xy 440.793484 -25.156615) (xy 440.824257 -25.203128)
			(xy 440.847929 -25.253625) (xy 440.863997 -25.307032) (xy 440.872117 -25.362208) (xy 440.872626 -25.390094)
			(xy 440.872117 -25.41798) (xy 440.863997 -25.473156) (xy 440.847929 -25.526563) (xy 440.83284 -25.55875)
			(xy 448.941696 -25.55875) (xy 448.945767 -25.503128) (xy 448.957893 -25.448691) (xy 448.977816 -25.3966)
			(xy 449.005112 -25.347965) (xy 449.039198 -25.303822) (xy 449.079347 -25.265113) (xy 449.124705 -25.232662)
			(xy 449.174305 -25.207161) (xy 449.227089 -25.189154) (xy 449.281932 -25.179024) (xy 449.337666 -25.176987)
			(xy 449.393103 -25.183087) (xy 449.44706 -25.197193) (xy 449.498389 -25.219005) (xy 449.545995 -25.248059)
			(xy 449.588863 -25.283734) (xy 449.62608 -25.325271) (xy 449.656853 -25.371784) (xy 449.680525 -25.422281)
			(xy 449.696593 -25.475688) (xy 449.704713 -25.530864) (xy 449.705222 -25.55875) (xy 449.704713 -25.586636)
			(xy 449.696593 -25.641812) (xy 449.680525 -25.695219) (xy 449.656853 -25.745716) (xy 449.62608 -25.792229)
			(xy 449.588863 -25.833766) (xy 449.545995 -25.869441) (xy 449.498389 -25.898495) (xy 449.44706 -25.920307)
			(xy 449.393103 -25.934413) (xy 449.337666 -25.940513) (xy 449.281932 -25.938476) (xy 449.227089 -25.928346)
			(xy 449.174305 -25.910339) (xy 449.124705 -25.884838) (xy 449.079347 -25.852387) (xy 449.039198 -25.813678)
			(xy 449.005112 -25.769535) (xy 448.977816 -25.7209) (xy 448.957893 -25.668809) (xy 448.945767 -25.614372)
			(xy 448.941696 -25.55875) (xy 440.83284 -25.55875) (xy 440.824257 -25.57706) (xy 440.793484 -25.623573)
			(xy 440.756267 -25.66511) (xy 440.713399 -25.700785) (xy 440.665793 -25.729839) (xy 440.614464 -25.751651)
			(xy 440.560507 -25.765757) (xy 440.50507 -25.771857) (xy 440.449336 -25.76982) (xy 440.394493 -25.75969)
			(xy 440.341709 -25.741683) (xy 440.292109 -25.716182) (xy 440.246751 -25.683731) (xy 440.206602 -25.645022)
			(xy 440.172516 -25.600879) (xy 440.14522 -25.552244) (xy 440.125297 -25.500153) (xy 440.113171 -25.445716)
			(xy 440.1091 -25.390094) (xy 423.665488 -25.390094) (xy 423.680577 -25.422281) (xy 423.696645 -25.475688)
			(xy 423.704765 -25.530864) (xy 423.705274 -25.55875) (xy 423.704765 -25.586636) (xy 423.696645 -25.641812)
			(xy 423.680577 -25.695219) (xy 423.656905 -25.745716) (xy 423.626132 -25.792229) (xy 423.588915 -25.833766)
			(xy 423.546047 -25.869441) (xy 423.498441 -25.898495) (xy 423.447112 -25.920307) (xy 423.393155 -25.934413)
			(xy 423.337718 -25.940513) (xy 423.281984 -25.938476) (xy 423.227141 -25.928346) (xy 423.174357 -25.910339)
			(xy 423.124757 -25.884838) (xy 423.079399 -25.852387) (xy 423.03925 -25.813678) (xy 423.005164 -25.769535)
			(xy 422.977868 -25.7209) (xy 422.957945 -25.668809) (xy 422.945819 -25.614372) (xy 422.941748 -25.55875)
			(xy 414.832892 -25.55875) (xy 414.824309 -25.57706) (xy 414.793536 -25.623573) (xy 414.756319 -25.66511)
			(xy 414.713451 -25.700785) (xy 414.665845 -25.729839) (xy 414.614516 -25.751651) (xy 414.560559 -25.765757)
			(xy 414.505122 -25.771857) (xy 414.449388 -25.76982) (xy 414.394545 -25.75969) (xy 414.341761 -25.741683)
			(xy 414.292161 -25.716182) (xy 414.246803 -25.683731) (xy 414.206654 -25.645022) (xy 414.172568 -25.600879)
			(xy 414.145272 -25.552244) (xy 414.125349 -25.500153) (xy 414.113223 -25.445716) (xy 414.109152 -25.390094)
			(xy 397.66554 -25.390094) (xy 397.680629 -25.422281) (xy 397.696697 -25.475688) (xy 397.704817 -25.530864)
			(xy 397.705326 -25.55875) (xy 397.704817 -25.586636) (xy 397.696697 -25.641812) (xy 397.680629 -25.695219)
			(xy 397.656957 -25.745716) (xy 397.626184 -25.792229) (xy 397.588967 -25.833766) (xy 397.546099 -25.869441)
			(xy 397.498493 -25.898495) (xy 397.447164 -25.920307) (xy 397.393207 -25.934413) (xy 397.33777 -25.940513)
			(xy 397.282036 -25.938476) (xy 397.227193 -25.928346) (xy 397.174409 -25.910339) (xy 397.124809 -25.884838)
			(xy 397.079451 -25.852387) (xy 397.039302 -25.813678) (xy 397.005216 -25.769535) (xy 396.97792 -25.7209)
			(xy 396.957997 -25.668809) (xy 396.945871 -25.614372) (xy 396.9418 -25.55875) (xy 388.832944 -25.55875)
			(xy 388.824361 -25.57706) (xy 388.793588 -25.623573) (xy 388.756371 -25.66511) (xy 388.713503 -25.700785)
			(xy 388.665897 -25.729839) (xy 388.614568 -25.751651) (xy 388.560611 -25.765757) (xy 388.505174 -25.771857)
			(xy 388.44944 -25.76982) (xy 388.394597 -25.75969) (xy 388.341813 -25.741683) (xy 388.292213 -25.716182)
			(xy 388.246855 -25.683731) (xy 388.206706 -25.645022) (xy 388.17262 -25.600879) (xy 388.145324 -25.552244)
			(xy 388.125401 -25.500153) (xy 388.113275 -25.445716) (xy 388.109204 -25.390094) (xy 371.665592 -25.390094)
			(xy 371.680681 -25.422281) (xy 371.696749 -25.475688) (xy 371.704869 -25.530864) (xy 371.705378 -25.55875)
			(xy 371.704869 -25.586636) (xy 371.696749 -25.641812) (xy 371.680681 -25.695219) (xy 371.657009 -25.745716)
			(xy 371.626236 -25.792229) (xy 371.589019 -25.833766) (xy 371.546151 -25.869441) (xy 371.498545 -25.898495)
			(xy 371.447216 -25.920307) (xy 371.393259 -25.934413) (xy 371.337822 -25.940513) (xy 371.282088 -25.938476)
			(xy 371.227245 -25.928346) (xy 371.174461 -25.910339) (xy 371.124861 -25.884838) (xy 371.079503 -25.852387)
			(xy 371.039354 -25.813678) (xy 371.005268 -25.769535) (xy 370.977972 -25.7209) (xy 370.958049 -25.668809)
			(xy 370.945923 -25.614372) (xy 370.941852 -25.55875) (xy 362.832996 -25.55875) (xy 362.824413 -25.57706)
			(xy 362.79364 -25.623573) (xy 362.756423 -25.66511) (xy 362.713555 -25.700785) (xy 362.665949 -25.729839)
			(xy 362.61462 -25.751651) (xy 362.560663 -25.765757) (xy 362.505226 -25.771857) (xy 362.449492 -25.76982)
			(xy 362.394649 -25.75969) (xy 362.341865 -25.741683) (xy 362.292265 -25.716182) (xy 362.246907 -25.683731)
			(xy 362.206758 -25.645022) (xy 362.172672 -25.600879) (xy 362.145376 -25.552244) (xy 362.125453 -25.500153)
			(xy 362.113327 -25.445716) (xy 362.109256 -25.390094) (xy 333.565338 -25.390094) (xy 333.580427 -25.422281)
			(xy 333.596495 -25.475688) (xy 333.604615 -25.530864) (xy 333.605124 -25.55875) (xy 333.604615 -25.586636)
			(xy 333.596495 -25.641812) (xy 333.580427 -25.695219) (xy 333.556755 -25.745716) (xy 333.525982 -25.792229)
			(xy 333.488765 -25.833766) (xy 333.445897 -25.869441) (xy 333.398291 -25.898495) (xy 333.346962 -25.920307)
			(xy 333.293005 -25.934413) (xy 333.237568 -25.940513) (xy 333.181834 -25.938476) (xy 333.126991 -25.928346)
			(xy 333.074207 -25.910339) (xy 333.024607 -25.884838) (xy 332.979249 -25.852387) (xy 332.9391 -25.813678)
			(xy 332.905014 -25.769535) (xy 332.877718 -25.7209) (xy 332.857795 -25.668809) (xy 332.845669 -25.614372)
			(xy 332.841598 -25.55875) (xy 324.732742 -25.55875) (xy 324.724159 -25.57706) (xy 324.693386 -25.623573)
			(xy 324.656169 -25.66511) (xy 324.613301 -25.700785) (xy 324.565695 -25.729839) (xy 324.514366 -25.751651)
			(xy 324.460409 -25.765757) (xy 324.404972 -25.771857) (xy 324.349238 -25.76982) (xy 324.294395 -25.75969)
			(xy 324.241611 -25.741683) (xy 324.192011 -25.716182) (xy 324.146653 -25.683731) (xy 324.106504 -25.645022)
			(xy 324.072418 -25.600879) (xy 324.045122 -25.552244) (xy 324.025199 -25.500153) (xy 324.013073 -25.445716)
			(xy 324.009002 -25.390094) (xy 307.56539 -25.390094) (xy 307.580479 -25.422281) (xy 307.596547 -25.475688)
			(xy 307.604667 -25.530864) (xy 307.605176 -25.55875) (xy 307.604667 -25.586636) (xy 307.596547 -25.641812)
			(xy 307.580479 -25.695219) (xy 307.556807 -25.745716) (xy 307.526034 -25.792229) (xy 307.488817 -25.833766)
			(xy 307.445949 -25.869441) (xy 307.398343 -25.898495) (xy 307.347014 -25.920307) (xy 307.293057 -25.934413)
			(xy 307.23762 -25.940513) (xy 307.181886 -25.938476) (xy 307.127043 -25.928346) (xy 307.074259 -25.910339)
			(xy 307.024659 -25.884838) (xy 306.979301 -25.852387) (xy 306.939152 -25.813678) (xy 306.905066 -25.769535)
			(xy 306.87777 -25.7209) (xy 306.857847 -25.668809) (xy 306.845721 -25.614372) (xy 306.84165 -25.55875)
			(xy 298.732794 -25.55875) (xy 298.724211 -25.57706) (xy 298.693438 -25.623573) (xy 298.656221 -25.66511)
			(xy 298.613353 -25.700785) (xy 298.565747 -25.729839) (xy 298.514418 -25.751651) (xy 298.460461 -25.765757)
			(xy 298.405024 -25.771857) (xy 298.34929 -25.76982) (xy 298.294447 -25.75969) (xy 298.241663 -25.741683)
			(xy 298.192063 -25.716182) (xy 298.146705 -25.683731) (xy 298.106556 -25.645022) (xy 298.07247 -25.600879)
			(xy 298.045174 -25.552244) (xy 298.025251 -25.500153) (xy 298.013125 -25.445716) (xy 298.009054 -25.390094)
			(xy 281.565442 -25.390094) (xy 281.580531 -25.422281) (xy 281.596599 -25.475688) (xy 281.604719 -25.530864)
			(xy 281.605228 -25.55875) (xy 281.604719 -25.586636) (xy 281.596599 -25.641812) (xy 281.580531 -25.695219)
			(xy 281.556859 -25.745716) (xy 281.526086 -25.792229) (xy 281.488869 -25.833766) (xy 281.446001 -25.869441)
			(xy 281.398395 -25.898495) (xy 281.347066 -25.920307) (xy 281.293109 -25.934413) (xy 281.237672 -25.940513)
			(xy 281.181938 -25.938476) (xy 281.127095 -25.928346) (xy 281.074311 -25.910339) (xy 281.024711 -25.884838)
			(xy 280.979353 -25.852387) (xy 280.939204 -25.813678) (xy 280.905118 -25.769535) (xy 280.877822 -25.7209)
			(xy 280.857899 -25.668809) (xy 280.845773 -25.614372) (xy 280.841702 -25.55875) (xy 272.732846 -25.55875)
			(xy 272.724263 -25.57706) (xy 272.69349 -25.623573) (xy 272.656273 -25.66511) (xy 272.613405 -25.700785)
			(xy 272.565799 -25.729839) (xy 272.51447 -25.751651) (xy 272.460513 -25.765757) (xy 272.405076 -25.771857)
			(xy 272.349342 -25.76982) (xy 272.294499 -25.75969) (xy 272.241715 -25.741683) (xy 272.192115 -25.716182)
			(xy 272.146757 -25.683731) (xy 272.106608 -25.645022) (xy 272.072522 -25.600879) (xy 272.045226 -25.552244)
			(xy 272.025303 -25.500153) (xy 272.013177 -25.445716) (xy 272.009106 -25.390094) (xy 255.565494 -25.390094)
			(xy 255.580583 -25.422281) (xy 255.596651 -25.475688) (xy 255.604771 -25.530864) (xy 255.60528 -25.55875)
			(xy 255.604771 -25.586636) (xy 255.596651 -25.641812) (xy 255.580583 -25.695219) (xy 255.556911 -25.745716)
			(xy 255.526138 -25.792229) (xy 255.488921 -25.833766) (xy 255.446053 -25.869441) (xy 255.398447 -25.898495)
			(xy 255.347118 -25.920307) (xy 255.293161 -25.934413) (xy 255.237724 -25.940513) (xy 255.18199 -25.938476)
			(xy 255.127147 -25.928346) (xy 255.074363 -25.910339) (xy 255.024763 -25.884838) (xy 254.979405 -25.852387)
			(xy 254.939256 -25.813678) (xy 254.90517 -25.769535) (xy 254.877874 -25.7209) (xy 254.857951 -25.668809)
			(xy 254.845825 -25.614372) (xy 254.841754 -25.55875) (xy 246.732898 -25.55875) (xy 246.724315 -25.57706)
			(xy 246.693542 -25.623573) (xy 246.656325 -25.66511) (xy 246.613457 -25.700785) (xy 246.565851 -25.729839)
			(xy 246.514522 -25.751651) (xy 246.460565 -25.765757) (xy 246.405128 -25.771857) (xy 246.349394 -25.76982)
			(xy 246.294551 -25.75969) (xy 246.241767 -25.741683) (xy 246.192167 -25.716182) (xy 246.146809 -25.683731)
			(xy 246.10666 -25.645022) (xy 246.072574 -25.600879) (xy 246.045278 -25.552244) (xy 246.025355 -25.500153)
			(xy 246.013229 -25.445716) (xy 246.009158 -25.390094) (xy 217.465494 -25.390094) (xy 217.480583 -25.422281)
			(xy 217.496651 -25.475688) (xy 217.504771 -25.530864) (xy 217.50528 -25.55875) (xy 217.504771 -25.586636)
			(xy 217.496651 -25.641812) (xy 217.480583 -25.695219) (xy 217.456911 -25.745716) (xy 217.426138 -25.792229)
			(xy 217.388921 -25.833766) (xy 217.346053 -25.869441) (xy 217.298447 -25.898495) (xy 217.247118 -25.920307)
			(xy 217.193161 -25.934413) (xy 217.137724 -25.940513) (xy 217.08199 -25.938476) (xy 217.027147 -25.928346)
			(xy 216.974363 -25.910339) (xy 216.924763 -25.884838) (xy 216.879405 -25.852387) (xy 216.839256 -25.813678)
			(xy 216.80517 -25.769535) (xy 216.777874 -25.7209) (xy 216.757951 -25.668809) (xy 216.745825 -25.614372)
			(xy 216.741754 -25.55875) (xy 208.632898 -25.55875) (xy 208.624315 -25.57706) (xy 208.593542 -25.623573)
			(xy 208.556325 -25.66511) (xy 208.513457 -25.700785) (xy 208.465851 -25.729839) (xy 208.414522 -25.751651)
			(xy 208.360565 -25.765757) (xy 208.305128 -25.771857) (xy 208.249394 -25.76982) (xy 208.194551 -25.75969)
			(xy 208.141767 -25.741683) (xy 208.092167 -25.716182) (xy 208.046809 -25.683731) (xy 208.00666 -25.645022)
			(xy 207.972574 -25.600879) (xy 207.945278 -25.552244) (xy 207.925355 -25.500153) (xy 207.913229 -25.445716)
			(xy 207.909158 -25.390094) (xy 191.465546 -25.390094) (xy 191.480635 -25.422281) (xy 191.496703 -25.475688)
			(xy 191.504823 -25.530864) (xy 191.505332 -25.55875) (xy 191.504823 -25.586636) (xy 191.496703 -25.641812)
			(xy 191.480635 -25.695219) (xy 191.456963 -25.745716) (xy 191.42619 -25.792229) (xy 191.388973 -25.833766)
			(xy 191.346105 -25.869441) (xy 191.298499 -25.898495) (xy 191.24717 -25.920307) (xy 191.193213 -25.934413)
			(xy 191.137776 -25.940513) (xy 191.082042 -25.938476) (xy 191.027199 -25.928346) (xy 190.974415 -25.910339)
			(xy 190.924815 -25.884838) (xy 190.879457 -25.852387) (xy 190.839308 -25.813678) (xy 190.805222 -25.769535)
			(xy 190.777926 -25.7209) (xy 190.758003 -25.668809) (xy 190.745877 -25.614372) (xy 190.741806 -25.55875)
			(xy 182.63295 -25.55875) (xy 182.624367 -25.57706) (xy 182.593594 -25.623573) (xy 182.556377 -25.66511)
			(xy 182.513509 -25.700785) (xy 182.465903 -25.729839) (xy 182.414574 -25.751651) (xy 182.360617 -25.765757)
			(xy 182.30518 -25.771857) (xy 182.249446 -25.76982) (xy 182.194603 -25.75969) (xy 182.141819 -25.741683)
			(xy 182.092219 -25.716182) (xy 182.046861 -25.683731) (xy 182.006712 -25.645022) (xy 181.972626 -25.600879)
			(xy 181.94533 -25.552244) (xy 181.925407 -25.500153) (xy 181.913281 -25.445716) (xy 181.90921 -25.390094)
			(xy 165.465598 -25.390094) (xy 165.480687 -25.422281) (xy 165.496755 -25.475688) (xy 165.504875 -25.530864)
			(xy 165.505384 -25.55875) (xy 165.504875 -25.586636) (xy 165.496755 -25.641812) (xy 165.480687 -25.695219)
			(xy 165.457015 -25.745716) (xy 165.426242 -25.792229) (xy 165.389025 -25.833766) (xy 165.346157 -25.869441)
			(xy 165.298551 -25.898495) (xy 165.247222 -25.920307) (xy 165.193265 -25.934413) (xy 165.137828 -25.940513)
			(xy 165.082094 -25.938476) (xy 165.027251 -25.928346) (xy 164.974467 -25.910339) (xy 164.924867 -25.884838)
			(xy 164.879509 -25.852387) (xy 164.83936 -25.813678) (xy 164.805274 -25.769535) (xy 164.777978 -25.7209)
			(xy 164.758055 -25.668809) (xy 164.745929 -25.614372) (xy 164.741858 -25.55875) (xy 156.633002 -25.55875)
			(xy 156.624419 -25.57706) (xy 156.593646 -25.623573) (xy 156.556429 -25.66511) (xy 156.513561 -25.700785)
			(xy 156.465955 -25.729839) (xy 156.414626 -25.751651) (xy 156.360669 -25.765757) (xy 156.305232 -25.771857)
			(xy 156.249498 -25.76982) (xy 156.194655 -25.75969) (xy 156.141871 -25.741683) (xy 156.092271 -25.716182)
			(xy 156.046913 -25.683731) (xy 156.006764 -25.645022) (xy 155.972678 -25.600879) (xy 155.945382 -25.552244)
			(xy 155.925459 -25.500153) (xy 155.913333 -25.445716) (xy 155.909262 -25.390094) (xy 139.46565 -25.390094)
			(xy 139.480739 -25.422281) (xy 139.496807 -25.475688) (xy 139.504927 -25.530864) (xy 139.505436 -25.55875)
			(xy 139.504927 -25.586636) (xy 139.496807 -25.641812) (xy 139.480739 -25.695219) (xy 139.457067 -25.745716)
			(xy 139.426294 -25.792229) (xy 139.389077 -25.833766) (xy 139.346209 -25.869441) (xy 139.298603 -25.898495)
			(xy 139.247274 -25.920307) (xy 139.193317 -25.934413) (xy 139.13788 -25.940513) (xy 139.082146 -25.938476)
			(xy 139.027303 -25.928346) (xy 138.974519 -25.910339) (xy 138.924919 -25.884838) (xy 138.879561 -25.852387)
			(xy 138.839412 -25.813678) (xy 138.805326 -25.769535) (xy 138.77803 -25.7209) (xy 138.758107 -25.668809)
			(xy 138.745981 -25.614372) (xy 138.74191 -25.55875) (xy 130.633054 -25.55875) (xy 130.624471 -25.57706)
			(xy 130.593698 -25.623573) (xy 130.556481 -25.66511) (xy 130.513613 -25.700785) (xy 130.466007 -25.729839)
			(xy 130.414678 -25.751651) (xy 130.360721 -25.765757) (xy 130.305284 -25.771857) (xy 130.24955 -25.76982)
			(xy 130.194707 -25.75969) (xy 130.141923 -25.741683) (xy 130.092323 -25.716182) (xy 130.046965 -25.683731)
			(xy 130.006816 -25.645022) (xy 129.97273 -25.600879) (xy 129.945434 -25.552244) (xy 129.925511 -25.500153)
			(xy 129.913385 -25.445716) (xy 129.909314 -25.390094) (xy 101.365396 -25.390094) (xy 101.380485 -25.422281)
			(xy 101.396553 -25.475688) (xy 101.404673 -25.530864) (xy 101.405182 -25.55875) (xy 101.404673 -25.586636)
			(xy 101.396553 -25.641812) (xy 101.380485 -25.695219) (xy 101.356813 -25.745716) (xy 101.32604 -25.792229)
			(xy 101.288823 -25.833766) (xy 101.245955 -25.869441) (xy 101.198349 -25.898495) (xy 101.14702 -25.920307)
			(xy 101.093063 -25.934413) (xy 101.037626 -25.940513) (xy 100.981892 -25.938476) (xy 100.927049 -25.928346)
			(xy 100.874265 -25.910339) (xy 100.824665 -25.884838) (xy 100.779307 -25.852387) (xy 100.739158 -25.813678)
			(xy 100.705072 -25.769535) (xy 100.677776 -25.7209) (xy 100.657853 -25.668809) (xy 100.645727 -25.614372)
			(xy 100.641656 -25.55875) (xy 92.5328 -25.55875) (xy 92.524217 -25.57706) (xy 92.493444 -25.623573)
			(xy 92.456227 -25.66511) (xy 92.413359 -25.700785) (xy 92.365753 -25.729839) (xy 92.314424 -25.751651)
			(xy 92.260467 -25.765757) (xy 92.20503 -25.771857) (xy 92.149296 -25.76982) (xy 92.094453 -25.75969)
			(xy 92.041669 -25.741683) (xy 91.992069 -25.716182) (xy 91.946711 -25.683731) (xy 91.906562 -25.645022)
			(xy 91.872476 -25.600879) (xy 91.84518 -25.552244) (xy 91.825257 -25.500153) (xy 91.813131 -25.445716)
			(xy 91.80906 -25.390094) (xy 75.365448 -25.390094) (xy 75.380537 -25.422281) (xy 75.396605 -25.475688)
			(xy 75.404725 -25.530864) (xy 75.405234 -25.55875) (xy 75.404725 -25.586636) (xy 75.396605 -25.641812)
			(xy 75.380537 -25.695219) (xy 75.356865 -25.745716) (xy 75.326092 -25.792229) (xy 75.288875 -25.833766)
			(xy 75.246007 -25.869441) (xy 75.198401 -25.898495) (xy 75.147072 -25.920307) (xy 75.093115 -25.934413)
			(xy 75.037678 -25.940513) (xy 74.981944 -25.938476) (xy 74.927101 -25.928346) (xy 74.874317 -25.910339)
			(xy 74.824717 -25.884838) (xy 74.779359 -25.852387) (xy 74.73921 -25.813678) (xy 74.705124 -25.769535)
			(xy 74.677828 -25.7209) (xy 74.657905 -25.668809) (xy 74.645779 -25.614372) (xy 74.641708 -25.55875)
			(xy 66.532852 -25.55875) (xy 66.524269 -25.57706) (xy 66.493496 -25.623573) (xy 66.456279 -25.66511)
			(xy 66.413411 -25.700785) (xy 66.365805 -25.729839) (xy 66.314476 -25.751651) (xy 66.260519 -25.765757)
			(xy 66.205082 -25.771857) (xy 66.149348 -25.76982) (xy 66.094505 -25.75969) (xy 66.041721 -25.741683)
			(xy 65.992121 -25.716182) (xy 65.946763 -25.683731) (xy 65.906614 -25.645022) (xy 65.872528 -25.600879)
			(xy 65.845232 -25.552244) (xy 65.825309 -25.500153) (xy 65.813183 -25.445716) (xy 65.809112 -25.390094)
			(xy 49.3655 -25.390094) (xy 49.380589 -25.422281) (xy 49.396657 -25.475688) (xy 49.404777 -25.530864)
			(xy 49.405286 -25.55875) (xy 49.404777 -25.586636) (xy 49.396657 -25.641812) (xy 49.380589 -25.695219)
			(xy 49.356917 -25.745716) (xy 49.326144 -25.792229) (xy 49.288927 -25.833766) (xy 49.246059 -25.869441)
			(xy 49.198453 -25.898495) (xy 49.147124 -25.920307) (xy 49.093167 -25.934413) (xy 49.03773 -25.940513)
			(xy 48.981996 -25.938476) (xy 48.927153 -25.928346) (xy 48.874369 -25.910339) (xy 48.824769 -25.884838)
			(xy 48.779411 -25.852387) (xy 48.739262 -25.813678) (xy 48.705176 -25.769535) (xy 48.67788 -25.7209)
			(xy 48.657957 -25.668809) (xy 48.645831 -25.614372) (xy 48.64176 -25.55875) (xy 40.532904 -25.55875)
			(xy 40.524321 -25.57706) (xy 40.493548 -25.623573) (xy 40.456331 -25.66511) (xy 40.413463 -25.700785)
			(xy 40.365857 -25.729839) (xy 40.314528 -25.751651) (xy 40.260571 -25.765757) (xy 40.205134 -25.771857)
			(xy 40.1494 -25.76982) (xy 40.094557 -25.75969) (xy 40.041773 -25.741683) (xy 39.992173 -25.716182)
			(xy 39.946815 -25.683731) (xy 39.906666 -25.645022) (xy 39.87258 -25.600879) (xy 39.845284 -25.552244)
			(xy 39.825361 -25.500153) (xy 39.813235 -25.445716) (xy 39.809164 -25.390094) (xy 18.701327 -25.390094)
			(xy 18.693286 -25.393511) (xy 18.639329 -25.407617) (xy 18.583892 -25.413717) (xy 18.528158 -25.41168)
			(xy 18.473315 -25.40155) (xy 18.420531 -25.383543) (xy 18.370931 -25.358042) (xy 18.325573 -25.325591)
			(xy 18.285424 -25.286882) (xy 18.251338 -25.242739) (xy 18.224042 -25.194104) (xy 18.204119 -25.142013)
			(xy 18.191993 -25.087576) (xy 18.187922 -25.031954) (xy 14.322621 -25.031954) (xy 14.365909 -25.050349)
			(xy 14.413515 -25.079403) (xy 14.456383 -25.115078) (xy 14.4936 -25.156615) (xy 14.524373 -25.203128)
			(xy 14.548045 -25.253625) (xy 14.564113 -25.307032) (xy 14.572233 -25.362208) (xy 14.572742 -25.390094)
			(xy 14.572233 -25.41798) (xy 14.564113 -25.473156) (xy 14.548045 -25.526563) (xy 14.524373 -25.57706)
			(xy 14.4936 -25.623573) (xy 14.456383 -25.66511) (xy 14.413515 -25.700785) (xy 14.365909 -25.729839)
			(xy 14.31458 -25.751651) (xy 14.260623 -25.765757) (xy 14.205186 -25.771857) (xy 14.149452 -25.76982)
			(xy 14.094609 -25.75969) (xy 14.041825 -25.741683) (xy 13.992225 -25.716182) (xy 13.946867 -25.683731)
			(xy 13.906718 -25.645022) (xy 13.872632 -25.600879) (xy 13.845336 -25.552244) (xy 13.825413 -25.500153)
			(xy 13.813287 -25.445716) (xy 13.809216 -25.390094) (xy 1.867916 -25.390094) (xy 1.867916 -25.551384)
			(xy 1.868932 -25.560528) (xy 1.869694 -25.56764) (xy 1.872996 -25.576276) (xy 1.877568 -25.58415)
			(xy 1.883918 -25.592786) (xy 1.902206 -25.609042) (xy 1.902714 -25.60955) (xy 1.942338 -25.644094)
			(xy 1.950466 -25.651206) (xy 1.97104 -25.657556) (xy 1.982216 -25.656286) (xy 1.982978 -25.656286)
			(xy 1.986026 -25.656032) (xy 1.997162 -25.654823) (xy 2.019529 -25.653552) (xy 2.03073 -25.653492)
			(xy 2.032 -25.653492) (xy 2.059251 -25.653978) (xy 2.113199 -25.661734) (xy 2.165494 -25.677089)
			(xy 2.215071 -25.699731) (xy 2.260921 -25.729197) (xy 2.302112 -25.764888) (xy 2.337803 -25.806079)
			(xy 2.367269 -25.851929) (xy 2.389911 -25.901506) (xy 2.402334 -25.943814) (xy 4.265674 -25.943814)
			(xy 4.269745 -25.888192) (xy 4.281871 -25.833755) (xy 4.301794 -25.781664) (xy 4.32909 -25.733029)
			(xy 4.363176 -25.688886) (xy 4.403325 -25.650177) (xy 4.448683 -25.617726) (xy 4.498283 -25.592225)
			(xy 4.551067 -25.574218) (xy 4.60591 -25.564088) (xy 4.661644 -25.562051) (xy 4.717081 -25.568151)
			(xy 4.771038 -25.582257) (xy 4.822367 -25.604069) (xy 4.869973 -25.633123) (xy 4.912841 -25.668798)
			(xy 4.950058 -25.710335) (xy 4.980831 -25.756848) (xy 5.004503 -25.807345) (xy 5.020571 -25.860752)
			(xy 5.028691 -25.915928) (xy 5.0292 -25.943814) (xy 5.028691 -25.9717) (xy 5.020571 -26.026876) (xy 5.018509 -26.03373)
			(xy 5.317488 -26.03373) (xy 5.321559 -25.978108) (xy 5.333685 -25.923671) (xy 5.353608 -25.87158)
			(xy 5.380904 -25.822945) (xy 5.41499 -25.778802) (xy 5.455139 -25.740093) (xy 5.500497 -25.707642)
			(xy 5.550097 -25.682141) (xy 5.602881 -25.664134) (xy 5.657724 -25.654004) (xy 5.713458 -25.651967)
			(xy 5.768895 -25.658067) (xy 5.822852 -25.672173) (xy 5.874181 -25.693985) (xy 5.921787 -25.723039)
			(xy 5.964655 -25.758714) (xy 6.001872 -25.800251) (xy 6.032645 -25.846764) (xy 6.056317 -25.897261)
			(xy 6.072385 -25.950668) (xy 6.080505 -26.005844) (xy 6.081014 -26.03373) (xy 6.080505 -26.061616)
			(xy 6.072385 -26.116792) (xy 6.056317 -26.170199) (xy 6.032645 -26.220696) (xy 6.001872 -26.267209)
			(xy 5.964655 -26.308746) (xy 5.921787 -26.344421) (xy 5.874181 -26.373475) (xy 5.822852 -26.395287)
			(xy 5.768895 -26.409393) (xy 5.713458 -26.415493) (xy 5.657724 -26.413456) (xy 5.602881 -26.403326)
			(xy 5.550097 -26.385319) (xy 5.500497 -26.359818) (xy 5.455139 -26.327367) (xy 5.41499 -26.288658)
			(xy 5.380904 -26.244515) (xy 5.353608 -26.19588) (xy 5.333685 -26.143789) (xy 5.321559 -26.089352)
			(xy 5.317488 -26.03373) (xy 5.018509 -26.03373) (xy 5.004503 -26.080283) (xy 4.980831 -26.13078)
			(xy 4.950058 -26.177293) (xy 4.912841 -26.21883) (xy 4.869973 -26.254505) (xy 4.822367 -26.283559)
			(xy 4.771038 -26.305371) (xy 4.717081 -26.319477) (xy 4.661644 -26.325577) (xy 4.60591 -26.32354)
			(xy 4.551067 -26.31341) (xy 4.498283 -26.295403) (xy 4.448683 -26.269902) (xy 4.403325 -26.237451)
			(xy 4.363176 -26.198742) (xy 4.32909 -26.154599) (xy 4.301794 -26.105964) (xy 4.281871 -26.053873)
			(xy 4.269745 -25.999436) (xy 4.265674 -25.943814) (xy 2.402334 -25.943814) (xy 2.405266 -25.953801)
			(xy 2.413022 -26.007749) (xy 2.413022 -26.062251) (xy 2.405266 -26.116199) (xy 2.389911 -26.168494)
			(xy 2.367269 -26.218071) (xy 2.337803 -26.263921) (xy 2.302112 -26.305112) (xy 2.260921 -26.340803)
			(xy 2.215071 -26.370269) (xy 2.165494 -26.392911) (xy 2.113199 -26.408266) (xy 2.059251 -26.416022)
			(xy 2.032 -26.416508) (xy 2.019711 -26.416433) (xy 1.995181 -26.414911) (xy 1.982978 -26.41346) (xy 1.976628 -26.412698)
			(xy 1.972757 -26.412746) (xy 1.965103 -26.413896) (xy 1.961388 -26.414984) (xy 1.95199 -26.418032)
			(xy 1.902968 -26.460196) (xy 1.902206 -26.460958) (xy 1.87706 -26.482294) (xy 1.872488 -26.492708)
			(xy 1.867916 -26.502614) (xy 1.867916 -29.330142) (xy 2.191256 -29.330142) (xy 2.195327 -29.27452)
			(xy 2.207453 -29.220083) (xy 2.227376 -29.167992) (xy 2.254672 -29.119357) (xy 2.288758 -29.075214)
			(xy 2.328907 -29.036505) (xy 2.374265 -29.004054) (xy 2.423865 -28.978553) (xy 2.476649 -28.960546)
			(xy 2.531492 -28.950416) (xy 2.587226 -28.948379) (xy 2.642663 -28.954479) (xy 2.69662 -28.968585)
			(xy 2.747949 -28.990397) (xy 2.795555 -29.019451) (xy 2.838423 -29.055126) (xy 2.87564 -29.096663)
			(xy 2.906413 -29.143176) (xy 2.930085 -29.193673) (xy 2.946153 -29.24708) (xy 2.954273 -29.302256)
			(xy 2.954782 -29.330142) (xy 2.954281 -29.357574) (xy 3.464304 -29.357574) (xy 3.468375 -29.301952)
			(xy 3.480501 -29.247515) (xy 3.500424 -29.195424) (xy 3.52772 -29.146789) (xy 3.561806 -29.102646)
			(xy 3.601955 -29.063937) (xy 3.647313 -29.031486) (xy 3.696913 -29.005985) (xy 3.749697 -28.987978)
			(xy 3.80454 -28.977848) (xy 3.860274 -28.975811) (xy 3.915711 -28.981911) (xy 3.969668 -28.996017)
			(xy 4.020997 -29.017829) (xy 4.068603 -29.046883) (xy 4.111471 -29.082558) (xy 4.148688 -29.124095)
			(xy 4.179461 -29.170608) (xy 4.203133 -29.221105) (xy 4.219201 -29.274512) (xy 4.227321 -29.329688)
			(xy 4.22783 -29.357574) (xy 4.227321 -29.38546) (xy 4.219201 -29.440636) (xy 4.203133 -29.494043)
			(xy 4.179461 -29.54454) (xy 4.148688 -29.591053) (xy 4.111471 -29.63259) (xy 4.068603 -29.668265)
			(xy 4.020997 -29.697319) (xy 3.969668 -29.719131) (xy 3.915711 -29.733237) (xy 3.860274 -29.739337)
			(xy 3.80454 -29.7373) (xy 3.749697 -29.72717) (xy 3.696913 -29.709163) (xy 3.647313 -29.683662) (xy 3.601955 -29.651211)
			(xy 3.561806 -29.612502) (xy 3.52772 -29.568359) (xy 3.500424 -29.519724) (xy 3.480501 -29.467633)
			(xy 3.468375 -29.413196) (xy 3.464304 -29.357574) (xy 2.954281 -29.357574) (xy 2.954273 -29.358028)
			(xy 2.946153 -29.413204) (xy 2.930085 -29.466611) (xy 2.906413 -29.517108) (xy 2.87564 -29.563621)
			(xy 2.838423 -29.605158) (xy 2.795555 -29.640833) (xy 2.747949 -29.669887) (xy 2.69662 -29.691699)
			(xy 2.642663 -29.705805) (xy 2.587226 -29.711905) (xy 2.531492 -29.709868) (xy 2.476649 -29.699738)
			(xy 2.423865 -29.681731) (xy 2.374265 -29.65623) (xy 2.328907 -29.623779) (xy 2.288758 -29.58507)
			(xy 2.254672 -29.540927) (xy 2.227376 -29.492292) (xy 2.207453 -29.440201) (xy 2.195327 -29.385764)
			(xy 2.191256 -29.330142) (xy 1.867916 -29.330142) (xy 1.867916 -33.710626) (xy 2.52425 -33.710626)
			(xy 2.528321 -33.655004) (xy 2.540447 -33.600567) (xy 2.56037 -33.548476) (xy 2.587666 -33.499841)
			(xy 2.621752 -33.455698) (xy 2.661901 -33.416989) (xy 2.707259 -33.384538) (xy 2.756859 -33.359037)
			(xy 2.809643 -33.34103) (xy 2.864486 -33.3309) (xy 2.92022 -33.328863) (xy 2.975657 -33.334963) (xy 3.029614 -33.349069)
			(xy 3.080943 -33.370881) (xy 3.128549 -33.399935) (xy 3.171417 -33.43561) (xy 3.208634 -33.477147)
			(xy 3.239407 -33.52366) (xy 3.263079 -33.574157) (xy 3.279147 -33.627564) (xy 3.287267 -33.68274)
			(xy 3.287776 -33.710626) (xy 3.287267 -33.738512) (xy 3.279596 -33.790636) (xy 3.426966 -33.790636)
			(xy 3.431037 -33.735014) (xy 3.443163 -33.680577) (xy 3.463086 -33.628486) (xy 3.490382 -33.579851)
			(xy 3.524468 -33.535708) (xy 3.564617 -33.496999) (xy 3.609975 -33.464548) (xy 3.659575 -33.439047)
			(xy 3.712359 -33.42104) (xy 3.767202 -33.41091) (xy 3.822936 -33.408873) (xy 3.878373 -33.414973)
			(xy 3.93233 -33.429079) (xy 3.983659 -33.450891) (xy 4.031265 -33.479945) (xy 4.074133 -33.51562)
			(xy 4.11135 -33.557157) (xy 4.142123 -33.60367) (xy 4.165795 -33.654167) (xy 4.181863 -33.707574)
			(xy 4.189983 -33.76275) (xy 4.190334 -33.782) (xy 4.661152 -33.782) (xy 4.665223 -33.726378) (xy 4.677349 -33.671941)
			(xy 4.697272 -33.61985) (xy 4.724568 -33.571215) (xy 4.758654 -33.527072) (xy 4.798803 -33.488363)
			(xy 4.844161 -33.455912) (xy 4.893761 -33.430411) (xy 4.946545 -33.412404) (xy 5.001388 -33.402274)
			(xy 5.057122 -33.400237) (xy 5.112559 -33.406337) (xy 5.166516 -33.420443) (xy 5.217845 -33.442255)
			(xy 5.265451 -33.471309) (xy 5.308319 -33.506984) (xy 5.345536 -33.548521) (xy 5.376309 -33.595034)
			(xy 5.399981 -33.645531) (xy 5.416049 -33.698938) (xy 5.424169 -33.754114) (xy 5.424678 -33.782)
			(xy 5.424169 -33.809886) (xy 5.416049 -33.865062) (xy 5.399981 -33.918469) (xy 5.376309 -33.968966)
			(xy 5.345536 -34.015479) (xy 5.308319 -34.057016) (xy 5.265451 -34.092691) (xy 5.217845 -34.121745)
			(xy 5.166516 -34.143557) (xy 5.112559 -34.157663) (xy 5.057122 -34.163763) (xy 5.001388 -34.161726)
			(xy 4.946545 -34.151596) (xy 4.893761 -34.133589) (xy 4.844161 -34.108088) (xy 4.798803 -34.075637)
			(xy 4.758654 -34.036928) (xy 4.724568 -33.992785) (xy 4.697272 -33.94415) (xy 4.677349 -33.892059)
			(xy 4.665223 -33.837622) (xy 4.661152 -33.782) (xy 4.190334 -33.782) (xy 4.190492 -33.790636) (xy 4.189983 -33.818522)
			(xy 4.181863 -33.873698) (xy 4.165795 -33.927105) (xy 4.142123 -33.977602) (xy 4.11135 -34.024115)
			(xy 4.074133 -34.065652) (xy 4.031265 -34.101327) (xy 3.983659 -34.130381) (xy 3.93233 -34.152193)
			(xy 3.878373 -34.166299) (xy 3.822936 -34.172399) (xy 3.767202 -34.170362) (xy 3.712359 -34.160232)
			(xy 3.659575 -34.142225) (xy 3.609975 -34.116724) (xy 3.564617 -34.084273) (xy 3.524468 -34.045564)
			(xy 3.490382 -34.001421) (xy 3.463086 -33.952786) (xy 3.443163 -33.900695) (xy 3.431037 -33.846258)
			(xy 3.426966 -33.790636) (xy 3.279596 -33.790636) (xy 3.279147 -33.793688) (xy 3.263079 -33.847095)
			(xy 3.239407 -33.897592) (xy 3.208634 -33.944105) (xy 3.171417 -33.985642) (xy 3.128549 -34.021317)
			(xy 3.080943 -34.050371) (xy 3.029614 -34.072183) (xy 2.975657 -34.086289) (xy 2.92022 -34.092389)
			(xy 2.864486 -34.090352) (xy 2.809643 -34.080222) (xy 2.756859 -34.062215) (xy 2.707259 -34.036714)
			(xy 2.661901 -34.004263) (xy 2.621752 -33.965554) (xy 2.587666 -33.921411) (xy 2.56037 -33.872776)
			(xy 2.540447 -33.820685) (xy 2.528321 -33.766248) (xy 2.52425 -33.710626) (xy 1.867916 -33.710626)
			(xy 1.867916 -34.14395) (xy 1.869948 -34.15792) (xy 1.869948 -34.158428) (xy 1.873126 -34.167831)
			(xy 1.885407 -34.183396) (xy 1.893824 -34.188654) (xy 1.898396 -34.191194) (xy 1.977644 -34.224722)
			(xy 1.982724 -34.226754) (xy 1.994916 -34.229294) (xy 2.00091 -34.230426) (xy 2.013103 -34.230163)
			(xy 2.019046 -34.228786) (xy 2.026158 -34.226754) (xy 2.036826 -34.220658) (xy 2.041652 -34.216086)
			(xy 2.041906 -34.215832) (xy 2.063361 -34.195871) (xy 2.111256 -34.162107) (xy 2.163753 -34.136068)
			(xy 2.219615 -34.118367) (xy 2.277528 -34.109421) (xy 2.306828 -34.108898) (xy 2.334079 -34.109384)
			(xy 2.388028 -34.11714) (xy 2.440323 -34.132495) (xy 2.489901 -34.155136) (xy 2.535752 -34.184602)
			(xy 2.576942 -34.220293) (xy 2.612634 -34.261484) (xy 2.642101 -34.307334) (xy 2.664743 -34.356912)
			(xy 2.680099 -34.409207) (xy 2.687856 -34.463155) (xy 2.688336 -34.490406) (xy 2.68788 -34.517217)
			(xy 2.680365 -34.570309) (xy 2.665485 -34.621825) (xy 2.643533 -34.670747) (xy 2.614942 -34.716111)
			(xy 2.580277 -34.757021) (xy 2.540222 -34.792669) (xy 2.518156 -34.807906) (xy 2.51714 -34.808668)
			(xy 2.512314 -34.81197) (xy 2.503932 -34.821114) (xy 2.501392 -34.826194) (xy 2.498698 -34.831726)
			(xy 2.495747 -34.843666) (xy 2.49555 -34.849816) (xy 2.49555 -34.864294) (xy 2.494788 -34.932366)
			(xy 2.494788 -34.933636) (xy 2.494877 -34.93758) (xy 2.496154 -34.945364) (xy 2.497328 -34.94913)
			(xy 2.500884 -34.959036) (xy 2.512314 -34.972244) (xy 2.517648 -34.976308) (xy 2.518156 -34.976816)
			(xy 2.519934 -34.978086) (xy 2.520442 -34.978594) (xy 2.520696 -34.978594) (xy 2.541697 -34.994016)
			(xy 2.579725 -35.029634) (xy 2.612564 -35.070086) (xy 2.639607 -35.114622) (xy 2.660352 -35.162417)
			(xy 2.674416 -35.212586) (xy 2.681538 -35.264201) (xy 2.681986 -35.290252) (xy 2.681986 -35.290506)
			(xy 2.681518 -35.31747) (xy 2.673921 -35.370859) (xy 2.658883 -35.422647) (xy 2.636703 -35.471802)
			(xy 2.607824 -35.517345) (xy 2.572821 -35.558368) (xy 2.53239 -35.594055) (xy 2.487339 -35.623694)
			(xy 2.438563 -35.646695) (xy 2.387034 -35.6626) (xy 2.33378 -35.671092) (xy 2.306828 -35.672014)
			(xy 2.29997 -35.672014) (xy 2.272086 -35.671488) (xy 2.216915 -35.663335) (xy 2.16352 -35.647236)
			(xy 2.113037 -35.623535) (xy 2.066543 -35.592737) (xy 2.045462 -35.574478) (xy 2.038604 -35.568128)
			(xy 2.015744 -35.559492) (xy 2.011857 -35.55825) (xy 2.003819 -35.556851) (xy 1.999742 -35.556698)
			(xy 1.988312 -35.556698) (xy 1.955038 -35.571176) (xy 1.899666 -35.59556) (xy 1.892943 -35.598719)
			(xy 1.881579 -35.608274) (xy 1.877314 -35.614356) (xy 1.872742 -35.62096) (xy 1.870456 -35.628072)
			(xy 1.869293 -35.631906) (xy 1.868014 -35.639815) (xy 1.867916 -35.64382) (xy 1.867916 -35.91941)
			(xy 2.665728 -35.91941) (xy 2.669799 -35.863788) (xy 2.681925 -35.809351) (xy 2.701848 -35.75726)
			(xy 2.729144 -35.708625) (xy 2.76323 -35.664482) (xy 2.803379 -35.625773) (xy 2.848737 -35.593322)
			(xy 2.898337 -35.567821) (xy 2.951121 -35.549814) (xy 3.005964 -35.539684) (xy 3.061698 -35.537647)
			(xy 3.117135 -35.543747) (xy 3.171092 -35.557853) (xy 3.222421 -35.579665) (xy 3.270027 -35.608719)
			(xy 3.312895 -35.644394) (xy 3.350112 -35.685931) (xy 3.380885 -35.732444) (xy 3.404557 -35.782941)
			(xy 3.420625 -35.836348) (xy 3.427317 -35.881818) (xy 3.668774 -35.881818) (xy 3.672845 -35.826196)
			(xy 3.684971 -35.771759) (xy 3.704894 -35.719668) (xy 3.73219 -35.671033) (xy 3.766276 -35.62689)
			(xy 3.806425 -35.588181) (xy 3.851783 -35.55573) (xy 3.901383 -35.530229) (xy 3.954167 -35.512222)
			(xy 4.00901 -35.502092) (xy 4.064744 -35.500055) (xy 4.120181 -35.506155) (xy 4.174138 -35.520261)
			(xy 4.225467 -35.542073) (xy 4.273073 -35.571127) (xy 4.315941 -35.606802) (xy 4.353158 -35.648339)
			(xy 4.383931 -35.694852) (xy 4.407603 -35.745349) (xy 4.423671 -35.798756) (xy 4.431791 -35.853932)
			(xy 4.4323 -35.881818) (xy 4.43186 -35.905948) (xy 4.661152 -35.905948) (xy 4.665223 -35.850326)
			(xy 4.677349 -35.795889) (xy 4.697272 -35.743798) (xy 4.724568 -35.695163) (xy 4.758654 -35.65102)
			(xy 4.798803 -35.612311) (xy 4.844161 -35.57986) (xy 4.893761 -35.554359) (xy 4.946545 -35.536352)
			(xy 5.001388 -35.526222) (xy 5.057122 -35.524185) (xy 5.112559 -35.530285) (xy 5.166516 -35.544391)
			(xy 5.217845 -35.566203) (xy 5.265451 -35.595257) (xy 5.308319 -35.630932) (xy 5.345536 -35.672469)
			(xy 5.376309 -35.718982) (xy 5.399981 -35.769479) (xy 5.416049 -35.822886) (xy 5.424169 -35.878062)
			(xy 5.424678 -35.905948) (xy 5.424169 -35.933834) (xy 5.416049 -35.98901) (xy 5.399981 -36.042417)
			(xy 5.376309 -36.092914) (xy 5.345536 -36.139427) (xy 5.308319 -36.180964) (xy 5.265451 -36.216639)
			(xy 5.217845 -36.245693) (xy 5.166516 -36.267505) (xy 5.112559 -36.281611) (xy 5.057122 -36.287711)
			(xy 5.001388 -36.285674) (xy 4.946545 -36.275544) (xy 4.893761 -36.257537) (xy 4.844161 -36.232036)
			(xy 4.798803 -36.199585) (xy 4.758654 -36.160876) (xy 4.724568 -36.116733) (xy 4.697272 -36.068098)
			(xy 4.677349 -36.016007) (xy 4.665223 -35.96157) (xy 4.661152 -35.905948) (xy 4.43186 -35.905948)
			(xy 4.431791 -35.909704) (xy 4.423671 -35.96488) (xy 4.407603 -36.018287) (xy 4.383931 -36.068784)
			(xy 4.353158 -36.115297) (xy 4.315941 -36.156834) (xy 4.273073 -36.192509) (xy 4.225467 -36.221563)
			(xy 4.174138 -36.243375) (xy 4.120181 -36.257481) (xy 4.064744 -36.263581) (xy 4.00901 -36.261544)
			(xy 3.954167 -36.251414) (xy 3.901383 -36.233407) (xy 3.851783 -36.207906) (xy 3.806425 -36.175455)
			(xy 3.766276 -36.136746) (xy 3.73219 -36.092603) (xy 3.704894 -36.043968) (xy 3.684971 -35.991877)
			(xy 3.672845 -35.93744) (xy 3.668774 -35.881818) (xy 3.427317 -35.881818) (xy 3.428745 -35.891524)
			(xy 3.429254 -35.91941) (xy 3.428745 -35.947296) (xy 3.420625 -36.002472) (xy 3.404557 -36.055879)
			(xy 3.380885 -36.106376) (xy 3.350112 -36.152889) (xy 3.312895 -36.194426) (xy 3.270027 -36.230101)
			(xy 3.222421 -36.259155) (xy 3.171092 -36.280967) (xy 3.117135 -36.295073) (xy 3.061698 -36.301173)
			(xy 3.005964 -36.299136) (xy 2.951121 -36.289006) (xy 2.898337 -36.270999) (xy 2.848737 -36.245498)
			(xy 2.803379 -36.213047) (xy 2.76323 -36.174338) (xy 2.729144 -36.130195) (xy 2.701848 -36.08156)
			(xy 2.681925 -36.029469) (xy 2.669799 -35.975032) (xy 2.665728 -35.91941) (xy 1.867916 -35.91941)
			(xy 1.867916 -38.928802) (xy 3.912868 -38.928802) (xy 3.916939 -38.87318) (xy 3.929065 -38.818743)
			(xy 3.948988 -38.766652) (xy 3.976284 -38.718017) (xy 4.01037 -38.673874) (xy 4.050519 -38.635165)
			(xy 4.095877 -38.602714) (xy 4.145477 -38.577213) (xy 4.198261 -38.559206) (xy 4.253104 -38.549076)
			(xy 4.308838 -38.547039) (xy 4.364275 -38.553139) (xy 4.418232 -38.567245) (xy 4.469561 -38.589057)
			(xy 4.517167 -38.618111) (xy 4.560035 -38.653786) (xy 4.597252 -38.695323) (xy 4.628025 -38.741836)
			(xy 4.651697 -38.792333) (xy 4.667765 -38.84574) (xy 4.675885 -38.900916) (xy 4.676394 -38.928802)
			(xy 5.182868 -38.928802) (xy 5.186939 -38.87318) (xy 5.199065 -38.818743) (xy 5.218988 -38.766652)
			(xy 5.246284 -38.718017) (xy 5.28037 -38.673874) (xy 5.320519 -38.635165) (xy 5.365877 -38.602714)
			(xy 5.415477 -38.577213) (xy 5.468261 -38.559206) (xy 5.523104 -38.549076) (xy 5.578838 -38.547039)
			(xy 5.634275 -38.553139) (xy 5.688232 -38.567245) (xy 5.739561 -38.589057) (xy 5.787167 -38.618111)
			(xy 5.830035 -38.653786) (xy 5.867252 -38.695323) (xy 5.898025 -38.741836) (xy 5.921697 -38.792333)
			(xy 5.937765 -38.84574) (xy 5.945885 -38.900916) (xy 5.946394 -38.928802) (xy 5.945885 -38.956688)
			(xy 5.937765 -39.011864) (xy 5.921697 -39.065271) (xy 5.898025 -39.115768) (xy 5.867252 -39.162281)
			(xy 5.830035 -39.203818) (xy 5.787167 -39.239493) (xy 5.739561 -39.268547) (xy 5.688232 -39.290359)
			(xy 5.634275 -39.304465) (xy 5.578838 -39.310565) (xy 5.523104 -39.308528) (xy 5.468261 -39.298398)
			(xy 5.415477 -39.280391) (xy 5.365877 -39.25489) (xy 5.320519 -39.222439) (xy 5.28037 -39.18373)
			(xy 5.246284 -39.139587) (xy 5.218988 -39.090952) (xy 5.199065 -39.038861) (xy 5.186939 -38.984424)
			(xy 5.182868 -38.928802) (xy 4.676394 -38.928802) (xy 4.675885 -38.956688) (xy 4.667765 -39.011864)
			(xy 4.651697 -39.065271) (xy 4.628025 -39.115768) (xy 4.597252 -39.162281) (xy 4.560035 -39.203818)
			(xy 4.517167 -39.239493) (xy 4.469561 -39.268547) (xy 4.418232 -39.290359) (xy 4.364275 -39.304465)
			(xy 4.308838 -39.310565) (xy 4.253104 -39.308528) (xy 4.198261 -39.298398) (xy 4.145477 -39.280391)
			(xy 4.095877 -39.25489) (xy 4.050519 -39.222439) (xy 4.01037 -39.18373) (xy 3.976284 -39.139587)
			(xy 3.948988 -39.090952) (xy 3.929065 -39.038861) (xy 3.916939 -38.984424) (xy 3.912868 -38.928802)
			(xy 1.867916 -38.928802) (xy 1.867916 -41.166542) (xy 2.403856 -41.166542) (xy 2.404383 -41.137625)
			(xy 2.413107 -41.080453) (xy 2.430362 -41.025254) (xy 2.455752 -40.973292) (xy 2.488695 -40.925758)
			(xy 2.528436 -40.883741) (xy 2.550922 -40.865552) (xy 2.559745 -40.85796) (xy 2.569919 -40.837048)
			(xy 2.57048 -40.82542) (xy 2.57048 -40.745664) (xy 2.569954 -40.73403) (xy 2.559757 -40.713121) (xy 2.550922 -40.705532)
			(xy 2.528438 -40.687342) (xy 2.488703 -40.645322) (xy 2.455764 -40.597787) (xy 2.430376 -40.545825)
			(xy 2.41312 -40.490628) (xy 2.404391 -40.433458) (xy 2.403856 -40.404542) (xy 2.404342 -40.377291)
			(xy 2.412098 -40.323343) (xy 2.427453 -40.271048) (xy 2.450095 -40.221471) (xy 2.479561 -40.175621)
			(xy 2.515252 -40.13443) (xy 2.556443 -40.098739) (xy 2.602293 -40.069273) (xy 2.65187 -40.046631)
			(xy 2.704165 -40.031276) (xy 2.758113 -40.02352) (xy 2.812615 -40.02352) (xy 2.866563 -40.031276)
			(xy 2.918858 -40.046631) (xy 2.968435 -40.069273) (xy 3.014285 -40.098739) (xy 3.055476 -40.13443)
			(xy 3.091167 -40.175621) (xy 3.120633 -40.221471) (xy 3.143275 -40.271048) (xy 3.15863 -40.323343)
			(xy 3.166386 -40.377291) (xy 3.166872 -40.404542) (xy 3.166323 -40.433458) (xy 3.157602 -40.490628)
			(xy 3.140351 -40.545827) (xy 3.114965 -40.597789) (xy 3.082026 -40.645324) (xy 3.04229 -40.687341)
			(xy 3.019806 -40.705532) (xy 3.010995 -40.713136) (xy 3.000813 -40.734039) (xy 3.000248 -40.745664)
			(xy 3.000248 -40.82542) (xy 3.000773 -40.837054) (xy 3.01097 -40.857964) (xy 3.019806 -40.865552)
			(xy 3.042287 -40.883746) (xy 3.082022 -40.925765) (xy 3.114961 -40.9733) (xy 3.14035 -41.02526) (xy 3.157607 -41.080457)
			(xy 3.166337 -41.137626) (xy 3.166872 -41.166542) (xy 5.443982 -41.166542) (xy 5.4445 -41.137625)
			(xy 5.453225 -41.080452) (xy 5.470481 -41.025252) (xy 5.495872 -40.97329) (xy 5.528818 -40.925756)
			(xy 5.568561 -40.883741) (xy 5.591048 -40.865552) (xy 5.599875 -40.857964) (xy 5.610046 -40.837048)
			(xy 5.610606 -40.82542) (xy 5.610606 -40.745664) (xy 5.610071 -40.734032) (xy 5.599879 -40.713122)
			(xy 5.591048 -40.705532) (xy 5.568569 -40.687336) (xy 5.528836 -40.645316) (xy 5.495898 -40.597781)
			(xy 5.470509 -40.545821) (xy 5.453251 -40.490625) (xy 5.444519 -40.433457) (xy 5.443982 -40.404542)
			(xy 5.444468 -40.377291) (xy 5.452224 -40.323343) (xy 5.467579 -40.271048) (xy 5.490221 -40.221471)
			(xy 5.519687 -40.175621) (xy 5.555378 -40.13443) (xy 5.596569 -40.098739) (xy 5.642419 -40.069273)
			(xy 5.691996 -40.046631) (xy 5.744291 -40.031276) (xy 5.798239 -40.02352) (xy 5.852741 -40.02352)
			(xy 5.906689 -40.031276) (xy 5.958984 -40.046631) (xy 6.008561 -40.069273) (xy 6.054411 -40.098739)
			(xy 6.095602 -40.13443) (xy 6.131293 -40.175621) (xy 6.160759 -40.221471) (xy 6.183401 -40.271048)
			(xy 6.198756 -40.323343) (xy 6.206512 -40.377291) (xy 6.206998 -40.404542) (xy 6.206439 -40.433457)
			(xy 6.197718 -40.490627) (xy 6.180469 -40.545825) (xy 6.155085 -40.597787) (xy 6.122148 -40.645322)
			(xy 6.082414 -40.687341) (xy 6.059932 -40.705532) (xy 6.051109 -40.713123) (xy 6.040937 -40.734036)
			(xy 6.040374 -40.745664) (xy 6.040374 -40.82542) (xy 6.04089 -40.837056) (xy 6.051092 -40.857967)
			(xy 6.059932 -40.865552) (xy 6.082412 -40.883747) (xy 6.122147 -40.925766) (xy 6.155087 -40.9733)
			(xy 6.180476 -41.025261) (xy 6.197733 -41.080457) (xy 6.206463 -41.137626) (xy 6.206998 -41.166542)
			(xy 6.206512 -41.193793) (xy 6.198756 -41.247741) (xy 6.183401 -41.300036) (xy 6.160759 -41.349613)
			(xy 6.131293 -41.395463) (xy 6.095602 -41.436654) (xy 6.054411 -41.472345) (xy 6.008561 -41.501811)
			(xy 5.958984 -41.524453) (xy 5.906689 -41.539808) (xy 5.852741 -41.547564) (xy 5.798239 -41.547564)
			(xy 5.744291 -41.539808) (xy 5.691996 -41.524453) (xy 5.642419 -41.501811) (xy 5.596569 -41.472345)
			(xy 5.555378 -41.436654) (xy 5.519687 -41.395463) (xy 5.490221 -41.349613) (xy 5.467579 -41.300036)
			(xy 5.452224 -41.247741) (xy 5.444468 -41.193793) (xy 5.443982 -41.166542) (xy 3.166872 -41.166542)
			(xy 3.166386 -41.193793) (xy 3.15863 -41.247741) (xy 3.143275 -41.300036) (xy 3.120633 -41.349613)
			(xy 3.091167 -41.395463) (xy 3.055476 -41.436654) (xy 3.014285 -41.472345) (xy 2.968435 -41.501811)
			(xy 2.918858 -41.524453) (xy 2.866563 -41.539808) (xy 2.812615 -41.547564) (xy 2.758113 -41.547564)
			(xy 2.704165 -41.539808) (xy 2.65187 -41.524453) (xy 2.602293 -41.501811) (xy 2.556443 -41.472345)
			(xy 2.515252 -41.436654) (xy 2.479561 -41.395463) (xy 2.450095 -41.349613) (xy 2.427453 -41.300036)
			(xy 2.412098 -41.247741) (xy 2.404342 -41.193793) (xy 2.403856 -41.166542) (xy 1.867916 -41.166542)
			(xy 1.867916 -42.250614) (xy 2.72872 -42.250614) (xy 2.732791 -42.194992) (xy 2.744917 -42.140555)
			(xy 2.76484 -42.088464) (xy 2.792136 -42.039829) (xy 2.826222 -41.995686) (xy 2.866371 -41.956977)
			(xy 2.911729 -41.924526) (xy 2.961329 -41.899025) (xy 3.014113 -41.881018) (xy 3.068956 -41.870888)
			(xy 3.12469 -41.868851) (xy 3.180127 -41.874951) (xy 3.234084 -41.889057) (xy 3.285413 -41.910869)
			(xy 3.333019 -41.939923) (xy 3.375887 -41.975598) (xy 3.413104 -42.017135) (xy 3.443877 -42.063648)
			(xy 3.467549 -42.114145) (xy 3.483617 -42.167552) (xy 3.491737 -42.222728) (xy 3.492246 -42.250614)
			(xy 3.491737 -42.2785) (xy 3.483617 -42.333676) (xy 3.467549 -42.387083) (xy 3.460557 -42.401998)
			(xy 4.015484 -42.401998) (xy 4.019555 -42.346376) (xy 4.031681 -42.291939) (xy 4.051604 -42.239848)
			(xy 4.0789 -42.191213) (xy 4.112986 -42.14707) (xy 4.153135 -42.108361) (xy 4.198493 -42.07591) (xy 4.248093 -42.050409)
			(xy 4.300877 -42.032402) (xy 4.35572 -42.022272) (xy 4.411454 -42.020235) (xy 4.466891 -42.026335)
			(xy 4.520848 -42.040441) (xy 4.572177 -42.062253) (xy 4.619783 -42.091307) (xy 4.662651 -42.126982)
			(xy 4.699868 -42.168519) (xy 4.730641 -42.215032) (xy 4.754313 -42.265529) (xy 4.770381 -42.318936)
			(xy 4.774531 -42.347134) (xy 5.291072 -42.347134) (xy 5.295143 -42.291512) (xy 5.307269 -42.237075)
			(xy 5.327192 -42.184984) (xy 5.354488 -42.136349) (xy 5.388574 -42.092206) (xy 5.428723 -42.053497)
			(xy 5.474081 -42.021046) (xy 5.523681 -41.995545) (xy 5.576465 -41.977538) (xy 5.631308 -41.967408)
			(xy 5.687042 -41.965371) (xy 5.742479 -41.971471) (xy 5.796436 -41.985577) (xy 5.847765 -42.007389)
			(xy 5.895371 -42.036443) (xy 5.938239 -42.072118) (xy 5.975456 -42.113655) (xy 6.006229 -42.160168)
			(xy 6.029901 -42.210665) (xy 6.045969 -42.264072) (xy 6.054089 -42.319248) (xy 6.054598 -42.347134)
			(xy 6.054089 -42.37502) (xy 6.045969 -42.430196) (xy 6.029901 -42.483603) (xy 6.006229 -42.5341)
			(xy 5.975456 -42.580613) (xy 5.938239 -42.62215) (xy 5.895371 -42.657825) (xy 5.847765 -42.686879)
			(xy 5.796436 -42.708691) (xy 5.742479 -42.722797) (xy 5.687042 -42.728897) (xy 5.631308 -42.72686)
			(xy 5.576465 -42.71673) (xy 5.523681 -42.698723) (xy 5.474081 -42.673222) (xy 5.428723 -42.640771)
			(xy 5.388574 -42.602062) (xy 5.354488 -42.557919) (xy 5.327192 -42.509284) (xy 5.307269 -42.457193)
			(xy 5.295143 -42.402756) (xy 5.291072 -42.347134) (xy 4.774531 -42.347134) (xy 4.778501 -42.374112)
			(xy 4.77901 -42.401998) (xy 4.778501 -42.429884) (xy 4.770381 -42.48506) (xy 4.754313 -42.538467)
			(xy 4.730641 -42.588964) (xy 4.699868 -42.635477) (xy 4.662651 -42.677014) (xy 4.619783 -42.712689)
			(xy 4.572177 -42.741743) (xy 4.520848 -42.763555) (xy 4.466891 -42.777661) (xy 4.411454 -42.783761)
			(xy 4.35572 -42.781724) (xy 4.300877 -42.771594) (xy 4.248093 -42.753587) (xy 4.198493 -42.728086)
			(xy 4.153135 -42.695635) (xy 4.112986 -42.656926) (xy 4.0789 -42.612783) (xy 4.051604 -42.564148)
			(xy 4.031681 -42.512057) (xy 4.019555 -42.45762) (xy 4.015484 -42.401998) (xy 3.460557 -42.401998)
			(xy 3.443877 -42.43758) (xy 3.413104 -42.484093) (xy 3.375887 -42.52563) (xy 3.333019 -42.561305)
			(xy 3.285413 -42.590359) (xy 3.234084 -42.612171) (xy 3.180127 -42.626277) (xy 3.12469 -42.632377)
			(xy 3.068956 -42.63034) (xy 3.014113 -42.62021) (xy 2.961329 -42.602203) (xy 2.911729 -42.576702)
			(xy 2.866371 -42.544251) (xy 2.826222 -42.505542) (xy 2.792136 -42.461399) (xy 2.76484 -42.412764)
			(xy 2.744917 -42.360673) (xy 2.732791 -42.306236) (xy 2.72872 -42.250614) (xy 1.867916 -42.250614)
			(xy 1.867916 -44.689522) (xy 3.862068 -44.689522) (xy 3.866139 -44.6339) (xy 3.878265 -44.579463)
			(xy 3.898188 -44.527372) (xy 3.925484 -44.478737) (xy 3.95957 -44.434594) (xy 3.999719 -44.395885)
			(xy 4.045077 -44.363434) (xy 4.094677 -44.337933) (xy 4.147461 -44.319926) (xy 4.202304 -44.309796)
			(xy 4.258038 -44.307759) (xy 4.313475 -44.313859) (xy 4.367432 -44.327965) (xy 4.418761 -44.349777)
			(xy 4.466367 -44.378831) (xy 4.509235 -44.414506) (xy 4.546452 -44.456043) (xy 4.577225 -44.502556)
			(xy 4.600897 -44.553053) (xy 4.616965 -44.60646) (xy 4.625085 -44.661636) (xy 4.625594 -44.689522)
			(xy 4.625085 -44.717408) (xy 4.616965 -44.772584) (xy 4.600897 -44.825991) (xy 4.577225 -44.876488)
			(xy 4.546452 -44.923001) (xy 4.509235 -44.964538) (xy 4.466367 -45.000213) (xy 4.418761 -45.029267)
			(xy 4.367432 -45.051079) (xy 4.313475 -45.065185) (xy 4.258038 -45.071285) (xy 4.202304 -45.069248)
			(xy 4.147461 -45.059118) (xy 4.094677 -45.041111) (xy 4.045077 -45.01561) (xy 3.999719 -44.983159)
			(xy 3.95957 -44.94445) (xy 3.925484 -44.900307) (xy 3.898188 -44.851672) (xy 3.878265 -44.799581)
			(xy 3.866139 -44.745144) (xy 3.862068 -44.689522) (xy 1.867916 -44.689522) (xy 1.867916 -45.071792)
			(xy 6.365492 -45.071792) (xy 6.369563 -45.01617) (xy 6.381689 -44.961733) (xy 6.401612 -44.909642)
			(xy 6.428908 -44.861007) (xy 6.462994 -44.816864) (xy 6.503143 -44.778155) (xy 6.548501 -44.745704)
			(xy 6.598101 -44.720203) (xy 6.650885 -44.702196) (xy 6.705728 -44.692066) (xy 6.761462 -44.690029)
			(xy 6.816899 -44.696129) (xy 6.870856 -44.710235) (xy 6.922185 -44.732047) (xy 6.969791 -44.761101)
			(xy 7.012659 -44.796776) (xy 7.049876 -44.838313) (xy 7.080649 -44.884826) (xy 7.104321 -44.935323)
			(xy 7.120389 -44.98873) (xy 7.128509 -45.043906) (xy 7.129018 -45.071792) (xy 7.128509 -45.099678)
			(xy 7.120389 -45.154854) (xy 7.104321 -45.208261) (xy 7.080649 -45.258758) (xy 7.049876 -45.305271)
			(xy 7.012659 -45.346808) (xy 6.969791 -45.382483) (xy 6.922185 -45.411537) (xy 6.870856 -45.433349)
			(xy 6.816899 -45.447455) (xy 6.761462 -45.453555) (xy 6.705728 -45.451518) (xy 6.650885 -45.441388)
			(xy 6.598101 -45.423381) (xy 6.548501 -45.39788) (xy 6.503143 -45.365429) (xy 6.462994 -45.32672)
			(xy 6.428908 -45.282577) (xy 6.401612 -45.233942) (xy 6.381689 -45.181851) (xy 6.369563 -45.127414)
			(xy 6.365492 -45.071792) (xy 1.867916 -45.071792) (xy 1.867916 -52.555973) (xy 6.583889 -52.555973)
			(xy 6.583889 -52.501467) (xy 6.591646 -52.447517) (xy 6.607002 -52.395219) (xy 6.629645 -52.345639)
			(xy 6.659113 -52.299786) (xy 6.694807 -52.258594) (xy 6.735999 -52.222901) (xy 6.781853 -52.193433)
			(xy 6.831433 -52.170791) (xy 6.88373 -52.155435) (xy 6.937681 -52.147679) (xy 6.964934 -52.147216)
			(xy 6.992305 -52.147658) (xy 7.046485 -52.155481) (xy 7.098989 -52.170976) (xy 7.148735 -52.193823)
			(xy 7.194701 -52.223552) (xy 7.215632 -52.241196) (xy 7.215886 -52.24145) (xy 7.222968 -52.247043)
			(xy 7.239888 -52.253285) (xy 7.248906 -52.253642) (xy 7.315962 -52.253642) (xy 7.324979 -52.253279)
			(xy 7.341896 -52.247037) (xy 7.348982 -52.24145) (xy 7.348982 -52.241196) (xy 7.349236 -52.241196)
			(xy 7.370181 -52.223573) (xy 7.41615 -52.193859) (xy 7.465894 -52.17102) (xy 7.518392 -52.155525)
			(xy 7.572566 -52.147692) (xy 7.599934 -52.147216) (xy 7.627185 -52.147694) (xy 7.681133 -52.155451)
			(xy 7.733428 -52.170807) (xy 7.783005 -52.193448) (xy 7.828856 -52.222915) (xy 7.870046 -52.258607)
			(xy 7.905737 -52.299798) (xy 7.935204 -52.345648) (xy 7.957845 -52.395226) (xy 7.9732 -52.447521)
			(xy 7.980956 -52.501469) (xy 7.980956 -52.555971) (xy 7.9732 -52.609919) (xy 7.957845 -52.662214)
			(xy 7.935204 -52.711792) (xy 7.905737 -52.757642) (xy 7.870046 -52.798833) (xy 7.828856 -52.834525)
			(xy 7.783005 -52.863992) (xy 7.733428 -52.886633) (xy 7.681133 -52.901989) (xy 7.627185 -52.909746)
			(xy 7.599934 -52.910232) (xy 7.572564 -52.909763) (xy 7.518384 -52.901948) (xy 7.46588 -52.886461)
			(xy 7.416133 -52.863619) (xy 7.370167 -52.833894) (xy 7.349236 -52.816252) (xy 7.348982 -52.815998)
			(xy 7.341905 -52.810398) (xy 7.324981 -52.804159) (xy 7.315962 -52.803806) (xy 7.248906 -52.803806)
			(xy 7.239889 -52.804165) (xy 7.222972 -52.810411) (xy 7.215886 -52.815998) (xy 7.215886 -52.816252)
			(xy 7.215632 -52.816252) (xy 7.194693 -52.833882) (xy 7.148723 -52.863597) (xy 7.098977 -52.886435)
			(xy 7.046478 -52.901928) (xy 6.992303 -52.909758) (xy 6.964934 -52.910232) (xy 6.937681 -52.909761)
			(xy 6.88373 -52.902005) (xy 6.831433 -52.886649) (xy 6.781853 -52.864007) (xy 6.735999 -52.834539)
			(xy 6.694807 -52.798846) (xy 6.659113 -52.757654) (xy 6.629645 -52.711801) (xy 6.607002 -52.662221)
			(xy 6.591646 -52.609923) (xy 6.583889 -52.555973) (xy 1.867916 -52.555973) (xy 1.867916 -53.496543)
			(xy 6.133541 -53.496543) (xy 6.133541 -53.442037) (xy 6.141298 -53.388085) (xy 6.156655 -53.335787)
			(xy 6.179298 -53.286206) (xy 6.208766 -53.240352) (xy 6.24446 -53.199159) (xy 6.285654 -53.163465)
			(xy 6.331508 -53.133997) (xy 6.381088 -53.111354) (xy 6.433387 -53.095998) (xy 6.487339 -53.088241)
			(xy 6.514592 -53.087778) (xy 6.541963 -53.08823) (xy 6.596143 -53.096048) (xy 6.648647 -53.111539)
			(xy 6.698394 -53.134385) (xy 6.74436 -53.164114) (xy 6.76529 -53.181758) (xy 6.765544 -53.182012)
			(xy 6.772641 -53.187583) (xy 6.78955 -53.193839) (xy 6.798564 -53.194204) (xy 6.86562 -53.194204)
			(xy 6.874638 -53.193856) (xy 6.891555 -53.187602) (xy 6.89864 -53.182012) (xy 6.89864 -53.181758)
			(xy 6.898894 -53.181758) (xy 6.919812 -53.164101) (xy 6.965789 -53.134393) (xy 7.01554 -53.111561)
			(xy 7.068044 -53.096074) (xy 7.122222 -53.08825) (xy 7.149592 -53.087778) (xy 7.176843 -53.088272)
			(xy 7.23079 -53.096029) (xy 7.283084 -53.111384) (xy 7.33266 -53.134025) (xy 7.37851 -53.163491)
			(xy 7.419699 -53.199182) (xy 7.45539 -53.240372) (xy 7.484856 -53.286222) (xy 7.507497 -53.335798)
			(xy 7.522852 -53.388092) (xy 7.530608 -53.442039) (xy 7.530608 -53.496541) (xy 7.522852 -53.550488)
			(xy 7.507497 -53.602782) (xy 7.484856 -53.652358) (xy 7.45539 -53.698208) (xy 7.419699 -53.739398)
			(xy 7.37851 -53.775089) (xy 7.33266 -53.804555) (xy 7.283084 -53.827196) (xy 7.23079 -53.842551)
			(xy 7.176843 -53.850308) (xy 7.149592 -53.850794) (xy 7.122222 -53.850334) (xy 7.068042 -53.842515)
			(xy 7.015539 -53.827025) (xy 6.965792 -53.804181) (xy 6.919826 -53.774456) (xy 6.898894 -53.756814)
			(xy 6.89864 -53.75656) (xy 6.89155 -53.750979) (xy 6.874636 -53.74473) (xy 6.86562 -53.744368) (xy 6.798564 -53.744368)
			(xy 6.789546 -53.744715) (xy 6.77263 -53.75097) (xy 6.765544 -53.75656) (xy 6.765544 -53.756814)
			(xy 6.76529 -53.756814) (xy 6.744374 -53.774473) (xy 6.698397 -53.804182) (xy 6.648645 -53.827014)
			(xy 6.596141 -53.8425) (xy 6.541962 -53.850323) (xy 6.514592 -53.850794) (xy 6.487339 -53.850339)
			(xy 6.433387 -53.842582) (xy 6.381088 -53.827226) (xy 6.331508 -53.804583) (xy 6.285654 -53.775115)
			(xy 6.24446 -53.739421) (xy 6.208766 -53.698228) (xy 6.179298 -53.652374) (xy 6.156655 -53.602793)
			(xy 6.141298 -53.550495) (xy 6.133541 -53.496543) (xy 1.867916 -53.496543) (xy 1.867916 -54.989041)
			(xy 3.901168 -54.989041) (xy 3.901168 -54.934539) (xy 3.908924 -54.880592) (xy 3.924279 -54.828297)
			(xy 3.94692 -54.77872) (xy 3.976386 -54.73287) (xy 4.012077 -54.69168) (xy 4.053267 -54.655988) (xy 4.099117 -54.626522)
			(xy 4.148693 -54.603881) (xy 4.200988 -54.588525) (xy 4.254935 -54.580768) (xy 4.282186 -54.580282)
			(xy 4.310277 -54.580788) (xy 4.365854 -54.589013) (xy 4.419622 -54.605302) (xy 4.47042 -54.629303)
			(xy 4.517147 -54.660496) (xy 4.558792 -54.698207) (xy 4.594455 -54.741618) (xy 4.609338 -54.765448)
			(xy 4.614672 -54.774338) (xy 4.63169 -54.78653) (xy 4.724908 -54.80685) (xy 4.745482 -54.802532)
			(xy 4.754118 -54.79669) (xy 4.778175 -54.780679) (xy 4.830109 -54.755339) (xy 4.885269 -54.738117)
			(xy 4.942395 -54.729405) (xy 4.971288 -54.728872) (xy 4.998541 -54.729337) (xy 5.052492 -54.737094)
			(xy 5.104789 -54.75245) (xy 5.15437 -54.775092) (xy 5.200223 -54.80456) (xy 5.241415 -54.840253)
			(xy 5.277109 -54.881446) (xy 5.306577 -54.927299) (xy 5.32922 -54.976879) (xy 5.344576 -55.029176)
			(xy 5.352333 -55.083127) (xy 5.352796 -55.11038) (xy 5.352319 -55.13775) (xy 5.344504 -55.191929)
			(xy 5.329018 -55.244432) (xy 5.306178 -55.294179) (xy 5.276456 -55.340146) (xy 5.258816 -55.361078)
			(xy 5.258562 -55.361332) (xy 5.252994 -55.368431) (xy 5.246737 -55.385338) (xy 5.24637 -55.394352)
			(xy 5.24637 -55.461408) (xy 5.24673 -55.470424) (xy 5.252976 -55.487341) (xy 5.258562 -55.494428)
			(xy 5.258816 -55.494428) (xy 5.258816 -55.494682) (xy 5.276457 -55.515615) (xy 5.306181 -55.561583)
			(xy 5.329026 -55.611329) (xy 5.344522 -55.663831) (xy 5.352351 -55.718009) (xy 5.352351 -55.772751)
			(xy 5.344522 -55.826929) (xy 5.329026 -55.879431) (xy 5.306181 -55.929177) (xy 5.276457 -55.975145)
			(xy 5.258816 -55.996078) (xy 5.258562 -55.996332) (xy 5.252994 -56.003431) (xy 5.246737 -56.020338)
			(xy 5.24637 -56.029352) (xy 5.24637 -56.096408) (xy 5.24673 -56.105424) (xy 5.252976 -56.122341)
			(xy 5.258562 -56.129428) (xy 5.258816 -56.129428) (xy 5.258816 -56.129682) (xy 5.276463 -56.150608)
			(xy 5.306173 -56.196583) (xy 5.329007 -56.246332) (xy 5.344496 -56.298834) (xy 5.352323 -56.35301)
			(xy 5.352796 -56.38038) (xy 5.35231 -56.407631) (xy 5.344554 -56.461579) (xy 5.329199 -56.513874)
			(xy 5.306557 -56.563451) (xy 5.277091 -56.609301) (xy 5.2414 -56.650492) (xy 5.200209 -56.686183)
			(xy 5.154359 -56.715649) (xy 5.104782 -56.738291) (xy 5.052487 -56.753646) (xy 4.998539 -56.761402)
			(xy 4.944037 -56.761402) (xy 4.890089 -56.753646) (xy 4.837794 -56.738291) (xy 4.788217 -56.715649)
			(xy 4.742367 -56.686183) (xy 4.701176 -56.650492) (xy 4.665485 -56.609301) (xy 4.636019 -56.563451)
			(xy 4.613377 -56.513874) (xy 4.598022 -56.461579) (xy 4.590266 -56.407631) (xy 4.58978 -56.38038)
			(xy 4.590215 -56.353008) (xy 4.598037 -56.298827) (xy 4.613533 -56.246323) (xy 4.636382 -56.196577)
			(xy 4.666114 -56.150612) (xy 4.68376 -56.129682) (xy 4.684014 -56.129428) (xy 4.689597 -56.122339)
			(xy 4.695845 -56.105424) (xy 4.696206 -56.096408) (xy 4.696206 -56.029352) (xy 4.695823 -56.020338)
			(xy 4.689593 -56.003421) (xy 4.684014 -55.996332) (xy 4.68376 -55.996332) (xy 4.68376 -55.996078)
			(xy 4.666119 -55.975145) (xy 4.636394 -55.929178) (xy 4.613549 -55.879431) (xy 4.598052 -55.826929)
			(xy 4.590224 -55.772751) (xy 4.590224 -55.718009) (xy 4.598052 -55.663831) (xy 4.613549 -55.611329)
			(xy 4.636394 -55.561582) (xy 4.666119 -55.515615) (xy 4.68376 -55.494682) (xy 4.684014 -55.494428)
			(xy 4.689597 -55.487339) (xy 4.695845 -55.470424) (xy 4.696206 -55.461408) (xy 4.696206 -55.394352)
			(xy 4.695823 -55.385338) (xy 4.689593 -55.368421) (xy 4.684014 -55.361332) (xy 4.68376 -55.360824)
			(xy 4.672814 -55.348091) (xy 4.652974 -55.320999) (xy 4.644136 -55.306722) (xy 4.638802 -55.297832)
			(xy 4.621784 -55.28564) (xy 4.528566 -55.26532) (xy 4.507992 -55.269638) (xy 4.499356 -55.27548)
			(xy 4.475304 -55.291499) (xy 4.423368 -55.316838) (xy 4.368207 -55.334058) (xy 4.31108 -55.342767)
			(xy 4.282186 -55.343298) (xy 4.254935 -55.342812) (xy 4.200988 -55.335055) (xy 4.148693 -55.319699)
			(xy 4.099117 -55.297058) (xy 4.053267 -55.267592) (xy 4.012077 -55.2319) (xy 3.976386 -55.19071)
			(xy 3.94692 -55.14486) (xy 3.924279 -55.095283) (xy 3.908924 -55.042988) (xy 3.901168 -54.989041)
			(xy 1.867916 -54.989041) (xy 1.867916 -55.420841) (xy 2.224768 -55.420841) (xy 2.224768 -55.366339)
			(xy 2.232524 -55.312392) (xy 2.247879 -55.260097) (xy 2.27052 -55.21052) (xy 2.299986 -55.16467)
			(xy 2.335677 -55.12348) (xy 2.376867 -55.087788) (xy 2.422717 -55.058322) (xy 2.472293 -55.035681)
			(xy 2.524588 -55.020325) (xy 2.578535 -55.012568) (xy 2.605786 -55.012082) (xy 2.632099 -55.012565)
			(xy 2.684227 -55.019797) (xy 2.734869 -55.034114) (xy 2.783068 -55.055243) (xy 2.827912 -55.082786)
			(xy 2.868553 -55.116222) (xy 2.88671 -55.135272) (xy 2.89423 -55.142676) (xy 2.913511 -55.1512) (xy 2.924048 -55.151782)
			(xy 2.998724 -55.151782) (xy 3.009271 -55.151231) (xy 3.028567 -55.142712) (xy 3.036062 -55.135272)
			(xy 3.054189 -55.116188) (xy 3.094825 -55.082735) (xy 3.139672 -55.05518) (xy 3.187878 -55.034047)
			(xy 3.23853 -55.019735) (xy 3.290668 -55.012517) (xy 3.316986 -55.012082) (xy 3.344239 -55.012545)
			(xy 3.39819 -55.020302) (xy 3.450489 -55.035657) (xy 3.500069 -55.0583) (xy 3.545923 -55.087767)
			(xy 3.587116 -55.123461) (xy 3.62281 -55.164654) (xy 3.652279 -55.210507) (xy 3.674921 -55.260088)
			(xy 3.690278 -55.312386) (xy 3.698035 -55.366337) (xy 3.698035 -55.420843) (xy 3.690278 -55.474794)
			(xy 3.674921 -55.527092) (xy 3.652279 -55.576673) (xy 3.62281 -55.622526) (xy 3.587116 -55.663719)
			(xy 3.545923 -55.699413) (xy 3.500069 -55.72888) (xy 3.450489 -55.751523) (xy 3.39819 -55.766878)
			(xy 3.344239 -55.774635) (xy 3.316986 -55.775098) (xy 3.290672 -55.774641) (xy 3.238543 -55.767404)
			(xy 3.1879 -55.753083) (xy 3.139701 -55.731948) (xy 3.094858 -55.704401) (xy 3.054218 -55.67096)
			(xy 3.036062 -55.651908) (xy 3.028555 -55.644489) (xy 3.009264 -55.635974) (xy 2.998724 -55.635398)
			(xy 2.924048 -55.635398) (xy 2.9135 -55.63594) (xy 2.894204 -55.644466) (xy 2.88671 -55.651908) (xy 2.868544 -55.670953)
			(xy 2.827916 -55.704411) (xy 2.783078 -55.731971) (xy 2.73488 -55.753111) (xy 2.684234 -55.767431)
			(xy 2.632102 -55.774658) (xy 2.605786 -55.775098) (xy 2.578535 -55.774612) (xy 2.524588 -55.766855)
			(xy 2.472293 -55.751499) (xy 2.422717 -55.728858) (xy 2.376867 -55.699392) (xy 2.335677 -55.6637)
			(xy 2.299986 -55.62251) (xy 2.27052 -55.57666) (xy 2.247879 -55.527083) (xy 2.232524 -55.474788)
			(xy 2.224768 -55.420841) (xy 1.867916 -55.420841) (xy 1.867916 -57.48528) (xy 4.606034 -57.48528)
			(xy 4.610105 -57.429658) (xy 4.622231 -57.375221) (xy 4.642154 -57.32313) (xy 4.66945 -57.274495)
			(xy 4.703536 -57.230352) (xy 4.743685 -57.191643) (xy 4.789043 -57.159192) (xy 4.838643 -57.133691)
			(xy 4.891427 -57.115684) (xy 4.94627 -57.105554) (xy 5.002004 -57.103517) (xy 5.057441 -57.109617)
			(xy 5.111398 -57.123723) (xy 5.162727 -57.145535) (xy 5.210333 -57.174589) (xy 5.253201 -57.210264)
			(xy 5.290418 -57.251801) (xy 5.321191 -57.298314) (xy 5.344863 -57.348811) (xy 5.360931 -57.402218)
			(xy 5.369051 -57.457394) (xy 5.36956 -57.48528) (xy 5.369051 -57.513166) (xy 5.360931 -57.568342)
			(xy 5.344863 -57.621749) (xy 5.321191 -57.672246) (xy 5.290418 -57.718759) (xy 5.253201 -57.760296)
			(xy 5.210333 -57.795971) (xy 5.162727 -57.825025) (xy 5.111398 -57.846837) (xy 5.057441 -57.860943)
			(xy 5.002004 -57.867043) (xy 4.94627 -57.865006) (xy 4.891427 -57.854876) (xy 4.838643 -57.836869)
			(xy 4.789043 -57.811368) (xy 4.743685 -57.778917) (xy 4.703536 -57.740208) (xy 4.66945 -57.696065)
			(xy 4.642154 -57.64743) (xy 4.622231 -57.595339) (xy 4.610105 -57.540902) (xy 4.606034 -57.48528)
			(xy 1.867916 -57.48528) (xy 1.867916 -58.076084) (xy 5.358128 -58.076084) (xy 5.362199 -58.020462)
			(xy 5.374325 -57.966025) (xy 5.394248 -57.913934) (xy 5.421544 -57.865299) (xy 5.45563 -57.821156)
			(xy 5.495779 -57.782447) (xy 5.541137 -57.749996) (xy 5.590737 -57.724495) (xy 5.643521 -57.706488)
			(xy 5.698364 -57.696358) (xy 5.754098 -57.694321) (xy 5.809535 -57.700421) (xy 5.863492 -57.714527)
			(xy 5.914821 -57.736339) (xy 5.962427 -57.765393) (xy 6.005295 -57.801068) (xy 6.042512 -57.842605)
			(xy 6.058848 -57.867296) (xy 7.643112 -57.867296) (xy 7.647183 -57.811674) (xy 7.659309 -57.757237)
			(xy 7.679232 -57.705146) (xy 7.706528 -57.656511) (xy 7.740614 -57.612368) (xy 7.780763 -57.573659)
			(xy 7.826121 -57.541208) (xy 7.875721 -57.515707) (xy 7.928505 -57.4977) (xy 7.983348 -57.48757)
			(xy 8.039082 -57.485533) (xy 8.094519 -57.491633) (xy 8.148476 -57.505739) (xy 8.199805 -57.527551)
			(xy 8.247411 -57.556605) (xy 8.290279 -57.59228) (xy 8.327496 -57.633817) (xy 8.358269 -57.68033)
			(xy 8.381941 -57.730827) (xy 8.398009 -57.784234) (xy 8.406129 -57.83941) (xy 8.406638 -57.867296)
			(xy 8.406129 -57.895182) (xy 8.398009 -57.950358) (xy 8.381941 -58.003765) (xy 8.358269 -58.054262)
			(xy 8.327496 -58.100775) (xy 8.290279 -58.142312) (xy 8.247411 -58.177987) (xy 8.199805 -58.207041)
			(xy 8.148476 -58.228853) (xy 8.094519 -58.242959) (xy 8.039082 -58.249059) (xy 7.983348 -58.247022)
			(xy 7.928505 -58.236892) (xy 7.875721 -58.218885) (xy 7.826121 -58.193384) (xy 7.780763 -58.160933)
			(xy 7.740614 -58.122224) (xy 7.706528 -58.078081) (xy 7.679232 -58.029446) (xy 7.659309 -57.977355)
			(xy 7.647183 -57.922918) (xy 7.643112 -57.867296) (xy 6.058848 -57.867296) (xy 6.073285 -57.889118)
			(xy 6.096957 -57.939615) (xy 6.113025 -57.993022) (xy 6.121145 -58.048198) (xy 6.121654 -58.076084)
			(xy 6.121145 -58.10397) (xy 6.113025 -58.159146) (xy 6.096957 -58.212553) (xy 6.073285 -58.26305)
			(xy 6.042512 -58.309563) (xy 6.005295 -58.3511) (xy 5.962427 -58.386775) (xy 5.914821 -58.415829)
			(xy 5.863492 -58.437641) (xy 5.809535 -58.451747) (xy 5.754098 -58.457847) (xy 5.698364 -58.45581)
			(xy 5.643521 -58.44568) (xy 5.590737 -58.427673) (xy 5.541137 -58.402172) (xy 5.495779 -58.369721)
			(xy 5.45563 -58.331012) (xy 5.421544 -58.286869) (xy 5.394248 -58.238234) (xy 5.374325 -58.186143)
			(xy 5.362199 -58.131706) (xy 5.358128 -58.076084) (xy 1.867916 -58.076084) (xy 1.867916 -58.561224)
			(xy 6.562342 -58.561224) (xy 6.566413 -58.505602) (xy 6.578539 -58.451165) (xy 6.598462 -58.399074)
			(xy 6.625758 -58.350439) (xy 6.659844 -58.306296) (xy 6.699993 -58.267587) (xy 6.745351 -58.235136)
			(xy 6.794951 -58.209635) (xy 6.847735 -58.191628) (xy 6.902578 -58.181498) (xy 6.958312 -58.179461)
			(xy 7.013749 -58.185561) (xy 7.067706 -58.199667) (xy 7.119035 -58.221479) (xy 7.166641 -58.250533)
			(xy 7.209509 -58.286208) (xy 7.246726 -58.327745) (xy 7.277499 -58.374258) (xy 7.301171 -58.424755)
			(xy 7.317239 -58.478162) (xy 7.325359 -58.533338) (xy 7.325868 -58.561224) (xy 7.325359 -58.58911)
			(xy 7.317239 -58.644286) (xy 7.301171 -58.697693) (xy 7.277499 -58.74819) (xy 7.246726 -58.794703)
			(xy 7.209509 -58.83624) (xy 7.166641 -58.871915) (xy 7.119035 -58.900969) (xy 7.067706 -58.922781)
			(xy 7.013749 -58.936887) (xy 6.958312 -58.942987) (xy 6.902578 -58.94095) (xy 6.847735 -58.93082)
			(xy 6.794951 -58.912813) (xy 6.745351 -58.887312) (xy 6.699993 -58.854861) (xy 6.659844 -58.816152)
			(xy 6.625758 -58.772009) (xy 6.598462 -58.723374) (xy 6.578539 -58.671283) (xy 6.566413 -58.616846)
			(xy 6.562342 -58.561224) (xy 1.867916 -58.561224) (xy 1.867916 -59.174634) (xy 5.093206 -59.174634)
			(xy 5.097277 -59.119012) (xy 5.109403 -59.064575) (xy 5.129326 -59.012484) (xy 5.156622 -58.963849)
			(xy 5.190708 -58.919706) (xy 5.230857 -58.880997) (xy 5.276215 -58.848546) (xy 5.325815 -58.823045)
			(xy 5.378599 -58.805038) (xy 5.433442 -58.794908) (xy 5.489176 -58.792871) (xy 5.544613 -58.798971)
			(xy 5.59857 -58.813077) (xy 5.649899 -58.834889) (xy 5.697505 -58.863943) (xy 5.740373 -58.899618)
			(xy 5.77759 -58.941155) (xy 5.808363 -58.987668) (xy 5.832035 -59.038165) (xy 5.848103 -59.091572)
			(xy 5.856223 -59.146748) (xy 5.856732 -59.174634) (xy 5.856223 -59.20252) (xy 5.848103 -59.257696)
			(xy 5.832035 -59.311103) (xy 5.808363 -59.3616) (xy 5.77759 -59.408113) (xy 5.740373 -59.44965) (xy 5.697505 -59.485325)
			(xy 5.649899 -59.514379) (xy 5.59857 -59.536191) (xy 5.544613 -59.550297) (xy 5.489176 -59.556397)
			(xy 5.433442 -59.55436) (xy 5.378599 -59.54423) (xy 5.325815 -59.526223) (xy 5.276215 -59.500722)
			(xy 5.230857 -59.468271) (xy 5.190708 -59.429562) (xy 5.156622 -59.385419) (xy 5.129326 -59.336784)
			(xy 5.109403 -59.284693) (xy 5.097277 -59.230256) (xy 5.093206 -59.174634) (xy 1.867916 -59.174634)
			(xy 1.867916 -60.781946) (xy 5.674358 -60.781946) (xy 5.678429 -60.726324) (xy 5.690555 -60.671887)
			(xy 5.710478 -60.619796) (xy 5.737774 -60.571161) (xy 5.77186 -60.527018) (xy 5.812009 -60.488309)
			(xy 5.857367 -60.455858) (xy 5.906967 -60.430357) (xy 5.959751 -60.41235) (xy 6.014594 -60.40222)
			(xy 6.070328 -60.400183) (xy 6.125765 -60.406283) (xy 6.179722 -60.420389) (xy 6.231051 -60.442201)
			(xy 6.278657 -60.471255) (xy 6.321525 -60.50693) (xy 6.358742 -60.548467) (xy 6.389515 -60.59498)
			(xy 6.407505 -60.633356) (xy 7.797036 -60.633356) (xy 7.801107 -60.577734) (xy 7.813233 -60.523297)
			(xy 7.833156 -60.471206) (xy 7.860452 -60.422571) (xy 7.894538 -60.378428) (xy 7.934687 -60.339719)
			(xy 7.980045 -60.307268) (xy 8.029645 -60.281767) (xy 8.082429 -60.26376) (xy 8.137272 -60.25363)
			(xy 8.193006 -60.251593) (xy 8.248443 -60.257693) (xy 8.3024 -60.271799) (xy 8.353729 -60.293611)
			(xy 8.401335 -60.322665) (xy 8.444203 -60.35834) (xy 8.48142 -60.399877) (xy 8.512193 -60.44639)
			(xy 8.535865 -60.496887) (xy 8.551933 -60.550294) (xy 8.560053 -60.60547) (xy 8.560562 -60.633356)
			(xy 8.560053 -60.661242) (xy 8.551933 -60.716418) (xy 8.535865 -60.769825) (xy 8.512193 -60.820322)
			(xy 8.48142 -60.866835) (xy 8.444203 -60.908372) (xy 8.401335 -60.944047) (xy 8.353729 -60.973101)
			(xy 8.3024 -60.994913) (xy 8.248443 -61.009019) (xy 8.193006 -61.015119) (xy 8.137272 -61.013082)
			(xy 8.082429 -61.002952) (xy 8.029645 -60.984945) (xy 7.980045 -60.959444) (xy 7.934687 -60.926993)
			(xy 7.894538 -60.888284) (xy 7.860452 -60.844141) (xy 7.833156 -60.795506) (xy 7.813233 -60.743415)
			(xy 7.801107 -60.688978) (xy 7.797036 -60.633356) (xy 6.407505 -60.633356) (xy 6.413187 -60.645477)
			(xy 6.429255 -60.698884) (xy 6.437375 -60.75406) (xy 6.437884 -60.781946) (xy 6.437375 -60.809832)
			(xy 6.429255 -60.865008) (xy 6.413187 -60.918415) (xy 6.389515 -60.968912) (xy 6.358742 -61.015425)
			(xy 6.321525 -61.056962) (xy 6.278657 -61.092637) (xy 6.231051 -61.121691) (xy 6.179722 -61.143503)
			(xy 6.125765 -61.157609) (xy 6.070328 -61.163709) (xy 6.014594 -61.161672) (xy 5.959751 -61.151542)
			(xy 5.906967 -61.133535) (xy 5.857367 -61.108034) (xy 5.812009 -61.075583) (xy 5.77186 -61.036874)
			(xy 5.737774 -60.992731) (xy 5.710478 -60.944096) (xy 5.690555 -60.892005) (xy 5.678429 -60.837568)
			(xy 5.674358 -60.781946) (xy 1.867916 -60.781946) (xy 1.867916 -62.121034) (xy 4.242306 -62.121034)
			(xy 4.246377 -62.065412) (xy 4.258503 -62.010975) (xy 4.278426 -61.958884) (xy 4.305722 -61.910249)
			(xy 4.339808 -61.866106) (xy 4.379957 -61.827397) (xy 4.425315 -61.794946) (xy 4.474915 -61.769445)
			(xy 4.527699 -61.751438) (xy 4.582542 -61.741308) (xy 4.638276 -61.739271) (xy 4.693713 -61.745371)
			(xy 4.74767 -61.759477) (xy 4.798999 -61.781289) (xy 4.846605 -61.810343) (xy 4.889473 -61.846018)
			(xy 4.92669 -61.887555) (xy 4.957463 -61.934068) (xy 4.981135 -61.984565) (xy 4.997203 -62.037972)
			(xy 5.005323 -62.093148) (xy 5.005832 -62.121034) (xy 5.005323 -62.14892) (xy 4.997203 -62.204096)
			(xy 4.981135 -62.257503) (xy 4.957463 -62.308) (xy 4.92669 -62.354513) (xy 4.889473 -62.39605) (xy 4.846605 -62.431725)
			(xy 4.798999 -62.460779) (xy 4.74767 -62.482591) (xy 4.693713 -62.496697) (xy 4.638276 -62.502797)
			(xy 4.582542 -62.50076) (xy 4.527699 -62.49063) (xy 4.474915 -62.472623) (xy 4.425315 -62.447122)
			(xy 4.379957 -62.414671) (xy 4.339808 -62.375962) (xy 4.305722 -62.331819) (xy 4.278426 -62.283184)
			(xy 4.258503 -62.231093) (xy 4.246377 -62.176656) (xy 4.242306 -62.121034) (xy 1.867916 -62.121034)
			(xy 1.867916 -62.733236) (xy 7.66615 -62.733236) (xy 7.666153 -62.678729) (xy 7.673912 -62.624777)
			(xy 7.689272 -62.572478) (xy 7.711917 -62.522898) (xy 7.741389 -62.477045) (xy 7.777086 -62.435854)
			(xy 7.818282 -62.400161) (xy 7.864138 -62.370696) (xy 7.913721 -62.348056) (xy 7.966021 -62.332703)
			(xy 8.019974 -62.324949) (xy 8.047228 -62.324488) (xy 8.070783 -62.324863) (xy 8.117527 -62.330723)
			(xy 8.140446 -62.336172) (xy 8.154202 -62.33921) (xy 8.182352 -62.338354) (xy 8.209199 -62.329848)
			(xy 8.232706 -62.314337) (xy 8.251087 -62.292999) (xy 8.262946 -62.267454) (xy 8.267383 -62.239643)
			(xy 8.264061 -62.211677) (xy 8.259064 -62.198504) (xy 8.249754 -62.175114) (xy 8.236628 -62.126514)
			(xy 8.230005 -62.076609) (xy 8.2296 -62.051438) (xy 8.230067 -62.024185) (xy 8.237825 -61.970235)
			(xy 8.253181 -61.917937) (xy 8.275824 -61.868357) (xy 8.305292 -61.822505) (xy 8.340985 -61.781312)
			(xy 8.382178 -61.745619) (xy 8.428031 -61.716152) (xy 8.477611 -61.69351) (xy 8.529909 -61.678154)
			(xy 8.583859 -61.670397) (xy 8.638365 -61.670397) (xy 8.692315 -61.678155) (xy 8.744613 -61.693511)
			(xy 8.794193 -61.716154) (xy 8.840045 -61.745622) (xy 8.881238 -61.781315) (xy 8.916931 -61.822508)
			(xy 8.946398 -61.868361) (xy 8.96904 -61.917941) (xy 8.984396 -61.970239) (xy 8.992153 -62.024189)
			(xy 8.992153 -62.078695) (xy 8.984395 -62.132645) (xy 8.969039 -62.184943) (xy 8.946396 -62.234523)
			(xy 8.916928 -62.280375) (xy 8.881235 -62.321568) (xy 8.840042 -62.357261) (xy 8.794189 -62.386728)
			(xy 8.744609 -62.40937) (xy 8.692311 -62.424726) (xy 8.638361 -62.432483) (xy 8.611108 -62.432946)
			(xy 8.587554 -62.432564) (xy 8.540809 -62.426708) (xy 8.51789 -62.421262) (xy 8.504134 -62.418214)
			(xy 8.475978 -62.419062) (xy 8.449124 -62.427564) (xy 8.425611 -62.443076) (xy 8.407227 -62.464418)
			(xy 8.395369 -62.489969) (xy 8.390937 -62.517786) (xy 8.394269 -62.545757) (xy 8.399272 -62.55893)
			(xy 8.408595 -62.582315) (xy 8.421715 -62.630918) (xy 8.428333 -62.680824) (xy 8.428736 -62.705996)
			(xy 8.428249 -62.73325) (xy 8.420492 -62.787202) (xy 8.405136 -62.839502) (xy 8.382493 -62.889083)
			(xy 8.353024 -62.934938) (xy 8.317329 -62.976131) (xy 8.276135 -63.011826) (xy 8.230281 -63.041294)
			(xy 8.180699 -63.063937) (xy 8.1284 -63.079293) (xy 8.074447 -63.087049) (xy 8.01994 -63.087048)
			(xy 7.965987 -63.07929) (xy 7.913688 -63.063932) (xy 7.864108 -63.041288) (xy 7.818254 -63.011818)
			(xy 7.777061 -62.976122) (xy 7.741368 -62.934927) (xy 7.711901 -62.889071) (xy 7.689259 -62.839489)
			(xy 7.673905 -62.787189) (xy 7.66615 -62.733236) (xy 1.867916 -62.733236) (xy 1.867916 -63.273432)
			(xy 3.576826 -63.273432) (xy 3.580897 -63.21781) (xy 3.593023 -63.163373) (xy 3.612946 -63.111282)
			(xy 3.640242 -63.062647) (xy 3.674328 -63.018504) (xy 3.714477 -62.979795) (xy 3.759835 -62.947344)
			(xy 3.809435 -62.921843) (xy 3.862219 -62.903836) (xy 3.917062 -62.893706) (xy 3.972796 -62.891669)
			(xy 4.028233 -62.897769) (xy 4.08219 -62.911875) (xy 4.133519 -62.933687) (xy 4.181125 -62.962741)
			(xy 4.223993 -62.998416) (xy 4.26121 -63.039953) (xy 4.291983 -63.086466) (xy 4.315655 -63.136963)
			(xy 4.331723 -63.19037) (xy 4.339843 -63.245546) (xy 4.340352 -63.273432) (xy 4.339843 -63.301318)
			(xy 4.331723 -63.356494) (xy 4.315655 -63.409901) (xy 4.291983 -63.460398) (xy 4.26121 -63.506911)
			(xy 4.223993 -63.548448) (xy 4.181125 -63.584123) (xy 4.133519 -63.613177) (xy 4.08219 -63.634989)
			(xy 4.028233 -63.649095) (xy 3.972796 -63.655195) (xy 3.917062 -63.653158) (xy 3.862219 -63.643028)
			(xy 3.809435 -63.625021) (xy 3.759835 -63.59952) (xy 3.714477 -63.567069) (xy 3.674328 -63.52836)
			(xy 3.640242 -63.484217) (xy 3.612946 -63.435582) (xy 3.593023 -63.383491) (xy 3.580897 -63.329054)
			(xy 3.576826 -63.273432) (xy 1.867916 -63.273432) (xy 1.867916 -64.365886) (xy 1.868294 -64.374989)
			(xy 1.874681 -64.392037) (xy 1.880362 -64.39916) (xy 1.88849 -64.40678) (xy 1.895856 -64.411098)
			(xy 1.956308 -64.439292) (xy 1.96469 -64.444372) (xy 1.973072 -64.450722) (xy 1.99263 -64.455548)
			(xy 2.003552 -64.454024) (xy 2.012696 -64.451484) (xy 2.01295 -64.451484) (xy 2.034286 -64.443864)
			(xy 2.04089 -64.43853) (xy 2.061208 -64.422926) (xy 2.105228 -64.396721) (xy 2.152356 -64.376635)
			(xy 2.201746 -64.363028) (xy 2.252511 -64.356144) (xy 2.278126 -64.355726) (xy 2.27838 -64.355726)
			(xy 2.306117 -64.356229) (xy 2.361004 -64.364271) (xy 2.414149 -64.380174) (xy 2.464432 -64.403604)
			(xy 2.510793 -64.434065) (xy 2.552257 -64.470918) (xy 2.587948 -64.513384) (xy 2.617116 -64.56057)
			(xy 2.639146 -64.611482) (xy 2.653573 -64.665046) (xy 2.657348 -64.69253) (xy 2.658872 -64.706246)
			(xy 2.660569 -64.732756) (xy 2.657495 -64.785788) (xy 2.647099 -64.837882) (xy 2.629582 -64.888031)
			(xy 2.605283 -64.935269) (xy 2.574671 -64.978682) (xy 2.538336 -65.017433) (xy 2.496981 -65.050773)
			(xy 2.451403 -65.078059) (xy 2.402483 -65.098763) (xy 2.351166 -65.112486) (xy 2.324862 -65.116202)
			(xy 2.308606 -65.117726) (xy 2.27838 -65.118996) (xy 2.278126 -65.118996) (xy 2.252417 -65.118577)
			(xy 2.201463 -65.111674) (xy 2.151899 -65.097989) (xy 2.104622 -65.077772) (xy 2.060489 -65.051387)
			(xy 2.040128 -65.035684) (xy 2.033524 -65.03035) (xy 2.010664 -65.021968) (xy 2.00157 -65.020003)
			(xy 1.983084 -65.021966) (xy 1.974596 -65.025778) (xy 1.974342 -65.025778) (xy 1.955546 -65.03543)
			(xy 1.955038 -65.03543) (xy 1.913128 -65.055496) (xy 1.91262 -65.055496) (xy 1.895856 -65.06337)
			(xy 1.890805 -65.066094) (xy 1.88196 -65.073403) (xy 1.87833 -65.077848) (xy 1.87071 -65.088008)
			(xy 1.868678 -65.100454) (xy 1.867916 -65.105026) (xy 1.867916 -65.124076) (xy 6.107428 -65.124076)
			(xy 6.111499 -65.068454) (xy 6.123625 -65.014017) (xy 6.143548 -64.961926) (xy 6.170844 -64.913291)
			(xy 6.20493 -64.869148) (xy 6.245079 -64.830439) (xy 6.290437 -64.797988) (xy 6.340037 -64.772487)
			(xy 6.392821 -64.75448) (xy 6.447664 -64.74435) (xy 6.503398 -64.742313) (xy 6.558835 -64.748413)
			(xy 6.612792 -64.762519) (xy 6.664121 -64.784331) (xy 6.711727 -64.813385) (xy 6.754595 -64.84906)
			(xy 6.791812 -64.890597) (xy 6.822585 -64.93711) (xy 6.846257 -64.987607) (xy 6.862325 -65.041014)
			(xy 6.870445 -65.09619) (xy 6.870954 -65.124076) (xy 6.870445 -65.151962) (xy 6.862325 -65.207138)
			(xy 6.846257 -65.260545) (xy 6.822585 -65.311042) (xy 6.791812 -65.357555) (xy 6.754595 -65.399092)
			(xy 6.711727 -65.434767) (xy 6.664121 -65.463821) (xy 6.612792 -65.485633) (xy 6.558835 -65.499739)
			(xy 6.503398 -65.505839) (xy 6.447664 -65.503802) (xy 6.392821 -65.493672) (xy 6.340037 -65.475665)
			(xy 6.290437 -65.450164) (xy 6.245079 -65.417713) (xy 6.20493 -65.379004) (xy 6.170844 -65.334861)
			(xy 6.143548 -65.286226) (xy 6.123625 -65.234135) (xy 6.111499 -65.179698) (xy 6.107428 -65.124076)
			(xy 1.867916 -65.124076) (xy 1.867916 -65.882774) (xy 3.101592 -65.882774) (xy 3.105663 -65.827152)
			(xy 3.117789 -65.772715) (xy 3.137712 -65.720624) (xy 3.165008 -65.671989) (xy 3.199094 -65.627846)
			(xy 3.239243 -65.589137) (xy 3.284601 -65.556686) (xy 3.334201 -65.531185) (xy 3.386985 -65.513178)
			(xy 3.441828 -65.503048) (xy 3.497562 -65.501011) (xy 3.552999 -65.507111) (xy 3.606956 -65.521217)
			(xy 3.658285 -65.543029) (xy 3.705891 -65.572083) (xy 3.748759 -65.607758) (xy 3.785976 -65.649295)
			(xy 3.816749 -65.695808) (xy 3.840421 -65.746305) (xy 3.856489 -65.799712) (xy 3.864609 -65.854888)
			(xy 3.865118 -65.882774) (xy 3.864609 -65.91066) (xy 3.856489 -65.965836) (xy 3.840421 -66.019243)
			(xy 3.816749 -66.06974) (xy 3.785976 -66.116253) (xy 3.748759 -66.15779) (xy 3.705891 -66.193465)
			(xy 3.658285 -66.222519) (xy 3.606956 -66.244331) (xy 3.552999 -66.258437) (xy 3.497562 -66.264537)
			(xy 3.441828 -66.2625) (xy 3.386985 -66.25237) (xy 3.334201 -66.234363) (xy 3.284601 -66.208862)
			(xy 3.239243 -66.176411) (xy 3.199094 -66.137702) (xy 3.165008 -66.093559) (xy 3.137712 -66.044924)
			(xy 3.117789 -65.992833) (xy 3.105663 -65.938396) (xy 3.101592 -65.882774) (xy 1.867916 -65.882774)
			(xy 1.867916 -66.567812) (xy 6.304532 -66.567812) (xy 6.308603 -66.51219) (xy 6.320729 -66.457753)
			(xy 6.340652 -66.405662) (xy 6.367948 -66.357027) (xy 6.402034 -66.312884) (xy 6.442183 -66.274175)
			(xy 6.487541 -66.241724) (xy 6.537141 -66.216223) (xy 6.589925 -66.198216) (xy 6.644768 -66.188086)
			(xy 6.700502 -66.186049) (xy 6.755939 -66.192149) (xy 6.809896 -66.206255) (xy 6.861225 -66.228067)
			(xy 6.908831 -66.257121) (xy 6.951699 -66.292796) (xy 6.988916 -66.334333) (xy 7.019689 -66.380846)
			(xy 7.043361 -66.431343) (xy 7.059429 -66.48475) (xy 7.067549 -66.539926) (xy 7.068058 -66.567812)
			(xy 7.067549 -66.595698) (xy 7.059429 -66.650874) (xy 7.043361 -66.704281) (xy 7.019689 -66.754778)
			(xy 6.988916 -66.801291) (xy 6.951699 -66.842828) (xy 6.908831 -66.878503) (xy 6.861225 -66.907557)
			(xy 6.809896 -66.929369) (xy 6.755939 -66.943475) (xy 6.700502 -66.949575) (xy 6.644768 -66.947538)
			(xy 6.589925 -66.937408) (xy 6.537141 -66.919401) (xy 6.487541 -66.8939) (xy 6.442183 -66.861449)
			(xy 6.402034 -66.82274) (xy 6.367948 -66.778597) (xy 6.340652 -66.729962) (xy 6.320729 -66.677871)
			(xy 6.308603 -66.623434) (xy 6.304532 -66.567812) (xy 1.867916 -66.567812) (xy 1.867916 -67.201034)
			(xy 4.242306 -67.201034) (xy 4.246377 -67.145412) (xy 4.258503 -67.090975) (xy 4.278426 -67.038884)
			(xy 4.305722 -66.990249) (xy 4.339808 -66.946106) (xy 4.379957 -66.907397) (xy 4.425315 -66.874946)
			(xy 4.474915 -66.849445) (xy 4.527699 -66.831438) (xy 4.582542 -66.821308) (xy 4.638276 -66.819271)
			(xy 4.693713 -66.825371) (xy 4.74767 -66.839477) (xy 4.798999 -66.861289) (xy 4.846605 -66.890343)
			(xy 4.889473 -66.926018) (xy 4.92669 -66.967555) (xy 4.957463 -67.014068) (xy 4.981135 -67.064565)
			(xy 4.997203 -67.117972) (xy 5.005323 -67.173148) (xy 5.005832 -67.201034) (xy 5.005323 -67.22892)
			(xy 4.997203 -67.284096) (xy 4.981135 -67.337503) (xy 4.957463 -67.388) (xy 4.92669 -67.434513) (xy 4.889473 -67.47605)
			(xy 4.846605 -67.511725) (xy 4.798999 -67.540779) (xy 4.74767 -67.562591) (xy 4.693713 -67.576697)
			(xy 4.638276 -67.582797) (xy 4.582542 -67.58076) (xy 4.527699 -67.57063) (xy 4.474915 -67.552623)
			(xy 4.425315 -67.527122) (xy 4.379957 -67.494671) (xy 4.339808 -67.455962) (xy 4.305722 -67.411819)
			(xy 4.278426 -67.363184) (xy 4.258503 -67.311093) (xy 4.246377 -67.256656) (xy 4.242306 -67.201034)
			(xy 1.867916 -67.201034) (xy 1.867916 -67.749674) (xy 1.868678 -67.755008) (xy 1.868678 -67.76466)
			(xy 1.874266 -67.775582) (xy 1.876951 -67.780331) (xy 1.881749 -67.785996) (xy 7.66521 -67.785996)
			(xy 7.669281 -67.730374) (xy 7.681407 -67.675937) (xy 7.70133 -67.623846) (xy 7.728626 -67.575211)
			(xy 7.762712 -67.531068) (xy 7.802861 -67.492359) (xy 7.848219 -67.459908) (xy 7.897819 -67.434407)
			(xy 7.950603 -67.4164) (xy 8.005446 -67.40627) (xy 8.06118 -67.404233) (xy 8.116617 -67.410333) (xy 8.170574 -67.424439)
			(xy 8.221903 -67.446251) (xy 8.269509 -67.475305) (xy 8.312377 -67.51098) (xy 8.349594 -67.552517)
			(xy 8.380367 -67.59903) (xy 8.404039 -67.649527) (xy 8.420107 -67.702934) (xy 8.428227 -67.75811)
			(xy 8.428736 -67.785996) (xy 8.428227 -67.813882) (xy 8.420107 -67.869058) (xy 8.404039 -67.922465)
			(xy 8.380367 -67.972962) (xy 8.349594 -68.019475) (xy 8.312377 -68.061012) (xy 8.269509 -68.096687)
			(xy 8.221903 -68.125741) (xy 8.170574 -68.147553) (xy 8.116617 -68.161659) (xy 8.06118 -68.167759)
			(xy 8.005446 -68.165722) (xy 7.950603 -68.155592) (xy 7.897819 -68.137585) (xy 7.848219 -68.112084)
			(xy 7.802861 -68.079633) (xy 7.762712 -68.040924) (xy 7.728626 -67.996781) (xy 7.70133 -67.948146)
			(xy 7.681407 -67.896055) (xy 7.669281 -67.841618) (xy 7.66521 -67.785996) (xy 1.881749 -67.785996)
			(xy 1.884 -67.788654) (xy 1.888236 -67.792092) (xy 1.902968 -67.802506) (xy 1.909826 -67.804792)
			(xy 1.936116 -67.814233) (xy 1.985828 -67.83971) (xy 2.031296 -67.872159) (xy 2.07155 -67.910887)
			(xy 2.105731 -67.955068) (xy 2.133109 -68.003759) (xy 2.153098 -68.055919) (xy 2.165274 -68.110436)
			(xy 2.169374 -68.166145) (xy 2.165313 -68.221857) (xy 2.153176 -68.276382) (xy 2.133223 -68.328556)
			(xy 2.119259 -68.353432) (xy 3.576826 -68.353432) (xy 3.580897 -68.29781) (xy 3.593023 -68.243373)
			(xy 3.612946 -68.191282) (xy 3.640242 -68.142647) (xy 3.674328 -68.098504) (xy 3.714477 -68.059795)
			(xy 3.759835 -68.027344) (xy 3.809435 -68.001843) (xy 3.862219 -67.983836) (xy 3.917062 -67.973706)
			(xy 3.972796 -67.971669) (xy 4.028233 -67.977769) (xy 4.08219 -67.991875) (xy 4.133519 -68.013687)
			(xy 4.181125 -68.042741) (xy 4.223993 -68.078416) (xy 4.26121 -68.119953) (xy 4.291983 -68.166466)
			(xy 4.315655 -68.216963) (xy 4.331723 -68.27037) (xy 4.339843 -68.325546) (xy 4.340352 -68.353432)
			(xy 4.339843 -68.381318) (xy 4.331723 -68.436494) (xy 4.315655 -68.489901) (xy 4.291983 -68.540398)
			(xy 4.26121 -68.586911) (xy 4.223993 -68.628448) (xy 4.181125 -68.664123) (xy 4.133519 -68.693177)
			(xy 4.08219 -68.714989) (xy 4.028233 -68.729095) (xy 3.972796 -68.735195) (xy 3.917062 -68.733158)
			(xy 3.862219 -68.723028) (xy 3.809435 -68.705021) (xy 3.759835 -68.67952) (xy 3.714477 -68.647069)
			(xy 3.674328 -68.60836) (xy 3.640242 -68.564217) (xy 3.612946 -68.515582) (xy 3.593023 -68.463491)
			(xy 3.580897 -68.409054) (xy 3.576826 -68.353432) (xy 2.119259 -68.353432) (xy 2.10588 -68.377266)
			(xy 2.071731 -68.421472) (xy 2.031504 -68.460229) (xy 1.986059 -68.49271) (xy 1.936365 -68.518221)
			(xy 1.91008 -68.527676) (xy 1.909826 -68.527676) (xy 1.902714 -68.530216) (xy 1.889506 -68.539614)
			(xy 1.882706 -68.54473) (xy 1.87271 -68.558489) (xy 1.869948 -68.566538) (xy 1.867916 -68.573904)
			(xy 1.867916 -68.765674) (xy 1.868678 -68.771008) (xy 1.868678 -68.78066) (xy 1.874266 -68.791582)
			(xy 1.876951 -68.796331) (xy 1.884 -68.804654) (xy 1.888236 -68.808092) (xy 1.902968 -68.818506)
			(xy 1.909826 -68.820792) (xy 1.936116 -68.830233) (xy 1.985828 -68.85571) (xy 2.031296 -68.888159)
			(xy 2.07155 -68.926887) (xy 2.105731 -68.971068) (xy 2.133109 -69.019759) (xy 2.153098 -69.071919)
			(xy 2.165274 -69.126436) (xy 2.169374 -69.182145) (xy 2.165313 -69.237857) (xy 2.153176 -69.292382)
			(xy 2.133223 -69.344556) (xy 2.10588 -69.393266) (xy 2.071731 -69.437472) (xy 2.031504 -69.476229)
			(xy 1.986059 -69.50871) (xy 1.936365 -69.534221) (xy 1.91008 -69.543676) (xy 1.909826 -69.543676)
			(xy 1.902714 -69.546216) (xy 1.889506 -69.555614) (xy 1.882706 -69.56073) (xy 1.87271 -69.574489)
			(xy 1.869948 -69.582538) (xy 1.867916 -69.589904) (xy 1.867916 -70.204076) (xy 6.107428 -70.204076)
			(xy 6.111499 -70.148454) (xy 6.123625 -70.094017) (xy 6.143548 -70.041926) (xy 6.170844 -69.993291)
			(xy 6.20493 -69.949148) (xy 6.245079 -69.910439) (xy 6.290437 -69.877988) (xy 6.340037 -69.852487)
			(xy 6.392821 -69.83448) (xy 6.447664 -69.82435) (xy 6.503398 -69.822313) (xy 6.558835 -69.828413)
			(xy 6.612792 -69.842519) (xy 6.664121 -69.864331) (xy 6.711727 -69.893385) (xy 6.754595 -69.92906)
			(xy 6.791812 -69.970597) (xy 6.822585 -70.01711) (xy 6.846257 -70.067607) (xy 6.862325 -70.121014)
			(xy 6.870445 -70.17619) (xy 6.870954 -70.204076) (xy 6.870445 -70.231962) (xy 6.862325 -70.287138)
			(xy 6.846257 -70.340545) (xy 6.822585 -70.391042) (xy 6.791812 -70.437555) (xy 6.754595 -70.479092)
			(xy 6.711727 -70.514767) (xy 6.664121 -70.543821) (xy 6.612792 -70.565633) (xy 6.558835 -70.579739)
			(xy 6.503398 -70.585839) (xy 6.447664 -70.583802) (xy 6.392821 -70.573672) (xy 6.340037 -70.555665)
			(xy 6.290437 -70.530164) (xy 6.245079 -70.497713) (xy 6.20493 -70.459004) (xy 6.170844 -70.414861)
			(xy 6.143548 -70.366226) (xy 6.123625 -70.314135) (xy 6.111499 -70.259698) (xy 6.107428 -70.204076)
			(xy 1.867916 -70.204076) (xy 1.867916 -70.823836) (xy 1.869186 -70.835012) (xy 1.87071 -70.84187)
			(xy 1.873257 -70.850293) (xy 1.883122 -70.864849) (xy 1.890014 -70.870318) (xy 1.890268 -70.870572)
			(xy 1.936496 -70.9041) (xy 1.952752 -70.915784) (xy 1.959356 -70.919848) (xy 1.963166 -70.921626)
			(xy 1.968493 -70.924083) (xy 1.979909 -70.926769) (xy 1.985772 -70.92696) (xy 1.994662 -70.92696)
			(xy 2.010156 -70.92188) (xy 2.036252 -70.914773) (xy 2.089794 -70.907119) (xy 2.116836 -70.90664)
			(xy 2.11709 -70.90664) (xy 2.144361 -70.907103) (xy 2.198349 -70.914864) (xy 2.250683 -70.930229)
			(xy 2.300297 -70.952886) (xy 2.346182 -70.982374) (xy 2.387403 -71.018091) (xy 2.423122 -71.059311)
			(xy 2.45261 -71.105196) (xy 2.475268 -71.154809) (xy 2.490634 -71.207143) (xy 2.498397 -71.261131)
			(xy 2.498852 -71.288402) (xy 2.498339 -71.316753) (xy 2.489964 -71.372831) (xy 2.473389 -71.427055)
			(xy 2.448978 -71.478233) (xy 2.417269 -71.525238) (xy 2.378958 -71.567038) (xy 2.334887 -71.602714)
			(xy 2.286026 -71.631481) (xy 2.233448 -71.652707) (xy 2.178309 -71.665926) (xy 2.15011 -71.668894)
			(xy 2.149094 -71.668894) (xy 2.146808 -71.669148) (xy 2.117344 -71.670164) (xy 2.116836 -71.670164)
			(xy 2.088404 -71.669635) (xy 2.032165 -71.661213) (xy 2.004822 -71.6534) (xy 1.99644 -71.650606)
			(xy 1.983994 -71.650606) (xy 1.970024 -71.652638) (xy 1.960118 -71.655686) (xy 1.942592 -71.668132)
			(xy 1.942084 -71.66864) (xy 1.93475 -71.673974) (xy 3.37896 -71.673974) (xy 3.383031 -71.618352)
			(xy 3.395157 -71.563915) (xy 3.41508 -71.511824) (xy 3.442376 -71.463189) (xy 3.476462 -71.419046)
			(xy 3.516611 -71.380337) (xy 3.561969 -71.347886) (xy 3.611569 -71.322385) (xy 3.664353 -71.304378)
			(xy 3.719196 -71.294248) (xy 3.77493 -71.292211) (xy 3.830367 -71.298311) (xy 3.884324 -71.312417)
			(xy 3.935653 -71.334229) (xy 3.983259 -71.363283) (xy 4.026127 -71.398958) (xy 4.033123 -71.406766)
			(xy 7.013446 -71.406766) (xy 7.017517 -71.351144) (xy 7.029643 -71.296707) (xy 7.049566 -71.244616)
			(xy 7.076862 -71.195981) (xy 7.110948 -71.151838) (xy 7.151097 -71.113129) (xy 7.196455 -71.080678)
			(xy 7.246055 -71.055177) (xy 7.298839 -71.03717) (xy 7.353682 -71.02704) (xy 7.409416 -71.025003)
			(xy 7.464853 -71.031103) (xy 7.51881 -71.045209) (xy 7.570139 -71.067021) (xy 7.617745 -71.096075)
			(xy 7.660613 -71.13175) (xy 7.69783 -71.173287) (xy 7.728603 -71.2198) (xy 7.752275 -71.270297) (xy 7.768343 -71.323704)
			(xy 7.776463 -71.37888) (xy 7.776972 -71.406766) (xy 7.776463 -71.434652) (xy 7.768343 -71.489828)
			(xy 7.752275 -71.543235) (xy 7.728603 -71.593732) (xy 7.69783 -71.640245) (xy 7.660613 -71.681782)
			(xy 7.617745 -71.717457) (xy 7.570139 -71.746511) (xy 7.51881 -71.768323) (xy 7.464853 -71.782429)
			(xy 7.409416 -71.788529) (xy 7.353682 -71.786492) (xy 7.298839 -71.776362) (xy 7.246055 -71.758355)
			(xy 7.196455 -71.732854) (xy 7.151097 -71.700403) (xy 7.110948 -71.661694) (xy 7.076862 -71.617551)
			(xy 7.049566 -71.568916) (xy 7.029643 -71.516825) (xy 7.017517 -71.462388) (xy 7.013446 -71.406766)
			(xy 4.033123 -71.406766) (xy 4.063344 -71.440495) (xy 4.094117 -71.487008) (xy 4.117789 -71.537505)
			(xy 4.133857 -71.590912) (xy 4.141977 -71.646088) (xy 4.142486 -71.673974) (xy 4.141977 -71.70186)
			(xy 4.133857 -71.757036) (xy 4.117789 -71.810443) (xy 4.094117 -71.86094) (xy 4.063344 -71.907453)
			(xy 4.026127 -71.94899) (xy 3.983259 -71.984665) (xy 3.935653 -72.013719) (xy 3.884324 -72.035531)
			(xy 3.830367 -72.049637) (xy 3.77493 -72.055737) (xy 3.719196 -72.0537) (xy 3.664353 -72.04357) (xy 3.611569 -72.025563)
			(xy 3.561969 -72.000062) (xy 3.516611 -71.967611) (xy 3.476462 -71.928902) (xy 3.442376 -71.884759)
			(xy 3.41508 -71.836124) (xy 3.395157 -71.784033) (xy 3.383031 -71.729596) (xy 3.37896 -71.673974)
			(xy 1.93475 -71.673974) (xy 1.928114 -71.6788) (xy 1.927606 -71.6788) (xy 1.885188 -71.710042) (xy 1.877767 -71.717221)
			(xy 1.868857 -71.735828) (xy 1.867916 -71.74611) (xy 1.867916 -72.553576) (xy 1.86823 -72.561859)
			(xy 1.873537 -72.577549) (xy 1.87833 -72.58431) (xy 1.879346 -72.585326) (xy 1.881632 -72.587866)
			(xy 1.88214 -72.588628) (xy 1.884426 -72.591168) (xy 1.885696 -72.592438) (xy 1.886204 -72.5932)
			(xy 1.89226 -72.600372) (xy 1.899053 -72.617857) (xy 1.899412 -72.627236) (xy 1.899412 -73.289668)
			(xy 3.554728 -73.289668) (xy 3.558799 -73.234046) (xy 3.570925 -73.179609) (xy 3.590848 -73.127518)
			(xy 3.618144 -73.078883) (xy 3.65223 -73.03474) (xy 3.692379 -72.996031) (xy 3.737737 -72.96358)
			(xy 3.787337 -72.938079) (xy 3.840121 -72.920072) (xy 3.894964 -72.909942) (xy 3.950698 -72.907905)
			(xy 4.006135 -72.914005) (xy 4.060092 -72.928111) (xy 4.111421 -72.949923) (xy 4.159027 -72.978977)
			(xy 4.201895 -73.014652) (xy 4.239112 -73.056189) (xy 4.269885 -73.102702) (xy 4.293557 -73.153199)
			(xy 4.309625 -73.206606) (xy 4.317745 -73.261782) (xy 4.318254 -73.289668) (xy 4.317745 -73.317554)
			(xy 4.309625 -73.37273) (xy 4.293557 -73.426137) (xy 4.269885 -73.476634) (xy 4.239112 -73.523147)
			(xy 4.201895 -73.564684) (xy 4.159027 -73.600359) (xy 4.111421 -73.629413) (xy 4.060092 -73.651225)
			(xy 4.006135 -73.665331) (xy 3.950698 -73.671431) (xy 3.894964 -73.669394) (xy 3.840121 -73.659264)
			(xy 3.787337 -73.641257) (xy 3.737737 -73.615756) (xy 3.692379 -73.583305) (xy 3.65223 -73.544596)
			(xy 3.618144 -73.500453) (xy 3.590848 -73.451818) (xy 3.570925 -73.399727) (xy 3.558799 -73.34529)
			(xy 3.554728 -73.289668) (xy 1.899412 -73.289668) (xy 1.899412 -75.087226) (xy 6.381748 -75.087226)
			(xy 6.385819 -75.031604) (xy 6.397945 -74.977167) (xy 6.417868 -74.925076) (xy 6.445164 -74.876441)
			(xy 6.47925 -74.832298) (xy 6.519399 -74.793589) (xy 6.564757 -74.761138) (xy 6.614357 -74.735637)
			(xy 6.667141 -74.71763) (xy 6.721984 -74.7075) (xy 6.777718 -74.705463) (xy 6.833155 -74.711563)
			(xy 6.887112 -74.725669) (xy 6.938441 -74.747481) (xy 6.986047 -74.776535) (xy 7.028915 -74.81221)
			(xy 7.066132 -74.853747) (xy 7.096905 -74.90026) (xy 7.120577 -74.950757) (xy 7.136645 -75.004164)
			(xy 7.144765 -75.05934) (xy 7.145274 -75.087226) (xy 7.144765 -75.115112) (xy 7.136645 -75.170288)
			(xy 7.120577 -75.223695) (xy 7.096905 -75.274192) (xy 7.066132 -75.320705) (xy 7.028915 -75.362242)
			(xy 6.986047 -75.397917) (xy 6.938441 -75.426971) (xy 6.887112 -75.448783) (xy 6.833155 -75.462889)
			(xy 6.777718 -75.468989) (xy 6.721984 -75.466952) (xy 6.667141 -75.456822) (xy 6.614357 -75.438815)
			(xy 6.564757 -75.413314) (xy 6.519399 -75.380863) (xy 6.47925 -75.342154) (xy 6.445164 -75.298011)
			(xy 6.417868 -75.249376) (xy 6.397945 -75.197285) (xy 6.385819 -75.142848) (xy 6.381748 -75.087226)
			(xy 1.899412 -75.087226) (xy 1.899412 -75.534774) (xy 1.900101 -75.542629) (xy 1.905674 -75.557368)
			(xy 1.910334 -75.56373) (xy 1.919986 -75.572874) (xy 1.966722 -75.602338) (xy 1.988312 -75.6158)
			(xy 1.994429 -75.619274) (xy 2.007953 -75.623125) (xy 2.014982 -75.62342) (xy 2.040382 -75.62342)
			(xy 2.050288 -75.618848) (xy 2.075105 -75.608159) (xy 2.126998 -75.5931) (xy 2.180497 -75.585516)
			(xy 2.207514 -75.585066) (xy 2.212086 -75.585066) (xy 2.239339 -75.585529) (xy 2.29329 -75.593285)
			(xy 2.345587 -75.608641) (xy 2.395167 -75.631283) (xy 2.441021 -75.660751) (xy 2.482213 -75.696444)
			(xy 2.517907 -75.737636) (xy 2.547375 -75.783489) (xy 2.570018 -75.833069) (xy 2.585374 -75.885367)
			(xy 2.593131 -75.939317) (xy 2.593131 -75.993823) (xy 2.585374 -76.047773) (xy 2.570018 -76.100071)
			(xy 2.547375 -76.149651) (xy 2.517907 -76.195504) (xy 2.482213 -76.236696) (xy 2.441021 -76.272389)
			(xy 2.395167 -76.301857) (xy 2.345587 -76.324499) (xy 2.29329 -76.339855) (xy 2.239339 -76.347611)
			(xy 2.212086 -76.348082) (xy 2.186863 -76.34766) (xy 2.136862 -76.340976) (xy 2.08818 -76.327753)
			(xy 2.064766 -76.318364) (xy 2.055368 -76.3143) (xy 2.055114 -76.3143) (xy 2.051812 -76.312776) (xy 2.048764 -76.311506)
			(xy 2.044954 -76.309728) (xy 2.040636 -76.30795) (xy 2.031746 -76.30541) (xy 2.023618 -76.304648)
			(xy 2.014982 -76.30541) (xy 2.009702 -76.306431) (xy 1.99971 -76.310402) (xy 1.99517 -76.313284)
			(xy 1.989328 -76.317094) (xy 1.989074 -76.317348) (xy 1.98374 -76.32065) (xy 1.92278 -76.359004)
			(xy 1.922526 -76.359258) (xy 1.917381 -76.362757) (xy 1.90879 -76.371751) (xy 1.905508 -76.377038)
			(xy 1.902714 -76.382372) (xy 1.900682 -76.391008) (xy 1.899412 -76.401422) (xy 1.899412 -81.755234)
			(xy 1.900174 -81.763362) (xy 1.900174 -81.76387) (xy 1.901779 -81.771387) (xy 1.90876 -81.78507)
			(xy 1.91389 -81.790794) (xy 5.705856 -85.58276) (xy 5.712698 -85.59016) (xy 5.720417 -85.608758)
			(xy 5.720842 -85.618828) (xy 5.720842 -112.501426) (xy 11.973304 -112.501426) (xy 11.977375 -112.445804)
			(xy 11.989501 -112.391367) (xy 12.009424 -112.339276) (xy 12.03672 -112.290641) (xy 12.070806 -112.246498)
			(xy 12.110955 -112.207789) (xy 12.156313 -112.175338) (xy 12.205913 -112.149837) (xy 12.258697 -112.13183)
			(xy 12.31354 -112.1217) (xy 12.369274 -112.119663) (xy 12.424711 -112.125763) (xy 12.478668 -112.139869)
			(xy 12.529997 -112.161681) (xy 12.577603 -112.190735) (xy 12.620471 -112.22641) (xy 12.657688 -112.267947)
			(xy 12.688461 -112.31446) (xy 12.712133 -112.364957) (xy 12.728201 -112.418364) (xy 12.736321 -112.47354)
			(xy 12.73683 -112.501426) (xy 12.736321 -112.529312) (xy 12.728201 -112.584488) (xy 12.712133 -112.637895)
			(xy 12.688461 -112.688392) (xy 12.657688 -112.734905) (xy 12.620471 -112.776442) (xy 12.577603 -112.812117)
			(xy 12.529997 -112.841171) (xy 12.478668 -112.862983) (xy 12.424711 -112.877089) (xy 12.369274 -112.883189)
			(xy 12.31354 -112.881152) (xy 12.258697 -112.871022) (xy 12.205913 -112.853015) (xy 12.156313 -112.827514)
			(xy 12.110955 -112.795063) (xy 12.070806 -112.756354) (xy 12.03672 -112.712211) (xy 12.009424 -112.663576)
			(xy 11.989501 -112.611485) (xy 11.977375 -112.557048) (xy 11.973304 -112.501426) (xy 5.720842 -112.501426)
			(xy 5.720842 -113.302034) (xy 14.31366 -113.302034) (xy 14.317731 -113.246412) (xy 14.329857 -113.191975)
			(xy 14.34978 -113.139884) (xy 14.377076 -113.091249) (xy 14.411162 -113.047106) (xy 14.451311 -113.008397)
			(xy 14.496669 -112.975946) (xy 14.546269 -112.950445) (xy 14.599053 -112.932438) (xy 14.653896 -112.922308)
			(xy 14.70963 -112.920271) (xy 14.765067 -112.926371) (xy 14.819024 -112.940477) (xy 14.870353 -112.962289)
			(xy 14.917959 -112.991343) (xy 14.960827 -113.027018) (xy 14.998044 -113.068555) (xy 15.028817 -113.115068)
			(xy 15.052489 -113.165565) (xy 15.068557 -113.218972) (xy 15.076677 -113.274148) (xy 15.077186 -113.302034)
			(xy 15.076677 -113.32992) (xy 15.068557 -113.385096) (xy 15.052489 -113.438503) (xy 15.028817 -113.489)
			(xy 14.998044 -113.535513) (xy 14.960827 -113.57705) (xy 14.917959 -113.612725) (xy 14.870353 -113.641779)
			(xy 14.819024 -113.663591) (xy 14.765067 -113.677697) (xy 14.70963 -113.683797) (xy 14.653896 -113.68176)
			(xy 14.599053 -113.67163) (xy 14.546269 -113.653623) (xy 14.496669 -113.628122) (xy 14.451311 -113.595671)
			(xy 14.411162 -113.556962) (xy 14.377076 -113.512819) (xy 14.34978 -113.464184) (xy 14.329857 -113.412093)
			(xy 14.317731 -113.357656) (xy 14.31366 -113.302034) (xy 5.720842 -113.302034) (xy 5.720842 -114.660426)
			(xy 11.961366 -114.660426) (xy 11.965437 -114.604804) (xy 11.977563 -114.550367) (xy 11.997486 -114.498276)
			(xy 12.024782 -114.449641) (xy 12.058868 -114.405498) (xy 12.099017 -114.366789) (xy 12.144375 -114.334338)
			(xy 12.193975 -114.308837) (xy 12.246759 -114.29083) (xy 12.301602 -114.2807) (xy 12.357336 -114.278663)
			(xy 12.412773 -114.284763) (xy 12.46673 -114.298869) (xy 12.518059 -114.320681) (xy 12.565665 -114.349735)
			(xy 12.608533 -114.38541) (xy 12.64575 -114.426947) (xy 12.676523 -114.47346) (xy 12.700195 -114.523957)
			(xy 12.716263 -114.577364) (xy 12.724383 -114.63254) (xy 12.724892 -114.660426) (xy 12.724383 -114.688312)
			(xy 12.716263 -114.743488) (xy 12.700195 -114.796895) (xy 12.676523 -114.847392) (xy 12.64575 -114.893905)
			(xy 12.608533 -114.935442) (xy 12.565665 -114.971117) (xy 12.518059 -115.000171) (xy 12.46673 -115.021983)
			(xy 12.412773 -115.036089) (xy 12.357336 -115.042189) (xy 12.301602 -115.040152) (xy 12.246759 -115.030022)
			(xy 12.193975 -115.012015) (xy 12.144375 -114.986514) (xy 12.099017 -114.954063) (xy 12.058868 -114.915354)
			(xy 12.024782 -114.871211) (xy 11.997486 -114.822576) (xy 11.977563 -114.770485) (xy 11.965437 -114.716048)
			(xy 11.961366 -114.660426) (xy 5.720842 -114.660426) (xy 5.720842 -117.434106) (xy 13.37691 -117.434106)
			(xy 13.377377 -117.406736) (xy 13.385194 -117.352557) (xy 13.400683 -117.300053) (xy 13.423525 -117.250307)
			(xy 13.453249 -117.20434) (xy 13.47089 -117.183408) (xy 13.471144 -117.183154) (xy 13.476719 -117.17606)
			(xy 13.482972 -117.159149) (xy 13.483336 -117.150134) (xy 13.483336 -117.083078) (xy 13.482982 -117.074061)
			(xy 13.476732 -117.057144) (xy 13.471144 -117.050058) (xy 13.47089 -117.050058) (xy 13.47089 -117.049804)
			(xy 13.453257 -117.028866) (xy 13.423535 -116.982898) (xy 13.400691 -116.933152) (xy 13.385196 -116.880652)
			(xy 13.377368 -116.826474) (xy 13.377367 -116.771735) (xy 13.385194 -116.717557) (xy 13.400688 -116.665056)
			(xy 13.42353 -116.61531) (xy 13.453251 -116.569341) (xy 13.47089 -116.548408) (xy 13.471144 -116.548154)
			(xy 13.476719 -116.54106) (xy 13.482972 -116.524149) (xy 13.483336 -116.515134) (xy 13.483336 -116.448078)
			(xy 13.482982 -116.439061) (xy 13.476732 -116.422144) (xy 13.471144 -116.415058) (xy 13.47089 -116.415058)
			(xy 13.47089 -116.414804) (xy 13.453238 -116.393883) (xy 13.423528 -116.347907) (xy 13.400695 -116.298156)
			(xy 13.385207 -116.245653) (xy 13.377382 -116.191476) (xy 13.37691 -116.164106) (xy 13.377361 -116.136852)
			(xy 13.385118 -116.0829) (xy 13.400474 -116.030601) (xy 13.423117 -115.98102) (xy 13.452586 -115.935166)
			(xy 13.488281 -115.893972) (xy 13.529475 -115.858279) (xy 13.57533 -115.828811) (xy 13.624912 -115.80617)
			(xy 13.677212 -115.790815) (xy 13.731164 -115.78306) (xy 13.758418 -115.782598) (xy 13.785789 -115.783054)
			(xy 13.839968 -115.790874) (xy 13.892471 -115.806366) (xy 13.942218 -115.82921) (xy 13.988184 -115.858936)
			(xy 14.009116 -115.876578) (xy 14.00937 -115.876832) (xy 14.016458 -115.882416) (xy 14.033374 -115.888663)
			(xy 14.04239 -115.889024) (xy 14.109446 -115.889024) (xy 14.11846 -115.888636) (xy 14.135377 -115.882409)
			(xy 14.142466 -115.876832) (xy 14.142466 -115.876578) (xy 14.14272 -115.876578) (xy 14.163669 -115.85896)
			(xy 14.209637 -115.829245) (xy 14.259381 -115.806406) (xy 14.311877 -115.79091) (xy 14.36605 -115.783075)
			(xy 14.393418 -115.782598) (xy 14.42067 -115.783061) (xy 14.474619 -115.79082) (xy 14.526914 -115.806178)
			(xy 14.576492 -115.828822) (xy 14.622343 -115.85829) (xy 14.663533 -115.893984) (xy 14.699224 -115.935177)
			(xy 14.72869 -115.981029) (xy 14.75133 -116.030608) (xy 14.766685 -116.082905) (xy 14.774441 -116.136854)
			(xy 14.774926 -116.164106) (xy 14.774481 -116.191477) (xy 14.766661 -116.245658) (xy 14.751168 -116.298162)
			(xy 14.728321 -116.347909) (xy 14.69859 -116.393874) (xy 14.680946 -116.414804) (xy 14.680692 -116.415058)
			(xy 14.675116 -116.422152) (xy 14.668863 -116.439063) (xy 14.6685 -116.448078) (xy 14.6685 -116.515134)
			(xy 14.668841 -116.524152) (xy 14.6751 -116.541069) (xy 14.680692 -116.548154) (xy 14.680946 -116.548154)
			(xy 14.680946 -116.548408) (xy 14.698594 -116.569335) (xy 14.72832 -116.615303) (xy 14.751167 -116.66505)
			(xy 14.766664 -116.717554) (xy 14.774493 -116.771733) (xy 14.774492 -116.826476) (xy 14.766662 -116.880655)
			(xy 14.751164 -116.933158) (xy 14.728316 -116.982904) (xy 14.698588 -117.028872) (xy 14.680946 -117.049804)
			(xy 14.680692 -117.050058) (xy 14.675116 -117.057152) (xy 14.668863 -117.074063) (xy 14.6685 -117.083078)
			(xy 14.6685 -117.150134) (xy 14.668841 -117.159152) (xy 14.6751 -117.176069) (xy 14.680692 -117.183154)
			(xy 14.680946 -117.183154) (xy 14.680946 -117.183408) (xy 14.698594 -117.204333) (xy 14.728306 -117.250307)
			(xy 14.751141 -117.300056) (xy 14.76663 -117.352559) (xy 14.774454 -117.406736) (xy 14.774926 -117.434106)
			(xy 14.774786 -117.442234) (xy 15.659098 -117.442234) (xy 15.663169 -117.386612) (xy 15.675295 -117.332175)
			(xy 15.695218 -117.280084) (xy 15.722514 -117.231449) (xy 15.7566 -117.187306) (xy 15.796749 -117.148597)
			(xy 15.842107 -117.116146) (xy 15.891707 -117.090645) (xy 15.944491 -117.072638) (xy 15.999334 -117.062508)
			(xy 16.055068 -117.060471) (xy 16.110505 -117.066571) (xy 16.164462 -117.080677) (xy 16.215791 -117.102489)
			(xy 16.263397 -117.131543) (xy 16.306265 -117.167218) (xy 16.343482 -117.208755) (xy 16.374255 -117.255268)
			(xy 16.397927 -117.305765) (xy 16.413995 -117.359172) (xy 16.422115 -117.414348) (xy 16.422624 -117.442234)
			(xy 16.422115 -117.47012) (xy 16.413995 -117.525296) (xy 16.397927 -117.578703) (xy 16.374255 -117.6292)
			(xy 16.343482 -117.675713) (xy 16.306265 -117.71725) (xy 16.263397 -117.752925) (xy 16.215791 -117.781979)
			(xy 16.164462 -117.803791) (xy 16.110505 -117.817897) (xy 16.055068 -117.823997) (xy 15.999334 -117.82196)
			(xy 15.944491 -117.81183) (xy 15.891707 -117.793823) (xy 15.842107 -117.768322) (xy 15.796749 -117.735871)
			(xy 15.7566 -117.697162) (xy 15.722514 -117.653019) (xy 15.695218 -117.604384) (xy 15.675295 -117.552293)
			(xy 15.663169 -117.497856) (xy 15.659098 -117.442234) (xy 14.774786 -117.442234) (xy 14.774469 -117.460662)
			(xy 14.767101 -117.513262) (xy 14.752509 -117.564331) (xy 14.74216 -117.588792) (xy 14.737815 -117.600161)
			(xy 14.739162 -117.624433) (xy 14.7447 -117.635274) (xy 14.786102 -117.706394) (xy 14.792839 -117.716462)
			(xy 14.813244 -117.729453) (xy 14.825218 -117.731286) (xy 14.853196 -117.734495) (xy 14.90786 -117.748027)
			(xy 14.959939 -117.769449) (xy 15.008302 -117.798296) (xy 15.051898 -117.833941) (xy 15.089779 -117.875609)
			(xy 15.121122 -117.922394) (xy 15.145244 -117.973279) (xy 15.161622 -118.027158) (xy 15.167063 -118.063772)
			(xy 16.806162 -118.063772) (xy 16.810233 -118.00815) (xy 16.822359 -117.953713) (xy 16.842282 -117.901622)
			(xy 16.869578 -117.852987) (xy 16.903664 -117.808844) (xy 16.943813 -117.770135) (xy 16.989171 -117.737684)
			(xy 17.038771 -117.712183) (xy 17.091555 -117.694176) (xy 17.146398 -117.684046) (xy 17.202132 -117.682009)
			(xy 17.257569 -117.688109) (xy 17.311526 -117.702215) (xy 17.362855 -117.724027) (xy 17.410461 -117.753081)
			(xy 17.453329 -117.788756) (xy 17.490546 -117.830293) (xy 17.521319 -117.876806) (xy 17.544991 -117.927303)
			(xy 17.561059 -117.98071) (xy 17.569179 -118.035886) (xy 17.569688 -118.063772) (xy 17.569179 -118.091658)
			(xy 17.561059 -118.146834) (xy 17.544991 -118.200241) (xy 17.521319 -118.250738) (xy 17.490546 -118.297251)
			(xy 17.453329 -118.338788) (xy 17.410461 -118.374463) (xy 17.362855 -118.403517) (xy 17.311526 -118.425329)
			(xy 17.257569 -118.439435) (xy 17.202132 -118.445535) (xy 17.146398 -118.443498) (xy 17.091555 -118.433368)
			(xy 17.038771 -118.415361) (xy 16.989171 -118.38986) (xy 16.943813 -118.357409) (xy 16.903664 -118.3187)
			(xy 16.869578 -118.274557) (xy 16.842282 -118.225922) (xy 16.822359 -118.173831) (xy 16.810233 -118.119394)
			(xy 16.806162 -118.063772) (xy 15.167063 -118.063772) (xy 15.1699 -118.082859) (xy 15.170404 -118.111016)
			(xy 15.169918 -118.138267) (xy 15.162162 -118.192215) (xy 15.146807 -118.24451) (xy 15.124165 -118.294087)
			(xy 15.094699 -118.339937) (xy 15.059008 -118.381128) (xy 15.017817 -118.416819) (xy 14.971967 -118.446285)
			(xy 14.92239 -118.468927) (xy 14.870095 -118.484282) (xy 14.816147 -118.492038) (xy 14.761645 -118.492038)
			(xy 14.707697 -118.484282) (xy 14.655402 -118.468927) (xy 14.605825 -118.446285) (xy 14.559975 -118.416819)
			(xy 14.518784 -118.381128) (xy 14.483093 -118.339937) (xy 14.453627 -118.294087) (xy 14.430985 -118.24451)
			(xy 14.41563 -118.192215) (xy 14.407874 -118.138267) (xy 14.407388 -118.111016) (xy 14.407851 -118.08446)
			(xy 14.415217 -118.031861) (xy 14.429807 -117.980792) (xy 14.440154 -117.95633) (xy 14.444483 -117.944956)
			(xy 14.443146 -117.920689) (xy 14.437614 -117.909848) (xy 14.396212 -117.838728) (xy 14.389488 -117.828651)
			(xy 14.369072 -117.815667) (xy 14.357096 -117.813836) (xy 14.32762 -117.810473) (xy 14.270151 -117.79575)
			(xy 14.215655 -117.772305) (xy 14.165446 -117.740706) (xy 14.14272 -117.721634) (xy 14.142466 -117.72138)
			(xy 14.135366 -117.715813) (xy 14.11846 -117.709555) (xy 14.109446 -117.709188) (xy 14.04239 -117.709188)
			(xy 14.033373 -117.709543) (xy 14.016456 -117.715792) (xy 14.00937 -117.72138) (xy 14.00937 -117.721634)
			(xy 14.009116 -117.721634) (xy 13.988193 -117.739284) (xy 13.942217 -117.768993) (xy 13.892467 -117.791827)
			(xy 13.839965 -117.807315) (xy 13.785788 -117.815141) (xy 13.758418 -117.815614) (xy 13.731166 -117.815128)
			(xy 13.677216 -117.807374) (xy 13.624919 -117.79202) (xy 13.575339 -117.76938) (xy 13.529486 -117.739915)
			(xy 13.488294 -117.704223) (xy 13.4526 -117.663033) (xy 13.423131 -117.617182) (xy 13.400488 -117.567604)
			(xy 13.385132 -117.515307) (xy 13.377374 -117.461358) (xy 13.37691 -117.434106) (xy 5.720842 -117.434106)
			(xy 5.720842 -118.089426) (xy 10.195304 -118.089426) (xy 10.199375 -118.033804) (xy 10.211501 -117.979367)
			(xy 10.231424 -117.927276) (xy 10.25872 -117.878641) (xy 10.292806 -117.834498) (xy 10.332955 -117.795789)
			(xy 10.378313 -117.763338) (xy 10.427913 -117.737837) (xy 10.480697 -117.71983) (xy 10.53554 -117.7097)
			(xy 10.591274 -117.707663) (xy 10.646711 -117.713763) (xy 10.700668 -117.727869) (xy 10.751997 -117.749681)
			(xy 10.799603 -117.778735) (xy 10.842471 -117.81441) (xy 10.879688 -117.855947) (xy 10.910461 -117.90246)
			(xy 10.934133 -117.952957) (xy 10.936982 -117.962426) (xy 12.227304 -117.962426) (xy 12.231375 -117.906804)
			(xy 12.243501 -117.852367) (xy 12.263424 -117.800276) (xy 12.29072 -117.751641) (xy 12.324806 -117.707498)
			(xy 12.364955 -117.668789) (xy 12.410313 -117.636338) (xy 12.459913 -117.610837) (xy 12.512697 -117.59283)
			(xy 12.56754 -117.5827) (xy 12.623274 -117.580663) (xy 12.678711 -117.586763) (xy 12.732668 -117.600869)
			(xy 12.783997 -117.622681) (xy 12.831603 -117.651735) (xy 12.874471 -117.68741) (xy 12.911688 -117.728947)
			(xy 12.942461 -117.77546) (xy 12.966133 -117.825957) (xy 12.982201 -117.879364) (xy 12.990321 -117.93454)
			(xy 12.99083 -117.962426) (xy 12.990321 -117.990312) (xy 12.982201 -118.045488) (xy 12.966133 -118.098895)
			(xy 12.942461 -118.149392) (xy 12.911688 -118.195905) (xy 12.874471 -118.237442) (xy 12.831603 -118.273117)
			(xy 12.783997 -118.302171) (xy 12.732668 -118.323983) (xy 12.678711 -118.338089) (xy 12.623274 -118.344189)
			(xy 12.56754 -118.342152) (xy 12.512697 -118.332022) (xy 12.459913 -118.314015) (xy 12.410313 -118.288514)
			(xy 12.364955 -118.256063) (xy 12.324806 -118.217354) (xy 12.29072 -118.173211) (xy 12.263424 -118.124576)
			(xy 12.243501 -118.072485) (xy 12.231375 -118.018048) (xy 12.227304 -117.962426) (xy 10.936982 -117.962426)
			(xy 10.950201 -118.006364) (xy 10.958321 -118.06154) (xy 10.95883 -118.089426) (xy 10.958321 -118.117312)
			(xy 10.950201 -118.172488) (xy 10.934133 -118.225895) (xy 10.910461 -118.276392) (xy 10.879688 -118.322905)
			(xy 10.842471 -118.364442) (xy 10.799603 -118.400117) (xy 10.751997 -118.429171) (xy 10.700668 -118.450983)
			(xy 10.646711 -118.465089) (xy 10.591274 -118.471189) (xy 10.53554 -118.469152) (xy 10.480697 -118.459022)
			(xy 10.427913 -118.441015) (xy 10.378313 -118.415514) (xy 10.332955 -118.383063) (xy 10.292806 -118.344354)
			(xy 10.25872 -118.300211) (xy 10.231424 -118.251576) (xy 10.211501 -118.199485) (xy 10.199375 -118.145048)
			(xy 10.195304 -118.089426) (xy 5.720842 -118.089426) (xy 5.720842 -120.248426) (xy 10.195304 -120.248426)
			(xy 10.199375 -120.192804) (xy 10.211501 -120.138367) (xy 10.231424 -120.086276) (xy 10.25872 -120.037641)
			(xy 10.292806 -119.993498) (xy 10.332955 -119.954789) (xy 10.378313 -119.922338) (xy 10.427913 -119.896837)
			(xy 10.480697 -119.87883) (xy 10.53554 -119.8687) (xy 10.591274 -119.866663) (xy 10.646711 -119.872763)
			(xy 10.700668 -119.886869) (xy 10.751997 -119.908681) (xy 10.799603 -119.937735) (xy 10.842471 -119.97341)
			(xy 10.879688 -120.014947) (xy 10.910461 -120.06146) (xy 10.934133 -120.111957) (xy 10.935912 -120.11787)
			(xy 11.211304 -120.11787) (xy 11.215375 -120.062248) (xy 11.227501 -120.007811) (xy 11.247424 -119.95572)
			(xy 11.27472 -119.907085) (xy 11.308806 -119.862942) (xy 11.348955 -119.824233) (xy 11.394313 -119.791782)
			(xy 11.443913 -119.766281) (xy 11.496697 -119.748274) (xy 11.55154 -119.738144) (xy 11.607274 -119.736107)
			(xy 11.662711 -119.742207) (xy 11.716668 -119.756313) (xy 11.767997 -119.778125) (xy 11.815603 -119.807179)
			(xy 11.858471 -119.842854) (xy 11.895688 -119.884391) (xy 11.926461 -119.930904) (xy 11.950133 -119.981401)
			(xy 11.966201 -120.034808) (xy 11.974321 -120.089984) (xy 11.97483 -120.11787) (xy 12.227304 -120.11787)
			(xy 12.231375 -120.062248) (xy 12.243501 -120.007811) (xy 12.263424 -119.95572) (xy 12.29072 -119.907085)
			(xy 12.324806 -119.862942) (xy 12.364955 -119.824233) (xy 12.410313 -119.791782) (xy 12.459913 -119.766281)
			(xy 12.512697 -119.748274) (xy 12.56754 -119.738144) (xy 12.623274 -119.736107) (xy 12.678711 -119.742207)
			(xy 12.732668 -119.756313) (xy 12.783997 -119.778125) (xy 12.831603 -119.807179) (xy 12.874471 -119.842854)
			(xy 12.911688 -119.884391) (xy 12.942461 -119.930904) (xy 12.966133 -119.981401) (xy 12.982201 -120.034808)
			(xy 12.990321 -120.089984) (xy 12.99083 -120.11787) (xy 12.990321 -120.145756) (xy 12.989192 -120.15343)
			(xy 15.422878 -120.15343) (xy 15.426949 -120.097808) (xy 15.439075 -120.043371) (xy 15.458998 -119.99128)
			(xy 15.486294 -119.942645) (xy 15.52038 -119.898502) (xy 15.560529 -119.859793) (xy 15.605887 -119.827342)
			(xy 15.655487 -119.801841) (xy 15.708271 -119.783834) (xy 15.763114 -119.773704) (xy 15.818848 -119.771667)
			(xy 15.874285 -119.777767) (xy 15.928242 -119.791873) (xy 15.979571 -119.813685) (xy 16.027177 -119.842739)
			(xy 16.070045 -119.878414) (xy 16.107262 -119.919951) (xy 16.138035 -119.966464) (xy 16.161707 -120.016961)
			(xy 16.177775 -120.070368) (xy 16.185895 -120.125544) (xy 16.186404 -120.15343) (xy 16.185895 -120.181316)
			(xy 16.177775 -120.236492) (xy 16.161707 -120.289899) (xy 16.138035 -120.340396) (xy 16.107262 -120.386909)
			(xy 16.070045 -120.428446) (xy 16.027177 -120.464121) (xy 15.979571 -120.493175) (xy 15.928242 -120.514987)
			(xy 15.874285 -120.529093) (xy 15.818848 -120.535193) (xy 15.763114 -120.533156) (xy 15.708271 -120.523026)
			(xy 15.655487 -120.505019) (xy 15.605887 -120.479518) (xy 15.560529 -120.447067) (xy 15.52038 -120.408358)
			(xy 15.486294 -120.364215) (xy 15.458998 -120.31558) (xy 15.439075 -120.263489) (xy 15.426949 -120.209052)
			(xy 15.422878 -120.15343) (xy 12.989192 -120.15343) (xy 12.982201 -120.200932) (xy 12.966133 -120.254339)
			(xy 12.942461 -120.304836) (xy 12.911688 -120.351349) (xy 12.874471 -120.392886) (xy 12.831603 -120.428561)
			(xy 12.783997 -120.457615) (xy 12.732668 -120.479427) (xy 12.678711 -120.493533) (xy 12.623274 -120.499633)
			(xy 12.56754 -120.497596) (xy 12.512697 -120.487466) (xy 12.459913 -120.469459) (xy 12.410313 -120.443958)
			(xy 12.364955 -120.411507) (xy 12.324806 -120.372798) (xy 12.29072 -120.328655) (xy 12.263424 -120.28002)
			(xy 12.243501 -120.227929) (xy 12.231375 -120.173492) (xy 12.227304 -120.11787) (xy 11.97483 -120.11787)
			(xy 11.974321 -120.145756) (xy 11.966201 -120.200932) (xy 11.950133 -120.254339) (xy 11.926461 -120.304836)
			(xy 11.895688 -120.351349) (xy 11.858471 -120.392886) (xy 11.815603 -120.428561) (xy 11.767997 -120.457615)
			(xy 11.716668 -120.479427) (xy 11.662711 -120.493533) (xy 11.607274 -120.499633) (xy 11.55154 -120.497596)
			(xy 11.496697 -120.487466) (xy 11.443913 -120.469459) (xy 11.394313 -120.443958) (xy 11.348955 -120.411507)
			(xy 11.308806 -120.372798) (xy 11.27472 -120.328655) (xy 11.247424 -120.28002) (xy 11.227501 -120.227929)
			(xy 11.215375 -120.173492) (xy 11.211304 -120.11787) (xy 10.935912 -120.11787) (xy 10.950201 -120.165364)
			(xy 10.958321 -120.22054) (xy 10.95883 -120.248426) (xy 10.958321 -120.276312) (xy 10.950201 -120.331488)
			(xy 10.934133 -120.384895) (xy 10.910461 -120.435392) (xy 10.879688 -120.481905) (xy 10.842471 -120.523442)
			(xy 10.799603 -120.559117) (xy 10.751997 -120.588171) (xy 10.700668 -120.609983) (xy 10.646711 -120.624089)
			(xy 10.591274 -120.630189) (xy 10.53554 -120.628152) (xy 10.480697 -120.618022) (xy 10.427913 -120.600015)
			(xy 10.378313 -120.574514) (xy 10.332955 -120.542063) (xy 10.292806 -120.503354) (xy 10.25872 -120.459211)
			(xy 10.231424 -120.410576) (xy 10.211501 -120.358485) (xy 10.199375 -120.304048) (xy 10.195304 -120.248426)
			(xy 5.720842 -120.248426) (xy 5.720842 -121.57075) (xy 13.619988 -121.57075) (xy 13.620426 -121.544435)
			(xy 13.627667 -121.492305) (xy 13.641992 -121.441662) (xy 13.66313 -121.393464) (xy 13.690682 -121.348621)
			(xy 13.724125 -121.307982) (xy 13.743178 -121.289826) (xy 13.750567 -121.282294) (xy 13.759099 -121.263022)
			(xy 13.759688 -121.252488) (xy 13.759688 -121.177812) (xy 13.759169 -121.167261) (xy 13.750627 -121.147966)
			(xy 13.743178 -121.140474) (xy 13.724113 -121.122328) (xy 13.690657 -121.081696) (xy 13.6631 -121.036854)
			(xy 13.641963 -120.988651) (xy 13.627648 -120.938002) (xy 13.620425 -120.885867) (xy 13.619988 -120.85955)
			(xy 13.620474 -120.832299) (xy 13.62823 -120.778351) (xy 13.643585 -120.726056) (xy 13.666227 -120.676479)
			(xy 13.695693 -120.630629) (xy 13.731384 -120.589438) (xy 13.772575 -120.553747) (xy 13.818425 -120.524281)
			(xy 13.868002 -120.501639) (xy 13.920297 -120.486284) (xy 13.974245 -120.478528) (xy 14.028747 -120.478528)
			(xy 14.082695 -120.486284) (xy 14.13499 -120.501639) (xy 14.184567 -120.524281) (xy 14.230417 -120.553747)
			(xy 14.271608 -120.589438) (xy 14.307299 -120.630629) (xy 14.336765 -120.676479) (xy 14.359407 -120.726056)
			(xy 14.374762 -120.778351) (xy 14.382518 -120.832299) (xy 14.383004 -120.85955) (xy 14.382569 -120.885865)
			(xy 14.375327 -120.937995) (xy 14.361002 -120.988638) (xy 14.339863 -121.036837) (xy 14.312311 -121.08168)
			(xy 14.278868 -121.122318) (xy 14.259814 -121.140474) (xy 14.252424 -121.148005) (xy 14.243892 -121.167278)
			(xy 14.243304 -121.177812) (xy 14.243304 -121.252488) (xy 14.243825 -121.263039) (xy 14.252366 -121.282334)
			(xy 14.259814 -121.289826) (xy 14.278878 -121.307973) (xy 14.312334 -121.348605) (xy 14.339891 -121.393447)
			(xy 14.361028 -121.44165) (xy 14.375344 -121.492298) (xy 14.382567 -121.544433) (xy 14.383004 -121.57075)
			(xy 14.382518 -121.598001) (xy 14.374762 -121.651949) (xy 14.359407 -121.704244) (xy 14.336765 -121.753821)
			(xy 14.307299 -121.799671) (xy 14.271608 -121.840862) (xy 14.230417 -121.876553) (xy 14.184567 -121.906019)
			(xy 14.13499 -121.928661) (xy 14.082695 -121.944016) (xy 14.028747 -121.951772) (xy 13.974245 -121.951772)
			(xy 13.920297 -121.944016) (xy 13.868002 -121.928661) (xy 13.818425 -121.906019) (xy 13.772575 -121.876553)
			(xy 13.731384 -121.840862) (xy 13.695693 -121.799671) (xy 13.666227 -121.753821) (xy 13.643585 -121.704244)
			(xy 13.62823 -121.651949) (xy 13.620474 -121.598001) (xy 13.619988 -121.57075) (xy 5.720842 -121.57075)
			(xy 5.720842 -122.292618) (xy 9.780268 -122.292618) (xy 9.784339 -122.236996) (xy 9.796465 -122.182559)
			(xy 9.816388 -122.130468) (xy 9.843684 -122.081833) (xy 9.87777 -122.03769) (xy 9.917919 -121.998981)
			(xy 9.963277 -121.96653) (xy 10.012877 -121.941029) (xy 10.065661 -121.923022) (xy 10.120504 -121.912892)
			(xy 10.176238 -121.910855) (xy 10.231675 -121.916955) (xy 10.285632 -121.931061) (xy 10.336961 -121.952873)
			(xy 10.384567 -121.981927) (xy 10.427435 -122.017602) (xy 10.464652 -122.059139) (xy 10.495425 -122.105652)
			(xy 10.519097 -122.156149) (xy 10.535165 -122.209556) (xy 10.543285 -122.264732) (xy 10.543794 -122.292618)
			(xy 10.543285 -122.320504) (xy 10.535165 -122.37568) (xy 10.519097 -122.429087) (xy 10.49996 -122.46991)
			(xy 10.936984 -122.46991) (xy 10.941055 -122.414288) (xy 10.953181 -122.359851) (xy 10.973104 -122.30776)
			(xy 11.0004 -122.259125) (xy 11.034486 -122.214982) (xy 11.074635 -122.176273) (xy 11.119993 -122.143822)
			(xy 11.169593 -122.118321) (xy 11.222377 -122.100314) (xy 11.27722 -122.090184) (xy 11.332954 -122.088147)
			(xy 11.388391 -122.094247) (xy 11.442348 -122.108353) (xy 11.493677 -122.130165) (xy 11.541283 -122.159219)
			(xy 11.584151 -122.194894) (xy 11.621368 -122.236431) (xy 11.652141 -122.282944) (xy 11.675813 -122.333441)
			(xy 11.691881 -122.386848) (xy 11.700001 -122.442024) (xy 11.70051 -122.46991) (xy 11.700001 -122.497796)
			(xy 11.691881 -122.552972) (xy 11.675813 -122.606379) (xy 11.652141 -122.656876) (xy 11.621368 -122.703389)
			(xy 11.584151 -122.744926) (xy 11.541283 -122.780601) (xy 11.493677 -122.809655) (xy 11.442348 -122.831467)
			(xy 11.388391 -122.845573) (xy 11.332954 -122.851673) (xy 11.27722 -122.849636) (xy 11.222377 -122.839506)
			(xy 11.169593 -122.821499) (xy 11.119993 -122.795998) (xy 11.074635 -122.763547) (xy 11.034486 -122.724838)
			(xy 11.0004 -122.680695) (xy 10.973104 -122.63206) (xy 10.953181 -122.579969) (xy 10.941055 -122.525532)
			(xy 10.936984 -122.46991) (xy 10.49996 -122.46991) (xy 10.495425 -122.479584) (xy 10.464652 -122.526097)
			(xy 10.427435 -122.567634) (xy 10.384567 -122.603309) (xy 10.336961 -122.632363) (xy 10.285632 -122.654175)
			(xy 10.231675 -122.668281) (xy 10.176238 -122.674381) (xy 10.120504 -122.672344) (xy 10.065661 -122.662214)
			(xy 10.012877 -122.644207) (xy 9.963277 -122.618706) (xy 9.917919 -122.586255) (xy 9.87777 -122.547546)
			(xy 9.843684 -122.503403) (xy 9.816388 -122.454768) (xy 9.796465 -122.402677) (xy 9.784339 -122.34824)
			(xy 9.780268 -122.292618) (xy 5.720842 -122.292618) (xy 5.720842 -123.249761) (xy 11.91004 -123.249761)
			(xy 11.91004 -123.195259) (xy 11.917796 -123.141311) (xy 11.933151 -123.089017) (xy 11.955792 -123.03944)
			(xy 11.985258 -122.99359) (xy 12.02095 -122.9524) (xy 12.06214 -122.916708) (xy 12.10799 -122.887242)
			(xy 12.157567 -122.864601) (xy 12.209861 -122.849246) (xy 12.263809 -122.84149) (xy 12.29106 -122.841004)
			(xy 12.318091 -122.841459) (xy 12.371611 -122.849105) (xy 12.423513 -122.864236) (xy 12.472757 -122.886548)
			(xy 12.518354 -122.915593) (xy 12.559391 -122.950789) (xy 12.577572 -122.970798) (xy 12.577826 -122.971052)
			(xy 12.585282 -122.978685) (xy 12.604757 -122.987361) (xy 12.615418 -122.987816) (xy 12.703048 -122.988324)
			(xy 12.722606 -122.979688) (xy 12.729972 -122.971306) (xy 12.748153 -122.951603) (xy 12.78905 -122.916937)
			(xy 12.834401 -122.888346) (xy 12.883312 -122.866393) (xy 12.934818 -122.851514) (xy 12.9879 -122.844)
			(xy 13.014706 -122.843544) (xy 13.042077 -122.843996) (xy 13.096257 -122.851815) (xy 13.148761 -122.867307)
			(xy 13.198507 -122.890152) (xy 13.244473 -122.919881) (xy 13.265404 -122.937524) (xy 13.265658 -122.937778)
			(xy 13.272746 -122.943362) (xy 13.289662 -122.949608) (xy 13.298678 -122.94997) (xy 13.365734 -122.94997)
			(xy 13.374753 -122.949636) (xy 13.39167 -122.943373) (xy 13.398754 -122.937778) (xy 13.398754 -122.937524)
			(xy 13.399008 -122.937524) (xy 13.419941 -122.919883) (xy 13.465909 -122.890159) (xy 13.515655 -122.867313)
			(xy 13.568157 -122.851817) (xy 13.622335 -122.843988) (xy 13.677077 -122.843988) (xy 13.731255 -122.851817)
			(xy 13.783757 -122.867313) (xy 13.833503 -122.890159) (xy 13.879471 -122.919883) (xy 13.900404 -122.937524)
			(xy 13.900658 -122.937778) (xy 13.907746 -122.943362) (xy 13.924662 -122.949608) (xy 13.933678 -122.94997)
			(xy 14.000734 -122.94997) (xy 14.009753 -122.949636) (xy 14.02667 -122.943373) (xy 14.033754 -122.937778)
			(xy 14.034262 -122.937524) (xy 14.046999 -122.926583) (xy 14.074088 -122.90674) (xy 14.088364 -122.8979)
			(xy 14.097254 -122.892566) (xy 14.109446 -122.875548) (xy 14.129766 -122.78233) (xy 14.125448 -122.761756)
			(xy 14.119606 -122.75312) (xy 14.103613 -122.729052) (xy 14.078269 -122.677122) (xy 14.061041 -122.621965)
			(xy 14.052324 -122.564842) (xy 14.051788 -122.53595) (xy 14.052274 -122.508699) (xy 14.06003 -122.454751)
			(xy 14.075385 -122.402456) (xy 14.098027 -122.352879) (xy 14.127493 -122.307029) (xy 14.163184 -122.265838)
			(xy 14.204375 -122.230147) (xy 14.250225 -122.200681) (xy 14.299802 -122.178039) (xy 14.352097 -122.162684)
			(xy 14.406045 -122.154928) (xy 14.460547 -122.154928) (xy 14.514495 -122.162684) (xy 14.56679 -122.178039)
			(xy 14.616367 -122.200681) (xy 14.662217 -122.230147) (xy 14.703408 -122.265838) (xy 14.739099 -122.307029)
			(xy 14.768565 -122.352879) (xy 14.791207 -122.402456) (xy 14.806562 -122.454751) (xy 14.814318 -122.508699)
			(xy 14.814804 -122.53595) (xy 14.814277 -122.56404) (xy 14.806056 -122.619616) (xy 14.789771 -122.673385)
			(xy 14.765774 -122.724183) (xy 14.734584 -122.77091) (xy 14.696876 -122.812556) (xy 14.653467 -122.848219)
			(xy 14.629638 -122.863102) (xy 14.620748 -122.868436) (xy 14.608556 -122.885454) (xy 14.588236 -122.978672)
			(xy 14.592554 -122.999246) (xy 14.598396 -123.007882) (xy 14.61439 -123.03195) (xy 14.639734 -123.08388)
			(xy 14.656962 -123.139036) (xy 14.665678 -123.19616) (xy 14.666214 -123.225052) (xy 14.6657 -123.252303)
			(xy 14.65795 -123.306252) (xy 14.6426 -123.358549) (xy 14.619964 -123.408128) (xy 14.590501 -123.453981)
			(xy 14.554813 -123.495174) (xy 14.513625 -123.530869) (xy 14.467776 -123.560338) (xy 14.418199 -123.582981)
			(xy 14.365905 -123.598338) (xy 14.311957 -123.606096) (xy 14.284706 -123.60656) (xy 14.257335 -123.6061)
			(xy 14.203156 -123.598282) (xy 14.150652 -123.582792) (xy 14.100905 -123.559949) (xy 14.054939 -123.530222)
			(xy 14.034008 -123.51258) (xy 14.033754 -123.512326) (xy 14.026662 -123.506747) (xy 14.009749 -123.500498)
			(xy 14.000734 -123.500134) (xy 13.933678 -123.500134) (xy 13.924659 -123.500473) (xy 13.907742 -123.506732)
			(xy 13.900658 -123.512326) (xy 13.900404 -123.51258) (xy 13.879471 -123.530221) (xy 13.833503 -123.559945)
			(xy 13.783757 -123.582791) (xy 13.731255 -123.598287) (xy 13.677077 -123.606116) (xy 13.622335 -123.606116)
			(xy 13.568157 -123.598287) (xy 13.515655 -123.582791) (xy 13.465909 -123.559945) (xy 13.419941 -123.530221)
			(xy 13.399008 -123.51258) (xy 13.398754 -123.512326) (xy 13.391662 -123.506747) (xy 13.374749 -123.500498)
			(xy 13.365734 -123.500134) (xy 13.298678 -123.500134) (xy 13.289659 -123.500473) (xy 13.272742 -123.506732)
			(xy 13.265658 -123.512326) (xy 13.265658 -123.51258) (xy 13.265404 -123.51258) (xy 13.244479 -123.530228)
			(xy 13.198504 -123.559939) (xy 13.148755 -123.582773) (xy 13.096253 -123.598262) (xy 13.042076 -123.606088)
			(xy 13.014706 -123.60656) (xy 12.987675 -123.606107) (xy 12.934156 -123.598457) (xy 12.882255 -123.583325)
			(xy 12.833012 -123.561012) (xy 12.787414 -123.531968) (xy 12.746376 -123.496774) (xy 12.728194 -123.476766)
			(xy 12.72794 -123.476512) (xy 12.720488 -123.468874) (xy 12.70101 -123.460199) (xy 12.690348 -123.459748)
			(xy 12.602718 -123.45924) (xy 12.58316 -123.467876) (xy 12.575794 -123.476258) (xy 12.557643 -123.495991)
			(xy 12.516739 -123.530651) (xy 12.471381 -123.559237) (xy 12.422464 -123.581184) (xy 12.370954 -123.596059)
			(xy 12.317867 -123.603567) (xy 12.29106 -123.60402) (xy 12.263809 -123.60353) (xy 12.209861 -123.595774)
			(xy 12.157567 -123.580419) (xy 12.10799 -123.557778) (xy 12.06214 -123.528312) (xy 12.02095 -123.49262)
			(xy 11.985258 -123.45143) (xy 11.955792 -123.40558) (xy 11.933151 -123.356003) (xy 11.917796 -123.303709)
			(xy 11.91004 -123.249761) (xy 5.720842 -123.249761) (xy 5.720842 -124.963428) (xy 8.673082 -124.963428)
			(xy 8.677153 -124.907806) (xy 8.689279 -124.853369) (xy 8.709202 -124.801278) (xy 8.736498 -124.752643)
			(xy 8.770584 -124.7085) (xy 8.810733 -124.669791) (xy 8.856091 -124.63734) (xy 8.905691 -124.611839)
			(xy 8.958475 -124.593832) (xy 9.013318 -124.583702) (xy 9.069052 -124.581665) (xy 9.124489 -124.587765)
			(xy 9.178446 -124.601871) (xy 9.229775 -124.623683) (xy 9.277381 -124.652737) (xy 9.320249 -124.688412)
			(xy 9.357466 -124.729949) (xy 9.388239 -124.776462) (xy 9.411911 -124.826959) (xy 9.427979 -124.880366)
			(xy 9.436099 -124.935542) (xy 9.436608 -124.963428) (xy 9.436099 -124.991314) (xy 9.435493 -124.995432)
			(xy 10.780774 -124.995432) (xy 10.784845 -124.93981) (xy 10.796971 -124.885373) (xy 10.816894 -124.833282)
			(xy 10.84419 -124.784647) (xy 10.878276 -124.740504) (xy 10.918425 -124.701795) (xy 10.963783 -124.669344)
			(xy 11.013383 -124.643843) (xy 11.066167 -124.625836) (xy 11.12101 -124.615706) (xy 11.176744 -124.613669)
			(xy 11.232181 -124.619769) (xy 11.286138 -124.633875) (xy 11.337467 -124.655687) (xy 11.385073 -124.684741)
			(xy 11.427941 -124.720416) (xy 11.465158 -124.761953) (xy 11.495931 -124.808466) (xy 11.519603 -124.858963)
			(xy 11.535671 -124.91237) (xy 11.543791 -124.967546) (xy 11.5443 -124.995432) (xy 11.543791 -125.023318)
			(xy 11.535671 -125.078494) (xy 11.519603 -125.131901) (xy 11.495931 -125.182398) (xy 11.465158 -125.228911)
			(xy 11.427941 -125.270448) (xy 11.385073 -125.306123) (xy 11.337467 -125.335177) (xy 11.286138 -125.356989)
			(xy 11.232181 -125.371095) (xy 11.176744 -125.377195) (xy 11.12101 -125.375158) (xy 11.066167 -125.365028)
			(xy 11.013383 -125.347021) (xy 10.963783 -125.32152) (xy 10.918425 -125.289069) (xy 10.878276 -125.25036)
			(xy 10.84419 -125.206217) (xy 10.816894 -125.157582) (xy 10.796971 -125.105491) (xy 10.784845 -125.051054)
			(xy 10.780774 -124.995432) (xy 9.435493 -124.995432) (xy 9.427979 -125.04649) (xy 9.411911 -125.099897)
			(xy 9.388239 -125.150394) (xy 9.357466 -125.196907) (xy 9.320249 -125.238444) (xy 9.277381 -125.274119)
			(xy 9.229775 -125.303173) (xy 9.178446 -125.324985) (xy 9.124489 -125.339091) (xy 9.069052 -125.345191)
			(xy 9.013318 -125.343154) (xy 8.958475 -125.333024) (xy 8.905691 -125.315017) (xy 8.856091 -125.289516)
			(xy 8.810733 -125.257065) (xy 8.770584 -125.218356) (xy 8.736498 -125.174213) (xy 8.709202 -125.125578)
			(xy 8.689279 -125.073487) (xy 8.677153 -125.01905) (xy 8.673082 -124.963428) (xy 5.720842 -124.963428)
			(xy 5.720842 -125.403356) (xy 15.544292 -125.403356) (xy 15.544793 -125.375987) (xy 15.552603 -125.32181)
			(xy 15.568084 -125.269307) (xy 15.590918 -125.219559) (xy 15.620634 -125.173591) (xy 15.638272 -125.152658)
			(xy 15.638526 -125.152404) (xy 15.64412 -125.145323) (xy 15.650361 -125.128402) (xy 15.650718 -125.119384)
			(xy 15.650718 -125.052328) (xy 15.650344 -125.043313) (xy 15.644108 -125.026396) (xy 15.638526 -125.019308)
			(xy 15.638272 -125.019308) (xy 15.638272 -125.019054) (xy 15.62064 -124.998116) (xy 15.590928 -124.952144)
			(xy 15.568091 -124.902398) (xy 15.552599 -124.849899) (xy 15.544768 -124.795725) (xy 15.544292 -124.768356)
			(xy 15.544778 -124.741105) (xy 15.552534 -124.687157) (xy 15.567889 -124.634862) (xy 15.590531 -124.585285)
			(xy 15.619997 -124.539435) (xy 15.655688 -124.498244) (xy 15.696879 -124.462553) (xy 15.742729 -124.433087)
			(xy 15.792306 -124.410445) (xy 15.844601 -124.39509) (xy 15.898549 -124.387334) (xy 15.953051 -124.387334)
			(xy 16.006999 -124.39509) (xy 16.059294 -124.410445) (xy 16.108871 -124.433087) (xy 16.154721 -124.462553)
			(xy 16.195912 -124.498244) (xy 16.231603 -124.539435) (xy 16.261069 -124.585285) (xy 16.283711 -124.634862)
			(xy 16.299066 -124.687157) (xy 16.306822 -124.741105) (xy 16.307308 -124.768356) (xy 16.306814 -124.795725)
			(xy 16.299003 -124.849903) (xy 16.28352 -124.902406) (xy 16.260685 -124.952153) (xy 16.230966 -124.998121)
			(xy 16.213328 -125.019054) (xy 16.213074 -125.019308) (xy 16.207475 -125.026386) (xy 16.201237 -125.043309)
			(xy 16.200882 -125.052328) (xy 16.200882 -125.119384) (xy 16.201251 -125.1284) (xy 16.207491 -125.145316)
			(xy 16.213074 -125.152404) (xy 16.213328 -125.152404) (xy 16.213328 -125.152658) (xy 16.230965 -125.173591)
			(xy 16.260676 -125.219564) (xy 16.283512 -125.269312) (xy 16.299004 -125.321812) (xy 16.306833 -125.375987)
			(xy 16.307308 -125.403356) (xy 16.306822 -125.430607) (xy 16.299066 -125.484555) (xy 16.283711 -125.53685)
			(xy 16.261069 -125.586427) (xy 16.231603 -125.632277) (xy 16.195912 -125.673468) (xy 16.154721 -125.709159)
			(xy 16.108871 -125.738625) (xy 16.059294 -125.761267) (xy 16.006999 -125.776622) (xy 15.953051 -125.784378)
			(xy 15.898549 -125.784378) (xy 15.844601 -125.776622) (xy 15.792306 -125.761267) (xy 15.742729 -125.738625)
			(xy 15.696879 -125.709159) (xy 15.655688 -125.673468) (xy 15.619997 -125.632277) (xy 15.590531 -125.586427)
			(xy 15.567889 -125.53685) (xy 15.552534 -125.484555) (xy 15.544778 -125.430607) (xy 15.544292 -125.403356)
			(xy 5.720842 -125.403356) (xy 5.720842 -125.979428) (xy 8.673082 -125.979428) (xy 8.677153 -125.923806)
			(xy 8.689279 -125.869369) (xy 8.709202 -125.817278) (xy 8.736498 -125.768643) (xy 8.770584 -125.7245)
			(xy 8.810733 -125.685791) (xy 8.856091 -125.65334) (xy 8.905691 -125.627839) (xy 8.958475 -125.609832)
			(xy 9.013318 -125.599702) (xy 9.069052 -125.597665) (xy 9.124489 -125.603765) (xy 9.178446 -125.617871)
			(xy 9.229775 -125.639683) (xy 9.277381 -125.668737) (xy 9.320249 -125.704412) (xy 9.357466 -125.745949)
			(xy 9.388239 -125.792462) (xy 9.411911 -125.842959) (xy 9.427979 -125.896366) (xy 9.436099 -125.951542)
			(xy 9.436608 -125.979428) (xy 9.436557 -125.982222) (xy 11.113006 -125.982222) (xy 11.117077 -125.9266)
			(xy 11.129203 -125.872163) (xy 11.149126 -125.820072) (xy 11.176422 -125.771437) (xy 11.210508 -125.727294)
			(xy 11.250657 -125.688585) (xy 11.296015 -125.656134) (xy 11.345615 -125.630633) (xy 11.398399 -125.612626)
			(xy 11.453242 -125.602496) (xy 11.508976 -125.600459) (xy 11.564413 -125.606559) (xy 11.61837 -125.620665)
			(xy 11.669699 -125.642477) (xy 11.717305 -125.671531) (xy 11.760173 -125.707206) (xy 11.79739 -125.748743)
			(xy 11.828163 -125.795256) (xy 11.851835 -125.845753) (xy 11.854225 -125.853698) (xy 16.484854 -125.853698)
			(xy 16.485306 -125.826327) (xy 16.493125 -125.772147) (xy 16.508617 -125.719643) (xy 16.531462 -125.669896)
			(xy 16.561191 -125.623931) (xy 16.578834 -125.603) (xy 16.579088 -125.602746) (xy 16.58466 -125.595649)
			(xy 16.590916 -125.57874) (xy 16.59128 -125.569726) (xy 16.59128 -125.50267) (xy 16.590942 -125.493651)
			(xy 16.584682 -125.476734) (xy 16.579088 -125.46965) (xy 16.578834 -125.46965) (xy 16.578834 -125.469396)
			(xy 16.561185 -125.448472) (xy 16.531473 -125.402497) (xy 16.508639 -125.352748) (xy 16.49315 -125.300245)
			(xy 16.485326 -125.246068) (xy 16.484854 -125.218698) (xy 16.48534 -125.191447) (xy 16.493096 -125.137499)
			(xy 16.508451 -125.085204) (xy 16.531093 -125.035627) (xy 16.560559 -124.989777) (xy 16.59625 -124.948586)
			(xy 16.637441 -124.912895) (xy 16.683291 -124.883429) (xy 16.732868 -124.860787) (xy 16.785163 -124.845432)
			(xy 16.839111 -124.837676) (xy 16.893613 -124.837676) (xy 16.947561 -124.845432) (xy 16.999856 -124.860787)
			(xy 17.049433 -124.883429) (xy 17.095283 -124.912895) (xy 17.136474 -124.948586) (xy 17.172165 -124.989777)
			(xy 17.201631 -125.035627) (xy 17.224273 -125.085204) (xy 17.239628 -125.137499) (xy 17.247384 -125.191447)
			(xy 17.24787 -125.218698) (xy 17.24741 -125.246069) (xy 17.239592 -125.300248) (xy 17.224102 -125.352752)
			(xy 17.201258 -125.402498) (xy 17.171532 -125.448465) (xy 17.15389 -125.469396) (xy 17.153636 -125.46965)
			(xy 17.148057 -125.476741) (xy 17.141807 -125.493655) (xy 17.141444 -125.50267) (xy 17.141444 -125.569726)
			(xy 17.141779 -125.578745) (xy 17.148041 -125.595663) (xy 17.153636 -125.602746) (xy 17.15389 -125.602746)
			(xy 17.15389 -125.603) (xy 17.171541 -125.623923) (xy 17.201251 -125.669898) (xy 17.224085 -125.719648)
			(xy 17.239573 -125.772151) (xy 17.247398 -125.826328) (xy 17.24787 -125.853698) (xy 17.247384 -125.880949)
			(xy 17.239628 -125.934897) (xy 17.224273 -125.987192) (xy 17.201631 -126.036769) (xy 17.172165 -126.082619)
			(xy 17.136474 -126.12381) (xy 17.095283 -126.159501) (xy 17.049433 -126.188967) (xy 16.999856 -126.211609)
			(xy 16.947561 -126.226964) (xy 16.893613 -126.23472) (xy 16.839111 -126.23472) (xy 16.785163 -126.226964)
			(xy 16.732868 -126.211609) (xy 16.683291 -126.188967) (xy 16.637441 -126.159501) (xy 16.59625 -126.12381)
			(xy 16.560559 -126.082619) (xy 16.531093 -126.036769) (xy 16.508451 -125.987192) (xy 16.493096 -125.934897)
			(xy 16.48534 -125.880949) (xy 16.484854 -125.853698) (xy 11.854225 -125.853698) (xy 11.867903 -125.89916)
			(xy 11.876023 -125.954336) (xy 11.876532 -125.982222) (xy 11.876023 -126.010108) (xy 11.867903 -126.065284)
			(xy 11.851835 -126.118691) (xy 11.828163 -126.169188) (xy 11.79739 -126.215701) (xy 11.760173 -126.257238)
			(xy 11.717305 -126.292913) (xy 11.669699 -126.321967) (xy 11.61837 -126.343779) (xy 11.564413 -126.357885)
			(xy 11.508976 -126.363985) (xy 11.453242 -126.361948) (xy 11.398399 -126.351818) (xy 11.345615 -126.333811)
			(xy 11.296015 -126.30831) (xy 11.250657 -126.275859) (xy 11.210508 -126.23715) (xy 11.176422 -126.193007)
			(xy 11.149126 -126.144372) (xy 11.129203 -126.092281) (xy 11.117077 -126.037844) (xy 11.113006 -125.982222)
			(xy 9.436557 -125.982222) (xy 9.436099 -126.007314) (xy 9.427979 -126.06249) (xy 9.411911 -126.115897)
			(xy 9.388239 -126.166394) (xy 9.357466 -126.212907) (xy 9.320249 -126.254444) (xy 9.277381 -126.290119)
			(xy 9.229775 -126.319173) (xy 9.178446 -126.340985) (xy 9.124489 -126.355091) (xy 9.069052 -126.361191)
			(xy 9.013318 -126.359154) (xy 8.958475 -126.349024) (xy 8.905691 -126.331017) (xy 8.856091 -126.305516)
			(xy 8.810733 -126.273065) (xy 8.770584 -126.234356) (xy 8.736498 -126.190213) (xy 8.709202 -126.141578)
			(xy 8.689279 -126.089487) (xy 8.677153 -126.03505) (xy 8.673082 -125.979428) (xy 5.720842 -125.979428)
			(xy 5.720842 -126.530354) (xy 17.769586 -126.530354) (xy 17.770111 -126.501437) (xy 17.778834 -126.444265)
			(xy 17.796088 -126.389065) (xy 17.821479 -126.337102) (xy 17.854423 -126.289568) (xy 17.894166 -126.247553)
			(xy 17.916652 -126.229364) (xy 17.925474 -126.221772) (xy 17.935648 -126.200859) (xy 17.93621 -126.189232)
			(xy 17.93621 -126.109476) (xy 17.935667 -126.097845) (xy 17.92548 -126.076936) (xy 17.916652 -126.069344)
			(xy 17.89418 -126.05114) (xy 17.854446 -126.009122) (xy 17.821507 -125.961589) (xy 17.796117 -125.90963)
			(xy 17.778858 -125.854436) (xy 17.770124 -125.797269) (xy 17.769586 -125.768354) (xy 17.770035 -125.741102)
			(xy 17.777798 -125.687153) (xy 17.793158 -125.634858) (xy 17.815804 -125.585281) (xy 17.845275 -125.539431)
			(xy 17.88097 -125.498242) (xy 17.922163 -125.462551) (xy 17.968016 -125.433085) (xy 18.017596 -125.410444)
			(xy 18.069892 -125.395089) (xy 18.123842 -125.387332) (xy 18.151094 -125.386846) (xy 18.178465 -125.387304)
			(xy 18.232645 -125.395122) (xy 18.285148 -125.410613) (xy 18.334895 -125.433456) (xy 18.380861 -125.463183)
			(xy 18.401792 -125.480826) (xy 18.402046 -125.48108) (xy 18.409137 -125.486659) (xy 18.426051 -125.492908)
			(xy 18.435066 -125.493272) (xy 18.502122 -125.493272) (xy 18.511141 -125.492932) (xy 18.528058 -125.486673)
			(xy 18.535142 -125.48108) (xy 18.535142 -125.480826) (xy 18.535396 -125.480826) (xy 18.556322 -125.463179)
			(xy 18.602296 -125.433468) (xy 18.652045 -125.410633) (xy 18.704547 -125.395144) (xy 18.758724 -125.387318)
			(xy 18.786094 -125.386846) (xy 18.813343 -125.387383) (xy 18.867287 -125.395138) (xy 18.919577 -125.41049)
			(xy 18.969152 -125.433127) (xy 19.015 -125.462588) (xy 19.056189 -125.498274) (xy 19.091881 -125.539458)
			(xy 19.121348 -125.585303) (xy 19.143992 -125.634874) (xy 19.159351 -125.687163) (xy 19.167113 -125.741105)
			(xy 19.167602 -125.768354) (xy 19.16705 -125.79727) (xy 19.158328 -125.854439) (xy 19.141076 -125.909637)
			(xy 19.115691 -125.961599) (xy 19.082754 -126.009134) (xy 19.043019 -126.051153) (xy 19.020536 -126.069344)
			(xy 19.011708 -126.076931) (xy 19.001538 -126.097847) (xy 19.000978 -126.109476) (xy 19.000978 -126.189232)
			(xy 19.001521 -126.200863) (xy 19.011708 -126.221772) (xy 19.020536 -126.229364) (xy 19.04301 -126.247566)
			(xy 19.082744 -126.289585) (xy 19.115683 -126.337118) (xy 19.141073 -126.389077) (xy 19.158332 -126.444272)
			(xy 19.167065 -126.501439) (xy 19.167602 -126.530354) (xy 19.167102 -126.557606) (xy 19.159351 -126.611556)
			(xy 19.144001 -126.663853) (xy 19.121363 -126.713434) (xy 19.091899 -126.759287) (xy 19.056209 -126.800481)
			(xy 19.01502 -126.836175) (xy 18.969169 -126.865644) (xy 18.919591 -126.888287) (xy 18.867295 -126.903643)
			(xy 18.813346 -126.911399) (xy 18.786094 -126.911862) (xy 18.758723 -126.911409) (xy 18.704543 -126.903589)
			(xy 18.65204 -126.888098) (xy 18.602293 -126.865253) (xy 18.556327 -126.835525) (xy 18.535396 -126.817882)
			(xy 18.535142 -126.817628) (xy 18.528054 -126.812044) (xy 18.511138 -126.805798) (xy 18.502122 -126.805436)
			(xy 18.435066 -126.805436) (xy 18.426047 -126.805769) (xy 18.409129 -126.812032) (xy 18.402046 -126.817628)
			(xy 18.402046 -126.817882) (xy 18.401792 -126.817882) (xy 18.380871 -126.835536) (xy 18.334896 -126.865246)
			(xy 18.285145 -126.888079) (xy 18.232642 -126.903567) (xy 18.178464 -126.911391) (xy 18.151094 -126.911862)
			(xy 18.123839 -126.91145) (xy 18.069884 -126.903691) (xy 18.017582 -126.888332) (xy 17.967999 -126.865685)
			(xy 17.922144 -126.836213) (xy 17.88095 -126.800513) (xy 17.845256 -126.759315) (xy 17.81579 -126.713455)
			(xy 17.79315 -126.663869) (xy 17.777798 -126.611565) (xy 17.770046 -126.557609) (xy 17.769586 -126.530354)
			(xy 5.720842 -126.530354) (xy 5.720842 -127.051308) (xy 10.744198 -127.051308) (xy 10.748269 -126.995686)
			(xy 10.760395 -126.941249) (xy 10.780318 -126.889158) (xy 10.807614 -126.840523) (xy 10.8417 -126.79638)
			(xy 10.881849 -126.757671) (xy 10.927207 -126.72522) (xy 10.976807 -126.699719) (xy 11.029591 -126.681712)
			(xy 11.084434 -126.671582) (xy 11.140168 -126.669545) (xy 11.195605 -126.675645) (xy 11.249562 -126.689751)
			(xy 11.300891 -126.711563) (xy 11.348497 -126.740617) (xy 11.391365 -126.776292) (xy 11.428582 -126.817829)
			(xy 11.459355 -126.864342) (xy 11.483027 -126.914839) (xy 11.499095 -126.968246) (xy 11.507215 -127.023422)
			(xy 11.507724 -127.051308) (xy 11.507215 -127.079194) (xy 11.499095 -127.13437) (xy 11.483027 -127.187777)
			(xy 11.459355 -127.238274) (xy 11.428582 -127.284787) (xy 11.391365 -127.326324) (xy 11.348497 -127.361999)
			(xy 11.300891 -127.391053) (xy 11.249562 -127.412865) (xy 11.195605 -127.426971) (xy 11.140168 -127.433071)
			(xy 11.084434 -127.431034) (xy 11.029591 -127.420904) (xy 10.976807 -127.402897) (xy 10.927207 -127.377396)
			(xy 10.881849 -127.344945) (xy 10.8417 -127.306236) (xy 10.807614 -127.262093) (xy 10.780318 -127.213458)
			(xy 10.760395 -127.161367) (xy 10.748269 -127.10693) (xy 10.744198 -127.051308) (xy 5.720842 -127.051308)
			(xy 5.720842 -128.252803) (xy 9.728405 -128.252803) (xy 9.728405 -128.198297) (xy 9.736162 -128.144346)
			(xy 9.751519 -128.092048) (xy 9.774161 -128.042467) (xy 9.80363 -127.996614) (xy 9.839324 -127.955421)
			(xy 9.880517 -127.919727) (xy 9.926371 -127.89026) (xy 9.975951 -127.867617) (xy 10.02825 -127.852262)
			(xy 10.082201 -127.844505) (xy 10.109454 -127.844042) (xy 10.136824 -127.844525) (xy 10.191003 -127.852337)
			(xy 10.243506 -127.867822) (xy 10.293253 -127.89066) (xy 10.33922 -127.920382) (xy 10.360152 -127.938022)
			(xy 10.360406 -127.938276) (xy 10.36748 -127.94388) (xy 10.384407 -127.950114) (xy 10.393426 -127.950468)
			(xy 10.460482 -127.950468) (xy 10.469499 -127.950109) (xy 10.486416 -127.943863) (xy 10.493502 -127.938276)
			(xy 10.493502 -127.938022) (xy 10.493756 -127.938022) (xy 10.514689 -127.920381) (xy 10.560657 -127.890657)
			(xy 10.610403 -127.867811) (xy 10.662905 -127.852315) (xy 10.717083 -127.844486) (xy 10.771825 -127.844486)
			(xy 10.826003 -127.852315) (xy 10.878505 -127.867811) (xy 10.928251 -127.890657) (xy 10.974219 -127.920381)
			(xy 10.995152 -127.938022) (xy 10.995406 -127.938276) (xy 11.00248 -127.94388) (xy 11.019407 -127.950114)
			(xy 11.028426 -127.950468) (xy 11.095482 -127.950468) (xy 11.104499 -127.950109) (xy 11.121416 -127.943863)
			(xy 11.128502 -127.938276) (xy 11.128502 -127.938022) (xy 11.128756 -127.938022) (xy 11.149697 -127.920393)
			(xy 11.195667 -127.890679) (xy 11.245412 -127.867841) (xy 11.297911 -127.852348) (xy 11.352085 -127.844517)
			(xy 11.379454 -127.844042) (xy 11.406705 -127.844528) (xy 11.460652 -127.852285) (xy 11.512947 -127.867641)
			(xy 11.562523 -127.890282) (xy 11.608373 -127.919748) (xy 11.649563 -127.95544) (xy 11.685254 -127.99663)
			(xy 11.71472 -128.04248) (xy 11.737361 -128.092057) (xy 11.752716 -128.144352) (xy 11.760472 -128.198299)
			(xy 11.760472 -128.252801) (xy 11.752716 -128.306748) (xy 11.737361 -128.359043) (xy 11.71472 -128.40862)
			(xy 11.685254 -128.45447) (xy 11.649563 -128.49566) (xy 11.608373 -128.531352) (xy 11.562523 -128.560818)
			(xy 11.512947 -128.583459) (xy 11.460652 -128.598815) (xy 11.406705 -128.606572) (xy 11.379454 -128.607058)
			(xy 11.352084 -128.606571) (xy 11.297906 -128.598759) (xy 11.245403 -128.583276) (xy 11.195655 -128.560439)
			(xy 11.149688 -128.530718) (xy 11.128756 -128.513078) (xy 11.128502 -128.512824) (xy 11.121425 -128.507223)
			(xy 11.104501 -128.500987) (xy 11.095482 -128.500632) (xy 11.028426 -128.500632) (xy 11.01941 -128.500995)
			(xy 11.002492 -128.507238) (xy 10.995406 -128.512824) (xy 10.995152 -128.513078) (xy 10.974219 -128.530719)
			(xy 10.928251 -128.560443) (xy 10.878505 -128.583289) (xy 10.826003 -128.598785) (xy 10.771825 -128.606614)
			(xy 10.717083 -128.606614) (xy 10.662905 -128.598785) (xy 10.610403 -128.583289) (xy 10.560657 -128.560443)
			(xy 10.514689 -128.530719) (xy 10.493756 -128.513078) (xy 10.493502 -128.512824) (xy 10.486425 -128.507223)
			(xy 10.469501 -128.500987) (xy 10.460482 -128.500632) (xy 10.393426 -128.500632) (xy 10.38441 -128.500995)
			(xy 10.367492 -128.507238) (xy 10.360406 -128.512824) (xy 10.360406 -128.513078) (xy 10.360152 -128.513078)
			(xy 10.339208 -128.530703) (xy 10.293239 -128.560418) (xy 10.243495 -128.583257) (xy 10.190996 -128.598751)
			(xy 10.136822 -128.606582) (xy 10.109454 -128.607058) (xy 10.082201 -128.606595) (xy 10.02825 -128.598838)
			(xy 9.975951 -128.583483) (xy 9.926371 -128.56084) (xy 9.880517 -128.531373) (xy 9.839324 -128.495679)
			(xy 9.80363 -128.454486) (xy 9.774161 -128.408633) (xy 9.751519 -128.359052) (xy 9.736162 -128.306754)
			(xy 9.728405 -128.252803) (xy 5.720842 -128.252803) (xy 5.720842 -131.447101) (xy 9.713452 -131.447101)
			(xy 9.713452 -131.392599) (xy 9.721208 -131.338652) (xy 9.736563 -131.286358) (xy 9.759204 -131.236782)
			(xy 9.78867 -131.190932) (xy 9.824361 -131.149742) (xy 9.86555 -131.114051) (xy 9.9114 -131.084585)
			(xy 9.960976 -131.061944) (xy 10.01327 -131.046589) (xy 10.067217 -131.038832) (xy 10.094468 -131.038346)
			(xy 10.121838 -131.03882) (xy 10.176017 -131.046634) (xy 10.228521 -131.062121) (xy 10.278268 -131.084961)
			(xy 10.324235 -131.114685) (xy 10.345166 -131.132326) (xy 10.34542 -131.13258) (xy 10.35249 -131.13819)
			(xy 10.36942 -131.144421) (xy 10.37844 -131.144772) (xy 10.445496 -131.144772) (xy 10.454513 -131.144419)
			(xy 10.471431 -131.13817) (xy 10.478516 -131.13258) (xy 10.478516 -131.132326) (xy 10.47877 -131.132326)
			(xy 10.499703 -131.114685) (xy 10.545671 -131.084961) (xy 10.595417 -131.062115) (xy 10.647919 -131.046619)
			(xy 10.702097 -131.03879) (xy 10.756839 -131.03879) (xy 10.811017 -131.046619) (xy 10.863519 -131.062115)
			(xy 10.913265 -131.084961) (xy 10.959233 -131.114685) (xy 10.980166 -131.132326) (xy 10.98042 -131.13258)
			(xy 10.98749 -131.13819) (xy 11.00442 -131.144421) (xy 11.01344 -131.144772) (xy 11.080496 -131.144772)
			(xy 11.089513 -131.144419) (xy 11.106431 -131.13817) (xy 11.113516 -131.13258) (xy 11.113516 -131.132326)
			(xy 11.11377 -131.132326) (xy 11.134706 -131.114692) (xy 11.180677 -131.084978) (xy 11.230424 -131.062141)
			(xy 11.282924 -131.046649) (xy 11.337099 -131.03882) (xy 11.364468 -131.038346) (xy 11.391721 -131.038801)
			(xy 11.445673 -131.046558) (xy 11.497972 -131.061914) (xy 11.547552 -131.084557) (xy 11.593406 -131.114025)
			(xy 11.6346 -131.149719) (xy 11.670294 -131.190912) (xy 11.699762 -131.236766) (xy 11.722405 -131.286347)
			(xy 11.737762 -131.338645) (xy 11.745519 -131.392597) (xy 11.745519 -131.447103) (xy 11.737762 -131.501055)
			(xy 11.722405 -131.553353) (xy 11.699762 -131.602934) (xy 11.670294 -131.648788) (xy 11.6346 -131.689981)
			(xy 11.593406 -131.725675) (xy 11.547552 -131.755143) (xy 11.497972 -131.777786) (xy 11.445673 -131.793142)
			(xy 11.391721 -131.800899) (xy 11.364468 -131.801362) (xy 11.337097 -131.800924) (xy 11.282916 -131.793101)
			(xy 11.230412 -131.777606) (xy 11.180666 -131.754757) (xy 11.1347 -131.725026) (xy 11.11377 -131.707382)
			(xy 11.113516 -131.707128) (xy 11.106435 -131.701534) (xy 11.089514 -131.695294) (xy 11.080496 -131.694936)
			(xy 11.01344 -131.694936) (xy 11.004424 -131.695304) (xy 10.987507 -131.701543) (xy 10.98042 -131.707128)
			(xy 10.980166 -131.707382) (xy 10.959233 -131.725023) (xy 10.913265 -131.754747) (xy 10.863519 -131.777593)
			(xy 10.811017 -131.793089) (xy 10.756839 -131.800918) (xy 10.702097 -131.800918) (xy 10.647919 -131.793089)
			(xy 10.595417 -131.777593) (xy 10.545671 -131.754747) (xy 10.499703 -131.725023) (xy 10.47877 -131.707382)
			(xy 10.478516 -131.707128) (xy 10.471435 -131.701534) (xy 10.454514 -131.695294) (xy 10.445496 -131.694936)
			(xy 10.37844 -131.694936) (xy 10.369424 -131.695304) (xy 10.352507 -131.701543) (xy 10.34542 -131.707128)
			(xy 10.34542 -131.707382) (xy 10.345166 -131.707382) (xy 10.324218 -131.725001) (xy 10.27825 -131.754716)
			(xy 10.228506 -131.777556) (xy 10.176009 -131.793052) (xy 10.121836 -131.800885) (xy 10.094468 -131.801362)
			(xy 10.067217 -131.800868) (xy 10.01327 -131.793111) (xy 9.960976 -131.777756) (xy 9.9114 -131.755115)
			(xy 9.86555 -131.725649) (xy 9.824361 -131.689958) (xy 9.78867 -131.648768) (xy 9.759204 -131.602918)
			(xy 9.736563 -131.553342) (xy 9.721208 -131.501048) (xy 9.713452 -131.447101) (xy 5.720842 -131.447101)
			(xy 5.720842 -133.443726) (xy 11.122914 -133.443726) (xy 11.123394 -133.417412) (xy 11.130626 -133.365284)
			(xy 11.144942 -133.314642) (xy 11.166072 -133.266442) (xy 11.193616 -133.221599) (xy 11.227053 -133.180959)
			(xy 11.246104 -133.162802) (xy 11.253507 -133.155282) (xy 11.26203 -133.136001) (xy 11.262614 -133.125464)
			(xy 11.262614 -133.050788) (xy 11.262101 -133.040237) (xy 11.253554 -133.020942) (xy 11.246104 -133.01345)
			(xy 11.227032 -132.995311) (xy 11.193576 -132.954678) (xy 11.166019 -132.909834) (xy 11.144884 -132.86163)
			(xy 11.13057 -132.81098) (xy 11.12335 -132.758843) (xy 11.122914 -132.732526) (xy 11.1234 -132.705275)
			(xy 11.131156 -132.651327) (xy 11.146511 -132.599032) (xy 11.169153 -132.549455) (xy 11.198619 -132.503605)
			(xy 11.23431 -132.462414) (xy 11.275501 -132.426723) (xy 11.321351 -132.397257) (xy 11.370928 -132.374615)
			(xy 11.423223 -132.35926) (xy 11.477171 -132.351504) (xy 11.531673 -132.351504) (xy 11.585621 -132.35926)
			(xy 11.637916 -132.374615) (xy 11.687493 -132.397257) (xy 11.733343 -132.426723) (xy 11.774534 -132.462414)
			(xy 11.810225 -132.503605) (xy 11.839691 -132.549455) (xy 11.862333 -132.599032) (xy 11.877688 -132.651327)
			(xy 11.885444 -132.705275) (xy 11.88593 -132.732526) (xy 11.88547 -132.75884) (xy 11.878233 -132.810969)
			(xy 11.863911 -132.861611) (xy 11.842777 -132.90981) (xy 11.81523 -132.954653) (xy 11.781791 -132.995293)
			(xy 11.76274 -133.01345) (xy 11.75532 -133.020957) (xy 11.746805 -133.040248) (xy 11.74623 -133.050788)
			(xy 11.74623 -133.125464) (xy 11.746756 -133.136014) (xy 11.755293 -133.15531) (xy 11.76274 -133.162802)
			(xy 11.781797 -133.180956) (xy 11.815253 -133.221587) (xy 11.84281 -133.266428) (xy 11.863948 -133.314629)
			(xy 11.878266 -133.365276) (xy 11.885491 -133.41741) (xy 11.88593 -133.443726) (xy 11.885444 -133.470977)
			(xy 11.877688 -133.524925) (xy 11.862333 -133.57722) (xy 11.839691 -133.626797) (xy 11.810225 -133.672647)
			(xy 11.774534 -133.713838) (xy 11.733343 -133.749529) (xy 11.687493 -133.778995) (xy 11.637916 -133.801637)
			(xy 11.585621 -133.816992) (xy 11.531673 -133.824748) (xy 11.477171 -133.824748) (xy 11.423223 -133.816992)
			(xy 11.370928 -133.801637) (xy 11.321351 -133.778995) (xy 11.275501 -133.749529) (xy 11.23431 -133.713838)
			(xy 11.198619 -133.672647) (xy 11.169153 -133.626797) (xy 11.146511 -133.57722) (xy 11.131156 -133.524925)
			(xy 11.1234 -133.470977) (xy 11.122914 -133.443726) (xy 5.720842 -133.443726) (xy 5.720842 -138.518138)
			(xy 5.721388 -138.532629) (xy 5.729599 -138.560425) (xy 5.745292 -138.584793) (xy 5.767201 -138.603769)
			(xy 5.79356 -138.615821) (xy 5.822243 -138.61998) (xy 5.836666 -138.618468) (xy 5.844707 -138.617015)
			(xy 5.859335 -138.609756) (xy 5.865368 -138.604244) (xy 6.140704 -138.328908) (xy 6.141466 -138.327384)
			(xy 6.141974 -138.326114) (xy 6.144006 -138.310366) (xy 6.144006 -138.310112) (xy 6.148189 -138.280149)
			(xy 6.164085 -138.221777) (xy 6.188248 -138.166315) (xy 6.220171 -138.114926) (xy 6.259185 -138.068689)
			(xy 6.30447 -138.028574) (xy 6.355077 -137.995424) (xy 6.409942 -137.969933) (xy 6.467914 -137.952638)
			(xy 6.527777 -137.9439) (xy 6.558026 -137.943336) (xy 6.589839 -137.943957) (xy 6.652724 -137.953652)
			(xy 6.683248 -137.96264) (xy 6.691376 -137.96518) (xy 6.698996 -137.96518) (xy 6.708648 -137.96391)
			(xy 6.713728 -137.962894) (xy 6.714236 -137.96264) (xy 6.72846 -137.957814) (xy 6.73608 -137.95375)
			(xy 6.763512 -137.932668) (xy 6.76783 -137.92835) (xy 6.772148 -137.92327) (xy 6.772148 -134.807706)
			(xy 6.771976 -134.801698) (xy 6.769146 -134.790019) (xy 6.76656 -134.784592) (xy 6.76472 -134.781118)
			(xy 6.760125 -134.774741) (xy 6.757416 -134.771892) (xy 6.343904 -134.35838) (xy 6.342634 -134.357364)
			(xy 6.321049 -134.342035) (xy 6.281921 -134.306375) (xy 6.248093 -134.265652) (xy 6.220215 -134.220646)
			(xy 6.198821 -134.172221) (xy 6.184322 -134.121305) (xy 6.176994 -134.068874) (xy 6.176518 -134.042404)
			(xy 6.176981 -134.015152) (xy 6.184738 -133.961202) (xy 6.200094 -133.908905) (xy 6.222736 -133.859326)
			(xy 6.252205 -133.813474) (xy 6.287899 -133.772283) (xy 6.329092 -133.736591) (xy 6.374945 -133.707126)
			(xy 6.424525 -133.684486) (xy 6.476823 -133.669133) (xy 6.530774 -133.66138) (xy 6.558026 -133.660896)
			(xy 6.585743 -133.661387) (xy 6.640594 -133.669397) (xy 6.69371 -133.685259) (xy 6.743971 -133.708639)
			(xy 6.790321 -133.739045) (xy 6.831784 -133.775838) (xy 6.867487 -133.818243) (xy 6.896679 -133.865367)
			(xy 6.918745 -133.916219) (xy 6.933221 -133.969729) (xy 6.936994 -133.997192) (xy 6.93801 -134.005828)
			(xy 6.945376 -134.021068) (xy 7.338822 -134.414514) (xy 7.356935 -134.433294) (xy 7.387622 -134.475491)
			(xy 7.411324 -134.521972) (xy 7.427457 -134.57159) (xy 7.435624 -134.623122) (xy 7.436104 -134.64921)
			(xy 7.436104 -135.142043) (xy 9.361887 -135.142043) (xy 9.361887 -135.087537) (xy 9.369644 -135.033586)
			(xy 9.385 -134.981289) (xy 9.407643 -134.931709) (xy 9.437111 -134.885856) (xy 9.472805 -134.844663)
			(xy 9.513997 -134.80897) (xy 9.55985 -134.779502) (xy 9.609431 -134.75686) (xy 9.661728 -134.741504)
			(xy 9.715679 -134.733747) (xy 9.742932 -134.733284) (xy 9.771849 -134.733819) (xy 9.82902 -134.74254)
			(xy 9.88422 -134.759793) (xy 9.936183 -134.785181) (xy 9.983717 -134.818123) (xy 10.025733 -134.857864)
			(xy 10.043922 -134.88035) (xy 10.051733 -134.889318) (xy 10.073184 -134.899517) (xy 10.08507 -134.899908)
			(xy 10.178542 -134.897876) (xy 10.199878 -134.8867) (xy 10.206736 -134.876794) (xy 10.22216 -134.855904)
			(xy 10.257734 -134.818076) (xy 10.298108 -134.785422) (xy 10.342538 -134.758545) (xy 10.390203 -134.737942)
			(xy 10.440221 -134.723993) (xy 10.491669 -134.716955) (xy 10.517632 -134.71652) (xy 10.545003 -134.716962)
			(xy 10.599183 -134.724785) (xy 10.651687 -134.74028) (xy 10.701433 -134.763127) (xy 10.747399 -134.792856)
			(xy 10.76833 -134.8105) (xy 10.768584 -134.810754) (xy 10.775666 -134.816346) (xy 10.792587 -134.822588)
			(xy 10.801604 -134.822946) (xy 10.86866 -134.822946) (xy 10.877676 -134.822582) (xy 10.894594 -134.81634)
			(xy 10.90168 -134.810754) (xy 10.90168 -134.8105) (xy 10.901934 -134.8105) (xy 10.922867 -134.792859)
			(xy 10.968835 -134.763135) (xy 11.018581 -134.740289) (xy 11.071083 -134.724793) (xy 11.125261 -134.716964)
			(xy 11.180003 -134.716964) (xy 11.234181 -134.724793) (xy 11.286683 -134.740289) (xy 11.336429 -134.763135)
			(xy 11.382397 -134.792859) (xy 11.40333 -134.8105) (xy 11.403584 -134.810754) (xy 11.410666 -134.816346)
			(xy 11.427587 -134.822588) (xy 11.436604 -134.822946) (xy 11.50366 -134.822946) (xy 11.512676 -134.822582)
			(xy 11.529594 -134.81634) (xy 11.53668 -134.810754) (xy 11.537188 -134.8105) (xy 11.549922 -134.799555)
			(xy 11.577013 -134.779714) (xy 11.59129 -134.770876) (xy 11.60018 -134.765542) (xy 11.612372 -134.748524)
			(xy 11.632692 -134.655306) (xy 11.628374 -134.634732) (xy 11.622532 -134.626096) (xy 11.606532 -134.602032)
			(xy 11.581188 -134.550101) (xy 11.563962 -134.494943) (xy 11.555248 -134.437819) (xy 11.554714 -134.408926)
			(xy 11.5552 -134.381675) (xy 11.562956 -134.327727) (xy 11.578311 -134.275432) (xy 11.600953 -134.225855)
			(xy 11.630419 -134.180005) (xy 11.66611 -134.138814) (xy 11.707301 -134.103123) (xy 11.753151 -134.073657)
			(xy 11.802728 -134.051015) (xy 11.855023 -134.03566) (xy 11.908971 -134.027904) (xy 11.963473 -134.027904)
			(xy 12.017421 -134.03566) (xy 12.069716 -134.051015) (xy 12.119293 -134.073657) (xy 12.165143 -134.103123)
			(xy 12.206334 -134.138814) (xy 12.242025 -134.180005) (xy 12.271491 -134.225855) (xy 12.294133 -134.275432)
			(xy 12.309488 -134.327727) (xy 12.317244 -134.381675) (xy 12.31773 -134.408926) (xy 12.31725 -134.437018)
			(xy 12.309019 -134.492596) (xy 12.292725 -134.546365) (xy 12.26872 -134.597162) (xy 12.237523 -134.643889)
			(xy 12.19981 -134.685533) (xy 12.156395 -134.721196) (xy 12.132564 -134.736078) (xy 12.123674 -134.741412)
			(xy 12.111482 -134.75843) (xy 12.091162 -134.851648) (xy 12.09548 -134.872222) (xy 12.101322 -134.880858)
			(xy 12.117309 -134.90493) (xy 12.142654 -134.956859) (xy 12.159883 -135.012014) (xy 12.168603 -135.069136)
			(xy 12.16914 -135.098028) (xy 12.168648 -135.125278) (xy 12.160889 -135.179224) (xy 12.145532 -135.231517)
			(xy 12.12289 -135.281092) (xy 12.093423 -135.326941) (xy 12.057733 -135.36813) (xy 12.016544 -135.403821)
			(xy 11.970696 -135.433288) (xy 11.921121 -135.45593) (xy 11.868828 -135.471288) (xy 11.814882 -135.479048)
			(xy 11.787632 -135.479536) (xy 11.760262 -135.479067) (xy 11.706082 -135.471252) (xy 11.653578 -135.455765)
			(xy 11.603831 -135.432923) (xy 11.557865 -135.403198) (xy 11.536934 -135.385556) (xy 11.53668 -135.385302)
			(xy 11.529603 -135.379701) (xy 11.512679 -135.373463) (xy 11.50366 -135.37311) (xy 11.436604 -135.37311)
			(xy 11.427587 -135.373467) (xy 11.41067 -135.379714) (xy 11.403584 -135.385302) (xy 11.403584 -135.385556)
			(xy 11.40333 -135.385556) (xy 11.382397 -135.403197) (xy 11.336429 -135.432921) (xy 11.286683 -135.455767)
			(xy 11.234181 -135.471263) (xy 11.180003 -135.479092) (xy 11.125261 -135.479092) (xy 11.071083 -135.471263)
			(xy 11.018581 -135.455767) (xy 10.968835 -135.432921) (xy 10.922867 -135.403197) (xy 10.901934 -135.385556)
			(xy 10.90168 -135.385302) (xy 10.894603 -135.379701) (xy 10.877679 -135.373463) (xy 10.86866 -135.37311)
			(xy 10.801604 -135.37311) (xy 10.792587 -135.373467) (xy 10.77567 -135.379714) (xy 10.768584 -135.385302)
			(xy 10.768584 -135.385556) (xy 10.76833 -135.385556) (xy 10.747392 -135.403188) (xy 10.701421 -135.432902)
			(xy 10.651676 -135.45574) (xy 10.599176 -135.471233) (xy 10.545001 -135.479062) (xy 10.517632 -135.479536)
			(xy 10.488715 -135.479019) (xy 10.431542 -135.470293) (xy 10.376342 -135.453037) (xy 10.32438 -135.427645)
			(xy 10.276847 -135.3947) (xy 10.234831 -135.354957) (xy 10.216642 -135.33247) (xy 10.208844 -135.323489)
			(xy 10.187383 -135.313296) (xy 10.175494 -135.312912) (xy 10.082022 -135.314944) (xy 10.060686 -135.32612)
			(xy 10.053828 -135.336026) (xy 10.038432 -135.356938) (xy 10.002853 -135.394764) (xy 9.962473 -135.427415)
			(xy 9.918038 -135.454289) (xy 9.87037 -135.474889) (xy 9.820348 -135.488834) (xy 9.768897 -135.495867)
			(xy 9.742932 -135.4963) (xy 9.715679 -135.495833) (xy 9.661728 -135.488076) (xy 9.609431 -135.47272)
			(xy 9.55985 -135.450078) (xy 9.513997 -135.42061) (xy 9.472805 -135.384917) (xy 9.437111 -135.343724)
			(xy 9.407643 -135.297871) (xy 9.385 -135.248291) (xy 9.369644 -135.195994) (xy 9.361887 -135.142043)
			(xy 7.436104 -135.142043) (xy 7.436104 -135.255508) (xy 7.43712 -135.257032) (xy 7.44601 -135.266684)
			(xy 7.46125 -135.278114) (xy 7.462012 -135.278876) (xy 7.512304 -135.316214) (xy 7.516622 -135.319008)
			(xy 7.518654 -135.320024) (xy 7.52202 -135.321774) (xy 7.529164 -135.324329) (xy 7.532878 -135.325104)
			(xy 7.5438 -135.327136) (xy 7.573127 -135.31802) (xy 7.633745 -135.308194) (xy 7.66445 -135.307578)
			(xy 7.664958 -135.307578) (xy 7.692247 -135.308041) (xy 7.746269 -135.315808) (xy 7.798637 -135.331185)
			(xy 7.848283 -135.353857) (xy 7.894197 -135.383364) (xy 7.935444 -135.419105) (xy 7.971185 -135.460352)
			(xy 8.000692 -135.506266) (xy 8.023365 -135.555911) (xy 8.038741 -135.608279) (xy 8.046508 -135.662301)
			(xy 8.046508 -135.716879) (xy 8.038741 -135.770901) (xy 8.023365 -135.823269) (xy 8.003445 -135.866886)
			(xy 8.43991 -135.866886) (xy 8.443981 -135.811264) (xy 8.456107 -135.756827) (xy 8.47603 -135.704736)
			(xy 8.503326 -135.656101) (xy 8.537412 -135.611958) (xy 8.577561 -135.573249) (xy 8.622919 -135.540798)
			(xy 8.672519 -135.515297) (xy 8.725303 -135.49729) (xy 8.780146 -135.48716) (xy 8.83588 -135.485123)
			(xy 8.891317 -135.491223) (xy 8.945274 -135.505329) (xy 8.996603 -135.527141) (xy 9.044209 -135.556195)
			(xy 9.087077 -135.59187) (xy 9.124294 -135.633407) (xy 9.155067 -135.67992) (xy 9.178739 -135.730417)
			(xy 9.194807 -135.783824) (xy 9.202927 -135.839) (xy 9.203436 -135.866886) (xy 9.202927 -135.894772)
			(xy 9.194807 -135.949948) (xy 9.178739 -136.003355) (xy 9.155067 -136.053852) (xy 9.124294 -136.100365)
			(xy 9.087077 -136.141902) (xy 9.044209 -136.177577) (xy 8.996603 -136.206631) (xy 8.945274 -136.228443)
			(xy 8.891317 -136.242549) (xy 8.83588 -136.248649) (xy 8.780146 -136.246612) (xy 8.725303 -136.236482)
			(xy 8.672519 -136.218475) (xy 8.622919 -136.192974) (xy 8.577561 -136.160523) (xy 8.537412 -136.121814)
			(xy 8.503326 -136.077671) (xy 8.47603 -136.029036) (xy 8.456107 -135.976945) (xy 8.443981 -135.922508)
			(xy 8.43991 -135.866886) (xy 8.003445 -135.866886) (xy 8.000692 -135.872914) (xy 7.971185 -135.918828)
			(xy 7.935444 -135.960075) (xy 7.894197 -135.995816) (xy 7.848283 -136.025323) (xy 7.798637 -136.047995)
			(xy 7.746269 -136.063372) (xy 7.692247 -136.071139) (xy 7.664958 -136.07161) (xy 7.66445 -136.07161)
			(xy 7.634347 -136.071042) (xy 7.574887 -136.061593) (xy 7.546086 -136.052814) (xy 7.536688 -136.053576)
			(xy 7.523988 -136.056624) (xy 7.517384 -136.059164) (xy 7.511542 -136.063482) (xy 7.469886 -136.094216)
			(xy 7.469378 -136.094724) (xy 7.460996 -136.101074) (xy 7.456932 -136.104122) (xy 7.441946 -136.115552)
			(xy 7.436104 -136.122156) (xy 7.436104 -137.44829) (xy 8.345168 -137.44829) (xy 8.349239 -137.392668)
			(xy 8.361365 -137.338231) (xy 8.381288 -137.28614) (xy 8.408584 -137.237505) (xy 8.44267 -137.193362)
			(xy 8.482819 -137.154653) (xy 8.528177 -137.122202) (xy 8.577777 -137.096701) (xy 8.630561 -137.078694)
			(xy 8.685404 -137.068564) (xy 8.741138 -137.066527) (xy 8.796575 -137.072627) (xy 8.850532 -137.086733)
			(xy 8.901861 -137.108545) (xy 8.949467 -137.137599) (xy 8.992335 -137.173274) (xy 9.029552 -137.214811)
			(xy 9.060325 -137.261324) (xy 9.06736 -137.276332) (xy 13.047218 -137.276332) (xy 13.047698 -137.248962)
			(xy 13.055512 -137.194784) (xy 13.070998 -137.14228) (xy 13.093836 -137.092533) (xy 13.123558 -137.046566)
			(xy 13.141198 -137.025634) (xy 13.141452 -137.02538) (xy 13.147059 -137.018308) (xy 13.153292 -137.00138)
			(xy 13.153644 -136.99236) (xy 13.153644 -136.925304) (xy 13.153297 -136.916286) (xy 13.147044 -136.899368)
			(xy 13.141452 -136.892284) (xy 13.141198 -136.892284) (xy 13.141198 -136.89203) (xy 13.123559 -136.871098)
			(xy 13.093847 -136.825125) (xy 13.071011 -136.775377) (xy 13.05552 -136.722877) (xy 13.047692 -136.668701)
			(xy 13.047218 -136.641332) (xy 13.047704 -136.614081) (xy 13.05546 -136.560133) (xy 13.070815 -136.507838)
			(xy 13.093457 -136.458261) (xy 13.122923 -136.412411) (xy 13.158614 -136.37122) (xy 13.199805 -136.335529)
			(xy 13.245655 -136.306063) (xy 13.295232 -136.283421) (xy 13.347527 -136.268066) (xy 13.401475 -136.26031)
			(xy 13.455977 -136.26031) (xy 13.509925 -136.268066) (xy 13.56222 -136.283421) (xy 13.611797 -136.306063)
			(xy 13.657647 -136.335529) (xy 13.698838 -136.37122) (xy 13.734529 -136.412411) (xy 13.763995 -136.458261)
			(xy 13.786637 -136.507838) (xy 13.801992 -136.560133) (xy 13.809748 -136.614081) (xy 13.810234 -136.641332)
			(xy 13.809803 -136.668704) (xy 13.801979 -136.722885) (xy 13.786483 -136.775389) (xy 13.763633 -136.825135)
			(xy 13.7339 -136.8711) (xy 13.716254 -136.89203) (xy 13.716 -136.892284) (xy 13.710414 -136.899371)
			(xy 13.704167 -136.916287) (xy 13.703808 -136.925304) (xy 13.703808 -136.99236) (xy 13.704183 -137.001375)
			(xy 13.710418 -137.018292) (xy 13.716 -137.02538) (xy 13.716254 -137.02538) (xy 13.716254 -137.025634)
			(xy 13.733868 -137.046586) (xy 13.763586 -137.092553) (xy 13.786427 -137.142295) (xy 13.801924 -137.194792)
			(xy 13.809757 -137.248964) (xy 13.810234 -137.276332) (xy 13.809748 -137.303583) (xy 13.801992 -137.357531)
			(xy 13.786637 -137.409826) (xy 13.763995 -137.459403) (xy 13.734529 -137.505253) (xy 13.698838 -137.546444)
			(xy 13.657647 -137.582135) (xy 13.611797 -137.611601) (xy 13.56222 -137.634243) (xy 13.509925 -137.649598)
			(xy 13.455977 -137.657354) (xy 13.401475 -137.657354) (xy 13.347527 -137.649598) (xy 13.295232 -137.634243)
			(xy 13.245655 -137.611601) (xy 13.199805 -137.582135) (xy 13.158614 -137.546444) (xy 13.122923 -137.505253)
			(xy 13.093457 -137.459403) (xy 13.070815 -137.409826) (xy 13.05546 -137.357531) (xy 13.047704 -137.303583)
			(xy 13.047218 -137.276332) (xy 9.06736 -137.276332) (xy 9.083997 -137.311821) (xy 9.100065 -137.365228)
			(xy 9.108185 -137.420404) (xy 9.108694 -137.44829) (xy 9.108185 -137.476176) (xy 9.100065 -137.531352)
			(xy 9.083997 -137.584759) (xy 9.060325 -137.635256) (xy 9.029552 -137.681769) (xy 8.992335 -137.723306)
			(xy 8.988288 -137.726674) (xy 13.98778 -137.726674) (xy 13.988211 -137.699302) (xy 13.996035 -137.645121)
			(xy 14.011531 -137.592617) (xy 14.034381 -137.54287) (xy 14.064114 -137.496906) (xy 14.08176 -137.475976)
			(xy 14.082014 -137.475722) (xy 14.087599 -137.468634) (xy 14.093846 -137.451718) (xy 14.094206 -137.442702)
			(xy 14.094206 -137.375646) (xy 14.093826 -137.366631) (xy 14.087594 -137.349714) (xy 14.082014 -137.342626)
			(xy 14.08176 -137.342626) (xy 14.08176 -137.342372) (xy 14.064135 -137.321429) (xy 14.034422 -137.275459)
			(xy 14.011584 -137.225714) (xy 13.996089 -137.173216) (xy 13.988256 -137.119042) (xy 13.98778 -137.091674)
			(xy 13.988266 -137.064423) (xy 13.996022 -137.010475) (xy 14.011377 -136.95818) (xy 14.034019 -136.908603)
			(xy 14.063485 -136.862753) (xy 14.099176 -136.821562) (xy 14.140367 -136.785871) (xy 14.186217 -136.756405)
			(xy 14.235794 -136.733763) (xy 14.288089 -136.718408) (xy 14.342037 -136.710652) (xy 14.396539 -136.710652)
			(xy 14.450487 -136.718408) (xy 14.502782 -136.733763) (xy 14.552359 -136.756405) (xy 14.598209 -136.785871)
			(xy 14.6394 -136.821562) (xy 14.675091 -136.862753) (xy 14.704557 -136.908603) (xy 14.727199 -136.95818)
			(xy 14.742554 -137.010475) (xy 14.75031 -137.064423) (xy 14.750796 -137.091674) (xy 14.750316 -137.119044)
			(xy 14.742501 -137.173222) (xy 14.727016 -137.225725) (xy 14.704177 -137.275472) (xy 14.674456 -137.32144)
			(xy 14.656816 -137.342372) (xy 14.656562 -137.342626) (xy 14.650996 -137.349726) (xy 14.644738 -137.366633)
			(xy 14.64437 -137.375646) (xy 14.64437 -137.442702) (xy 14.644733 -137.451718) (xy 14.650977 -137.468635)
			(xy 14.656562 -137.475722) (xy 14.656816 -137.475722) (xy 14.656816 -137.475976) (xy 14.67446 -137.496904)
			(xy 14.70417 -137.542878) (xy 14.727005 -137.592627) (xy 14.742495 -137.645128) (xy 14.750322 -137.699305)
			(xy 14.750796 -137.726674) (xy 14.75031 -137.753925) (xy 14.742554 -137.807873) (xy 14.727199 -137.860168)
			(xy 14.704557 -137.909745) (xy 14.675091 -137.955595) (xy 14.6394 -137.996786) (xy 14.598209 -138.032477)
			(xy 14.552359 -138.061943) (xy 14.502782 -138.084585) (xy 14.450487 -138.09994) (xy 14.396539 -138.107696)
			(xy 14.342037 -138.107696) (xy 14.288089 -138.09994) (xy 14.235794 -138.084585) (xy 14.186217 -138.061943)
			(xy 14.140367 -138.032477) (xy 14.099176 -137.996786) (xy 14.063485 -137.955595) (xy 14.034019 -137.909745)
			(xy 14.011377 -137.860168) (xy 13.996022 -137.807873) (xy 13.988266 -137.753925) (xy 13.98778 -137.726674)
			(xy 8.988288 -137.726674) (xy 8.949467 -137.758981) (xy 8.901861 -137.788035) (xy 8.850532 -137.809847)
			(xy 8.796575 -137.823953) (xy 8.741138 -137.830053) (xy 8.685404 -137.828016) (xy 8.630561 -137.817886)
			(xy 8.577777 -137.799879) (xy 8.528177 -137.774378) (xy 8.482819 -137.741927) (xy 8.44267 -137.703218)
			(xy 8.408584 -137.659075) (xy 8.381288 -137.61044) (xy 8.361365 -137.558349) (xy 8.349239 -137.503912)
			(xy 8.345168 -137.44829) (xy 7.436104 -137.44829) (xy 7.436104 -138.40333) (xy 15.196312 -138.40333)
			(xy 15.196842 -138.375665) (xy 15.204838 -138.320917) (xy 15.220651 -138.267895) (xy 15.243951 -138.217711)
			(xy 15.274249 -138.171415) (xy 15.310912 -138.129977) (xy 15.353172 -138.094264) (xy 15.376398 -138.079226)
			(xy 15.386055 -138.072565) (xy 15.398512 -138.052722) (xy 15.400274 -138.041126) (xy 15.408148 -137.961116)
			(xy 15.408763 -137.949478) (xy 15.400695 -137.927642) (xy 15.392654 -137.919206) (xy 15.3924 -137.918952)
			(xy 15.373813 -137.900876) (xy 15.341235 -137.860543) (xy 15.314423 -137.816168) (xy 15.293871 -137.768568)
			(xy 15.279959 -137.718623) (xy 15.272943 -137.667253) (xy 15.272512 -137.64133) (xy 15.272983 -137.614077)
			(xy 15.280737 -137.560125) (xy 15.29609 -137.507826) (xy 15.31873 -137.458245) (xy 15.348197 -137.412391)
			(xy 15.38389 -137.371197) (xy 15.425083 -137.335503) (xy 15.470936 -137.306035) (xy 15.520517 -137.283393)
			(xy 15.572816 -137.268039) (xy 15.626767 -137.260284) (xy 15.65402 -137.259822) (xy 15.681391 -137.260271)
			(xy 15.735571 -137.268092) (xy 15.788074 -137.283585) (xy 15.837821 -137.306431) (xy 15.883787 -137.336159)
			(xy 15.904718 -137.353802) (xy 15.904972 -137.354056) (xy 15.912058 -137.359644) (xy 15.928975 -137.365888)
			(xy 15.937992 -137.366248) (xy 16.005048 -137.366248) (xy 16.014064 -137.365877) (xy 16.030981 -137.359641)
			(xy 16.038068 -137.354056) (xy 16.038068 -137.353802) (xy 16.038322 -137.353802) (xy 16.059273 -137.336186)
			(xy 16.105241 -137.306471) (xy 16.154983 -137.28363) (xy 16.20748 -137.268134) (xy 16.261652 -137.260299)
			(xy 16.28902 -137.259822) (xy 16.316275 -137.260236) (xy 16.370229 -137.267997) (xy 16.42253 -137.283357)
			(xy 16.472112 -137.306004) (xy 16.517966 -137.335477) (xy 16.55916 -137.371176) (xy 16.594853 -137.412374)
			(xy 16.62432 -137.458232) (xy 16.646961 -137.507817) (xy 16.662314 -137.56012) (xy 16.670067 -137.614075)
			(xy 16.670528 -137.64133) (xy 16.669987 -137.670246) (xy 16.661266 -137.727418) (xy 16.644015 -137.782617)
			(xy 16.618627 -137.83458) (xy 16.585686 -137.882114) (xy 16.545947 -137.92413) (xy 16.523462 -137.94232)
			(xy 16.514649 -137.949922) (xy 16.50447 -137.970827) (xy 16.503904 -137.982452) (xy 16.503904 -138.062208)
			(xy 16.504451 -138.073839) (xy 16.514634 -138.094749) (xy 16.523462 -138.10234) (xy 16.545957 -138.120518)
			(xy 16.585693 -138.162539) (xy 16.618632 -138.210077) (xy 16.644019 -138.262041) (xy 16.661272 -138.317241)
			(xy 16.669996 -138.374413) (xy 16.670528 -138.40333) (xy 16.67005 -138.430581) (xy 16.66229 -138.484528)
			(xy 16.646932 -138.536822) (xy 16.624289 -138.586398) (xy 16.594821 -138.632247) (xy 16.559129 -138.673436)
			(xy 16.517939 -138.709127) (xy 16.472089 -138.738594) (xy 16.422512 -138.761236) (xy 16.370218 -138.776592)
			(xy 16.316271 -138.784351) (xy 16.28902 -138.784838) (xy 16.262706 -138.784377) (xy 16.210576 -138.777144)
			(xy 16.159932 -138.762825) (xy 16.111733 -138.741691) (xy 16.06689 -138.714143) (xy 16.026251 -138.680701)
			(xy 16.008096 -138.661648) (xy 16.000571 -138.65425) (xy 15.981294 -138.645722) (xy 15.970758 -138.645138)
			(xy 15.896082 -138.645138) (xy 15.885534 -138.645687) (xy 15.866238 -138.654207) (xy 15.858744 -138.661648)
			(xy 15.840618 -138.680733) (xy 15.799981 -138.714185) (xy 15.755134 -138.741739) (xy 15.706928 -138.762872)
			(xy 15.656276 -138.777184) (xy 15.604138 -138.784403) (xy 15.57782 -138.784838) (xy 15.550571 -138.784303)
			(xy 15.496626 -138.77655) (xy 15.444334 -138.761199) (xy 15.394759 -138.738563) (xy 15.34891 -138.709101)
			(xy 15.307721 -138.673415) (xy 15.272029 -138.63223) (xy 15.242561 -138.586385) (xy 15.219918 -138.536813)
			(xy 15.20456 -138.484523) (xy 15.1968 -138.430579) (xy 15.196312 -138.40333) (xy 7.436104 -138.40333)
			(xy 7.436104 -138.824462) (xy 8.361932 -138.824462) (xy 8.366003 -138.76884) (xy 8.378129 -138.714403)
			(xy 8.398052 -138.662312) (xy 8.425348 -138.613677) (xy 8.459434 -138.569534) (xy 8.499583 -138.530825)
			(xy 8.544941 -138.498374) (xy 8.594541 -138.472873) (xy 8.647325 -138.454866) (xy 8.702168 -138.444736)
			(xy 8.757902 -138.442699) (xy 8.813339 -138.448799) (xy 8.867296 -138.462905) (xy 8.918625 -138.484717)
			(xy 8.966231 -138.513771) (xy 9.009099 -138.549446) (xy 9.046316 -138.590983) (xy 9.077089 -138.637496)
			(xy 9.100761 -138.687993) (xy 9.116829 -138.7414) (xy 9.124949 -138.796576) (xy 9.125458 -138.824462)
			(xy 9.124949 -138.852348) (xy 9.116829 -138.907524) (xy 9.100761 -138.960931) (xy 9.077089 -139.011428)
			(xy 9.046316 -139.057941) (xy 9.009099 -139.099478) (xy 8.966231 -139.135153) (xy 8.918625 -139.164207)
			(xy 8.867296 -139.186019) (xy 8.813339 -139.200125) (xy 8.757902 -139.206225) (xy 8.702168 -139.204188)
			(xy 8.647325 -139.194058) (xy 8.594541 -139.176051) (xy 8.544941 -139.15055) (xy 8.499583 -139.118099)
			(xy 8.459434 -139.07939) (xy 8.425348 -139.035247) (xy 8.398052 -138.986612) (xy 8.378129 -138.934521)
			(xy 8.366003 -138.880084) (xy 8.361932 -138.824462) (xy 7.436104 -138.824462) (xy 7.436104 -139.282932)
			(xy 16.938244 -139.282932) (xy 16.938754 -139.25414) (xy 16.947436 -139.197214) (xy 16.964578 -139.14224)
			(xy 16.989789 -139.090467) (xy 17.022498 -139.043074) (xy 17.061959 -139.001136) (xy 17.084294 -138.982958)
			(xy 17.092898 -138.975378) (xy 17.102912 -138.954782) (xy 17.103598 -138.943334) (xy 17.104106 -138.851894)
			(xy 17.093946 -138.830812) (xy 17.084802 -138.8237) (xy 17.062892 -138.805501) (xy 17.024216 -138.763691)
			(xy 16.992191 -138.716591) (xy 16.967531 -138.665251) (xy 16.950784 -138.610813) (xy 16.942323 -138.55449)
			(xy 16.9418 -138.526012) (xy 16.9418 -138.525758) (xy 16.9423 -138.498389) (xy 16.95011 -138.444211)
			(xy 16.965591 -138.391709) (xy 16.988425 -138.341961) (xy 17.018142 -138.295993) (xy 17.03578 -138.27506)
			(xy 17.036034 -138.274806) (xy 17.041628 -138.267725) (xy 17.047869 -138.250804) (xy 17.048226 -138.241786)
			(xy 17.048226 -138.17473) (xy 17.047849 -138.165715) (xy 17.041615 -138.148798) (xy 17.036034 -138.14171)
			(xy 17.03578 -138.14171) (xy 17.03578 -138.141456) (xy 17.018137 -138.120525) (xy 16.988412 -138.074557)
			(xy 16.965567 -138.02481) (xy 16.950071 -137.972308) (xy 16.942242 -137.918129) (xy 16.942242 -137.863388)
			(xy 16.950071 -137.809209) (xy 16.965568 -137.756707) (xy 16.988414 -137.70696) (xy 17.018139 -137.660993)
			(xy 17.03578 -137.64006) (xy 17.036034 -137.639806) (xy 17.041628 -137.632725) (xy 17.047869 -137.615804)
			(xy 17.048226 -137.606786) (xy 17.048226 -137.53973) (xy 17.047849 -137.530715) (xy 17.041615 -137.513798)
			(xy 17.036034 -137.50671) (xy 17.03578 -137.50671) (xy 17.03578 -137.506456) (xy 17.018137 -137.485525)
			(xy 16.988412 -137.439557) (xy 16.965567 -137.38981) (xy 16.950071 -137.337308) (xy 16.942242 -137.283129)
			(xy 16.942242 -137.228388) (xy 16.950071 -137.174209) (xy 16.965568 -137.121707) (xy 16.988414 -137.07196)
			(xy 17.018139 -137.025993) (xy 17.03578 -137.00506) (xy 17.036034 -137.004806) (xy 17.041628 -136.997725)
			(xy 17.047869 -136.980804) (xy 17.048226 -136.971786) (xy 17.048226 -136.90473) (xy 17.047849 -136.895715)
			(xy 17.041615 -136.878798) (xy 17.036034 -136.87171) (xy 17.03578 -136.87171) (xy 17.03578 -136.871456)
			(xy 17.018151 -136.850516) (xy 16.988438 -136.804545) (xy 16.9656 -136.7548) (xy 16.950107 -136.702301)
			(xy 16.942276 -136.648127) (xy 16.9418 -136.620758) (xy 16.942286 -136.593507) (xy 16.950042 -136.539559)
			(xy 16.965397 -136.487264) (xy 16.988039 -136.437687) (xy 17.017505 -136.391837) (xy 17.053196 -136.350646)
			(xy 17.094387 -136.314955) (xy 17.140237 -136.285489) (xy 17.189814 -136.262847) (xy 17.242109 -136.247492)
			(xy 17.296057 -136.239736) (xy 17.350559 -136.239736) (xy 17.404507 -136.247492) (xy 17.456802 -136.262847)
			(xy 17.506379 -136.285489) (xy 17.552229 -136.314955) (xy 17.59342 -136.350646) (xy 17.629111 -136.391837)
			(xy 17.658577 -136.437687) (xy 17.681219 -136.487264) (xy 17.696574 -136.539559) (xy 17.70433 -136.593507)
			(xy 17.704816 -136.620758) (xy 17.704346 -136.648128) (xy 17.696532 -136.702308) (xy 17.681045 -136.754812)
			(xy 17.658204 -136.804559) (xy 17.628478 -136.850525) (xy 17.610836 -136.871456) (xy 17.610582 -136.87171)
			(xy 17.604983 -136.878788) (xy 17.598744 -136.895711) (xy 17.59839 -136.90473) (xy 17.59839 -136.971786)
			(xy 17.598756 -136.980802) (xy 17.604998 -136.997719) (xy 17.610582 -137.004806) (xy 17.610836 -137.004806)
			(xy 17.610836 -137.00506) (xy 17.628475 -137.025994) (xy 17.658199 -137.071962) (xy 17.681045 -137.121708)
			(xy 17.696541 -137.17421) (xy 17.70437 -137.228388) (xy 17.70437 -137.283129) (xy 17.696541 -137.337307)
			(xy 17.681046 -137.389809) (xy 17.658201 -137.439555) (xy 17.628476 -137.485523) (xy 17.610836 -137.506456)
			(xy 17.610582 -137.50671) (xy 17.604983 -137.513788) (xy 17.598744 -137.530711) (xy 17.59839 -137.53973)
			(xy 17.59839 -137.606786) (xy 17.598756 -137.615802) (xy 17.604998 -137.632719) (xy 17.610582 -137.639806)
			(xy 17.610836 -137.639806) (xy 17.610836 -137.64006) (xy 17.628475 -137.660994) (xy 17.658199 -137.706962)
			(xy 17.681045 -137.756708) (xy 17.696541 -137.80921) (xy 17.70437 -137.863388) (xy 17.70437 -137.918129)
			(xy 17.696541 -137.972307) (xy 17.681046 -138.024809) (xy 17.658201 -138.074555) (xy 17.628476 -138.120523)
			(xy 17.610836 -138.141456) (xy 17.610582 -138.14171) (xy 17.604983 -138.148788) (xy 17.598744 -138.165711)
			(xy 17.59839 -138.17473) (xy 17.59839 -138.241786) (xy 17.598756 -138.250802) (xy 17.604998 -138.267719)
			(xy 17.610582 -138.274806) (xy 17.610836 -138.274806) (xy 17.610836 -138.27506) (xy 17.628475 -138.295992)
			(xy 17.658186 -138.341965) (xy 17.681021 -138.391713) (xy 17.696512 -138.444213) (xy 17.704341 -138.498389)
			(xy 17.704816 -138.525758) (xy 17.704314 -138.554551) (xy 17.695632 -138.611478) (xy 17.67849 -138.666453)
			(xy 17.653277 -138.718225) (xy 17.620567 -138.765619) (xy 17.581102 -138.807555) (xy 17.558766 -138.825732)
			(xy 17.550177 -138.833327) (xy 17.540152 -138.853911) (xy 17.539462 -138.865356) (xy 17.538954 -138.956796)
			(xy 17.549114 -138.977878) (xy 17.558258 -138.98499) (xy 17.57045 -138.995404) (xy 17.570704 -138.995658)
			(xy 17.57778 -139.001259) (xy 17.594705 -139.007496) (xy 17.603724 -139.00785) (xy 17.67078 -139.00785)
			(xy 17.679797 -139.007494) (xy 17.696715 -139.001247) (xy 17.7038 -138.995658) (xy 17.7038 -138.995404)
			(xy 17.704054 -138.995404) (xy 17.724987 -138.977763) (xy 17.770955 -138.948039) (xy 17.820701 -138.925193)
			(xy 17.873203 -138.909697) (xy 17.927381 -138.901868) (xy 17.982123 -138.901868) (xy 18.036301 -138.909697)
			(xy 18.088803 -138.925193) (xy 18.138549 -138.948039) (xy 18.184517 -138.977763) (xy 18.20545 -138.995404)
			(xy 18.205704 -138.995658) (xy 18.21278 -139.001259) (xy 18.229705 -139.007496) (xy 18.238724 -139.00785)
			(xy 18.30578 -139.00785) (xy 18.314797 -139.007494) (xy 18.331715 -139.001247) (xy 18.3388 -138.995658)
			(xy 18.3388 -138.995404) (xy 18.339054 -138.995404) (xy 18.359987 -138.977763) (xy 18.405955 -138.948039)
			(xy 18.455701 -138.925193) (xy 18.508203 -138.909697) (xy 18.562381 -138.901868) (xy 18.617123 -138.901868)
			(xy 18.671301 -138.909697) (xy 18.723803 -138.925193) (xy 18.773549 -138.948039) (xy 18.819517 -138.977763)
			(xy 18.84045 -138.995404) (xy 18.840704 -138.995658) (xy 18.84778 -139.001259) (xy 18.864705 -139.007496)
			(xy 18.873724 -139.00785) (xy 18.94078 -139.00785) (xy 18.949797 -139.007494) (xy 18.966715 -139.001247)
			(xy 18.9738 -138.995658) (xy 18.9738 -138.995404) (xy 18.974054 -138.995404) (xy 18.994993 -138.977774)
			(xy 19.040964 -138.94806) (xy 19.09071 -138.925223) (xy 19.143209 -138.90973) (xy 19.197383 -138.901899)
			(xy 19.224752 -138.901424) (xy 19.252003 -138.901906) (xy 19.305951 -138.909663) (xy 19.358246 -138.925018)
			(xy 19.407823 -138.947659) (xy 19.453674 -138.977126) (xy 19.494864 -139.012818) (xy 19.530555 -139.054008)
			(xy 19.560021 -139.099859) (xy 19.582663 -139.149436) (xy 19.598018 -139.201731) (xy 19.605774 -139.255679)
			(xy 19.605774 -139.310181) (xy 19.598018 -139.364129) (xy 19.582663 -139.416424) (xy 19.560021 -139.466001)
			(xy 19.530555 -139.511852) (xy 19.494864 -139.553042) (xy 19.453674 -139.588734) (xy 19.407823 -139.618201)
			(xy 19.358246 -139.640842) (xy 19.305951 -139.656197) (xy 19.252003 -139.663954) (xy 19.224752 -139.66444)
			(xy 19.197382 -139.663958) (xy 19.143203 -139.656146) (xy 19.0907 -139.640662) (xy 19.040952 -139.617823)
			(xy 18.994986 -139.588101) (xy 18.974054 -139.57046) (xy 18.9738 -139.570206) (xy 18.966717 -139.564614)
			(xy 18.949798 -139.55837) (xy 18.94078 -139.558014) (xy 18.873724 -139.558014) (xy 18.864708 -139.558379)
			(xy 18.847791 -139.564621) (xy 18.840704 -139.570206) (xy 18.84045 -139.57046) (xy 18.819517 -139.588101)
			(xy 18.773549 -139.617825) (xy 18.723803 -139.640671) (xy 18.671301 -139.656167) (xy 18.617123 -139.663996)
			(xy 18.562381 -139.663996) (xy 18.508203 -139.656167) (xy 18.455701 -139.640671) (xy 18.405955 -139.617825)
			(xy 18.359987 -139.588101) (xy 18.339054 -139.57046) (xy 18.3388 -139.570206) (xy 18.331717 -139.564614)
			(xy 18.314798 -139.55837) (xy 18.30578 -139.558014) (xy 18.238724 -139.558014) (xy 18.229708 -139.558379)
			(xy 18.212791 -139.564621) (xy 18.205704 -139.570206) (xy 18.205704 -139.57046) (xy 18.20545 -139.57046)
			(xy 18.184517 -139.588101) (xy 18.138549 -139.617825) (xy 18.088803 -139.640671) (xy 18.036301 -139.656167)
			(xy 17.982123 -139.663996) (xy 17.927381 -139.663996) (xy 17.873203 -139.656167) (xy 17.820701 -139.640671)
			(xy 17.770955 -139.617825) (xy 17.724987 -139.588101) (xy 17.704054 -139.57046) (xy 17.7038 -139.570206)
			(xy 17.696717 -139.564614) (xy 17.679798 -139.55837) (xy 17.67078 -139.558014) (xy 17.603724 -139.558014)
			(xy 17.594708 -139.558379) (xy 17.577791 -139.564621) (xy 17.570704 -139.570206) (xy 17.570704 -139.57046)
			(xy 17.57045 -139.57046) (xy 17.549505 -139.588083) (xy 17.503536 -139.617799) (xy 17.453792 -139.640638)
			(xy 17.401294 -139.656133) (xy 17.34712 -139.663964) (xy 17.319752 -139.66444) (xy 17.292501 -139.663967)
			(xy 17.238555 -139.656205) (xy 17.186262 -139.640845) (xy 17.136686 -139.618201) (xy 17.090838 -139.588732)
			(xy 17.049649 -139.55304) (xy 17.013958 -139.51185) (xy 16.984492 -139.466) (xy 16.961849 -139.416423)
			(xy 16.946492 -139.36413) (xy 16.938732 -139.310183) (xy 16.938244 -139.282932) (xy 7.436104 -139.282932)
			(xy 7.436104 -140.392404) (xy 8.367774 -140.392404) (xy 8.371845 -140.336782) (xy 8.383971 -140.282345)
			(xy 8.403894 -140.230254) (xy 8.43119 -140.181619) (xy 8.465276 -140.137476) (xy 8.505425 -140.098767)
			(xy 8.550783 -140.066316) (xy 8.600383 -140.040815) (xy 8.653167 -140.022808) (xy 8.70801 -140.012678)
			(xy 8.763744 -140.010641) (xy 8.819181 -140.016741) (xy 8.873138 -140.030847) (xy 8.924467 -140.052659)
			(xy 8.972073 -140.081713) (xy 9.014941 -140.117388) (xy 9.052158 -140.158925) (xy 9.082931 -140.205438)
			(xy 9.106603 -140.255935) (xy 9.122671 -140.309342) (xy 9.130791 -140.364518) (xy 9.1313 -140.392404)
			(xy 9.130791 -140.42029) (xy 9.122671 -140.475466) (xy 9.106603 -140.528873) (xy 9.082931 -140.57937)
			(xy 9.052158 -140.625883) (xy 9.014941 -140.66742) (xy 8.972073 -140.703095) (xy 8.924467 -140.732149)
			(xy 8.873138 -140.753961) (xy 8.819181 -140.768067) (xy 8.763744 -140.774167) (xy 8.70801 -140.77213)
			(xy 8.653167 -140.762) (xy 8.600383 -140.743993) (xy 8.550783 -140.718492) (xy 8.505425 -140.686041)
			(xy 8.465276 -140.647332) (xy 8.43119 -140.603189) (xy 8.403894 -140.554554) (xy 8.383971 -140.502463)
			(xy 8.371845 -140.448026) (xy 8.367774 -140.392404) (xy 7.436104 -140.392404) (xy 7.436104 -141.046533)
			(xy 10.755071 -141.046533) (xy 10.755071 -140.992027) (xy 10.762828 -140.938075) (xy 10.778185 -140.885777)
			(xy 10.800828 -140.836196) (xy 10.830296 -140.790342) (xy 10.86599 -140.749149) (xy 10.907184 -140.713455)
			(xy 10.953038 -140.683987) (xy 11.002618 -140.661344) (xy 11.054917 -140.645988) (xy 11.108869 -140.638231)
			(xy 11.136122 -140.637768) (xy 11.162436 -140.638231) (xy 11.214564 -140.645468) (xy 11.265207 -140.659789)
			(xy 11.313405 -140.680922) (xy 11.358249 -140.708469) (xy 11.398889 -140.741907) (xy 11.417046 -140.760958)
			(xy 11.424554 -140.768376) (xy 11.443844 -140.776892) (xy 11.454384 -140.777468) (xy 11.52906 -140.777468)
			(xy 11.53961 -140.77694) (xy 11.558906 -140.768405) (xy 11.566398 -140.760958) (xy 11.584553 -140.741902)
			(xy 11.625184 -140.708447) (xy 11.670025 -140.680889) (xy 11.718225 -140.659751) (xy 11.768872 -140.645433)
			(xy 11.821006 -140.638207) (xy 11.847322 -140.637768) (xy 11.874573 -140.638262) (xy 11.92852 -140.646019)
			(xy 11.980814 -140.661374) (xy 12.03039 -140.684015) (xy 12.07624 -140.713481) (xy 12.117429 -140.749172)
			(xy 12.15312 -140.790362) (xy 12.182586 -140.836212) (xy 12.205227 -140.885788) (xy 12.220582 -140.938082)
			(xy 12.228338 -140.992029) (xy 12.228338 -141.046531) (xy 12.220582 -141.100478) (xy 12.205227 -141.152772)
			(xy 12.182586 -141.202348) (xy 12.15312 -141.248198) (xy 12.117429 -141.289388) (xy 12.07624 -141.325079)
			(xy 12.03039 -141.354545) (xy 11.980814 -141.377186) (xy 11.92852 -141.392541) (xy 11.874573 -141.400298)
			(xy 11.847322 -141.400784) (xy 11.821008 -141.400307) (xy 11.76888 -141.393075) (xy 11.718237 -141.378758)
			(xy 11.670038 -141.357627) (xy 11.625194 -141.330083) (xy 11.584555 -141.296645) (xy 11.566398 -141.277594)
			(xy 11.55888 -141.270189) (xy 11.539597 -141.261667) (xy 11.52906 -141.261084) (xy 11.454384 -141.261084)
			(xy 11.443832 -141.261596) (xy 11.424538 -141.270144) (xy 11.417046 -141.277594) (xy 11.398909 -141.296668)
			(xy 11.358275 -141.330123) (xy 11.313431 -141.35768) (xy 11.265227 -141.378815) (xy 11.214576 -141.393129)
			(xy 11.162439 -141.400348) (xy 11.136122 -141.400784) (xy 11.108869 -141.400329) (xy 11.054917 -141.392572)
			(xy 11.002618 -141.377216) (xy 10.953038 -141.354573) (xy 10.907184 -141.325105) (xy 10.86599 -141.289411)
			(xy 10.830296 -141.248218) (xy 10.800828 -141.202364) (xy 10.778185 -141.152783) (xy 10.762828 -141.100485)
			(xy 10.755071 -141.046533) (xy 7.436104 -141.046533) (xy 7.436104 -143.078533) (xy 10.755071 -143.078533)
			(xy 10.755071 -143.024027) (xy 10.762828 -142.970075) (xy 10.778185 -142.917777) (xy 10.800828 -142.868196)
			(xy 10.830296 -142.822342) (xy 10.86599 -142.781149) (xy 10.907184 -142.745455) (xy 10.953038 -142.715987)
			(xy 11.002618 -142.693344) (xy 11.054917 -142.677988) (xy 11.108869 -142.670231) (xy 11.136122 -142.669768)
			(xy 11.162436 -142.670231) (xy 11.214564 -142.677468) (xy 11.265207 -142.691789) (xy 11.313405 -142.712922)
			(xy 11.358249 -142.740469) (xy 11.398889 -142.773907) (xy 11.417046 -142.792958) (xy 11.424554 -142.800376)
			(xy 11.443844 -142.808892) (xy 11.454384 -142.809468) (xy 11.52906 -142.809468) (xy 11.53961 -142.80894)
			(xy 11.558906 -142.800405) (xy 11.566398 -142.792958) (xy 11.584553 -142.773902) (xy 11.625184 -142.740447)
			(xy 11.670025 -142.712889) (xy 11.718225 -142.691751) (xy 11.768872 -142.677433) (xy 11.821006 -142.670207)
			(xy 11.847322 -142.669768) (xy 11.874573 -142.670262) (xy 11.92852 -142.678019) (xy 11.980814 -142.693374)
			(xy 12.03039 -142.716015) (xy 12.07624 -142.745481) (xy 12.117429 -142.781172) (xy 12.15312 -142.822362)
			(xy 12.182586 -142.868212) (xy 12.205227 -142.917788) (xy 12.220582 -142.970082) (xy 12.228338 -143.024029)
			(xy 12.228338 -143.078531) (xy 12.220582 -143.132478) (xy 12.205227 -143.184772) (xy 12.182586 -143.234348)
			(xy 12.15312 -143.280198) (xy 12.117429 -143.321388) (xy 12.07624 -143.357079) (xy 12.03039 -143.386545)
			(xy 11.980814 -143.409186) (xy 11.92852 -143.424541) (xy 11.874573 -143.432298) (xy 11.847322 -143.432784)
			(xy 11.821008 -143.432307) (xy 11.76888 -143.425075) (xy 11.718237 -143.410758) (xy 11.670038 -143.389627)
			(xy 11.625194 -143.362083) (xy 11.584555 -143.328645) (xy 11.566398 -143.309594) (xy 11.55888 -143.302189)
			(xy 11.539597 -143.293667) (xy 11.52906 -143.293084) (xy 11.454384 -143.293084) (xy 11.443832 -143.293596)
			(xy 11.424538 -143.302144) (xy 11.417046 -143.309594) (xy 11.398909 -143.328668) (xy 11.358275 -143.362123)
			(xy 11.313431 -143.38968) (xy 11.265227 -143.410815) (xy 11.214576 -143.425129) (xy 11.162439 -143.432348)
			(xy 11.136122 -143.432784) (xy 11.108869 -143.432329) (xy 11.054917 -143.424572) (xy 11.002618 -143.409216)
			(xy 10.953038 -143.386573) (xy 10.907184 -143.357105) (xy 10.86599 -143.321411) (xy 10.830296 -143.280218)
			(xy 10.800828 -143.234364) (xy 10.778185 -143.184783) (xy 10.762828 -143.132485) (xy 10.755071 -143.078533)
			(xy 7.436104 -143.078533) (xy 7.436104 -143.915638) (xy 19.464274 -143.915638) (xy 19.464775 -143.888065)
			(xy 19.472722 -143.833494) (xy 19.48844 -143.780635) (xy 19.511604 -143.730589) (xy 19.541729 -143.684399)
			(xy 19.57819 -143.643025) (xy 19.598894 -143.624808) (xy 19.606965 -143.617249) (xy 19.616322 -143.597241)
			(xy 19.616928 -143.5862) (xy 19.616928 -143.508476) (xy 19.616341 -143.497428) (xy 19.606991 -143.477406)
			(xy 19.598894 -143.469868) (xy 19.578163 -143.451679) (xy 19.541694 -143.410305) (xy 19.511565 -143.364111)
			(xy 19.488403 -143.314058) (xy 19.472691 -143.261192) (xy 19.464756 -143.206614) (xy 19.464274 -143.179038)
			(xy 19.464767 -143.150298) (xy 19.473398 -143.09347) (xy 19.490456 -143.038579) (xy 19.515554 -142.986868)
			(xy 19.548125 -142.939506) (xy 19.567398 -142.91818) (xy 19.574002 -142.911322) (xy 19.581114 -142.893288)
			(xy 19.581114 -142.804388) (xy 19.574002 -142.786354) (xy 19.567398 -142.779496) (xy 19.548166 -142.758136)
			(xy 19.515602 -142.710778) (xy 19.49051 -142.659072) (xy 19.473458 -142.604187) (xy 19.464833 -142.547364)
			(xy 19.464829 -142.489891) (xy 19.473446 -142.433068) (xy 19.490489 -142.37818) (xy 19.515574 -142.32647)
			(xy 19.548131 -142.279107) (xy 19.567398 -142.25778) (xy 19.574002 -142.250922) (xy 19.581114 -142.232888)
			(xy 19.581114 -142.143988) (xy 19.574002 -142.125954) (xy 19.567398 -142.119096) (xy 19.548166 -142.097736)
			(xy 19.515602 -142.050378) (xy 19.49051 -141.998672) (xy 19.473458 -141.943787) (xy 19.464833 -141.886964)
			(xy 19.464829 -141.829491) (xy 19.473446 -141.772668) (xy 19.490489 -141.71778) (xy 19.515574 -141.66607)
			(xy 19.548131 -141.618707) (xy 19.567398 -141.59738) (xy 19.574002 -141.590522) (xy 19.581114 -141.572488)
			(xy 19.581114 -141.483588) (xy 19.574002 -141.465554) (xy 19.567398 -141.458696) (xy 19.548166 -141.437336)
			(xy 19.515602 -141.389978) (xy 19.49051 -141.338272) (xy 19.473458 -141.283387) (xy 19.464833 -141.226564)
			(xy 19.464829 -141.169091) (xy 19.473446 -141.112268) (xy 19.490489 -141.05738) (xy 19.515574 -141.00567)
			(xy 19.548131 -140.958307) (xy 19.567398 -140.93698) (xy 19.574002 -140.930122) (xy 19.581114 -140.912088)
			(xy 19.581114 -140.823188) (xy 19.574002 -140.805154) (xy 19.567398 -140.798296) (xy 19.548156 -140.776944)
			(xy 19.515583 -140.72959) (xy 19.490484 -140.677885) (xy 19.473427 -140.622999) (xy 19.464798 -140.566175)
			(xy 19.464274 -140.537438) (xy 19.46476 -140.510187) (xy 19.472516 -140.456239) (xy 19.487871 -140.403944)
			(xy 19.510513 -140.354367) (xy 19.539979 -140.308517) (xy 19.57567 -140.267326) (xy 19.616861 -140.231635)
			(xy 19.662711 -140.202169) (xy 19.712288 -140.179527) (xy 19.764583 -140.164172) (xy 19.818531 -140.156416)
			(xy 19.873033 -140.156416) (xy 19.926981 -140.164172) (xy 19.979276 -140.179527) (xy 20.028853 -140.202169)
			(xy 20.074703 -140.231635) (xy 20.115894 -140.267326) (xy 20.151585 -140.308517) (xy 20.181051 -140.354367)
			(xy 20.203693 -140.403944) (xy 20.219048 -140.456239) (xy 20.226804 -140.510187) (xy 20.22729 -140.537438)
			(xy 20.226792 -140.566178) (xy 20.218164 -140.623007) (xy 20.201108 -140.677898) (xy 20.17601 -140.729609)
			(xy 20.143439 -140.77697) (xy 20.124166 -140.798296) (xy 20.117562 -140.805154) (xy 20.11045 -140.823188)
			(xy 20.11045 -140.912088) (xy 20.117562 -140.930122) (xy 20.124166 -140.93698) (xy 20.143475 -140.958274)
			(xy 20.17604 -141.005642) (xy 20.20113 -141.057359) (xy 20.218178 -141.112255) (xy 20.226797 -141.169087)
			(xy 20.226793 -141.226569) (xy 20.218165 -141.283399) (xy 20.20111 -141.338293) (xy 20.176012 -141.390006)
			(xy 20.14344 -141.437369) (xy 20.124166 -141.458696) (xy 20.117562 -141.465554) (xy 20.11045 -141.483588)
			(xy 20.11045 -141.572488) (xy 20.117562 -141.590522) (xy 20.124166 -141.59738) (xy 20.143475 -141.618674)
			(xy 20.17604 -141.666042) (xy 20.20113 -141.717759) (xy 20.218178 -141.772655) (xy 20.226797 -141.829487)
			(xy 20.226793 -141.886969) (xy 20.218165 -141.943799) (xy 20.20111 -141.998693) (xy 20.176012 -142.050406)
			(xy 20.14344 -142.097769) (xy 20.124166 -142.119096) (xy 20.117562 -142.125954) (xy 20.11045 -142.143988)
			(xy 20.11045 -142.232888) (xy 20.117562 -142.250922) (xy 20.124166 -142.25778) (xy 20.143475 -142.279074)
			(xy 20.17604 -142.326442) (xy 20.20113 -142.378159) (xy 20.218178 -142.433055) (xy 20.226797 -142.489887)
			(xy 20.226793 -142.547369) (xy 20.218165 -142.604199) (xy 20.20111 -142.659093) (xy 20.176012 -142.710806)
			(xy 20.14344 -142.758169) (xy 20.124166 -142.779496) (xy 20.117562 -142.786354) (xy 20.11045 -142.804388)
			(xy 20.11045 -142.893288) (xy 20.117562 -142.911322) (xy 20.124166 -142.91818) (xy 20.143455 -142.939491)
			(xy 20.176019 -142.986857) (xy 20.201108 -143.038573) (xy 20.218154 -143.093467) (xy 20.226772 -143.150298)
			(xy 20.22729 -143.179038) (xy 20.226785 -143.206611) (xy 20.218841 -143.261182) (xy 20.203124 -143.314042)
			(xy 20.179961 -143.364088) (xy 20.149836 -143.410279) (xy 20.113374 -143.451651) (xy 20.09267 -143.469868)
			(xy 20.084604 -143.477431) (xy 20.075246 -143.497437) (xy 20.074636 -143.508476) (xy 20.074636 -143.5862)
			(xy 20.075248 -143.597244) (xy 20.084581 -143.617266) (xy 20.09267 -143.624808) (xy 20.113382 -143.643018)
			(xy 20.149854 -143.684386) (xy 20.179987 -143.730576) (xy 20.203152 -143.780625) (xy 20.218868 -143.833488)
			(xy 20.226806 -143.888063) (xy 20.22729 -143.915638) (xy 20.226804 -143.942889) (xy 20.219048 -143.996837)
			(xy 20.203693 -144.049132) (xy 20.181051 -144.098709) (xy 20.151585 -144.144559) (xy 20.115894 -144.18575)
			(xy 20.074703 -144.221441) (xy 20.028853 -144.250907) (xy 19.979276 -144.273549) (xy 19.926981 -144.288904)
			(xy 19.873033 -144.29666) (xy 19.818531 -144.29666) (xy 19.764583 -144.288904) (xy 19.712288 -144.273549)
			(xy 19.662711 -144.250907) (xy 19.616861 -144.221441) (xy 19.57567 -144.18575) (xy 19.539979 -144.144559)
			(xy 19.510513 -144.098709) (xy 19.487871 -144.049132) (xy 19.472516 -143.996837) (xy 19.46476 -143.942889)
			(xy 19.464274 -143.915638) (xy 7.436104 -143.915638) (xy 7.436104 -144.867884) (xy 7.435619 -144.893972)
			(xy 7.427456 -144.945506) (xy 7.411327 -144.995127) (xy 7.387631 -145.041612) (xy 7.356952 -145.083815)
			(xy 7.338822 -145.10258) (xy 7.330869 -145.110533) (xy 10.755071 -145.110533) (xy 10.755071 -145.056027)
			(xy 10.762828 -145.002075) (xy 10.778185 -144.949777) (xy 10.800828 -144.900196) (xy 10.830296 -144.854342)
			(xy 10.86599 -144.813149) (xy 10.907184 -144.777455) (xy 10.953038 -144.747987) (xy 11.002618 -144.725344)
			(xy 11.054917 -144.709988) (xy 11.108869 -144.702231) (xy 11.136122 -144.701768) (xy 11.162436 -144.702231)
			(xy 11.214564 -144.709468) (xy 11.265207 -144.723789) (xy 11.313405 -144.744922) (xy 11.358249 -144.772469)
			(xy 11.398889 -144.805907) (xy 11.417046 -144.824958) (xy 11.424554 -144.832376) (xy 11.443844 -144.840892)
			(xy 11.454384 -144.841468) (xy 11.52906 -144.841468) (xy 11.53961 -144.84094) (xy 11.558906 -144.832405)
			(xy 11.566398 -144.824958) (xy 11.584553 -144.805902) (xy 11.625184 -144.772447) (xy 11.670025 -144.744889)
			(xy 11.718225 -144.723751) (xy 11.768872 -144.709433) (xy 11.821006 -144.702207) (xy 11.847322 -144.701768)
			(xy 11.874573 -144.702262) (xy 11.92852 -144.710019) (xy 11.980814 -144.725374) (xy 12.03039 -144.748015)
			(xy 12.07624 -144.777481) (xy 12.117429 -144.813172) (xy 12.15312 -144.854362) (xy 12.182586 -144.900212)
			(xy 12.205227 -144.949788) (xy 12.206535 -144.954244) (xy 17.939004 -144.954244) (xy 17.939496 -144.926992)
			(xy 17.947248 -144.873041) (xy 17.962599 -144.820743) (xy 17.985237 -144.771162) (xy 18.014701 -144.725308)
			(xy 18.050392 -144.684115) (xy 18.091583 -144.648421) (xy 18.137434 -144.618952) (xy 18.187013 -144.59631)
			(xy 18.23931 -144.580954) (xy 18.29326 -144.573199) (xy 18.320512 -144.572736) (xy 18.349288 -144.573223)
			(xy 18.406184 -144.581882) (xy 18.461135 -144.598986) (xy 18.512895 -144.624148) (xy 18.560289 -144.656798)
			(xy 18.581624 -144.676114) (xy 18.589498 -144.68348) (xy 18.60931 -144.690592) (xy 18.705576 -144.683226)
			(xy 18.724372 -144.67332) (xy 18.730976 -144.664938) (xy 18.749179 -144.642735) (xy 18.791119 -144.603525)
			(xy 18.838459 -144.571041) (xy 18.890131 -144.546016) (xy 18.944969 -144.529014) (xy 19.001735 -144.520419)
			(xy 19.030442 -144.519904) (xy 19.057695 -144.520339) (xy 19.111645 -144.528101) (xy 19.163941 -144.543462)
			(xy 19.21352 -144.566109) (xy 19.25937 -144.595581) (xy 19.30056 -144.631278) (xy 19.336251 -144.672473)
			(xy 19.365717 -144.718328) (xy 19.388357 -144.767909) (xy 19.40371 -144.820208) (xy 19.411465 -144.874159)
			(xy 19.41195 -144.901412) (xy 19.411476 -144.928314) (xy 19.403904 -144.981583) (xy 19.388925 -145.03326)
			(xy 19.366836 -145.082321) (xy 19.338076 -145.127793) (xy 19.303214 -145.168775) (xy 19.262942 -145.204455)
			(xy 19.240754 -145.219674) (xy 19.229832 -145.226786) (xy 19.217894 -145.249646) (xy 19.219926 -145.361914)
			(xy 19.23288 -145.384266) (xy 19.244056 -145.391124) (xy 19.267647 -145.406062) (xy 19.310602 -145.441736)
			(xy 19.347897 -145.483291) (xy 19.378737 -145.529838) (xy 19.402462 -145.580383) (xy 19.418566 -145.633847)
			(xy 19.426704 -145.689088) (xy 19.42719 -145.717006) (xy 19.426721 -145.743999) (xy 19.419116 -145.797446)
			(xy 19.404057 -145.849289) (xy 19.381845 -145.898494) (xy 19.352923 -145.944079) (xy 19.33575 -145.96491)
			(xy 19.328638 -145.973038) (xy 19.322542 -145.993612) (xy 19.333464 -146.078956) (xy 19.335269 -146.089493)
			(xy 19.346303 -146.107777) (xy 19.3548 -146.114262) (xy 19.376018 -146.129632) (xy 19.414469 -146.165218)
			(xy 19.447687 -146.205732) (xy 19.475047 -146.250413) (xy 19.496032 -146.298418) (xy 19.510249 -146.348843)
			(xy 19.517429 -146.40074) (xy 19.517868 -146.426936) (xy 19.517382 -146.454187) (xy 19.509626 -146.508135)
			(xy 19.494271 -146.56043) (xy 19.471629 -146.610007) (xy 19.442163 -146.655857) (xy 19.406472 -146.697048)
			(xy 19.365281 -146.732739) (xy 19.319431 -146.762205) (xy 19.269854 -146.784847) (xy 19.217559 -146.800202)
			(xy 19.163611 -146.807958) (xy 19.109109 -146.807958) (xy 19.055161 -146.800202) (xy 19.002866 -146.784847)
			(xy 18.953289 -146.762205) (xy 18.907439 -146.732739) (xy 18.866248 -146.697048) (xy 18.830557 -146.655857)
			(xy 18.801091 -146.610007) (xy 18.778449 -146.56043) (xy 18.763094 -146.508135) (xy 18.755338 -146.454187)
			(xy 18.754852 -146.426936) (xy 18.755335 -146.399943) (xy 18.762936 -146.346496) (xy 18.777991 -146.294653)
			(xy 18.8002 -146.245448) (xy 18.82912 -146.199863) (xy 18.846292 -146.179032) (xy 18.853404 -146.170904)
			(xy 18.8595 -146.15033) (xy 18.848578 -146.064986) (xy 18.846822 -146.054437) (xy 18.835755 -146.036156)
			(xy 18.827242 -146.02968) (xy 18.802936 -146.012074) (xy 18.75968 -145.970474) (xy 18.741136 -145.946876)
			(xy 18.735294 -145.939002) (xy 18.717768 -145.928588) (xy 18.627344 -145.91538) (xy 18.60804 -145.920206)
			(xy 18.600166 -145.926048) (xy 18.599912 -145.926048) (xy 18.575181 -145.943571) (xy 18.521324 -145.97137)
			(xy 18.463748 -145.990301) (xy 18.403902 -145.999887) (xy 18.373598 -146.00047) (xy 18.346343 -146.000046)
			(xy 18.292389 -145.992288) (xy 18.240088 -145.97693) (xy 18.190505 -145.954284) (xy 18.144651 -145.924813)
			(xy 18.103457 -145.889115) (xy 18.067763 -145.847917) (xy 18.038296 -145.802059) (xy 18.015656 -145.752474)
			(xy 18.000303 -145.700172) (xy 17.992551 -145.646217) (xy 17.99209 -145.618962) (xy 17.992513 -145.592928)
			(xy 17.999606 -145.541344) (xy 18.01364 -145.491201) (xy 18.034357 -145.443431) (xy 18.061371 -145.398917)
			(xy 18.077434 -145.378424) (xy 18.08318 -145.37067) (xy 18.088917 -145.352257) (xy 18.08861 -145.34261)
			(xy 18.08226 -145.262854) (xy 18.073624 -145.245074) (xy 18.066258 -145.238724) (xy 18.046611 -145.220544)
			(xy 18.012087 -145.179638) (xy 17.983617 -145.134309) (xy 17.961759 -145.085447) (xy 17.946943 -145.03401)
			(xy 17.939458 -144.981008) (xy 17.939004 -144.954244) (xy 12.206535 -144.954244) (xy 12.220582 -145.002082)
			(xy 12.228338 -145.056029) (xy 12.228338 -145.110531) (xy 12.220582 -145.164478) (xy 12.205227 -145.216772)
			(xy 12.182586 -145.266348) (xy 12.15312 -145.312198) (xy 12.117429 -145.353388) (xy 12.07624 -145.389079)
			(xy 12.03039 -145.418545) (xy 11.980814 -145.441186) (xy 11.92852 -145.456541) (xy 11.874573 -145.464298)
			(xy 11.847322 -145.464784) (xy 11.821008 -145.464307) (xy 11.76888 -145.457075) (xy 11.718237 -145.442758)
			(xy 11.670038 -145.421627) (xy 11.625194 -145.394083) (xy 11.584555 -145.360645) (xy 11.566398 -145.341594)
			(xy 11.55888 -145.334189) (xy 11.539597 -145.325667) (xy 11.52906 -145.325084) (xy 11.454384 -145.325084)
			(xy 11.443832 -145.325596) (xy 11.424538 -145.334144) (xy 11.417046 -145.341594) (xy 11.398909 -145.360668)
			(xy 11.358275 -145.394123) (xy 11.313431 -145.42168) (xy 11.265227 -145.442815) (xy 11.214576 -145.457129)
			(xy 11.162439 -145.464348) (xy 11.136122 -145.464784) (xy 11.108869 -145.464329) (xy 11.054917 -145.456572)
			(xy 11.002618 -145.441216) (xy 10.953038 -145.418573) (xy 10.907184 -145.389105) (xy 10.86599 -145.353411)
			(xy 10.830296 -145.312218) (xy 10.800828 -145.266364) (xy 10.778185 -145.216783) (xy 10.762828 -145.164485)
			(xy 10.755071 -145.110533) (xy 7.330869 -145.110533) (xy 6.499352 -145.94205) (xy 6.496643 -145.944899)
			(xy 6.492043 -145.951274) (xy 6.490208 -145.95475) (xy 6.487625 -145.960177) (xy 6.484803 -145.971857)
			(xy 6.48462 -145.977864) (xy 6.48462 -146.91487) (xy 19.616164 -146.91487) (xy 19.620235 -146.859248)
			(xy 19.632361 -146.804811) (xy 19.652284 -146.75272) (xy 19.67958 -146.704085) (xy 19.713666 -146.659942)
			(xy 19.753815 -146.621233) (xy 19.799173 -146.588782) (xy 19.848773 -146.563281) (xy 19.901557 -146.545274)
			(xy 19.9564 -146.535144) (xy 20.012134 -146.533107) (xy 20.067571 -146.539207) (xy 20.121528 -146.553313)
			(xy 20.172857 -146.575125) (xy 20.220463 -146.604179) (xy 20.263331 -146.639854) (xy 20.300548 -146.681391)
			(xy 20.331321 -146.727904) (xy 20.354993 -146.778401) (xy 20.371061 -146.831808) (xy 20.379181 -146.886984)
			(xy 20.37969 -146.91487) (xy 20.379181 -146.942756) (xy 20.371061 -146.997932) (xy 20.354993 -147.051339)
			(xy 20.349787 -147.062444) (xy 20.994368 -147.062444) (xy 20.998439 -147.006822) (xy 21.010565 -146.952385)
			(xy 21.030488 -146.900294) (xy 21.057784 -146.851659) (xy 21.09187 -146.807516) (xy 21.132019 -146.768807)
			(xy 21.177377 -146.736356) (xy 21.226977 -146.710855) (xy 21.279761 -146.692848) (xy 21.334604 -146.682718)
			(xy 21.390338 -146.680681) (xy 21.445775 -146.686781) (xy 21.499732 -146.700887) (xy 21.551061 -146.722699)
			(xy 21.598667 -146.751753) (xy 21.641535 -146.787428) (xy 21.678752 -146.828965) (xy 21.709525 -146.875478)
			(xy 21.733197 -146.925975) (xy 21.749265 -146.979382) (xy 21.757385 -147.034558) (xy 21.757894 -147.062444)
			(xy 21.757385 -147.09033) (xy 21.749265 -147.145506) (xy 21.733197 -147.198913) (xy 21.709525 -147.24941)
			(xy 21.678752 -147.295923) (xy 21.641535 -147.33746) (xy 21.598667 -147.373135) (xy 21.551061 -147.402189)
			(xy 21.499732 -147.424001) (xy 21.445775 -147.438107) (xy 21.390338 -147.444207) (xy 21.334604 -147.44217)
			(xy 21.279761 -147.43204) (xy 21.226977 -147.414033) (xy 21.177377 -147.388532) (xy 21.132019 -147.356081)
			(xy 21.09187 -147.317372) (xy 21.057784 -147.273229) (xy 21.030488 -147.224594) (xy 21.010565 -147.172503)
			(xy 20.998439 -147.118066) (xy 20.994368 -147.062444) (xy 20.349787 -147.062444) (xy 20.331321 -147.101836)
			(xy 20.300548 -147.148349) (xy 20.263331 -147.189886) (xy 20.220463 -147.225561) (xy 20.172857 -147.254615)
			(xy 20.121528 -147.276427) (xy 20.067571 -147.290533) (xy 20.012134 -147.296633) (xy 19.9564 -147.294596)
			(xy 19.901557 -147.284466) (xy 19.848773 -147.266459) (xy 19.799173 -147.240958) (xy 19.753815 -147.208507)
			(xy 19.713666 -147.169798) (xy 19.67958 -147.125655) (xy 19.652284 -147.07702) (xy 19.632361 -147.024929)
			(xy 19.620235 -146.970492) (xy 19.616164 -146.91487) (xy 6.48462 -146.91487) (xy 6.48462 -147.657652)
			(xy 11.150566 -147.657652) (xy 11.150566 -147.603148) (xy 11.158323 -147.549198) (xy 11.173678 -147.496902)
			(xy 11.19632 -147.447323) (xy 11.225787 -147.401471) (xy 11.26148 -147.36028) (xy 11.302671 -147.324587)
			(xy 11.348523 -147.29512) (xy 11.398102 -147.272478) (xy 11.450398 -147.257123) (xy 11.504348 -147.249366)
			(xy 11.5316 -147.24888) (xy 11.557914 -147.249354) (xy 11.610042 -147.256588) (xy 11.660684 -147.270907)
			(xy 11.708883 -147.292038) (xy 11.753727 -147.319582) (xy 11.794367 -147.353019) (xy 11.812524 -147.37207)
			(xy 11.820039 -147.37948) (xy 11.839324 -147.388001) (xy 11.849862 -147.38858) (xy 11.924538 -147.38858)
			(xy 11.935086 -147.388037) (xy 11.954382 -147.379512) (xy 11.961876 -147.37207) (xy 11.981696 -147.351282)
			(xy 12.026468 -147.315307) (xy 12.076126 -147.286447) (xy 12.129548 -147.265354) (xy 12.185527 -147.252505)
			(xy 12.2428 -147.24819) (xy 12.300073 -147.252505) (xy 12.356052 -147.265354) (xy 12.409474 -147.286447)
			(xy 12.459132 -147.315307) (xy 12.503904 -147.351282) (xy 12.523724 -147.37207) (xy 12.531239 -147.37948)
			(xy 12.550524 -147.388001) (xy 12.561062 -147.38858) (xy 12.635738 -147.38858) (xy 12.646286 -147.388037)
			(xy 12.665582 -147.379512) (xy 12.673076 -147.37207) (xy 12.691244 -147.353027) (xy 12.731872 -147.31957)
			(xy 12.77671 -147.29201) (xy 12.824908 -147.27087) (xy 12.875553 -147.256549) (xy 12.927685 -147.249321)
			(xy 12.954 -147.24888) (xy 12.98125 -147.24939) (xy 13.035196 -147.257147) (xy 13.087489 -147.272501)
			(xy 13.137065 -147.295142) (xy 13.182914 -147.324607) (xy 13.224103 -147.360297) (xy 13.259793 -147.401486)
			(xy 13.289258 -147.447335) (xy 13.311899 -147.496911) (xy 13.327253 -147.549204) (xy 13.33501 -147.60315)
			(xy 13.33501 -147.65765) (xy 13.327253 -147.711596) (xy 13.311899 -147.763889) (xy 13.289258 -147.813465)
			(xy 13.259793 -147.859314) (xy 13.224103 -147.900503) (xy 13.182914 -147.936193) (xy 13.137065 -147.965658)
			(xy 13.087489 -147.988299) (xy 13.035196 -148.003653) (xy 12.98125 -148.01141) (xy 12.954 -148.011896)
			(xy 12.927686 -148.01143) (xy 12.875557 -148.004195) (xy 12.824915 -147.989876) (xy 12.776716 -147.968743)
			(xy 12.731872 -147.941197) (xy 12.691233 -147.907758) (xy 12.673076 -147.888706) (xy 12.665564 -147.881293)
			(xy 12.646277 -147.872775) (xy 12.635738 -147.872196) (xy 12.561062 -147.872196) (xy 12.550515 -147.872746)
			(xy 12.531219 -147.881267) (xy 12.523724 -147.888706) (xy 12.503904 -147.909494) (xy 12.459132 -147.945469)
			(xy 12.409474 -147.974329) (xy 12.356052 -147.995422) (xy 12.300073 -148.008271) (xy 12.2428 -148.012586)
			(xy 12.185527 -148.008271) (xy 12.129548 -147.995422) (xy 12.076126 -147.974329) (xy 12.026468 -147.945469)
			(xy 11.981696 -147.909494) (xy 11.961876 -147.888706) (xy 11.954364 -147.881293) (xy 11.935077 -147.872775)
			(xy 11.924538 -147.872196) (xy 11.849862 -147.872196) (xy 11.839315 -147.872746) (xy 11.820019 -147.881267)
			(xy 11.812524 -147.888706) (xy 11.794351 -147.907744) (xy 11.753725 -147.941203) (xy 11.708888 -147.968764)
			(xy 11.660691 -147.989905) (xy 11.610047 -148.004226) (xy 11.557915 -148.011455) (xy 11.5316 -148.011896)
			(xy 11.504348 -148.011434) (xy 11.450398 -148.003677) (xy 11.398102 -147.988322) (xy 11.348523 -147.96568)
			(xy 11.302671 -147.936213) (xy 11.26148 -147.90052) (xy 11.225787 -147.859329) (xy 11.19632 -147.813477)
			(xy 11.173678 -147.763898) (xy 11.158323 -147.711602) (xy 11.150566 -147.657652) (xy 6.48462 -147.657652)
			(xy 6.48462 -148.017738) (xy 15.977614 -148.017738) (xy 15.981685 -147.962116) (xy 15.993811 -147.907679)
			(xy 16.013734 -147.855588) (xy 16.04103 -147.806953) (xy 16.075116 -147.76281) (xy 16.115265 -147.724101)
			(xy 16.160623 -147.69165) (xy 16.210223 -147.666149) (xy 16.263007 -147.648142) (xy 16.31785 -147.638012)
			(xy 16.373584 -147.635975) (xy 16.429021 -147.642075) (xy 16.482978 -147.656181) (xy 16.534307 -147.677993)
			(xy 16.581913 -147.707047) (xy 16.623176 -147.741386) (xy 21.662134 -147.741386) (xy 21.666205 -147.685764)
			(xy 21.678331 -147.631327) (xy 21.698254 -147.579236) (xy 21.72555 -147.530601) (xy 21.759636 -147.486458)
			(xy 21.799785 -147.447749) (xy 21.845143 -147.415298) (xy 21.894743 -147.389797) (xy 21.947527 -147.37179)
			(xy 22.00237 -147.36166) (xy 22.058104 -147.359623) (xy 22.113541 -147.365723) (xy 22.167498 -147.379829)
			(xy 22.218827 -147.401641) (xy 22.266433 -147.430695) (xy 22.309301 -147.46637) (xy 22.346518 -147.507907)
			(xy 22.377291 -147.55442) (xy 22.400963 -147.604917) (xy 22.417031 -147.658324) (xy 22.425151 -147.7135)
			(xy 22.42566 -147.741386) (xy 22.425151 -147.769272) (xy 22.417031 -147.824448) (xy 22.400963 -147.877855)
			(xy 22.377291 -147.928352) (xy 22.346518 -147.974865) (xy 22.309301 -148.016402) (xy 22.266433 -148.052077)
			(xy 22.218827 -148.081131) (xy 22.167498 -148.102943) (xy 22.113541 -148.117049) (xy 22.058104 -148.123149)
			(xy 22.00237 -148.121112) (xy 21.947527 -148.110982) (xy 21.894743 -148.092975) (xy 21.845143 -148.067474)
			(xy 21.799785 -148.035023) (xy 21.759636 -147.996314) (xy 21.72555 -147.952171) (xy 21.698254 -147.903536)
			(xy 21.678331 -147.851445) (xy 21.666205 -147.797008) (xy 21.662134 -147.741386) (xy 16.623176 -147.741386)
			(xy 16.624781 -147.742722) (xy 16.661998 -147.784259) (xy 16.692771 -147.830772) (xy 16.716443 -147.881269)
			(xy 16.732511 -147.934676) (xy 16.740631 -147.989852) (xy 16.74114 -148.017738) (xy 16.740631 -148.045624)
			(xy 16.732511 -148.1008) (xy 16.716443 -148.154207) (xy 16.692771 -148.204704) (xy 16.661998 -148.251217)
			(xy 16.624781 -148.292754) (xy 16.581913 -148.328429) (xy 16.534307 -148.357483) (xy 16.482978 -148.379295)
			(xy 16.429021 -148.393401) (xy 16.373584 -148.399501) (xy 16.31785 -148.397464) (xy 16.263007 -148.387334)
			(xy 16.210223 -148.369327) (xy 16.160623 -148.343826) (xy 16.115265 -148.311375) (xy 16.075116 -148.272666)
			(xy 16.04103 -148.228523) (xy 16.013734 -148.179888) (xy 15.993811 -148.127797) (xy 15.981685 -148.07336)
			(xy 15.977614 -148.017738) (xy 6.48462 -148.017738) (xy 6.48462 -150.19585) (xy 11.150588 -150.19585)
			(xy 11.150588 -150.14135) (xy 11.158345 -150.087403) (xy 11.173699 -150.03511) (xy 11.19634 -149.985534)
			(xy 11.225805 -149.939685) (xy 11.261496 -149.898496) (xy 11.302685 -149.862805) (xy 11.348534 -149.83334)
			(xy 11.39811 -149.810699) (xy 11.450403 -149.795345) (xy 11.50435 -149.787588) (xy 11.5316 -149.787102)
			(xy 11.557914 -149.787569) (xy 11.610043 -149.794804) (xy 11.660685 -149.809123) (xy 11.708884 -149.830255)
			(xy 11.753728 -149.857802) (xy 11.794367 -149.89124) (xy 11.812524 -149.910292) (xy 11.820036 -149.917705)
			(xy 11.839323 -149.926223) (xy 11.849862 -149.926802) (xy 11.924538 -149.926802) (xy 11.935085 -149.926252)
			(xy 11.954381 -149.917732) (xy 11.961876 -149.910292) (xy 11.981696 -149.889504) (xy 12.026468 -149.853529)
			(xy 12.076126 -149.824669) (xy 12.129548 -149.803576) (xy 12.185527 -149.790727) (xy 12.2428 -149.786412)
			(xy 12.300073 -149.790727) (xy 12.356052 -149.803576) (xy 12.409474 -149.824669) (xy 12.459132 -149.853529)
			(xy 12.503904 -149.889504) (xy 12.523724 -149.910292) (xy 12.531236 -149.917705) (xy 12.550523 -149.926223)
			(xy 12.561062 -149.926802) (xy 12.635738 -149.926802) (xy 12.646285 -149.926252) (xy 12.665581 -149.917732)
			(xy 12.673076 -149.910292) (xy 12.691249 -149.891254) (xy 12.731875 -149.857795) (xy 12.776712 -149.830234)
			(xy 12.824909 -149.809093) (xy 12.875553 -149.794772) (xy 12.927685 -149.787543) (xy 12.954 -149.787102)
			(xy 12.981252 -149.787568) (xy 13.035201 -149.795325) (xy 13.087497 -149.81068) (xy 13.137076 -149.833322)
			(xy 13.182927 -149.862789) (xy 13.224119 -149.898481) (xy 13.259811 -149.939673) (xy 13.289278 -149.985524)
			(xy 13.31192 -150.035103) (xy 13.320244 -150.063454) (xy 15.838168 -150.063454) (xy 15.842239 -150.007832)
			(xy 15.854365 -149.953395) (xy 15.874288 -149.901304) (xy 15.901584 -149.852669) (xy 15.93567 -149.808526)
			(xy 15.975819 -149.769817) (xy 16.021177 -149.737366) (xy 16.070777 -149.711865) (xy 16.123561 -149.693858)
			(xy 16.178404 -149.683728) (xy 16.234138 -149.681691) (xy 16.289575 -149.687791) (xy 16.343532 -149.701897)
			(xy 16.394861 -149.723709) (xy 16.442467 -149.752763) (xy 16.485335 -149.788438) (xy 16.522552 -149.829975)
			(xy 16.553325 -149.876488) (xy 16.576997 -149.926985) (xy 16.593065 -149.980392) (xy 16.601185 -150.035568)
			(xy 16.601694 -150.063454) (xy 16.601185 -150.09134) (xy 16.593065 -150.146516) (xy 16.576997 -150.199923)
			(xy 16.553325 -150.25042) (xy 16.522552 -150.296933) (xy 16.485335 -150.33847) (xy 16.442467 -150.374145)
			(xy 16.394861 -150.403199) (xy 16.343532 -150.425011) (xy 16.289575 -150.439117) (xy 16.234138 -150.445217)
			(xy 16.178404 -150.44318) (xy 16.123561 -150.43305) (xy 16.070777 -150.415043) (xy 16.021177 -150.389542)
			(xy 15.975819 -150.357091) (xy 15.93567 -150.318382) (xy 15.901584 -150.274239) (xy 15.874288 -150.225604)
			(xy 15.854365 -150.173513) (xy 15.842239 -150.119076) (xy 15.838168 -150.063454) (xy 13.320244 -150.063454)
			(xy 13.327275 -150.087399) (xy 13.335032 -150.141348) (xy 13.335032 -150.195852) (xy 13.327275 -150.249801)
			(xy 13.31192 -150.302097) (xy 13.289278 -150.351676) (xy 13.259811 -150.397527) (xy 13.224119 -150.438719)
			(xy 13.182927 -150.474411) (xy 13.137076 -150.503878) (xy 13.087497 -150.52652) (xy 13.035201 -150.541875)
			(xy 12.981252 -150.549632) (xy 12.954 -150.550118) (xy 12.927686 -150.549645) (xy 12.875558 -150.54241)
			(xy 12.824916 -150.528092) (xy 12.776717 -150.506961) (xy 12.731873 -150.479416) (xy 12.691233 -150.445979)
			(xy 12.673076 -150.426928) (xy 12.665562 -150.419518) (xy 12.646276 -150.410997) (xy 12.635738 -150.410418)
			(xy 12.561062 -150.410418) (xy 12.550514 -150.410962) (xy 12.531218 -150.419486) (xy 12.523724 -150.426928)
			(xy 12.503904 -150.447716) (xy 12.459132 -150.483691) (xy 12.409474 -150.512551) (xy 12.356052 -150.533644)
			(xy 12.300073 -150.546493) (xy 12.2428 -150.550808) (xy 12.185527 -150.546493) (xy 12.129548 -150.533644)
			(xy 12.076126 -150.512551) (xy 12.026468 -150.483691) (xy 11.981696 -150.447716) (xy 11.961876 -150.426928)
			(xy 11.954362 -150.419518) (xy 11.935076 -150.410997) (xy 11.924538 -150.410418) (xy 11.849862 -150.410418)
			(xy 11.839314 -150.410962) (xy 11.820018 -150.419486) (xy 11.812524 -150.426928) (xy 11.794355 -150.44597)
			(xy 11.753728 -150.479428) (xy 11.70889 -150.506988) (xy 11.660692 -150.528128) (xy 11.610047 -150.542449)
			(xy 11.557915 -150.549677) (xy 11.5316 -150.550118) (xy 11.50435 -150.549612) (xy 11.450403 -150.541855)
			(xy 11.39811 -150.526501) (xy 11.348534 -150.50386) (xy 11.302685 -150.474395) (xy 11.261496 -150.438704)
			(xy 11.225805 -150.397515) (xy 11.19634 -150.351666) (xy 11.173699 -150.30209) (xy 11.158345 -150.249797)
			(xy 11.150588 -150.19585) (xy 6.48462 -150.19585) (xy 6.48462 -151.67102) (xy 15.793718 -151.67102)
			(xy 15.797789 -151.615398) (xy 15.809915 -151.560961) (xy 15.829838 -151.50887) (xy 15.857134 -151.460235)
			(xy 15.89122 -151.416092) (xy 15.931369 -151.377383) (xy 15.976727 -151.344932) (xy 16.026327 -151.319431)
			(xy 16.079111 -151.301424) (xy 16.133954 -151.291294) (xy 16.189688 -151.289257) (xy 16.245125 -151.295357)
			(xy 16.299082 -151.309463) (xy 16.350411 -151.331275) (xy 16.398017 -151.360329) (xy 16.440885 -151.396004)
			(xy 16.478102 -151.437541) (xy 16.508875 -151.484054) (xy 16.532547 -151.534551) (xy 16.548615 -151.587958)
			(xy 16.556735 -151.643134) (xy 16.557244 -151.67102) (xy 16.556771 -151.696928) (xy 16.809718 -151.696928)
			(xy 16.813789 -151.641306) (xy 16.825915 -151.586869) (xy 16.845838 -151.534778) (xy 16.873134 -151.486143)
			(xy 16.90722 -151.442) (xy 16.947369 -151.403291) (xy 16.992727 -151.37084) (xy 17.042327 -151.345339)
			(xy 17.095111 -151.327332) (xy 17.149954 -151.317202) (xy 17.205688 -151.315165) (xy 17.261125 -151.321265)
			(xy 17.315082 -151.335371) (xy 17.366411 -151.357183) (xy 17.414017 -151.386237) (xy 17.438493 -151.406606)
			(xy 18.036792 -151.406606) (xy 18.040863 -151.350984) (xy 18.052989 -151.296547) (xy 18.072912 -151.244456)
			(xy 18.100208 -151.195821) (xy 18.134294 -151.151678) (xy 18.174443 -151.112969) (xy 18.219801 -151.080518)
			(xy 18.269401 -151.055017) (xy 18.322185 -151.03701) (xy 18.377028 -151.02688) (xy 18.432762 -151.024843)
			(xy 18.488199 -151.030943) (xy 18.542156 -151.045049) (xy 18.593485 -151.066861) (xy 18.641091 -151.095915)
			(xy 18.683959 -151.13159) (xy 18.721176 -151.173127) (xy 18.751949 -151.21964) (xy 18.775621 -151.270137)
			(xy 18.791689 -151.323544) (xy 18.799809 -151.37872) (xy 18.800318 -151.406606) (xy 18.799809 -151.434492)
			(xy 18.791689 -151.489668) (xy 18.775621 -151.543075) (xy 18.757079 -151.582628) (xy 19.362418 -151.582628)
			(xy 19.366489 -151.527006) (xy 19.378615 -151.472569) (xy 19.398538 -151.420478) (xy 19.425834 -151.371843)
			(xy 19.45992 -151.3277) (xy 19.500069 -151.288991) (xy 19.545427 -151.25654) (xy 19.595027 -151.231039)
			(xy 19.647811 -151.213032) (xy 19.702654 -151.202902) (xy 19.758388 -151.200865) (xy 19.813825 -151.206965)
			(xy 19.867782 -151.221071) (xy 19.919111 -151.242883) (xy 19.966717 -151.271937) (xy 20.009585 -151.307612)
			(xy 20.046802 -151.349149) (xy 20.077575 -151.395662) (xy 20.101247 -151.446159) (xy 20.117315 -151.499566)
			(xy 20.125435 -151.554742) (xy 20.125698 -151.569166) (xy 20.873718 -151.569166) (xy 20.877789 -151.513544)
			(xy 20.889915 -151.459107) (xy 20.909838 -151.407016) (xy 20.937134 -151.358381) (xy 20.97122 -151.314238)
			(xy 21.011369 -151.275529) (xy 21.056727 -151.243078) (xy 21.106327 -151.217577) (xy 21.159111 -151.19957)
			(xy 21.213954 -151.18944) (xy 21.269688 -151.187403) (xy 21.325125 -151.193503) (xy 21.379082 -151.207609)
			(xy 21.430411 -151.229421) (xy 21.478017 -151.258475) (xy 21.520885 -151.29415) (xy 21.558102 -151.335687)
			(xy 21.588875 -151.3822) (xy 21.612547 -151.432697) (xy 21.628615 -151.486104) (xy 21.636735 -151.54128)
			(xy 21.637244 -151.569166) (xy 21.636735 -151.597052) (xy 21.628615 -151.652228) (xy 21.612547 -151.705635)
			(xy 21.588875 -151.756132) (xy 21.558102 -151.802645) (xy 21.520885 -151.844182) (xy 21.478017 -151.879857)
			(xy 21.430411 -151.908911) (xy 21.379082 -151.930723) (xy 21.325125 -151.944829) (xy 21.269688 -151.950929)
			(xy 21.213954 -151.948892) (xy 21.159111 -151.938762) (xy 21.106327 -151.920755) (xy 21.056727 -151.895254)
			(xy 21.011369 -151.862803) (xy 20.97122 -151.824094) (xy 20.937134 -151.779951) (xy 20.909838 -151.731316)
			(xy 20.889915 -151.679225) (xy 20.877789 -151.624788) (xy 20.873718 -151.569166) (xy 20.125698 -151.569166)
			(xy 20.125944 -151.582628) (xy 20.125435 -151.610514) (xy 20.117315 -151.66569) (xy 20.101247 -151.719097)
			(xy 20.077575 -151.769594) (xy 20.046802 -151.816107) (xy 20.009585 -151.857644) (xy 19.966717 -151.893319)
			(xy 19.919111 -151.922373) (xy 19.867782 -151.944185) (xy 19.813825 -151.958291) (xy 19.758388 -151.964391)
			(xy 19.702654 -151.962354) (xy 19.647811 -151.952224) (xy 19.595027 -151.934217) (xy 19.545427 -151.908716)
			(xy 19.500069 -151.876265) (xy 19.45992 -151.837556) (xy 19.425834 -151.793413) (xy 19.398538 -151.744778)
			(xy 19.378615 -151.692687) (xy 19.366489 -151.63825) (xy 19.362418 -151.582628) (xy 18.757079 -151.582628)
			(xy 18.751949 -151.593572) (xy 18.721176 -151.640085) (xy 18.683959 -151.681622) (xy 18.641091 -151.717297)
			(xy 18.593485 -151.746351) (xy 18.542156 -151.768163) (xy 18.488199 -151.782269) (xy 18.432762 -151.788369)
			(xy 18.377028 -151.786332) (xy 18.322185 -151.776202) (xy 18.269401 -151.758195) (xy 18.219801 -151.732694)
			(xy 18.174443 -151.700243) (xy 18.134294 -151.661534) (xy 18.100208 -151.617391) (xy 18.072912 -151.568756)
			(xy 18.052989 -151.516665) (xy 18.040863 -151.462228) (xy 18.036792 -151.406606) (xy 17.438493 -151.406606)
			(xy 17.456885 -151.421912) (xy 17.494102 -151.463449) (xy 17.524875 -151.509962) (xy 17.548547 -151.560459)
			(xy 17.564615 -151.613866) (xy 17.572735 -151.669042) (xy 17.573244 -151.696928) (xy 17.572735 -151.724814)
			(xy 17.564615 -151.77999) (xy 17.548547 -151.833397) (xy 17.524875 -151.883894) (xy 17.494102 -151.930407)
			(xy 17.456885 -151.971944) (xy 17.414017 -152.007619) (xy 17.366411 -152.036673) (xy 17.315082 -152.058485)
			(xy 17.261125 -152.072591) (xy 17.205688 -152.078691) (xy 17.149954 -152.076654) (xy 17.095111 -152.066524)
			(xy 17.042327 -152.048517) (xy 16.992727 -152.023016) (xy 16.947369 -151.990565) (xy 16.90722 -151.951856)
			(xy 16.873134 -151.907713) (xy 16.845838 -151.859078) (xy 16.825915 -151.806987) (xy 16.813789 -151.75255)
			(xy 16.809718 -151.696928) (xy 16.556771 -151.696928) (xy 16.556735 -151.698906) (xy 16.548615 -151.754082)
			(xy 16.532547 -151.807489) (xy 16.508875 -151.857986) (xy 16.478102 -151.904499) (xy 16.440885 -151.946036)
			(xy 16.398017 -151.981711) (xy 16.350411 -152.010765) (xy 16.299082 -152.032577) (xy 16.245125 -152.046683)
			(xy 16.189688 -152.052783) (xy 16.133954 -152.050746) (xy 16.079111 -152.040616) (xy 16.026327 -152.022609)
			(xy 15.976727 -151.997108) (xy 15.931369 -151.964657) (xy 15.89122 -151.925948) (xy 15.857134 -151.881805)
			(xy 15.829838 -151.83317) (xy 15.809915 -151.781079) (xy 15.797789 -151.726642) (xy 15.793718 -151.67102)
			(xy 6.48462 -151.67102) (xy 6.48462 -153.782522) (xy 14.777718 -153.782522) (xy 14.781789 -153.7269)
			(xy 14.793915 -153.672463) (xy 14.813838 -153.620372) (xy 14.841134 -153.571737) (xy 14.87522 -153.527594)
			(xy 14.915369 -153.488885) (xy 14.960727 -153.456434) (xy 15.010327 -153.430933) (xy 15.063111 -153.412926)
			(xy 15.117954 -153.402796) (xy 15.173688 -153.400759) (xy 15.229125 -153.406859) (xy 15.283082 -153.420965)
			(xy 15.334411 -153.442777) (xy 15.382017 -153.471831) (xy 15.424885 -153.507506) (xy 15.462102 -153.549043)
			(xy 15.492875 -153.595556) (xy 15.516547 -153.646053) (xy 15.532615 -153.69946) (xy 15.540735 -153.754636)
			(xy 15.541244 -153.782522) (xy 15.793718 -153.782522) (xy 15.797789 -153.7269) (xy 15.809915 -153.672463)
			(xy 15.829838 -153.620372) (xy 15.857134 -153.571737) (xy 15.89122 -153.527594) (xy 15.931369 -153.488885)
			(xy 15.976727 -153.456434) (xy 16.026327 -153.430933) (xy 16.079111 -153.412926) (xy 16.133954 -153.402796)
			(xy 16.189688 -153.400759) (xy 16.245125 -153.406859) (xy 16.299082 -153.420965) (xy 16.350411 -153.442777)
			(xy 16.398017 -153.471831) (xy 16.440885 -153.507506) (xy 16.478102 -153.549043) (xy 16.508875 -153.595556)
			(xy 16.532547 -153.646053) (xy 16.548615 -153.69946) (xy 16.556735 -153.754636) (xy 16.557244 -153.782522)
			(xy 16.556735 -153.810408) (xy 16.553587 -153.831798) (xy 16.809718 -153.831798) (xy 16.813789 -153.776176)
			(xy 16.825915 -153.721739) (xy 16.845838 -153.669648) (xy 16.873134 -153.621013) (xy 16.90722 -153.57687)
			(xy 16.947369 -153.538161) (xy 16.992727 -153.50571) (xy 17.042327 -153.480209) (xy 17.095111 -153.462202)
			(xy 17.149954 -153.452072) (xy 17.205688 -153.450035) (xy 17.261125 -153.456135) (xy 17.315082 -153.470241)
			(xy 17.366411 -153.492053) (xy 17.414017 -153.521107) (xy 17.456885 -153.556782) (xy 17.494102 -153.598319)
			(xy 17.524875 -153.644832) (xy 17.548547 -153.695329) (xy 17.564615 -153.748736) (xy 17.569587 -153.782522)
			(xy 19.857718 -153.782522) (xy 19.861789 -153.7269) (xy 19.873915 -153.672463) (xy 19.893838 -153.620372)
			(xy 19.921134 -153.571737) (xy 19.95522 -153.527594) (xy 19.995369 -153.488885) (xy 20.040727 -153.456434)
			(xy 20.090327 -153.430933) (xy 20.143111 -153.412926) (xy 20.197954 -153.402796) (xy 20.253688 -153.400759)
			(xy 20.309125 -153.406859) (xy 20.363082 -153.420965) (xy 20.414411 -153.442777) (xy 20.462017 -153.471831)
			(xy 20.504885 -153.507506) (xy 20.542102 -153.549043) (xy 20.572875 -153.595556) (xy 20.596547 -153.646053)
			(xy 20.612615 -153.69946) (xy 20.620735 -153.754636) (xy 20.621244 -153.782522) (xy 21.889718 -153.782522)
			(xy 21.893789 -153.7269) (xy 21.905915 -153.672463) (xy 21.925838 -153.620372) (xy 21.953134 -153.571737)
			(xy 21.98722 -153.527594) (xy 22.027369 -153.488885) (xy 22.072727 -153.456434) (xy 22.122327 -153.430933)
			(xy 22.175111 -153.412926) (xy 22.229954 -153.402796) (xy 22.285688 -153.400759) (xy 22.341125 -153.406859)
			(xy 22.395082 -153.420965) (xy 22.446411 -153.442777) (xy 22.494017 -153.471831) (xy 22.536885 -153.507506)
			(xy 22.574102 -153.549043) (xy 22.604875 -153.595556) (xy 22.628547 -153.646053) (xy 22.644615 -153.69946)
			(xy 22.652735 -153.754636) (xy 22.653244 -153.782522) (xy 22.652735 -153.810408) (xy 22.644615 -153.865584)
			(xy 22.628547 -153.918991) (xy 22.604875 -153.969488) (xy 22.574102 -154.016001) (xy 22.536885 -154.057538)
			(xy 22.494017 -154.093213) (xy 22.446411 -154.122267) (xy 22.395082 -154.144079) (xy 22.341125 -154.158185)
			(xy 22.285688 -154.164285) (xy 22.229954 -154.162248) (xy 22.175111 -154.152118) (xy 22.122327 -154.134111)
			(xy 22.072727 -154.10861) (xy 22.027369 -154.076159) (xy 21.98722 -154.03745) (xy 21.953134 -153.993307)
			(xy 21.925838 -153.944672) (xy 21.905915 -153.892581) (xy 21.893789 -153.838144) (xy 21.889718 -153.782522)
			(xy 20.621244 -153.782522) (xy 20.620735 -153.810408) (xy 20.612615 -153.865584) (xy 20.596547 -153.918991)
			(xy 20.572875 -153.969488) (xy 20.542102 -154.016001) (xy 20.504885 -154.057538) (xy 20.462017 -154.093213)
			(xy 20.414411 -154.122267) (xy 20.363082 -154.144079) (xy 20.309125 -154.158185) (xy 20.253688 -154.164285)
			(xy 20.197954 -154.162248) (xy 20.143111 -154.152118) (xy 20.090327 -154.134111) (xy 20.040727 -154.10861)
			(xy 19.995369 -154.076159) (xy 19.95522 -154.03745) (xy 19.921134 -153.993307) (xy 19.893838 -153.944672)
			(xy 19.873915 -153.892581) (xy 19.861789 -153.838144) (xy 19.857718 -153.782522) (xy 17.569587 -153.782522)
			(xy 17.572735 -153.803912) (xy 17.573244 -153.831798) (xy 17.572735 -153.859684) (xy 17.564615 -153.91486)
			(xy 17.548547 -153.968267) (xy 17.524875 -154.018764) (xy 17.494102 -154.065277) (xy 17.456885 -154.106814)
			(xy 17.414017 -154.142489) (xy 17.366411 -154.171543) (xy 17.315082 -154.193355) (xy 17.261125 -154.207461)
			(xy 17.205688 -154.213561) (xy 17.149954 -154.211524) (xy 17.095111 -154.201394) (xy 17.042327 -154.183387)
			(xy 16.992727 -154.157886) (xy 16.947369 -154.125435) (xy 16.90722 -154.086726) (xy 16.873134 -154.042583)
			(xy 16.845838 -153.993948) (xy 16.825915 -153.941857) (xy 16.813789 -153.88742) (xy 16.809718 -153.831798)
			(xy 16.553587 -153.831798) (xy 16.548615 -153.865584) (xy 16.532547 -153.918991) (xy 16.508875 -153.969488)
			(xy 16.478102 -154.016001) (xy 16.440885 -154.057538) (xy 16.398017 -154.093213) (xy 16.350411 -154.122267)
			(xy 16.299082 -154.144079) (xy 16.245125 -154.158185) (xy 16.189688 -154.164285) (xy 16.133954 -154.162248)
			(xy 16.079111 -154.152118) (xy 16.026327 -154.134111) (xy 15.976727 -154.10861) (xy 15.931369 -154.076159)
			(xy 15.89122 -154.03745) (xy 15.857134 -153.993307) (xy 15.829838 -153.944672) (xy 15.809915 -153.892581)
			(xy 15.797789 -153.838144) (xy 15.793718 -153.782522) (xy 15.541244 -153.782522) (xy 15.540735 -153.810408)
			(xy 15.532615 -153.865584) (xy 15.516547 -153.918991) (xy 15.492875 -153.969488) (xy 15.462102 -154.016001)
			(xy 15.424885 -154.057538) (xy 15.382017 -154.093213) (xy 15.334411 -154.122267) (xy 15.283082 -154.144079)
			(xy 15.229125 -154.158185) (xy 15.173688 -154.164285) (xy 15.117954 -154.162248) (xy 15.063111 -154.152118)
			(xy 15.010327 -154.134111) (xy 14.960727 -154.10861) (xy 14.915369 -154.076159) (xy 14.87522 -154.03745)
			(xy 14.841134 -153.993307) (xy 14.813838 -153.944672) (xy 14.793915 -153.892581) (xy 14.781789 -153.838144)
			(xy 14.777718 -153.782522) (xy 6.48462 -153.782522) (xy 6.48462 -155.093162) (xy 6.485636 -155.102814)
			(xy 6.487259 -155.110061) (xy 6.494094 -155.123236) (xy 6.499098 -155.128722) (xy 6.58241 -155.212034)
			(xy 7.269224 -155.212034) (xy 7.273295 -155.156412) (xy 7.285421 -155.101975) (xy 7.305344 -155.049884)
			(xy 7.33264 -155.001249) (xy 7.366726 -154.957106) (xy 7.406875 -154.918397) (xy 7.452233 -154.885946)
			(xy 7.501833 -154.860445) (xy 7.554617 -154.842438) (xy 7.60946 -154.832308) (xy 7.665194 -154.830271)
			(xy 7.720631 -154.836371) (xy 7.774588 -154.850477) (xy 7.825917 -154.872289) (xy 7.873523 -154.901343)
			(xy 7.916391 -154.937018) (xy 7.953608 -154.978555) (xy 7.984381 -155.025068) (xy 8.008053 -155.075565)
			(xy 8.009144 -155.079192) (xy 9.86993 -155.079192) (xy 9.874001 -155.02357) (xy 9.886127 -154.969133)
			(xy 9.90605 -154.917042) (xy 9.933346 -154.868407) (xy 9.967432 -154.824264) (xy 10.007581 -154.785555)
			(xy 10.052939 -154.753104) (xy 10.102539 -154.727603) (xy 10.155323 -154.709596) (xy 10.210166 -154.699466)
			(xy 10.2659 -154.697429) (xy 10.321337 -154.703529) (xy 10.375294 -154.717635) (xy 10.426623 -154.739447)
			(xy 10.474229 -154.768501) (xy 10.517097 -154.804176) (xy 10.554314 -154.845713) (xy 10.585087 -154.892226)
			(xy 10.608759 -154.942723) (xy 10.624827 -154.99613) (xy 10.632947 -155.051306) (xy 10.633456 -155.079192)
			(xy 10.633391 -155.082748) (xy 11.19378 -155.082748) (xy 11.194219 -155.056433) (xy 11.201461 -155.004304)
			(xy 11.215786 -154.953661) (xy 11.236924 -154.905462) (xy 11.264474 -154.860619) (xy 11.297917 -154.81998)
			(xy 11.31697 -154.801824) (xy 11.324359 -154.794291) (xy 11.332892 -154.77502) (xy 11.33348 -154.764486)
			(xy 11.33348 -154.68981) (xy 11.332965 -154.679259) (xy 11.32442 -154.659963) (xy 11.31697 -154.652472)
			(xy 11.297902 -154.634329) (xy 11.264447 -154.593696) (xy 11.236891 -154.548853) (xy 11.215755 -154.50065)
			(xy 11.20144 -154.45) (xy 11.194217 -154.397865) (xy 11.19378 -154.371548) (xy 11.1943 -154.344297)
			(xy 11.20205 -154.290349) (xy 11.217399 -154.238053) (xy 11.240035 -154.188473) (xy 11.269497 -154.142621)
			(xy 11.305185 -154.101428) (xy 11.346372 -154.065733) (xy 11.392221 -154.036264) (xy 11.441796 -154.01362)
			(xy 11.49409 -153.998263) (xy 11.548037 -153.990504) (xy 11.575288 -153.99004) (xy 11.601602 -153.990503)
			(xy 11.653731 -153.997737) (xy 11.704375 -154.012056) (xy 11.752574 -154.033189) (xy 11.797417 -154.060737)
			(xy 11.838056 -154.094177) (xy 11.856212 -154.11323) (xy 11.863737 -154.120629) (xy 11.883014 -154.129157)
			(xy 11.89355 -154.12974) (xy 11.968226 -154.12974) (xy 11.978771 -154.129173) (xy 11.998066 -154.120663)
			(xy 12.005564 -154.11323) (xy 12.025384 -154.092442) (xy 12.070156 -154.056467) (xy 12.119814 -154.027607)
			(xy 12.173236 -154.006514) (xy 12.229215 -153.993665) (xy 12.286488 -153.98935) (xy 12.343761 -153.993665)
			(xy 12.39974 -154.006514) (xy 12.453162 -154.027607) (xy 12.50282 -154.056467) (xy 12.547592 -154.092442)
			(xy 12.567412 -154.11323) (xy 12.574937 -154.120629) (xy 12.594214 -154.129157) (xy 12.60475 -154.12974)
			(xy 12.679426 -154.12974) (xy 12.689971 -154.129173) (xy 12.709266 -154.120663) (xy 12.716764 -154.11323)
			(xy 12.736584 -154.092442) (xy 12.781356 -154.056467) (xy 12.831014 -154.027607) (xy 12.884436 -154.006514)
			(xy 12.940415 -153.993665) (xy 12.997688 -153.98935) (xy 13.054961 -153.993665) (xy 13.11094 -154.006514)
			(xy 13.164362 -154.027607) (xy 13.21402 -154.056467) (xy 13.258792 -154.092442) (xy 13.278612 -154.11323)
			(xy 13.286137 -154.120629) (xy 13.305414 -154.129157) (xy 13.31595 -154.12974) (xy 13.390626 -154.12974)
			(xy 13.401171 -154.129173) (xy 13.420466 -154.120663) (xy 13.427964 -154.11323) (xy 13.446101 -154.094156)
			(xy 13.486734 -154.060699) (xy 13.531578 -154.033142) (xy 13.579783 -154.012007) (xy 13.630434 -153.997694)
			(xy 13.682571 -153.990475) (xy 13.708888 -153.99004) (xy 13.736143 -153.990467) (xy 13.790097 -153.998223)
			(xy 13.842399 -154.01358) (xy 13.891982 -154.036225) (xy 13.937838 -154.065696) (xy 13.979032 -154.101394)
			(xy 14.014726 -154.142591) (xy 14.044193 -154.188449) (xy 14.066832 -154.238035) (xy 14.082184 -154.290338)
			(xy 14.089936 -154.344293) (xy 14.090396 -154.371548) (xy 14.089962 -154.397863) (xy 14.08272 -154.449993)
			(xy 14.068395 -154.500637) (xy 14.047256 -154.548835) (xy 14.019704 -154.593678) (xy 13.98626 -154.634316)
			(xy 13.967206 -154.652472) (xy 13.959816 -154.660003) (xy 13.951285 -154.679276) (xy 13.950696 -154.68981)
			(xy 13.950696 -154.764486) (xy 13.951221 -154.775036) (xy 13.959759 -154.794331) (xy 13.967206 -154.801824)
			(xy 13.986267 -154.819974) (xy 14.019724 -154.860605) (xy 14.047282 -154.905446) (xy 14.068419 -154.953648)
			(xy 14.082735 -155.004297) (xy 14.089958 -155.056432) (xy 14.090396 -155.082748) (xy 14.089967 -155.110001)
			(xy 14.082203 -155.163951) (xy 14.066842 -155.216248) (xy 14.044194 -155.265826) (xy 14.014722 -155.311677)
			(xy 13.979024 -155.352867) (xy 13.937829 -155.388558) (xy 13.891973 -155.418023) (xy 13.842392 -155.440663)
			(xy 13.790093 -155.456016) (xy 13.736141 -155.463771) (xy 13.708888 -155.464256) (xy 13.682573 -155.463811)
			(xy 13.630443 -155.456573) (xy 13.579799 -155.442251) (xy 13.5316 -155.421114) (xy 13.486757 -155.393564)
			(xy 13.446119 -155.36012) (xy 13.427964 -155.341066) (xy 13.420449 -155.333656) (xy 13.401164 -155.325134)
			(xy 13.390626 -155.324556) (xy 13.31595 -155.324556) (xy 13.305404 -155.325112) (xy 13.286109 -155.33363)
			(xy 13.278612 -155.341066) (xy 13.258792 -155.361854) (xy 13.21402 -155.397829) (xy 13.164362 -155.426689)
			(xy 13.11094 -155.447782) (xy 13.054961 -155.460631) (xy 12.997688 -155.464946) (xy 12.940415 -155.460631)
			(xy 12.884436 -155.447782) (xy 12.831014 -155.426689) (xy 12.781356 -155.397829) (xy 12.736584 -155.361854)
			(xy 12.716764 -155.341066) (xy 12.709249 -155.333656) (xy 12.689964 -155.325134) (xy 12.679426 -155.324556)
			(xy 12.60475 -155.324556) (xy 12.594204 -155.325112) (xy 12.574909 -155.33363) (xy 12.567412 -155.341066)
			(xy 12.547592 -155.361854) (xy 12.50282 -155.397829) (xy 12.453162 -155.426689) (xy 12.39974 -155.447782)
			(xy 12.343761 -155.460631) (xy 12.286488 -155.464946) (xy 12.229215 -155.460631) (xy 12.173236 -155.447782)
			(xy 12.119814 -155.426689) (xy 12.070156 -155.397829) (xy 12.025384 -155.361854) (xy 12.005564 -155.341066)
			(xy 11.998049 -155.333656) (xy 11.978764 -155.325134) (xy 11.968226 -155.324556) (xy 11.89355 -155.324556)
			(xy 11.883004 -155.325112) (xy 11.863709 -155.33363) (xy 11.856212 -155.341066) (xy 11.838057 -155.360121)
			(xy 11.797425 -155.393576) (xy 11.752585 -155.421133) (xy 11.704384 -155.442271) (xy 11.653737 -155.456589)
			(xy 11.601604 -155.463816) (xy 11.575288 -155.464256) (xy 11.548037 -155.463774) (xy 11.494089 -155.456017)
			(xy 11.441794 -155.440662) (xy 11.392216 -155.41802) (xy 11.346366 -155.388554) (xy 11.305176 -155.352862)
			(xy 11.269484 -155.311671) (xy 11.240018 -155.26582) (xy 11.217377 -155.216243) (xy 11.202022 -155.163947)
			(xy 11.194266 -155.109999) (xy 11.19378 -155.082748) (xy 10.633391 -155.082748) (xy 10.632947 -155.107078)
			(xy 10.624827 -155.162254) (xy 10.608759 -155.215661) (xy 10.585087 -155.266158) (xy 10.554314 -155.312671)
			(xy 10.517097 -155.354208) (xy 10.474229 -155.389883) (xy 10.426623 -155.418937) (xy 10.375294 -155.440749)
			(xy 10.321337 -155.454855) (xy 10.2659 -155.460955) (xy 10.210166 -155.458918) (xy 10.155323 -155.448788)
			(xy 10.102539 -155.430781) (xy 10.052939 -155.40528) (xy 10.007581 -155.372829) (xy 9.967432 -155.33412)
			(xy 9.933346 -155.289977) (xy 9.90605 -155.241342) (xy 9.886127 -155.189251) (xy 9.874001 -155.134814)
			(xy 9.86993 -155.079192) (xy 8.009144 -155.079192) (xy 8.024121 -155.128972) (xy 8.032241 -155.184148)
			(xy 8.03275 -155.212034) (xy 8.032241 -155.23992) (xy 8.024121 -155.295096) (xy 8.008053 -155.348503)
			(xy 7.984381 -155.399) (xy 7.953608 -155.445513) (xy 7.916391 -155.48705) (xy 7.873523 -155.522725)
			(xy 7.825917 -155.551779) (xy 7.774588 -155.573591) (xy 7.720631 -155.587697) (xy 7.665194 -155.593797)
			(xy 7.60946 -155.59176) (xy 7.554617 -155.58163) (xy 7.501833 -155.563623) (xy 7.452233 -155.538122)
			(xy 7.406875 -155.505671) (xy 7.366726 -155.466962) (xy 7.33264 -155.422819) (xy 7.305344 -155.374184)
			(xy 7.285421 -155.322093) (xy 7.273295 -155.267656) (xy 7.269224 -155.212034) (xy 6.58241 -155.212034)
			(xy 8.064246 -156.69387) (xy 8.887458 -156.69387) (xy 8.891529 -156.638248) (xy 8.903655 -156.583811)
			(xy 8.923578 -156.53172) (xy 8.950874 -156.483085) (xy 8.98496 -156.438942) (xy 9.025109 -156.400233)
			(xy 9.070467 -156.367782) (xy 9.120067 -156.342281) (xy 9.172851 -156.324274) (xy 9.227694 -156.314144)
			(xy 9.283428 -156.312107) (xy 9.338865 -156.318207) (xy 9.392822 -156.332313) (xy 9.444151 -156.354125)
			(xy 9.491757 -156.383179) (xy 9.534625 -156.418854) (xy 9.571842 -156.460391) (xy 9.602615 -156.506904)
			(xy 9.626287 -156.557401) (xy 9.642355 -156.610808) (xy 9.650475 -156.665984) (xy 9.650984 -156.69387)
			(xy 9.650475 -156.721756) (xy 9.642355 -156.776932) (xy 9.626287 -156.830339) (xy 9.602615 -156.880836)
			(xy 9.571842 -156.927349) (xy 9.534625 -156.968886) (xy 9.491757 -157.004561) (xy 9.444151 -157.033615)
			(xy 9.392822 -157.055427) (xy 9.338865 -157.069533) (xy 9.283428 -157.075633) (xy 9.227694 -157.073596)
			(xy 9.172851 -157.063466) (xy 9.120067 -157.045459) (xy 9.070467 -157.019958) (xy 9.025109 -156.987507)
			(xy 8.98496 -156.948798) (xy 8.950874 -156.904655) (xy 8.923578 -156.85602) (xy 8.903655 -156.803929)
			(xy 8.891529 -156.749492) (xy 8.887458 -156.69387) (xy 8.064246 -156.69387) (xy 8.414512 -157.044136)
			(xy 8.43255 -157.062904) (xy 8.463142 -157.105018) (xy 8.48678 -157.151393) (xy 8.502883 -157.200892)
			(xy 8.511057 -157.252298) (xy 8.51154 -157.278324) (xy 8.51154 -157.647894) (xy 11.013948 -157.647894)
			(xy 11.014459 -157.62125) (xy 11.022984 -157.568649) (xy 11.039844 -157.518099) (xy 11.064602 -157.470913)
			(xy 11.096615 -157.428313) (xy 11.135053 -157.391407) (xy 11.156696 -157.37586) (xy 11.167989 -157.367504)
			(xy 11.185848 -157.34583) (xy 11.197132 -157.320114) (xy 11.20099 -157.292297) (xy 11.19713 -157.26448)
			(xy 11.185844 -157.238764) (xy 11.167984 -157.217092) (xy 11.156696 -157.208728) (xy 11.135107 -157.193114)
			(xy 11.096689 -157.156206) (xy 11.064685 -157.113615) (xy 11.039924 -157.066445) (xy 11.023047 -157.015914)
			(xy 11.014491 -156.963331) (xy 11.013948 -156.936694) (xy 11.014458 -156.910707) (xy 11.022588 -156.859372)
			(xy 11.038649 -156.809942) (xy 11.062245 -156.763632) (xy 11.092795 -156.721584) (xy 11.129546 -156.684833)
			(xy 11.171594 -156.654283) (xy 11.217904 -156.630687) (xy 11.267334 -156.614626) (xy 11.318669 -156.606496)
			(xy 11.370643 -156.606496) (xy 11.421978 -156.614626) (xy 11.471408 -156.630687) (xy 11.517718 -156.654283)
			(xy 11.559766 -156.684833) (xy 11.596517 -156.721584) (xy 11.627067 -156.763632) (xy 11.650663 -156.809942)
			(xy 11.666724 -156.859372) (xy 11.674854 -156.910707) (xy 11.675364 -156.936694) (xy 11.674839 -156.963337)
			(xy 11.666316 -157.015937) (xy 11.649459 -157.066487) (xy 11.624703 -157.113673) (xy 11.592693 -157.156273)
			(xy 11.554258 -157.193181) (xy 11.532616 -157.208728) (xy 11.521334 -157.217098) (xy 11.503473 -157.238768)
			(xy 11.492187 -157.264482) (xy 11.488327 -157.292297) (xy 11.492185 -157.320112) (xy 11.50347 -157.345826)
			(xy 11.521328 -157.367497) (xy 11.532616 -157.37586) (xy 11.554202 -157.391478) (xy 11.59262 -157.428386)
			(xy 11.624623 -157.470975) (xy 11.649384 -157.518145) (xy 11.666262 -157.568675) (xy 11.674821 -157.621257)
			(xy 11.675364 -157.647894) (xy 11.91387 -157.647894) (xy 11.914371 -157.62125) (xy 11.922897 -157.568648)
			(xy 11.939758 -157.518097) (xy 11.964518 -157.47091) (xy 11.996533 -157.428311) (xy 12.034973 -157.391406)
			(xy 12.056618 -157.37586) (xy 12.067909 -157.367503) (xy 12.085764 -157.345828) (xy 12.097046 -157.320112)
			(xy 12.100903 -157.292297) (xy 12.097044 -157.264481) (xy 12.08576 -157.238766) (xy 12.067904 -157.217092)
			(xy 12.056618 -157.208728) (xy 12.035012 -157.193137) (xy 11.996598 -157.156222) (xy 11.964599 -157.113625)
			(xy 11.939842 -157.066451) (xy 11.922968 -157.015917) (xy 11.914412 -156.963332) (xy 11.91387 -156.936694)
			(xy 11.91438 -156.910707) (xy 11.92251 -156.859372) (xy 11.938571 -156.809942) (xy 11.962167 -156.763632)
			(xy 11.992717 -156.721584) (xy 12.029468 -156.684833) (xy 12.071516 -156.654283) (xy 12.117826 -156.630687)
			(xy 12.167256 -156.614626) (xy 12.218591 -156.606496) (xy 12.270565 -156.606496) (xy 12.3219 -156.614626)
			(xy 12.37133 -156.630687) (xy 12.41764 -156.654283) (xy 12.459688 -156.684833) (xy 12.496439 -156.721584)
			(xy 12.526989 -156.763632) (xy 12.550585 -156.809942) (xy 12.566646 -156.859372) (xy 12.574776 -156.910707)
			(xy 12.575286 -156.936694) (xy 12.574752 -156.963337) (xy 12.56623 -157.015936) (xy 12.549373 -157.066485)
			(xy 12.52462 -157.113671) (xy 12.492611 -157.156271) (xy 12.454179 -157.19318) (xy 12.432538 -157.208728)
			(xy 12.421262 -157.217102) (xy 12.403416 -157.238776) (xy 12.392139 -157.264487) (xy 12.388282 -157.292297)
			(xy 12.392137 -157.320106) (xy 12.403412 -157.345818) (xy 12.421257 -157.367493) (xy 12.432538 -157.37586)
			(xy 12.454129 -157.391471) (xy 12.492545 -157.428381) (xy 12.524548 -157.470973) (xy 12.549308 -157.518144)
			(xy 12.566185 -157.568674) (xy 12.574743 -157.621257) (xy 12.575286 -157.647894) (xy 12.813792 -157.647894)
			(xy 12.814327 -157.621251) (xy 12.82285 -157.568653) (xy 12.839707 -157.518105) (xy 12.864461 -157.470918)
			(xy 12.896468 -157.428318) (xy 12.9349 -157.391409) (xy 12.95654 -157.37586) (xy 12.967829 -157.367502)
			(xy 12.98568 -157.345826) (xy 12.996959 -157.320111) (xy 13.000815 -157.292297) (xy 12.996957 -157.264483)
			(xy 12.985677 -157.238768) (xy 12.967824 -157.217094) (xy 12.95654 -157.208728) (xy 12.934939 -157.193131)
			(xy 12.896524 -157.156217) (xy 12.864523 -157.113623) (xy 12.839765 -157.066449) (xy 12.82289 -157.015916)
			(xy 12.814334 -156.963332) (xy 12.813792 -156.936694) (xy 12.814302 -156.910707) (xy 12.822432 -156.859372)
			(xy 12.838493 -156.809942) (xy 12.862089 -156.763632) (xy 12.892639 -156.721584) (xy 12.92939 -156.684833)
			(xy 12.971438 -156.654283) (xy 13.017748 -156.630687) (xy 13.067178 -156.614626) (xy 13.118513 -156.606496)
			(xy 13.170487 -156.606496) (xy 13.221822 -156.614626) (xy 13.271252 -156.630687) (xy 13.317562 -156.654283)
			(xy 13.35961 -156.684833) (xy 13.396361 -156.721584) (xy 13.426911 -156.763632) (xy 13.450507 -156.809942)
			(xy 13.466568 -156.859372) (xy 13.474698 -156.910707) (xy 13.475208 -156.936694) (xy 13.474664 -156.963336)
			(xy 13.466143 -157.015935) (xy 13.449288 -157.066482) (xy 13.424536 -157.113669) (xy 13.39253 -157.156269)
			(xy 13.3541 -157.193179) (xy 13.33246 -157.208728) (xy 13.321182 -157.217101) (xy 13.303332 -157.238773)
			(xy 13.292052 -157.264485) (xy 13.288195 -157.292297) (xy 13.29205 -157.320108) (xy 13.303328 -157.345821)
			(xy 13.321177 -157.367494) (xy 13.33246 -157.37586) (xy 13.354056 -157.391465) (xy 13.392471 -157.428377)
			(xy 13.424472 -157.47097) (xy 13.449231 -157.518142) (xy 13.466107 -157.568673) (xy 13.474665 -157.621257)
			(xy 13.475208 -157.647894) (xy 13.713968 -157.647894) (xy 13.71447 -157.62125) (xy 13.722996 -157.568648)
			(xy 13.739857 -157.518098) (xy 13.764617 -157.470911) (xy 13.796632 -157.428312) (xy 13.835071 -157.391406)
			(xy 13.856716 -157.37586) (xy 13.868008 -157.367503) (xy 13.885863 -157.345828) (xy 13.897145 -157.320112)
			(xy 13.901002 -157.292297) (xy 13.897143 -157.264481) (xy 13.885859 -157.238766) (xy 13.868002 -157.217092)
			(xy 13.856716 -157.208728) (xy 13.83511 -157.193138) (xy 13.796696 -157.156222) (xy 13.764697 -157.113626)
			(xy 13.73994 -157.066451) (xy 13.723066 -157.015917) (xy 13.71451 -156.963332) (xy 13.713968 -156.936694)
			(xy 13.714478 -156.910707) (xy 13.722608 -156.859372) (xy 13.738669 -156.809942) (xy 13.762265 -156.763632)
			(xy 13.792815 -156.721584) (xy 13.829566 -156.684833) (xy 13.871614 -156.654283) (xy 13.917924 -156.630687)
			(xy 13.967354 -156.614626) (xy 14.018689 -156.606496) (xy 14.070663 -156.606496) (xy 14.121998 -156.614626)
			(xy 14.171428 -156.630687) (xy 14.217738 -156.654283) (xy 14.259786 -156.684833) (xy 14.296537 -156.721584)
			(xy 14.327087 -156.763632) (xy 14.350683 -156.809942) (xy 14.366744 -156.859372) (xy 14.374874 -156.910707)
			(xy 14.375384 -156.936694) (xy 14.374851 -156.963337) (xy 14.366328 -157.015936) (xy 14.349472 -157.066485)
			(xy 14.324718 -157.113671) (xy 14.29271 -157.156271) (xy 14.254277 -157.19318) (xy 14.232636 -157.208728)
			(xy 14.221352 -157.217097) (xy 14.203488 -157.238766) (xy 14.192199 -157.26448) (xy 14.188338 -157.292297)
			(xy 14.192197 -157.320113) (xy 14.203484 -157.345828) (xy 14.221347 -157.367498) (xy 14.232636 -157.37586)
			(xy 14.254226 -157.391472) (xy 14.292643 -157.428382) (xy 14.324645 -157.470973) (xy 14.349405 -157.518144)
			(xy 14.366283 -157.568674) (xy 14.374841 -157.621257) (xy 14.375343 -157.645862) (xy 15.329408 -157.645862)
			(xy 15.329848 -157.619547) (xy 15.337088 -157.567417) (xy 15.351412 -157.516774) (xy 15.37255 -157.468575)
			(xy 15.400101 -157.423732) (xy 15.433544 -157.383094) (xy 15.452598 -157.364938) (xy 15.459984 -157.357404)
			(xy 15.468517 -157.338133) (xy 15.469108 -157.3276) (xy 15.469108 -157.252924) (xy 15.468577 -157.242375)
			(xy 15.460043 -157.223079) (xy 15.452598 -157.215586) (xy 15.433542 -157.197431) (xy 15.400085 -157.156801)
			(xy 15.372526 -157.111961) (xy 15.351388 -157.06376) (xy 15.337071 -157.013112) (xy 15.329846 -156.960978)
			(xy 15.329408 -156.934662) (xy 15.329894 -156.907411) (xy 15.33765 -156.853463) (xy 15.353005 -156.801168)
			(xy 15.375647 -156.751591) (xy 15.405113 -156.705741) (xy 15.440804 -156.66455) (xy 15.481995 -156.628859)
			(xy 15.527845 -156.599393) (xy 15.577422 -156.576751) (xy 15.629717 -156.561396) (xy 15.683665 -156.55364)
			(xy 15.738167 -156.55364) (xy 15.792115 -156.561396) (xy 15.84441 -156.576751) (xy 15.893987 -156.599393)
			(xy 15.939837 -156.628859) (xy 15.958582 -156.645101) (xy 17.31399 -156.645101) (xy 17.318305 -156.587829)
			(xy 17.331153 -156.531851) (xy 17.352244 -156.478429) (xy 17.381102 -156.428772) (xy 17.417075 -156.383999)
			(xy 17.437862 -156.364178) (xy 17.445269 -156.356661) (xy 17.453792 -156.337378) (xy 17.454372 -156.32684)
			(xy 17.454372 -156.252164) (xy 17.45383 -156.241616) (xy 17.445305 -156.22232) (xy 17.437862 -156.214826)
			(xy 17.418819 -156.196658) (xy 17.385362 -156.15603) (xy 17.357802 -156.111192) (xy 17.336662 -156.062994)
			(xy 17.322342 -156.012349) (xy 17.315113 -155.960217) (xy 17.314672 -155.933902) (xy 17.315158 -155.906651)
			(xy 17.322914 -155.852703) (xy 17.338269 -155.800408) (xy 17.360911 -155.750831) (xy 17.390377 -155.704981)
			(xy 17.426068 -155.66379) (xy 17.467259 -155.628099) (xy 17.513109 -155.598633) (xy 17.562686 -155.575991)
			(xy 17.614981 -155.560636) (xy 17.668929 -155.55288) (xy 17.723431 -155.55288) (xy 17.777379 -155.560636)
			(xy 17.829674 -155.575991) (xy 17.879251 -155.598633) (xy 17.925101 -155.628099) (xy 17.966292 -155.66379)
			(xy 18.001983 -155.704981) (xy 18.031449 -155.750831) (xy 18.054091 -155.800408) (xy 18.069446 -155.852703)
			(xy 18.077202 -155.906651) (xy 18.077688 -155.933902) (xy 18.077226 -155.960216) (xy 18.06999 -156.012345)
			(xy 18.055671 -156.062988) (xy 18.034537 -156.111187) (xy 18.00699 -156.15603) (xy 17.97355 -156.19667)
			(xy 17.954498 -156.214826) (xy 17.947083 -156.222336) (xy 17.938566 -156.241625) (xy 17.937988 -156.252164)
			(xy 17.937988 -156.32684) (xy 17.938539 -156.337387) (xy 17.947059 -156.356682) (xy 17.954498 -156.364178)
			(xy 17.975289 -156.383995) (xy 18.011266 -156.428768) (xy 18.040127 -156.478425) (xy 18.061221 -156.531848)
			(xy 18.07407 -156.587828) (xy 18.078386 -156.645101) (xy 18.07407 -156.702375) (xy 18.072934 -156.707322)
			(xy 20.379798 -156.707322) (xy 20.38411 -156.650054) (xy 20.396954 -156.594078) (xy 20.41804 -156.540659)
			(xy 20.446892 -156.491002) (xy 20.482858 -156.446229) (xy 20.503642 -156.426408) (xy 20.511034 -156.418878)
			(xy 20.519566 -156.399605) (xy 20.520152 -156.38907) (xy 20.520152 -156.314394) (xy 20.519654 -156.30384)
			(xy 20.511098 -156.284544) (xy 20.503642 -156.277056) (xy 20.484561 -156.258926) (xy 20.451108 -156.21829)
			(xy 20.423554 -156.173444) (xy 20.402421 -156.125238) (xy 20.388108 -156.074587) (xy 20.380888 -156.022449)
			(xy 20.380452 -155.996132) (xy 20.380938 -155.968881) (xy 20.388694 -155.914933) (xy 20.404049 -155.862638)
			(xy 20.426691 -155.813061) (xy 20.456157 -155.767211) (xy 20.491848 -155.72602) (xy 20.533039 -155.690329)
			(xy 20.578889 -155.660863) (xy 20.628466 -155.638221) (xy 20.680761 -155.622866) (xy 20.734709 -155.61511)
			(xy 20.789211 -155.61511) (xy 20.843159 -155.622866) (xy 20.895454 -155.638221) (xy 20.945031 -155.660863)
			(xy 20.990881 -155.690329) (xy 21.032072 -155.72602) (xy 21.067763 -155.767211) (xy 21.097229 -155.813061)
			(xy 21.119871 -155.862638) (xy 21.135226 -155.914933) (xy 21.142982 -155.968881) (xy 21.143468 -155.996132)
			(xy 21.143032 -156.022447) (xy 21.135792 -156.074577) (xy 21.121468 -156.125221) (xy 21.100329 -156.17342)
			(xy 21.072777 -156.218263) (xy 21.039333 -156.258901) (xy 21.020278 -156.277056) (xy 21.01289 -156.284589)
			(xy 21.004359 -156.303861) (xy 21.003768 -156.314394) (xy 21.003768 -156.38907) (xy 21.004309 -156.399618)
			(xy 21.012837 -156.418913) (xy 21.020278 -156.426408) (xy 21.0411 -156.446195) (xy 21.077078 -156.490971)
			(xy 21.10594 -156.540633) (xy 21.127033 -156.59406) (xy 21.139882 -156.650044) (xy 21.144195 -156.707322)
			(xy 21.139875 -156.764599) (xy 21.12702 -156.820582) (xy 21.105921 -156.874006) (xy 21.077054 -156.923665)
			(xy 21.04107 -156.968437) (xy 21.020278 -156.988256) (xy 21.01289 -156.995789) (xy 21.004359 -157.015061)
			(xy 21.003768 -157.025594) (xy 21.003768 -157.10027) (xy 21.004309 -157.110818) (xy 21.012837 -157.130113)
			(xy 21.020278 -157.137608) (xy 21.039326 -157.155771) (xy 21.072785 -157.196399) (xy 21.100345 -157.241237)
			(xy 21.121485 -157.289437) (xy 21.135804 -157.340083) (xy 21.143029 -157.392216) (xy 21.143468 -157.418532)
			(xy 21.142982 -157.445783) (xy 21.135226 -157.499731) (xy 21.119871 -157.552026) (xy 21.097229 -157.601603)
			(xy 21.067763 -157.647453) (xy 21.032072 -157.688644) (xy 20.990881 -157.724335) (xy 20.945031 -157.753801)
			(xy 20.895454 -157.776443) (xy 20.843159 -157.791798) (xy 20.789211 -157.799554) (xy 20.734709 -157.799554)
			(xy 20.680761 -157.791798) (xy 20.628466 -157.776443) (xy 20.578889 -157.753801) (xy 20.533039 -157.724335)
			(xy 20.491848 -157.688644) (xy 20.456157 -157.647453) (xy 20.426691 -157.601603) (xy 20.404049 -157.552026)
			(xy 20.388694 -157.499731) (xy 20.380938 -157.445783) (xy 20.380452 -157.418532) (xy 20.380857 -157.392216)
			(xy 20.388103 -157.340084) (xy 20.402433 -157.289439) (xy 20.423577 -157.24124) (xy 20.451135 -157.196398)
			(xy 20.484585 -157.155762) (xy 20.503642 -157.137608) (xy 20.511034 -157.130078) (xy 20.519566 -157.110805)
			(xy 20.520152 -157.10027) (xy 20.520152 -157.025594) (xy 20.519654 -157.01504) (xy 20.511098 -156.995744)
			(xy 20.503642 -156.988256) (xy 20.482888 -156.968403) (xy 20.446916 -156.923634) (xy 20.418059 -156.87398)
			(xy 20.396967 -156.820564) (xy 20.384116 -156.764589) (xy 20.379798 -156.707322) (xy 18.072934 -156.707322)
			(xy 18.06122 -156.758355) (xy 18.040126 -156.811777) (xy 18.011264 -156.861435) (xy 17.975287 -156.906207)
			(xy 17.954498 -156.926026) (xy 17.947083 -156.933536) (xy 17.938566 -156.952825) (xy 17.937988 -156.963364)
			(xy 17.937988 -157.03804) (xy 17.938539 -157.048587) (xy 17.947059 -157.067882) (xy 17.954498 -157.075378)
			(xy 17.973536 -157.093552) (xy 18.006994 -157.134177) (xy 18.034556 -157.179014) (xy 18.055697 -157.227211)
			(xy 18.070018 -157.277855) (xy 18.077247 -157.329987) (xy 18.077688 -157.356302) (xy 18.077202 -157.383553)
			(xy 18.069446 -157.437501) (xy 18.054091 -157.489796) (xy 18.031449 -157.539373) (xy 18.001983 -157.585223)
			(xy 17.966292 -157.626414) (xy 17.925101 -157.662105) (xy 17.879251 -157.691571) (xy 17.829674 -157.714213)
			(xy 17.777379 -157.729568) (xy 17.723431 -157.737324) (xy 17.668929 -157.737324) (xy 17.614981 -157.729568)
			(xy 17.562686 -157.714213) (xy 17.513109 -157.691571) (xy 17.467259 -157.662105) (xy 17.426068 -157.626414)
			(xy 17.390377 -157.585223) (xy 17.360911 -157.539373) (xy 17.338269 -157.489796) (xy 17.322914 -157.437501)
			(xy 17.315158 -157.383553) (xy 17.314672 -157.356302) (xy 17.31515 -157.329988) (xy 17.322384 -157.277861)
			(xy 17.336701 -157.227219) (xy 17.357832 -157.17902) (xy 17.385376 -157.134176) (xy 17.418812 -157.093535)
			(xy 17.437862 -157.075378) (xy 17.445269 -157.067861) (xy 17.453792 -157.048578) (xy 17.454372 -157.03804)
			(xy 17.454372 -156.963364) (xy 17.45383 -156.952816) (xy 17.445305 -156.93352) (xy 17.437862 -156.926026)
			(xy 17.417077 -156.906203) (xy 17.381104 -156.861431) (xy 17.352245 -156.811773) (xy 17.331154 -156.758352)
			(xy 17.318305 -156.702373) (xy 17.31399 -156.645101) (xy 15.958582 -156.645101) (xy 15.981028 -156.66455)
			(xy 16.016719 -156.705741) (xy 16.046185 -156.751591) (xy 16.068827 -156.801168) (xy 16.084182 -156.853463)
			(xy 16.091938 -156.907411) (xy 16.092424 -156.934662) (xy 16.09199 -156.960977) (xy 16.084747 -157.013107)
			(xy 16.070421 -157.06375) (xy 16.049282 -157.111948) (xy 16.021731 -157.156791) (xy 15.988288 -157.19743)
			(xy 15.969234 -157.215586) (xy 15.961841 -157.223115) (xy 15.953311 -157.242389) (xy 15.952724 -157.252924)
			(xy 15.952724 -157.3276) (xy 15.953233 -157.338152) (xy 15.961781 -157.357448) (xy 15.969234 -157.364938)
			(xy 15.988307 -157.383075) (xy 16.021762 -157.42371) (xy 16.049317 -157.468554) (xy 16.070453 -157.516758)
			(xy 16.084766 -157.567409) (xy 16.091987 -157.619545) (xy 16.092424 -157.645862) (xy 16.091938 -157.673113)
			(xy 16.084182 -157.727061) (xy 16.068827 -157.779356) (xy 16.046185 -157.828933) (xy 16.016719 -157.874783)
			(xy 15.981028 -157.915974) (xy 15.939837 -157.951665) (xy 15.893987 -157.981131) (xy 15.84441 -158.003773)
			(xy 15.792115 -158.019128) (xy 15.738167 -158.026884) (xy 15.683665 -158.026884) (xy 15.629717 -158.019128)
			(xy 15.577422 -158.003773) (xy 15.527845 -157.981131) (xy 15.481995 -157.951665) (xy 15.440804 -157.915974)
			(xy 15.405113 -157.874783) (xy 15.375647 -157.828933) (xy 15.353005 -157.779356) (xy 15.33765 -157.727061)
			(xy 15.329894 -157.673113) (xy 15.329408 -157.645862) (xy 14.375343 -157.645862) (xy 14.375384 -157.647894)
			(xy 14.374874 -157.673881) (xy 14.366744 -157.725216) (xy 14.350683 -157.774646) (xy 14.327087 -157.820956)
			(xy 14.296537 -157.863004) (xy 14.259786 -157.899755) (xy 14.217738 -157.930305) (xy 14.171428 -157.953901)
			(xy 14.121998 -157.969962) (xy 14.070663 -157.978092) (xy 14.018689 -157.978092) (xy 13.967354 -157.969962)
			(xy 13.917924 -157.953901) (xy 13.871614 -157.930305) (xy 13.829566 -157.899755) (xy 13.792815 -157.863004)
			(xy 13.762265 -157.820956) (xy 13.738669 -157.774646) (xy 13.722608 -157.725216) (xy 13.714478 -157.673881)
			(xy 13.713968 -157.647894) (xy 13.475208 -157.647894) (xy 13.474698 -157.673881) (xy 13.466568 -157.725216)
			(xy 13.450507 -157.774646) (xy 13.426911 -157.820956) (xy 13.396361 -157.863004) (xy 13.35961 -157.899755)
			(xy 13.317562 -157.930305) (xy 13.271252 -157.953901) (xy 13.221822 -157.969962) (xy 13.170487 -157.978092)
			(xy 13.118513 -157.978092) (xy 13.067178 -157.969962) (xy 13.017748 -157.953901) (xy 12.971438 -157.930305)
			(xy 12.92939 -157.899755) (xy 12.892639 -157.863004) (xy 12.862089 -157.820956) (xy 12.838493 -157.774646)
			(xy 12.822432 -157.725216) (xy 12.814302 -157.673881) (xy 12.813792 -157.647894) (xy 12.575286 -157.647894)
			(xy 12.574776 -157.673881) (xy 12.566646 -157.725216) (xy 12.550585 -157.774646) (xy 12.526989 -157.820956)
			(xy 12.496439 -157.863004) (xy 12.459688 -157.899755) (xy 12.41764 -157.930305) (xy 12.37133 -157.953901)
			(xy 12.3219 -157.969962) (xy 12.270565 -157.978092) (xy 12.218591 -157.978092) (xy 12.167256 -157.969962)
			(xy 12.117826 -157.953901) (xy 12.071516 -157.930305) (xy 12.029468 -157.899755) (xy 11.992717 -157.863004)
			(xy 11.962167 -157.820956) (xy 11.938571 -157.774646) (xy 11.92251 -157.725216) (xy 11.91438 -157.673881)
			(xy 11.91387 -157.647894) (xy 11.675364 -157.647894) (xy 11.674854 -157.673881) (xy 11.666724 -157.725216)
			(xy 11.650663 -157.774646) (xy 11.627067 -157.820956) (xy 11.596517 -157.863004) (xy 11.559766 -157.899755)
			(xy 11.517718 -157.930305) (xy 11.471408 -157.953901) (xy 11.421978 -157.969962) (xy 11.370643 -157.978092)
			(xy 11.318669 -157.978092) (xy 11.267334 -157.969962) (xy 11.217904 -157.953901) (xy 11.171594 -157.930305)
			(xy 11.129546 -157.899755) (xy 11.092795 -157.863004) (xy 11.062245 -157.820956) (xy 11.038649 -157.774646)
			(xy 11.022588 -157.725216) (xy 11.014458 -157.673881) (xy 11.013948 -157.647894) (xy 8.51154 -157.647894)
			(xy 8.51154 -158.06039) (xy 8.839706 -158.06039) (xy 8.843777 -158.004768) (xy 8.855903 -157.950331)
			(xy 8.875826 -157.89824) (xy 8.903122 -157.849605) (xy 8.937208 -157.805462) (xy 8.977357 -157.766753)
			(xy 9.022715 -157.734302) (xy 9.072315 -157.708801) (xy 9.125099 -157.690794) (xy 9.179942 -157.680664)
			(xy 9.235676 -157.678627) (xy 9.291113 -157.684727) (xy 9.34507 -157.698833) (xy 9.396399 -157.720645)
			(xy 9.444005 -157.749699) (xy 9.486873 -157.785374) (xy 9.52409 -157.826911) (xy 9.554863 -157.873424)
			(xy 9.578535 -157.923921) (xy 9.594603 -157.977328) (xy 9.602723 -158.032504) (xy 9.603232 -158.06039)
			(xy 9.602723 -158.088276) (xy 9.594603 -158.143452) (xy 9.578535 -158.196859) (xy 9.554863 -158.247356)
			(xy 9.52409 -158.293869) (xy 9.486873 -158.335406) (xy 9.444005 -158.371081) (xy 9.396399 -158.400135)
			(xy 9.34507 -158.421947) (xy 9.291113 -158.436053) (xy 9.235676 -158.442153) (xy 9.179942 -158.440116)
			(xy 9.125099 -158.429986) (xy 9.072315 -158.411979) (xy 9.022715 -158.386478) (xy 8.977357 -158.354027)
			(xy 8.937208 -158.315318) (xy 8.903122 -158.271175) (xy 8.875826 -158.22254) (xy 8.855903 -158.170449)
			(xy 8.843777 -158.116012) (xy 8.839706 -158.06039) (xy 8.51154 -158.06039) (xy 8.51154 -158.753302)
			(xy 16.516602 -158.753302) (xy 16.520673 -158.69768) (xy 16.532799 -158.643243) (xy 16.552722 -158.591152)
			(xy 16.580018 -158.542517) (xy 16.614104 -158.498374) (xy 16.654253 -158.459665) (xy 16.699611 -158.427214)
			(xy 16.749211 -158.401713) (xy 16.801995 -158.383706) (xy 16.856838 -158.373576) (xy 16.912572 -158.371539)
			(xy 16.968009 -158.377639) (xy 17.021966 -158.391745) (xy 17.073295 -158.413557) (xy 17.120901 -158.442611)
			(xy 17.163769 -158.478286) (xy 17.200986 -158.519823) (xy 17.231759 -158.566336) (xy 17.255431 -158.616833)
			(xy 17.271499 -158.67024) (xy 17.279619 -158.725416) (xy 17.280128 -158.753302) (xy 17.279619 -158.781188)
			(xy 17.271499 -158.836364) (xy 17.255431 -158.889771) (xy 17.231759 -158.940268) (xy 17.200986 -158.986781)
			(xy 17.163769 -159.028318) (xy 17.120901 -159.063993) (xy 17.073295 -159.093047) (xy 17.021966 -159.114859)
			(xy 16.968009 -159.128965) (xy 16.912572 -159.135065) (xy 16.856838 -159.133028) (xy 16.801995 -159.122898)
			(xy 16.749211 -159.104891) (xy 16.699611 -159.07939) (xy 16.654253 -159.046939) (xy 16.614104 -159.00823)
			(xy 16.580018 -158.964087) (xy 16.552722 -158.915452) (xy 16.532799 -158.863361) (xy 16.520673 -158.808924)
			(xy 16.516602 -158.753302) (xy 8.51154 -158.753302) (xy 8.51154 -159.439102) (xy 8.908032 -159.439102)
			(xy 8.912103 -159.38348) (xy 8.924229 -159.329043) (xy 8.944152 -159.276952) (xy 8.971448 -159.228317)
			(xy 9.005534 -159.184174) (xy 9.045683 -159.145465) (xy 9.091041 -159.113014) (xy 9.140641 -159.087513)
			(xy 9.193425 -159.069506) (xy 9.248268 -159.059376) (xy 9.304002 -159.057339) (xy 9.359439 -159.063439)
			(xy 9.413396 -159.077545) (xy 9.464725 -159.099357) (xy 9.512331 -159.128411) (xy 9.555199 -159.164086)
			(xy 9.592416 -159.205623) (xy 9.623189 -159.252136) (xy 9.646861 -159.302633) (xy 9.662929 -159.35604)
			(xy 9.671049 -159.411216) (xy 9.671558 -159.439102) (xy 9.671049 -159.466988) (xy 9.662929 -159.522164)
			(xy 9.660026 -159.531812) (xy 12.11275 -159.531812) (xy 12.116821 -159.47619) (xy 12.128947 -159.421753)
			(xy 12.14887 -159.369662) (xy 12.176166 -159.321027) (xy 12.210252 -159.276884) (xy 12.250401 -159.238175)
			(xy 12.295759 -159.205724) (xy 12.345359 -159.180223) (xy 12.398143 -159.162216) (xy 12.452986 -159.152086)
			(xy 12.50872 -159.150049) (xy 12.564157 -159.156149) (xy 12.618114 -159.170255) (xy 12.669443 -159.192067)
			(xy 12.717049 -159.221121) (xy 12.759917 -159.256796) (xy 12.797134 -159.298333) (xy 12.827907 -159.344846)
			(xy 12.851579 -159.395343) (xy 12.867647 -159.44875) (xy 12.873516 -159.488632) (xy 14.395956 -159.488632)
			(xy 14.400027 -159.43301) (xy 14.412153 -159.378573) (xy 14.432076 -159.326482) (xy 14.459372 -159.277847)
			(xy 14.493458 -159.233704) (xy 14.533607 -159.194995) (xy 14.578965 -159.162544) (xy 14.628565 -159.137043)
			(xy 14.681349 -159.119036) (xy 14.736192 -159.108906) (xy 14.791926 -159.106869) (xy 14.847363 -159.112969)
			(xy 14.90132 -159.127075) (xy 14.952649 -159.148887) (xy 15.000255 -159.177941) (xy 15.043123 -159.213616)
			(xy 15.08034 -159.255153) (xy 15.111113 -159.301666) (xy 15.134785 -159.352163) (xy 15.150853 -159.40557)
			(xy 15.158973 -159.460746) (xy 15.159482 -159.488632) (xy 15.158973 -159.516518) (xy 15.150853 -159.571694)
			(xy 15.134785 -159.625101) (xy 15.111113 -159.675598) (xy 15.08034 -159.722111) (xy 15.043123 -159.763648)
			(xy 15.000255 -159.799323) (xy 14.952649 -159.828377) (xy 14.90132 -159.850189) (xy 14.847363 -159.864295)
			(xy 14.791926 -159.870395) (xy 14.736192 -159.868358) (xy 14.681349 -159.858228) (xy 14.628565 -159.840221)
			(xy 14.578965 -159.81472) (xy 14.533607 -159.782269) (xy 14.493458 -159.74356) (xy 14.459372 -159.699417)
			(xy 14.432076 -159.650782) (xy 14.412153 -159.598691) (xy 14.400027 -159.544254) (xy 14.395956 -159.488632)
			(xy 12.873516 -159.488632) (xy 12.875767 -159.503926) (xy 12.876276 -159.531812) (xy 12.875767 -159.559698)
			(xy 12.867647 -159.614874) (xy 12.851579 -159.668281) (xy 12.827907 -159.718778) (xy 12.797134 -159.765291)
			(xy 12.759917 -159.806828) (xy 12.717049 -159.842503) (xy 12.669443 -159.871557) (xy 12.618114 -159.893369)
			(xy 12.564157 -159.907475) (xy 12.50872 -159.913575) (xy 12.452986 -159.911538) (xy 12.398143 -159.901408)
			(xy 12.345359 -159.883401) (xy 12.295759 -159.8579) (xy 12.250401 -159.825449) (xy 12.210252 -159.78674)
			(xy 12.176166 -159.742597) (xy 12.14887 -159.693962) (xy 12.128947 -159.641871) (xy 12.116821 -159.587434)
			(xy 12.11275 -159.531812) (xy 9.660026 -159.531812) (xy 9.646861 -159.575571) (xy 9.623189 -159.626068)
			(xy 9.592416 -159.672581) (xy 9.555199 -159.714118) (xy 9.512331 -159.749793) (xy 9.464725 -159.778847)
			(xy 9.413396 -159.800659) (xy 9.359439 -159.814765) (xy 9.304002 -159.820865) (xy 9.248268 -159.818828)
			(xy 9.193425 -159.808698) (xy 9.140641 -159.790691) (xy 9.091041 -159.76519) (xy 9.045683 -159.732739)
			(xy 9.005534 -159.69403) (xy 8.971448 -159.649887) (xy 8.944152 -159.601252) (xy 8.924229 -159.549161)
			(xy 8.912103 -159.494724) (xy 8.908032 -159.439102) (xy 8.51154 -159.439102) (xy 8.51154 -160.636712)
			(xy 8.511794 -160.641538) (xy 8.512556 -160.64738) (xy 8.51433 -160.654538) (xy 8.521424 -160.667457)
			(xy 8.526526 -160.67278) (xy 8.790178 -160.936178) (xy 8.79729 -160.936686) (xy 8.856472 -160.936686)
			(xy 8.863584 -160.936178) (xy 8.874252 -160.934654) (xy 8.885682 -160.931352) (xy 8.898382 -160.927542)
			(xy 8.910828 -160.921954) (xy 8.916416 -160.918398) (xy 8.921242 -160.913318) (xy 8.922512 -160.912048)
			(xy 8.935466 -160.89757) (xy 8.93957 -160.892755) (xy 8.945486 -160.881576) (xy 8.94715 -160.875472)
			(xy 8.954328 -160.847976) (xy 8.97569 -160.795319) (xy 9.004595 -160.746394) (xy 9.040408 -160.702274)
			(xy 9.082345 -160.663927) (xy 9.129485 -160.632195) (xy 9.180795 -160.607772) (xy 9.235149 -160.591195)
			(xy 9.291355 -160.582828) (xy 9.319768 -160.582356) (xy 9.347168 -160.582819) (xy 9.40141 -160.590614)
			(xy 9.45399 -160.606049) (xy 9.503839 -160.62881) (xy 9.54994 -160.658434) (xy 9.591357 -160.694318)
			(xy 9.627244 -160.735731) (xy 9.656873 -160.78183) (xy 9.679638 -160.831676) (xy 9.695078 -160.884255)
			(xy 9.702878 -160.938496) (xy 9.703308 -160.965896) (xy 9.702856 -160.992468) (xy 9.695516 -161.045103)
			(xy 9.680978 -161.096219) (xy 9.65952 -161.144839) (xy 9.631553 -161.190028) (xy 9.614916 -161.210752)
			(xy 9.61347 -161.214289) (xy 9.611563 -161.22169) (xy 9.611106 -161.225484) (xy 9.609836 -161.238692)
			(xy 9.63803 -161.29762) (xy 9.642856 -161.307526) (xy 9.656318 -161.335212) (xy 9.656572 -161.33572)
			(xy 9.659216 -161.340553) (xy 9.666258 -161.349021) (xy 9.670542 -161.352484) (xy 10.360406 -161.352484)
			(xy 10.36566 -161.348716) (xy 10.374274 -161.33908) (xy 10.377424 -161.333434) (xy 10.377932 -161.332418)
			(xy 10.39114 -161.30524) (xy 10.406126 -161.274252) (xy 10.40847 -161.269029) (xy 10.411038 -161.257876)
			(xy 10.411206 -161.252154) (xy 10.411206 -161.216848) (xy 10.411054 -161.21098) (xy 10.408356 -161.19956)
			(xy 10.405872 -161.194242) (xy 10.403332 -161.189162) (xy 10.401046 -161.18586) (xy 10.400792 -161.185606)
			(xy 10.38424 -161.161398) (xy 10.357973 -161.108967) (xy 10.340036 -161.053134) (xy 10.330852 -160.995215)
			(xy 10.33018 -160.965896) (xy 10.33018 -160.963356) (xy 10.331958 -160.92678) (xy 10.332212 -160.92424)
			(xy 10.33272 -160.918652) (xy 10.336517 -160.891198) (xy 10.351016 -160.837705) (xy 10.373096 -160.786871)
			(xy 10.402294 -160.739763) (xy 10.437996 -160.697371) (xy 10.479452 -160.660587) (xy 10.52579 -160.630184)
			(xy 10.576038 -160.6068) (xy 10.629139 -160.590926) (xy 10.683977 -160.582897) (xy 10.711688 -160.582356)
			(xy 10.739424 -160.58286) (xy 10.794309 -160.590903) (xy 10.847451 -160.606807) (xy 10.897731 -160.630238)
			(xy 10.94409 -160.6607) (xy 10.985549 -160.697553) (xy 11.021237 -160.74002) (xy 11.050401 -160.787207)
			(xy 11.072426 -160.838118) (xy 11.086849 -160.891681) (xy 11.090656 -160.91916) (xy 11.09218 -160.932876)
			(xy 11.09345 -160.963864) (xy 11.092865 -160.994676) (xy 11.08298 -161.055503) (xy 11.06346 -161.113955)
			(xy 11.034812 -161.168516) (xy 11.016742 -161.19348) (xy 11.011916 -161.19983) (xy 11.00455 -161.22142)
			(xy 11.00328 -161.228278) (xy 11.003026 -161.237168) (xy 11.00338 -161.24135) (xy 11.005301 -161.249518)
			(xy 11.006836 -161.253424) (xy 11.030712 -161.302192) (xy 11.030712 -161.3027) (xy 11.046714 -161.334958)
			(xy 11.049357 -161.340009) (xy 11.056534 -161.348864) (xy 11.060938 -161.352484) (xy 11.630152 -161.352484)
			(xy 11.633906 -161.349415) (xy 11.6403 -161.342128) (xy 11.642852 -161.338006) (xy 11.642852 -161.337498)
			(xy 11.644376 -161.334958) (xy 11.664696 -161.294318) (xy 11.664696 -161.29381) (xy 11.685778 -161.25063)
			(xy 11.6882 -161.244781) (xy 11.690378 -161.232316) (xy 11.690096 -161.225992) (xy 11.689588 -161.219134)
			(xy 11.684254 -161.205926) (xy 11.682222 -161.203132) (xy 11.679428 -161.199576) (xy 11.674602 -161.192972)
			(xy 11.674094 -161.192464) (xy 11.654028 -161.161476) (xy 11.653774 -161.160968) (xy 11.641499 -161.139039)
			(xy 11.622163 -161.092653) (xy 11.609053 -161.044137) (xy 11.602396 -160.994325) (xy 11.601958 -160.969198)
			(xy 11.601958 -160.968944) (xy 11.602444 -160.941693) (xy 11.6102 -160.887745) (xy 11.625555 -160.83545)
			(xy 11.648197 -160.785873) (xy 11.677663 -160.740023) (xy 11.713354 -160.698832) (xy 11.754545 -160.663141)
			(xy 11.800395 -160.633675) (xy 11.849972 -160.611033) (xy 11.902267 -160.595678) (xy 11.956215 -160.587922)
			(xy 12.010717 -160.587922) (xy 12.064665 -160.595678) (xy 12.11696 -160.611033) (xy 12.166537 -160.633675)
			(xy 12.212387 -160.663141) (xy 12.253578 -160.698832) (xy 12.289269 -160.740023) (xy 12.318735 -160.785873)
			(xy 12.341377 -160.83545) (xy 12.356732 -160.887745) (xy 12.364488 -160.941693) (xy 12.364974 -160.968944)
			(xy 12.364416 -160.999005) (xy 12.355004 -161.058386) (xy 12.336403 -161.115558) (xy 12.309073 -161.16911)
			(xy 12.291822 -161.193734) (xy 12.28725 -161.200084) (xy 12.281662 -161.216086) (xy 12.280138 -161.220658)
			(xy 12.278868 -161.227516) (xy 12.27836 -161.235644) (xy 12.277852 -161.244534) (xy 12.280138 -161.252916)
			(xy 12.281455 -161.257206) (xy 12.28541 -161.265262) (xy 12.288012 -161.268918) (xy 12.291822 -161.274252)
			(xy 12.295886 -161.28111) (xy 12.302236 -161.29381) (xy 12.302236 -161.294318) (xy 12.322556 -161.334958)
			(xy 12.323318 -161.336482) (xy 12.325945 -161.341051) (xy 12.332723 -161.34912) (xy 12.33678 -161.352484)
			(xy 13.473176 -161.352484) (xy 13.477908 -161.348508) (xy 13.485487 -161.338751) (xy 13.488162 -161.33318)
			(xy 13.48867 -161.33191) (xy 13.506196 -161.286444) (xy 13.506196 -161.285936) (xy 13.520674 -161.247582)
			(xy 13.520674 -161.247074) (xy 13.52423 -161.238438) (xy 13.52423 -161.22904) (xy 13.524004 -161.224611)
			(xy 13.522223 -161.215923) (xy 13.520674 -161.211768) (xy 13.51026 -161.186876) (xy 13.50264 -161.17951)
			(xy 13.502386 -161.179256) (xy 13.483933 -161.161175) (xy 13.451572 -161.120904) (xy 13.424936 -161.076638)
			(xy 13.404511 -161.029185) (xy 13.39067 -160.979412) (xy 13.383665 -160.928227) (xy 13.38326 -160.902396)
			(xy 13.38326 -160.897316) (xy 13.38407 -160.87029) (xy 13.392375 -160.816863) (xy 13.408141 -160.765143)
			(xy 13.431052 -160.716169) (xy 13.460649 -160.67092) (xy 13.496339 -160.630303) (xy 13.537406 -160.595133)
			(xy 13.583028 -160.566115) (xy 13.63229 -160.543828) (xy 13.684205 -160.528721) (xy 13.737734 -160.521096)
			(xy 13.764768 -160.520634) (xy 13.792021 -160.521095) (xy 13.845973 -160.528849) (xy 13.898273 -160.544202)
			(xy 13.947854 -160.566844) (xy 13.993708 -160.596311) (xy 14.034901 -160.632006) (xy 14.070595 -160.6732)
			(xy 14.100061 -160.719055) (xy 14.122701 -160.768637) (xy 14.138053 -160.820936) (xy 14.145806 -160.874889)
			(xy 14.146276 -160.902142) (xy 14.146276 -160.902904) (xy 14.145836 -160.929578) (xy 14.138411 -160.982407)
			(xy 14.123692 -161.033685) (xy 14.101966 -161.082409) (xy 14.073659 -161.127628) (xy 14.039324 -161.168458)
			(xy 14.019784 -161.186622) (xy 14.013688 -161.192464) (xy 14.010132 -161.198306) (xy 14.006576 -161.204402)
			(xy 14.005052 -161.209736) (xy 14.003782 -161.215324) (xy 14.002803 -161.221633) (xy 14.003693 -161.234365)
			(xy 14.00556 -161.24047) (xy 14.018006 -161.272982) (xy 14.04112 -161.332672) (xy 14.043772 -161.338418)
			(xy 14.051486 -161.348448) (xy 14.05636 -161.352484) (xy 15.001748 -161.352484) (xy 15.028926 -161.353054)
			(xy 15.08255 -161.361954) (xy 15.134011 -161.37946) (xy 15.181938 -161.405105) (xy 15.225055 -161.438206)
			(xy 15.244064 -161.45764) (xy 15.24508 -161.458656) (xy 16.519906 -162.733482) (xy 16.529558 -162.741102)
			(xy 16.544544 -162.749992) (xy 16.545052 -162.750246) (xy 16.570617 -162.758695) (xy 16.619262 -162.781776)
			(xy 16.664181 -162.811463) (xy 16.704482 -162.847167) (xy 16.739367 -162.88818) (xy 16.768142 -162.933688)
			(xy 16.790237 -162.982788) (xy 16.805214 -163.034506) (xy 16.812775 -163.087815) (xy 16.813276 -163.114736)
			(xy 16.812787 -163.141985) (xy 16.805026 -163.195927) (xy 16.789668 -163.248215) (xy 16.767024 -163.297786)
			(xy 16.737557 -163.343629) (xy 16.701865 -163.384813) (xy 16.660675 -163.420497) (xy 16.614826 -163.449957)
			(xy 16.565252 -163.472592) (xy 16.51296 -163.487941) (xy 16.459017 -163.495692) (xy 16.431768 -163.496244)
			(xy 16.404868 -163.495781) (xy 16.351603 -163.488219) (xy 16.299927 -163.473249) (xy 16.250868 -163.451169)
			(xy 16.205396 -163.422416) (xy 16.164414 -163.387561) (xy 16.128735 -163.347294) (xy 16.099067 -163.302414)
			(xy 16.075997 -163.253812) (xy 16.067532 -163.228274) (xy 16.067278 -163.227766) (xy 16.058388 -163.21278)
			(xy 16.050768 -163.203128) (xy 15.347696 -162.499802) (xy 14.876018 -162.028378) (xy 14.870417 -162.02396)
			(xy 14.857395 -162.018151) (xy 14.850364 -162.016948) (xy 9.069324 -162.016948) (xy 9.042143 -162.016384)
			(xy 8.988513 -162.007495) (xy 8.937043 -161.989998) (xy 8.889105 -161.964361) (xy 8.845977 -161.931266)
			(xy 8.827008 -161.911792) (xy 8.825992 -161.910776) (xy 7.94512 -161.029904) (xy 7.927089 -161.011133)
			(xy 7.896511 -160.969016) (xy 7.872886 -160.922639) (xy 7.856795 -160.873142) (xy 7.848632 -160.821739)
			(xy 7.848092 -160.795716) (xy 7.848092 -157.437328) (xy 7.847584 -157.429454) (xy 7.846107 -157.421684)
			(xy 7.838988 -157.407571) (xy 7.833614 -157.401768) (xy 6.714744 -156.283152) (xy 6.163818 -155.732226)
			(xy 6.157808 -155.726682) (xy 6.143168 -155.719423) (xy 6.135116 -155.718002) (xy 6.128031 -155.717122)
			(xy 6.113753 -155.717122) (xy 6.106668 -155.718002) (xy 6.093839 -155.720206) (xy 6.069835 -155.73025)
			(xy 6.049173 -155.746067) (xy 6.040882 -155.756102) (xy 6.040374 -155.75661) (xy 6.04012 -155.757118)
			(xy 6.039866 -155.757626) (xy 6.035144 -155.764353) (xy 6.029832 -155.779896) (xy 6.029452 -155.788106)
			(xy 6.029452 -157.335982) (xy 6.029758 -157.344177) (xy 6.034931 -157.359729) (xy 6.039612 -157.366462)
			(xy 6.51002 -157.837124) (xy 6.513759 -157.837549) (xy 6.521284 -157.837428) (xy 6.525006 -157.83687)
			(xy 6.531864 -157.835346) (xy 6.595364 -157.81401) (xy 6.595618 -157.81401) (xy 6.603492 -157.811216)
			(xy 6.609748 -157.809293) (xy 6.62107 -157.802738) (xy 6.625844 -157.798262) (xy 6.628384 -157.795722)
			(xy 6.643878 -157.776418) (xy 6.649212 -157.769814) (xy 6.654292 -157.758638) (xy 6.655054 -157.754066)
			(xy 6.655308 -157.75305) (xy 6.655562 -157.751272) (xy 6.66038 -157.724821) (xy 6.676466 -157.67352)
			(xy 6.699591 -157.624983) (xy 6.729296 -157.58017) (xy 6.764995 -157.539969) (xy 6.805981 -157.505173)
			(xy 6.851444 -157.476473) (xy 6.900483 -157.454434) (xy 6.95213 -157.439493) (xy 7.005362 -157.431947)
			(xy 7.032244 -157.431486) (xy 7.059983 -157.431987) (xy 7.114876 -157.440024) (xy 7.168028 -157.455924)
			(xy 7.218317 -157.47935) (xy 7.264686 -157.50981) (xy 7.306157 -157.546661) (xy 7.341856 -157.589127)
			(xy 7.371032 -157.636315) (xy 7.393069 -157.687228) (xy 7.407504 -157.740796) (xy 7.411212 -157.76829)
			(xy 7.412736 -157.782006) (xy 7.414518 -157.810366) (xy 7.41068 -157.867058) (xy 7.398485 -157.922555)
			(xy 7.3782 -157.975633) (xy 7.350276 -158.02512) (xy 7.315327 -158.069923) (xy 7.274126 -158.109053)
			(xy 7.227582 -158.141646) (xy 7.176722 -158.166984) (xy 7.122669 -158.184506) (xy 7.094728 -158.189676)
			(xy 7.09422 -158.189676) (xy 7.087108 -158.190946) (xy 7.082028 -158.193232) (xy 7.075932 -158.196534)
			(xy 7.075424 -158.197042) (xy 7.071614 -158.199582) (xy 7.055866 -158.212028) (xy 7.055612 -158.212282)
			(xy 7.055104 -158.21279) (xy 7.052564 -158.214568) (xy 7.052056 -158.214822) (xy 7.046976 -158.218632)
			(xy 7.042404 -158.224474) (xy 7.040055 -158.227812) (xy 7.036359 -158.23509) (xy 7.035038 -158.238952)
			(xy 7.023608 -158.27248) (xy 7.00913 -158.314644) (xy 7.007928 -158.319566) (xy 7.007288 -158.329676)
			(xy 7.00786 -158.33471) (xy 7.13359 -158.460694) (xy 7.138924 -158.462472) (xy 7.145274 -158.46425)
			(xy 7.170861 -158.472701) (xy 7.219549 -158.495792) (xy 7.264509 -158.525496) (xy 7.304849 -158.561223)
			(xy 7.339768 -158.602264) (xy 7.368573 -158.647805) (xy 7.390692 -158.696942) (xy 7.405687 -158.7487)
			(xy 7.413261 -158.802051) (xy 7.413752 -158.828994) (xy 7.413267 -158.856247) (xy 7.405511 -158.910197)
			(xy 7.390157 -158.962495) (xy 7.367517 -159.012076) (xy 7.338051 -159.05793) (xy 7.30236 -159.099125)
			(xy 7.261171 -159.134821) (xy 7.21532 -159.164293) (xy 7.165742 -159.186939) (xy 7.113446 -159.2023)
			(xy 7.059497 -159.210063) (xy 7.032244 -159.210502) (xy 7.005332 -159.210042) (xy 6.952042 -159.202479)
			(xy 6.900345 -159.187498) (xy 6.851269 -159.165394) (xy 6.805788 -159.13661) (xy 6.764808 -159.101715)
			(xy 6.729142 -159.061404) (xy 6.699499 -159.016478) (xy 6.676469 -158.96783) (xy 6.668008 -158.942278)
			(xy 6.666992 -158.938722) (xy 6.665384 -158.935017) (xy 6.661171 -158.928128) (xy 6.65861 -158.925006)
			(xy 5.86232 -158.128716) (xy 5.85672 -158.124295) (xy 5.843699 -158.118481) (xy 5.836666 -158.117286)
			(xy 5.822241 -158.115757) (xy 5.793548 -158.119917) (xy 5.76718 -158.13197) (xy 5.74526 -158.150947)
			(xy 5.729556 -158.175319) (xy 5.721332 -158.203121) (xy 5.720842 -158.217616) (xy 5.720842 -159.844994)
			(xy 6.650226 -159.844994) (xy 6.654297 -159.789372) (xy 6.666423 -159.734935) (xy 6.686346 -159.682844)
			(xy 6.713642 -159.634209) (xy 6.747728 -159.590066) (xy 6.787877 -159.551357) (xy 6.833235 -159.518906)
			(xy 6.882835 -159.493405) (xy 6.935619 -159.475398) (xy 6.990462 -159.465268) (xy 7.046196 -159.463231)
			(xy 7.101633 -159.469331) (xy 7.15559 -159.483437) (xy 7.206919 -159.505249) (xy 7.254525 -159.534303)
			(xy 7.297393 -159.569978) (xy 7.33461 -159.611515) (xy 7.365383 -159.658028) (xy 7.389055 -159.708525)
			(xy 7.405123 -159.761932) (xy 7.413243 -159.817108) (xy 7.413752 -159.844994) (xy 7.413243 -159.87288)
			(xy 7.405123 -159.928056) (xy 7.389055 -159.981463) (xy 7.365383 -160.03196) (xy 7.33461 -160.078473)
			(xy 7.297393 -160.12001) (xy 7.254525 -160.155685) (xy 7.206919 -160.184739) (xy 7.15559 -160.206551)
			(xy 7.101633 -160.220657) (xy 7.046196 -160.226757) (xy 6.990462 -160.22472) (xy 6.935619 -160.21459)
			(xy 6.882835 -160.196583) (xy 6.833235 -160.171082) (xy 6.787877 -160.138631) (xy 6.747728 -160.099922)
			(xy 6.713642 -160.055779) (xy 6.686346 -160.007144) (xy 6.666423 -159.955053) (xy 6.654297 -159.900616)
			(xy 6.650226 -159.844994) (xy 5.720842 -159.844994) (xy 5.720842 -167.667178) (xy 18.392138 -167.667178)
			(xy 18.396209 -167.611556) (xy 18.408335 -167.557119) (xy 18.428258 -167.505028) (xy 18.455554 -167.456393)
			(xy 18.48964 -167.41225) (xy 18.529789 -167.373541) (xy 18.575147 -167.34109) (xy 18.624747 -167.315589)
			(xy 18.677531 -167.297582) (xy 18.732374 -167.287452) (xy 18.788108 -167.285415) (xy 18.843545 -167.291515)
			(xy 18.897502 -167.305621) (xy 18.948831 -167.327433) (xy 18.996437 -167.356487) (xy 19.039305 -167.392162)
			(xy 19.076522 -167.433699) (xy 19.107295 -167.480212) (xy 19.130967 -167.530709) (xy 19.147035 -167.584116)
			(xy 19.149914 -167.603678) (xy 21.168612 -167.603678) (xy 21.172683 -167.548056) (xy 21.184809 -167.493619)
			(xy 21.204732 -167.441528) (xy 21.232028 -167.392893) (xy 21.266114 -167.34875) (xy 21.306263 -167.310041)
			(xy 21.351621 -167.27759) (xy 21.401221 -167.252089) (xy 21.454005 -167.234082) (xy 21.508848 -167.223952)
			(xy 21.564582 -167.221915) (xy 21.620019 -167.228015) (xy 21.673976 -167.242121) (xy 21.69359 -167.250456)
			(xy 23.214741 -167.250456) (xy 23.214741 -167.195944) (xy 23.222499 -167.141988) (xy 23.237858 -167.089685)
			(xy 23.260504 -167.040101) (xy 23.289977 -166.994244) (xy 23.325676 -166.953049) (xy 23.366874 -166.917354)
			(xy 23.412734 -166.887886) (xy 23.462321 -166.865244) (xy 23.514625 -166.849891) (xy 23.568582 -166.842138)
			(xy 23.595838 -166.841678) (xy 23.625175 -166.842247) (xy 23.683154 -166.851246) (xy 23.739073 -166.869012)
			(xy 23.791615 -166.895126) (xy 23.839542 -166.928972) (xy 23.881725 -166.969754) (xy 23.899876 -166.992808)
			(xy 23.899876 -166.993062) (xy 23.907479 -167.001907) (xy 23.928364 -167.012232) (xy 23.940008 -167.012874)
			(xy 24.032718 -167.013382) (xy 24.054054 -167.002968) (xy 24.061166 -166.99357) (xy 24.070432 -166.981847)
			(xy 24.090519 -166.959723) (xy 24.101298 -166.949374) (xy 24.101552 -166.94912) (xy 24.108437 -166.941841)
			(xy 24.116552 -166.923549) (xy 24.1173 -166.91356) (xy 24.119078 -166.830502) (xy 24.111712 -166.811706)
			(xy 24.104346 -166.80434) (xy 24.08411 -166.782802) (xy 24.049802 -166.734686) (xy 24.023324 -166.681855)
			(xy 24.005311 -166.625574) (xy 23.996191 -166.567187) (xy 23.995634 -166.53764) (xy 23.99612 -166.510389)
			(xy 24.003876 -166.456441) (xy 24.019231 -166.404146) (xy 24.041873 -166.354569) (xy 24.071339 -166.308719)
			(xy 24.10703 -166.267528) (xy 24.148221 -166.231837) (xy 24.194071 -166.202371) (xy 24.243648 -166.179729)
			(xy 24.295943 -166.164374) (xy 24.349891 -166.156618) (xy 24.404393 -166.156618) (xy 24.458341 -166.164374)
			(xy 24.510636 -166.179729) (xy 24.560213 -166.202371) (xy 24.606063 -166.231837) (xy 24.647254 -166.267528)
			(xy 24.682945 -166.308719) (xy 24.712411 -166.354569) (xy 24.735053 -166.404146) (xy 24.750408 -166.456441)
			(xy 24.758164 -166.510389) (xy 24.75865 -166.53764) (xy 24.758194 -166.56356) (xy 24.751159 -166.614922)
			(xy 24.737239 -166.664858) (xy 24.716688 -166.712452) (xy 24.689886 -166.756826) (xy 24.657325 -166.797165)
			(xy 24.638762 -166.815262) (xy 24.638508 -166.815516) (xy 24.631617 -166.82279) (xy 24.623503 -166.841085)
			(xy 24.62276 -166.851076) (xy 24.620982 -166.934134) (xy 24.628348 -166.95293) (xy 24.635714 -166.960296)
			(xy 24.655977 -166.981809) (xy 24.690279 -167.029933) (xy 24.716751 -167.08277) (xy 24.734758 -167.139057)
			(xy 24.743871 -167.197447) (xy 24.744426 -167.226996) (xy 24.743919 -167.254246) (xy 24.736163 -167.308192)
			(xy 24.720809 -167.360486) (xy 24.69817 -167.410062) (xy 24.668706 -167.455911) (xy 24.633017 -167.497101)
			(xy 24.591829 -167.532793) (xy 24.545981 -167.562259) (xy 24.496406 -167.584902) (xy 24.444114 -167.600258)
			(xy 24.390168 -167.608017) (xy 24.362918 -167.608504) (xy 24.33358 -167.607974) (xy 24.275599 -167.598967)
			(xy 24.219678 -167.581194) (xy 24.167136 -167.555073) (xy 24.119211 -167.52122) (xy 24.07703 -167.480431)
			(xy 24.05888 -167.457374) (xy 24.05888 -167.45712) (xy 24.0513 -167.448252) (xy 24.030398 -167.437941)
			(xy 24.018748 -167.437308) (xy 23.926038 -167.4368) (xy 23.904702 -167.447214) (xy 23.89759 -167.456612)
			(xy 23.879385 -167.479219) (xy 23.837332 -167.519221) (xy 23.789705 -167.552392) (xy 23.737602 -167.577965)
			(xy 23.682228 -167.595351) (xy 23.624858 -167.604149) (xy 23.595838 -167.604694) (xy 23.568582 -167.604262)
			(xy 23.514625 -167.596509) (xy 23.462321 -167.581156) (xy 23.412734 -167.558514) (xy 23.366874 -167.529046)
			(xy 23.325676 -167.493351) (xy 23.289977 -167.452156) (xy 23.260504 -167.406299) (xy 23.237858 -167.356715)
			(xy 23.222499 -167.304412) (xy 23.214741 -167.250456) (xy 21.69359 -167.250456) (xy 21.725305 -167.263933)
			(xy 21.772911 -167.292987) (xy 21.815779 -167.328662) (xy 21.852996 -167.370199) (xy 21.883769 -167.416712)
			(xy 21.907441 -167.467209) (xy 21.923509 -167.520616) (xy 21.931629 -167.575792) (xy 21.932138 -167.603678)
			(xy 21.931629 -167.631564) (xy 21.923509 -167.68674) (xy 21.907441 -167.740147) (xy 21.883769 -167.790644)
			(xy 21.852996 -167.837157) (xy 21.815779 -167.878694) (xy 21.772911 -167.914369) (xy 21.725305 -167.943423)
			(xy 21.673976 -167.965235) (xy 21.620019 -167.979341) (xy 21.564582 -167.985441) (xy 21.508848 -167.983404)
			(xy 21.454005 -167.973274) (xy 21.401221 -167.955267) (xy 21.351621 -167.929766) (xy 21.306263 -167.897315)
			(xy 21.266114 -167.858606) (xy 21.232028 -167.814463) (xy 21.204732 -167.765828) (xy 21.184809 -167.713737)
			(xy 21.172683 -167.6593) (xy 21.168612 -167.603678) (xy 19.149914 -167.603678) (xy 19.155155 -167.639292)
			(xy 19.155664 -167.667178) (xy 19.155155 -167.695064) (xy 19.147035 -167.75024) (xy 19.130967 -167.803647)
			(xy 19.107295 -167.854144) (xy 19.076522 -167.900657) (xy 19.039305 -167.942194) (xy 18.996437 -167.977869)
			(xy 18.948831 -168.006923) (xy 18.897502 -168.028735) (xy 18.843545 -168.042841) (xy 18.788108 -168.048941)
			(xy 18.732374 -168.046904) (xy 18.677531 -168.036774) (xy 18.624747 -168.018767) (xy 18.575147 -167.993266)
			(xy 18.529789 -167.960815) (xy 18.48964 -167.922106) (xy 18.455554 -167.877963) (xy 18.428258 -167.829328)
			(xy 18.408335 -167.777237) (xy 18.396209 -167.7228) (xy 18.392138 -167.667178) (xy 5.720842 -167.667178)
			(xy 5.720842 -168.417063) (xy 8.583373 -168.417063) (xy 8.583373 -168.362557) (xy 8.59113 -168.308606)
			(xy 8.606487 -168.256307) (xy 8.629129 -168.206727) (xy 8.658598 -168.160873) (xy 8.694292 -168.11968)
			(xy 8.735485 -168.083987) (xy 8.781339 -168.054518) (xy 8.830919 -168.031876) (xy 8.883217 -168.01652)
			(xy 8.937169 -168.008763) (xy 8.964422 -168.0083) (xy 8.991897 -168.008773) (xy 9.046277 -168.016668)
			(xy 9.09896 -168.032292) (xy 9.148852 -168.055319) (xy 9.19492 -168.085273) (xy 9.215882 -168.103042)
			(xy 9.223155 -168.108845) (xy 9.240617 -168.115223) (xy 9.249918 -168.115488) (xy 9.32815 -168.114218)
			(xy 9.345422 -168.107106) (xy 9.35228 -168.100756) (xy 9.373594 -168.08147) (xy 9.420959 -168.048905)
			(xy 9.472674 -168.023815) (xy 9.527568 -168.006768) (xy 9.584398 -167.99815) (xy 9.613138 -167.997632)
			(xy 9.640391 -167.998095) (xy 9.694342 -168.005852) (xy 9.74664 -168.021208) (xy 9.796221 -168.04385)
			(xy 9.842074 -168.073318) (xy 9.883267 -168.109012) (xy 9.918961 -168.150204) (xy 9.948429 -168.196058)
			(xy 9.971072 -168.245638) (xy 9.986428 -168.297936) (xy 9.994185 -168.351887) (xy 9.994185 -168.406393)
			(xy 9.986428 -168.460344) (xy 9.971072 -168.512642) (xy 9.948429 -168.562222) (xy 9.918961 -168.608076)
			(xy 9.883267 -168.649268) (xy 9.842074 -168.684962) (xy 9.796221 -168.71443) (xy 9.74664 -168.737072)
			(xy 9.694342 -168.752428) (xy 9.640391 -168.760185) (xy 9.613138 -168.760648) (xy 9.585664 -168.760152)
			(xy 9.531284 -168.752264) (xy 9.478601 -168.736647) (xy 9.428708 -168.713624) (xy 9.38264 -168.683673)
			(xy 9.361678 -168.665906) (xy 9.354383 -168.660134) (xy 9.336938 -168.653736) (xy 9.327642 -168.65346)
			(xy 9.24941 -168.65473) (xy 9.232138 -168.661842) (xy 9.22528 -168.668192) (xy 9.203948 -168.687457)
			(xy 9.156587 -168.720023) (xy 9.104877 -168.745116) (xy 9.049987 -168.762168) (xy 9.008124 -168.768522)
			(xy 23.884888 -168.768522) (xy 23.888959 -168.7129) (xy 23.901085 -168.658463) (xy 23.921008 -168.606372)
			(xy 23.948304 -168.557737) (xy 23.98239 -168.513594) (xy 24.022539 -168.474885) (xy 24.067897 -168.442434)
			(xy 24.117497 -168.416933) (xy 24.170281 -168.398926) (xy 24.225124 -168.388796) (xy 24.280858 -168.386759)
			(xy 24.336295 -168.392859) (xy 24.390252 -168.406965) (xy 24.441581 -168.428777) (xy 24.489187 -168.457831)
			(xy 24.532055 -168.493506) (xy 24.569272 -168.535043) (xy 24.600045 -168.581556) (xy 24.623717 -168.632053)
			(xy 24.639785 -168.68546) (xy 24.647905 -168.740636) (xy 24.648414 -168.768522) (xy 24.647905 -168.796408)
			(xy 24.639785 -168.851584) (xy 24.623717 -168.904991) (xy 24.600045 -168.955488) (xy 24.569272 -169.002001)
			(xy 24.532055 -169.043538) (xy 24.489187 -169.079213) (xy 24.441581 -169.108267) (xy 24.390252 -169.130079)
			(xy 24.336295 -169.144185) (xy 24.280858 -169.150285) (xy 24.225124 -169.148248) (xy 24.170281 -169.138118)
			(xy 24.117497 -169.120111) (xy 24.067897 -169.09461) (xy 24.022539 -169.062159) (xy 23.98239 -169.02345)
			(xy 23.948304 -168.979307) (xy 23.921008 -168.930672) (xy 23.901085 -168.878581) (xy 23.888959 -168.824144)
			(xy 23.884888 -168.768522) (xy 9.008124 -168.768522) (xy 8.993161 -168.770793) (xy 8.964422 -168.771316)
			(xy 8.937169 -168.770857) (xy 8.883217 -168.7631) (xy 8.830919 -168.747744) (xy 8.781339 -168.725102)
			(xy 8.735485 -168.695633) (xy 8.694292 -168.65994) (xy 8.658598 -168.618747) (xy 8.629129 -168.572893)
			(xy 8.606487 -168.523313) (xy 8.59113 -168.471014) (xy 8.583373 -168.417063) (xy 5.720842 -168.417063)
			(xy 5.720842 -169.517314) (xy 19.694904 -169.517314) (xy 19.698975 -169.461692) (xy 19.711101 -169.407255)
			(xy 19.731024 -169.355164) (xy 19.75832 -169.306529) (xy 19.792406 -169.262386) (xy 19.832555 -169.223677)
			(xy 19.877913 -169.191226) (xy 19.927513 -169.165725) (xy 19.980297 -169.147718) (xy 20.03514 -169.137588)
			(xy 20.090874 -169.135551) (xy 20.146311 -169.141651) (xy 20.200268 -169.155757) (xy 20.251597 -169.177569)
			(xy 20.299203 -169.206623) (xy 20.342071 -169.242298) (xy 20.379288 -169.283835) (xy 20.410061 -169.330348)
			(xy 20.433733 -169.380845) (xy 20.449801 -169.434252) (xy 20.457921 -169.489428) (xy 20.45843 -169.517314)
			(xy 20.457921 -169.5452) (xy 20.449801 -169.600376) (xy 20.433733 -169.653783) (xy 20.410061 -169.70428)
			(xy 20.379288 -169.750793) (xy 20.342071 -169.79233) (xy 20.299203 -169.828005) (xy 20.251597 -169.857059)
			(xy 20.200268 -169.878871) (xy 20.146311 -169.892977) (xy 20.090874 -169.899077) (xy 20.03514 -169.89704)
			(xy 19.980297 -169.88691) (xy 19.927513 -169.868903) (xy 19.877913 -169.843402) (xy 19.832555 -169.810951)
			(xy 19.792406 -169.772242) (xy 19.75832 -169.728099) (xy 19.731024 -169.679464) (xy 19.711101 -169.627373)
			(xy 19.698975 -169.572936) (xy 19.694904 -169.517314) (xy 5.720842 -169.517314) (xy 5.720842 -170.590281)
			(xy 8.57248 -170.590281) (xy 8.57248 -170.535779) (xy 8.580236 -170.481831) (xy 8.595591 -170.429537)
			(xy 8.618232 -170.37996) (xy 8.647698 -170.33411) (xy 8.68339 -170.29292) (xy 8.72458 -170.257228)
			(xy 8.77043 -170.227762) (xy 8.820007 -170.205121) (xy 8.872301 -170.189766) (xy 8.926249 -170.18201)
			(xy 8.9535 -170.181524) (xy 8.981589 -170.182012) (xy 9.037157 -170.190259) (xy 9.090913 -170.206574)
			(xy 9.141691 -170.230605) (xy 9.188391 -170.26183) (xy 9.209532 -170.28033) (xy 9.209786 -170.280584)
			(xy 9.216994 -170.286556) (xy 9.234468 -170.293221) (xy 9.243822 -170.293538) (xy 9.311894 -170.293538)
			(xy 9.32123 -170.293116) (xy 9.338682 -170.286482) (xy 9.34593 -170.280584) (xy 9.346184 -170.28033)
			(xy 9.367346 -170.26186) (xy 9.414058 -170.230668) (xy 9.464833 -170.206652) (xy 9.518577 -170.190328)
			(xy 9.574132 -170.182049) (xy 9.602216 -170.181524) (xy 9.629469 -170.181983) (xy 9.683421 -170.18974)
			(xy 9.735719 -170.205095) (xy 9.7853 -170.227738) (xy 9.831154 -170.257206) (xy 9.872348 -170.2929)
			(xy 9.908042 -170.334093) (xy 9.91985 -170.352466) (xy 20.610574 -170.352466) (xy 20.614645 -170.296844)
			(xy 20.626771 -170.242407) (xy 20.646694 -170.190316) (xy 20.67399 -170.141681) (xy 20.708076 -170.097538)
			(xy 20.748225 -170.058829) (xy 20.793583 -170.026378) (xy 20.843183 -170.000877) (xy 20.895967 -169.98287)
			(xy 20.95081 -169.97274) (xy 21.006544 -169.970703) (xy 21.061981 -169.976803) (xy 21.115938 -169.990909)
			(xy 21.167267 -170.012721) (xy 21.214873 -170.041775) (xy 21.257741 -170.07745) (xy 21.294958 -170.118987)
			(xy 21.325731 -170.1655) (xy 21.349403 -170.215997) (xy 21.365471 -170.269404) (xy 21.373591 -170.32458)
			(xy 21.3741 -170.352466) (xy 21.373591 -170.380352) (xy 21.365471 -170.435528) (xy 21.349403 -170.488935)
			(xy 21.325731 -170.539432) (xy 21.294958 -170.585945) (xy 21.257741 -170.627482) (xy 21.214873 -170.663157)
			(xy 21.167267 -170.692211) (xy 21.115938 -170.714023) (xy 21.061981 -170.728129) (xy 21.006544 -170.734229)
			(xy 20.95081 -170.732192) (xy 20.895967 -170.722062) (xy 20.843183 -170.704055) (xy 20.793583 -170.678554)
			(xy 20.748225 -170.646103) (xy 20.708076 -170.607394) (xy 20.67399 -170.563251) (xy 20.646694 -170.514616)
			(xy 20.626771 -170.462525) (xy 20.614645 -170.408088) (xy 20.610574 -170.352466) (xy 9.91985 -170.352466)
			(xy 9.93751 -170.379946) (xy 9.960153 -170.429527) (xy 9.97551 -170.481825) (xy 9.983267 -170.535777)
			(xy 9.983267 -170.590283) (xy 9.97551 -170.644235) (xy 9.960153 -170.696533) (xy 9.93751 -170.746114)
			(xy 9.908042 -170.791967) (xy 9.872348 -170.83316) (xy 9.831154 -170.868854) (xy 9.7853 -170.898322)
			(xy 9.735719 -170.920965) (xy 9.683421 -170.93632) (xy 9.629469 -170.944077) (xy 9.602216 -170.94454)
			(xy 9.574127 -170.944051) (xy 9.518559 -170.935806) (xy 9.464803 -170.919491) (xy 9.414025 -170.89546)
			(xy 9.367325 -170.864235) (xy 9.346184 -170.845734) (xy 9.34593 -170.84548) (xy 9.338721 -170.839511)
			(xy 9.321247 -170.832845) (xy 9.311894 -170.832526) (xy 9.243822 -170.832526) (xy 9.234488 -170.832963)
			(xy 9.217036 -170.839587) (xy 9.209786 -170.84548) (xy 9.209532 -170.845734) (xy 9.188359 -170.864191)
			(xy 9.141651 -170.895386) (xy 9.090878 -170.919405) (xy 9.037136 -170.935732) (xy 8.981583 -170.944014)
			(xy 8.9535 -170.94454) (xy 8.926249 -170.94405) (xy 8.872301 -170.936294) (xy 8.820007 -170.920939)
			(xy 8.77043 -170.898298) (xy 8.72458 -170.868832) (xy 8.68339 -170.83314) (xy 8.647698 -170.79195)
			(xy 8.618232 -170.7461) (xy 8.595591 -170.696523) (xy 8.580236 -170.644229) (xy 8.57248 -170.590281)
			(xy 5.720842 -170.590281) (xy 5.720842 -172.729398) (xy 20.58873 -172.729398) (xy 20.592801 -172.673776)
			(xy 20.604927 -172.619339) (xy 20.62485 -172.567248) (xy 20.652146 -172.518613) (xy 20.686232 -172.47447)
			(xy 20.726381 -172.435761) (xy 20.771739 -172.40331) (xy 20.821339 -172.377809) (xy 20.874123 -172.359802)
			(xy 20.928966 -172.349672) (xy 20.9847 -172.347635) (xy 21.040137 -172.353735) (xy 21.094094 -172.367841)
			(xy 21.145423 -172.389653) (xy 21.193029 -172.418707) (xy 21.235897 -172.454382) (xy 21.273114 -172.495919)
			(xy 21.303887 -172.542432) (xy 21.327559 -172.592929) (xy 21.343627 -172.646336) (xy 21.351747 -172.701512)
			(xy 21.352256 -172.729398) (xy 21.351747 -172.757284) (xy 21.343627 -172.81246) (xy 21.327559 -172.865867)
			(xy 21.303887 -172.916364) (xy 21.273114 -172.962877) (xy 21.235897 -173.004414) (xy 21.193029 -173.040089)
			(xy 21.145423 -173.069143) (xy 21.094094 -173.090955) (xy 21.040137 -173.105061) (xy 20.9847 -173.111161)
			(xy 20.928966 -173.109124) (xy 20.874123 -173.098994) (xy 20.821339 -173.080987) (xy 20.771739 -173.055486)
			(xy 20.726381 -173.023035) (xy 20.686232 -172.984326) (xy 20.652146 -172.940183) (xy 20.62485 -172.891548)
			(xy 20.604927 -172.839457) (xy 20.592801 -172.78502) (xy 20.58873 -172.729398) (xy 5.720842 -172.729398)
			(xy 5.720842 -173.282681) (xy 8.99412 -173.282681) (xy 8.99412 -173.228179) (xy 9.001876 -173.174231)
			(xy 9.017231 -173.121937) (xy 9.039872 -173.07236) (xy 9.069338 -173.02651) (xy 9.10503 -172.98532)
			(xy 9.14622 -172.949628) (xy 9.19207 -172.920162) (xy 9.241647 -172.897521) (xy 9.293941 -172.882166)
			(xy 9.347889 -172.87441) (xy 9.37514 -172.873924) (xy 9.404399 -172.874486) (xy 9.462231 -172.883433)
			(xy 9.518021 -172.901096) (xy 9.570464 -172.927062) (xy 9.618333 -172.960722) (xy 9.639808 -172.980604)
			(xy 9.647174 -172.987716) (xy 9.664954 -172.994828) (xy 9.755632 -172.994828) (xy 9.773412 -172.987716)
			(xy 9.780778 -172.980604) (xy 9.802223 -172.960685) (xy 9.850091 -172.92701) (xy 9.902541 -172.90104)
			(xy 9.958341 -172.883382) (xy 10.016182 -172.874453) (xy 10.045446 -172.873924) (xy 10.072699 -172.874383)
			(xy 10.126651 -172.88214) (xy 10.178949 -172.897495) (xy 10.22853 -172.920138) (xy 10.274384 -172.949606)
			(xy 10.315578 -172.9853) (xy 10.351272 -173.026493) (xy 10.38074 -173.072346) (xy 10.403383 -173.121927)
			(xy 10.41874 -173.174225) (xy 10.426497 -173.228177) (xy 10.426497 -173.282683) (xy 10.41874 -173.336635)
			(xy 10.403383 -173.388933) (xy 10.38074 -173.438514) (xy 10.351272 -173.484367) (xy 10.315578 -173.52556)
			(xy 10.274384 -173.561254) (xy 10.229336 -173.590204) (xy 19.616672 -173.590204) (xy 19.620743 -173.534582)
			(xy 19.632869 -173.480145) (xy 19.652792 -173.428054) (xy 19.680088 -173.379419) (xy 19.714174 -173.335276)
			(xy 19.754323 -173.296567) (xy 19.799681 -173.264116) (xy 19.849281 -173.238615) (xy 19.902065 -173.220608)
			(xy 19.956908 -173.210478) (xy 20.012642 -173.208441) (xy 20.068079 -173.214541) (xy 20.122036 -173.228647)
			(xy 20.173365 -173.250459) (xy 20.220971 -173.279513) (xy 20.263839 -173.315188) (xy 20.301056 -173.356725)
			(xy 20.331829 -173.403238) (xy 20.355501 -173.453735) (xy 20.371569 -173.507142) (xy 20.379689 -173.562318)
			(xy 20.380198 -173.590204) (xy 20.379689 -173.61809) (xy 20.371569 -173.673266) (xy 20.355501 -173.726673)
			(xy 20.331829 -173.77717) (xy 20.301056 -173.823683) (xy 20.263839 -173.86522) (xy 20.220971 -173.900895)
			(xy 20.173365 -173.929949) (xy 20.122036 -173.951761) (xy 20.068079 -173.965867) (xy 20.012642 -173.971967)
			(xy 19.956908 -173.96993) (xy 19.902065 -173.9598) (xy 19.849281 -173.941793) (xy 19.799681 -173.916292)
			(xy 19.754323 -173.883841) (xy 19.714174 -173.845132) (xy 19.680088 -173.800989) (xy 19.652792 -173.752354)
			(xy 19.632869 -173.700263) (xy 19.620743 -173.645826) (xy 19.616672 -173.590204) (xy 10.229336 -173.590204)
			(xy 10.22853 -173.590722) (xy 10.178949 -173.613365) (xy 10.126651 -173.62872) (xy 10.072699 -173.636477)
			(xy 10.045446 -173.63694) (xy 10.016186 -173.636396) (xy 9.958353 -173.627446) (xy 9.902562 -173.60978)
			(xy 9.85012 -173.58381) (xy 9.802252 -173.550144) (xy 9.780778 -173.53026) (xy 9.773412 -173.523148)
			(xy 9.755632 -173.516036) (xy 9.664954 -173.516036) (xy 9.647174 -173.523148) (xy 9.639808 -173.53026)
			(xy 9.618364 -173.550179) (xy 9.570496 -173.583855) (xy 9.518046 -173.609827) (xy 9.462246 -173.627484)
			(xy 9.404404 -173.636412) (xy 9.37514 -173.63694) (xy 9.347889 -173.63645) (xy 9.293941 -173.628694)
			(xy 9.241647 -173.613339) (xy 9.19207 -173.590698) (xy 9.14622 -173.561232) (xy 9.10503 -173.52554)
			(xy 9.069338 -173.48435) (xy 9.039872 -173.4385) (xy 9.017231 -173.388923) (xy 9.001876 -173.336629)
			(xy 8.99412 -173.282681) (xy 5.720842 -173.282681) (xy 5.720842 -174.271178) (xy 21.033738 -174.271178)
			(xy 21.037809 -174.215556) (xy 21.049935 -174.161119) (xy 21.069858 -174.109028) (xy 21.097154 -174.060393)
			(xy 21.13124 -174.01625) (xy 21.171389 -173.977541) (xy 21.216747 -173.94509) (xy 21.266347 -173.919589)
			(xy 21.319131 -173.901582) (xy 21.373974 -173.891452) (xy 21.429708 -173.889415) (xy 21.485145 -173.895515)
			(xy 21.539102 -173.909621) (xy 21.590431 -173.931433) (xy 21.638037 -173.960487) (xy 21.680905 -173.996162)
			(xy 21.718122 -174.037699) (xy 21.748895 -174.084212) (xy 21.772567 -174.134709) (xy 21.788635 -174.188116)
			(xy 21.796755 -174.243292) (xy 21.797264 -174.271178) (xy 21.796755 -174.299064) (xy 21.788635 -174.35424)
			(xy 21.772567 -174.407647) (xy 21.748895 -174.458144) (xy 21.718122 -174.504657) (xy 21.680905 -174.546194)
			(xy 21.638037 -174.581869) (xy 21.590431 -174.610923) (xy 21.539102 -174.632735) (xy 21.485145 -174.646841)
			(xy 21.429708 -174.652941) (xy 21.373974 -174.650904) (xy 21.319131 -174.640774) (xy 21.266347 -174.622767)
			(xy 21.216747 -174.597266) (xy 21.171389 -174.564815) (xy 21.13124 -174.526106) (xy 21.097154 -174.481963)
			(xy 21.069858 -174.433328) (xy 21.049935 -174.381237) (xy 21.037809 -174.3268) (xy 21.033738 -174.271178)
			(xy 5.720842 -174.271178) (xy 5.720842 -177.594081) (xy 8.398486 -177.594081) (xy 8.398486 -177.539579)
			(xy 8.406242 -177.485631) (xy 8.421598 -177.433336) (xy 8.444239 -177.383758) (xy 8.473705 -177.337907)
			(xy 8.509397 -177.296717) (xy 8.550587 -177.261025) (xy 8.596438 -177.231559) (xy 8.646016 -177.208918)
			(xy 8.698311 -177.193562) (xy 8.752259 -177.185806) (xy 8.77951 -177.18532) (xy 8.805824 -177.185774)
			(xy 8.857954 -177.193011) (xy 8.908597 -177.207332) (xy 8.956796 -177.228467) (xy 9.001639 -177.256016)
			(xy 9.042278 -177.289457) (xy 9.060434 -177.30851) (xy 9.06794 -177.31593) (xy 9.087232 -177.324444)
			(xy 9.097772 -177.32502) (xy 9.172448 -177.32502) (xy 9.182995 -177.32447) (xy 9.20229 -177.315949)
			(xy 9.209786 -177.30851) (xy 9.229606 -177.287722) (xy 9.274378 -177.251747) (xy 9.324036 -177.222887)
			(xy 9.377458 -177.201794) (xy 9.433437 -177.188945) (xy 9.49071 -177.18463) (xy 9.547983 -177.188945)
			(xy 9.603962 -177.201794) (xy 9.657384 -177.222887) (xy 9.707042 -177.251747) (xy 9.751814 -177.287722)
			(xy 9.771634 -177.30851) (xy 9.77914 -177.31593) (xy 9.798432 -177.324444) (xy 9.808972 -177.32502)
			(xy 9.883648 -177.32502) (xy 9.894195 -177.32447) (xy 9.91349 -177.315949) (xy 9.920986 -177.30851)
			(xy 9.939157 -177.28947) (xy 9.979783 -177.256011) (xy 10.02462 -177.22845) (xy 10.072818 -177.207309)
			(xy 10.123463 -177.192988) (xy 10.175595 -177.18576) (xy 10.20191 -177.18532) (xy 10.229161 -177.18581)
			(xy 10.283109 -177.193566) (xy 10.335403 -177.208921) (xy 10.38498 -177.231562) (xy 10.43083 -177.261028)
			(xy 10.47202 -177.29672) (xy 10.507712 -177.33791) (xy 10.537178 -177.38376) (xy 10.559819 -177.433337)
			(xy 10.575174 -177.485631) (xy 10.58293 -177.539579) (xy 10.58293 -177.594081) (xy 10.575174 -177.648029)
			(xy 10.559819 -177.700323) (xy 10.537178 -177.7499) (xy 10.507712 -177.79575) (xy 10.47202 -177.83694)
			(xy 10.43083 -177.872632) (xy 10.38498 -177.902098) (xy 10.335403 -177.924739) (xy 10.283109 -177.940094)
			(xy 10.229161 -177.94785) (xy 10.20191 -177.948336) (xy 10.175597 -177.94785) (xy 10.12347 -177.940618)
			(xy 10.072828 -177.926301) (xy 10.024629 -177.905172) (xy 9.979785 -177.87763) (xy 9.939144 -177.844195)
			(xy 9.920986 -177.825146) (xy 9.913465 -177.817743) (xy 9.894185 -177.809218) (xy 9.883648 -177.808636)
			(xy 9.808972 -177.808636) (xy 9.798424 -177.80918) (xy 9.779127 -177.817703) (xy 9.771634 -177.825146)
			(xy 9.751814 -177.845934) (xy 9.707042 -177.881909) (xy 9.657384 -177.910769) (xy 9.603962 -177.931862)
			(xy 9.547983 -177.944711) (xy 9.49071 -177.949026) (xy 9.433437 -177.944711) (xy 9.377458 -177.931862)
			(xy 9.324036 -177.910769) (xy 9.274378 -177.881909) (xy 9.229606 -177.845934) (xy 9.209786 -177.825146)
			(xy 9.202265 -177.817743) (xy 9.182985 -177.809218) (xy 9.172448 -177.808636) (xy 9.097772 -177.808636)
			(xy 9.087224 -177.80918) (xy 9.067927 -177.817703) (xy 9.060434 -177.825146) (xy 9.042313 -177.844235)
			(xy 9.001674 -177.877688) (xy 8.956827 -177.905241) (xy 8.908619 -177.926373) (xy 8.857966 -177.940684)
			(xy 8.805828 -177.947901) (xy 8.77951 -177.948336) (xy 8.752259 -177.947854) (xy 8.698311 -177.940098)
			(xy 8.646016 -177.924742) (xy 8.596438 -177.902101) (xy 8.550587 -177.872635) (xy 8.509397 -177.836943)
			(xy 8.473705 -177.795753) (xy 8.444239 -177.749902) (xy 8.421598 -177.700324) (xy 8.406242 -177.648029)
			(xy 8.398486 -177.594081) (xy 5.720842 -177.594081) (xy 5.720842 -180.365908) (xy 28.064204 -180.365908)
			(xy 28.068275 -180.310286) (xy 28.080401 -180.255849) (xy 28.100324 -180.203758) (xy 28.12762 -180.155123)
			(xy 28.161706 -180.11098) (xy 28.201855 -180.072271) (xy 28.247213 -180.03982) (xy 28.296813 -180.014319)
			(xy 28.349597 -179.996312) (xy 28.40444 -179.986182) (xy 28.460174 -179.984145) (xy 28.515611 -179.990245)
			(xy 28.569568 -180.004351) (xy 28.620897 -180.026163) (xy 28.668503 -180.055217) (xy 28.711371 -180.090892)
			(xy 28.748588 -180.132429) (xy 28.779361 -180.178942) (xy 28.803033 -180.229439) (xy 28.819101 -180.282846)
			(xy 28.827221 -180.338022) (xy 28.82773 -180.365908) (xy 28.827221 -180.393794) (xy 28.819101 -180.44897)
			(xy 28.803033 -180.502377) (xy 28.779361 -180.552874) (xy 28.748588 -180.599387) (xy 28.711371 -180.640924)
			(xy 28.668503 -180.676599) (xy 28.620897 -180.705653) (xy 28.569568 -180.727465) (xy 28.515611 -180.741571)
			(xy 28.460174 -180.747671) (xy 28.40444 -180.745634) (xy 28.349597 -180.735504) (xy 28.296813 -180.717497)
			(xy 28.247213 -180.691996) (xy 28.201855 -180.659545) (xy 28.161706 -180.620836) (xy 28.12762 -180.576693)
			(xy 28.100324 -180.528058) (xy 28.080401 -180.475967) (xy 28.068275 -180.42153) (xy 28.064204 -180.365908)
			(xy 5.720842 -180.365908) (xy 5.720842 -191.783208) (xy 29.869128 -191.783208) (xy 29.873199 -191.727586)
			(xy 29.885325 -191.673149) (xy 29.905248 -191.621058) (xy 29.932544 -191.572423) (xy 29.96663 -191.52828)
			(xy 30.006779 -191.489571) (xy 30.052137 -191.45712) (xy 30.101737 -191.431619) (xy 30.154521 -191.413612)
			(xy 30.209364 -191.403482) (xy 30.265098 -191.401445) (xy 30.320535 -191.407545) (xy 30.374492 -191.421651)
			(xy 30.425821 -191.443463) (xy 30.473427 -191.472517) (xy 30.516295 -191.508192) (xy 30.553512 -191.549729)
			(xy 30.584285 -191.596242) (xy 30.607957 -191.646739) (xy 30.624025 -191.700146) (xy 30.632145 -191.755322)
			(xy 30.632654 -191.783208) (xy 30.632145 -191.811094) (xy 30.624025 -191.86627) (xy 30.607957 -191.919677)
			(xy 30.584285 -191.970174) (xy 30.553512 -192.016687) (xy 30.516295 -192.058224) (xy 30.473427 -192.093899)
			(xy 30.425821 -192.122953) (xy 30.374492 -192.144765) (xy 30.320535 -192.158871) (xy 30.265098 -192.164971)
			(xy 30.209364 -192.162934) (xy 30.154521 -192.152804) (xy 30.101737 -192.134797) (xy 30.052137 -192.109296)
			(xy 30.006779 -192.076845) (xy 29.96663 -192.038136) (xy 29.932544 -191.993993) (xy 29.905248 -191.945358)
			(xy 29.885325 -191.893267) (xy 29.873199 -191.83883) (xy 29.869128 -191.783208) (xy 5.720842 -191.783208)
			(xy 5.720842 -192.745614) (xy 30.161482 -192.745614) (xy 30.165553 -192.689992) (xy 30.177679 -192.635555)
			(xy 30.197602 -192.583464) (xy 30.224898 -192.534829) (xy 30.258984 -192.490686) (xy 30.299133 -192.451977)
			(xy 30.344491 -192.419526) (xy 30.394091 -192.394025) (xy 30.446875 -192.376018) (xy 30.501718 -192.365888)
			(xy 30.557452 -192.363851) (xy 30.612889 -192.369951) (xy 30.666846 -192.384057) (xy 30.718175 -192.405869)
			(xy 30.765781 -192.434923) (xy 30.808649 -192.470598) (xy 30.845866 -192.512135) (xy 30.876639 -192.558648)
			(xy 30.900311 -192.609145) (xy 30.916379 -192.662552) (xy 30.924499 -192.717728) (xy 30.925008 -192.745614)
			(xy 30.924499 -192.7735) (xy 30.916379 -192.828676) (xy 30.900311 -192.882083) (xy 30.876639 -192.93258)
			(xy 30.845866 -192.979093) (xy 30.808649 -193.02063) (xy 30.765781 -193.056305) (xy 30.718175 -193.085359)
			(xy 30.666846 -193.107171) (xy 30.612889 -193.121277) (xy 30.557452 -193.127377) (xy 30.501718 -193.12534)
			(xy 30.446875 -193.11521) (xy 30.394091 -193.097203) (xy 30.344491 -193.071702) (xy 30.299133 -193.039251)
			(xy 30.258984 -193.000542) (xy 30.224898 -192.956399) (xy 30.197602 -192.907764) (xy 30.177679 -192.855673)
			(xy 30.165553 -192.801236) (xy 30.161482 -192.745614) (xy 5.720842 -192.745614) (xy 5.720842 -202.41387)
			(xy 27.454096 -202.41387) (xy 27.458167 -202.358248) (xy 27.470293 -202.303811) (xy 27.490216 -202.25172)
			(xy 27.517512 -202.203085) (xy 27.551598 -202.158942) (xy 27.591747 -202.120233) (xy 27.637105 -202.087782)
			(xy 27.686705 -202.062281) (xy 27.739489 -202.044274) (xy 27.794332 -202.034144) (xy 27.850066 -202.032107)
			(xy 27.905503 -202.038207) (xy 27.95946 -202.052313) (xy 28.010789 -202.074125) (xy 28.058395 -202.103179)
			(xy 28.101263 -202.138854) (xy 28.13848 -202.180391) (xy 28.169253 -202.226904) (xy 28.192925 -202.277401)
			(xy 28.208993 -202.330808) (xy 28.217113 -202.385984) (xy 28.217395 -202.401424) (xy 28.448252 -202.401424)
			(xy 28.452323 -202.345802) (xy 28.464449 -202.291365) (xy 28.484372 -202.239274) (xy 28.511668 -202.190639)
			(xy 28.545754 -202.146496) (xy 28.585903 -202.107787) (xy 28.631261 -202.075336) (xy 28.680861 -202.049835)
			(xy 28.733645 -202.031828) (xy 28.788488 -202.021698) (xy 28.844222 -202.019661) (xy 28.899659 -202.025761)
			(xy 28.953616 -202.039867) (xy 29.004945 -202.061679) (xy 29.052551 -202.090733) (xy 29.095419 -202.126408)
			(xy 29.132636 -202.167945) (xy 29.163409 -202.214458) (xy 29.187081 -202.264955) (xy 29.203149 -202.318362)
			(xy 29.211269 -202.373538) (xy 29.211449 -202.38339) (xy 29.7086 -202.38339) (xy 29.712671 -202.327768)
			(xy 29.724797 -202.273331) (xy 29.74472 -202.22124) (xy 29.772016 -202.172605) (xy 29.806102 -202.128462)
			(xy 29.846251 -202.089753) (xy 29.891609 -202.057302) (xy 29.941209 -202.031801) (xy 29.993993 -202.013794)
			(xy 30.048836 -202.003664) (xy 30.10457 -202.001627) (xy 30.160007 -202.007727) (xy 30.213964 -202.021833)
			(xy 30.265293 -202.043645) (xy 30.312899 -202.072699) (xy 30.355767 -202.108374) (xy 30.392984 -202.149911)
			(xy 30.423757 -202.196424) (xy 30.447429 -202.246921) (xy 30.463497 -202.300328) (xy 30.471617 -202.355504)
			(xy 30.472126 -202.38339) (xy 30.471617 -202.411276) (xy 30.463497 -202.466452) (xy 30.447429 -202.519859)
			(xy 30.423757 -202.570356) (xy 30.392984 -202.616869) (xy 30.355767 -202.658406) (xy 30.312899 -202.694081)
			(xy 30.265293 -202.723135) (xy 30.213964 -202.744947) (xy 30.160007 -202.759053) (xy 30.10457 -202.765153)
			(xy 30.048836 -202.763116) (xy 29.993993 -202.752986) (xy 29.941209 -202.734979) (xy 29.891609 -202.709478)
			(xy 29.846251 -202.677027) (xy 29.806102 -202.638318) (xy 29.772016 -202.594175) (xy 29.74472 -202.54554)
			(xy 29.724797 -202.493449) (xy 29.712671 -202.439012) (xy 29.7086 -202.38339) (xy 29.211449 -202.38339)
			(xy 29.211778 -202.401424) (xy 29.211269 -202.42931) (xy 29.203149 -202.484486) (xy 29.187081 -202.537893)
			(xy 29.163409 -202.58839) (xy 29.132636 -202.634903) (xy 29.095419 -202.67644) (xy 29.052551 -202.712115)
			(xy 29.004945 -202.741169) (xy 28.953616 -202.762981) (xy 28.899659 -202.777087) (xy 28.844222 -202.783187)
			(xy 28.788488 -202.78115) (xy 28.733645 -202.77102) (xy 28.680861 -202.753013) (xy 28.631261 -202.727512)
			(xy 28.585903 -202.695061) (xy 28.545754 -202.656352) (xy 28.511668 -202.612209) (xy 28.484372 -202.563574)
			(xy 28.464449 -202.511483) (xy 28.452323 -202.457046) (xy 28.448252 -202.401424) (xy 28.217395 -202.401424)
			(xy 28.217622 -202.41387) (xy 28.217113 -202.441756) (xy 28.208993 -202.496932) (xy 28.192925 -202.550339)
			(xy 28.169253 -202.600836) (xy 28.13848 -202.647349) (xy 28.101263 -202.688886) (xy 28.058395 -202.724561)
			(xy 28.010789 -202.753615) (xy 27.95946 -202.775427) (xy 27.905503 -202.789533) (xy 27.850066 -202.795633)
			(xy 27.794332 -202.793596) (xy 27.739489 -202.783466) (xy 27.686705 -202.765459) (xy 27.637105 -202.739958)
			(xy 27.591747 -202.707507) (xy 27.551598 -202.668798) (xy 27.517512 -202.624655) (xy 27.490216 -202.57602)
			(xy 27.470293 -202.523929) (xy 27.458167 -202.469492) (xy 27.454096 -202.41387) (xy 5.720842 -202.41387)
			(xy 5.720842 -210.113372) (xy 13.854428 -210.113372) (xy 13.858499 -210.05775) (xy 13.870625 -210.003313)
			(xy 13.890548 -209.951222) (xy 13.917844 -209.902587) (xy 13.95193 -209.858444) (xy 13.992079 -209.819735)
			(xy 14.037437 -209.787284) (xy 14.087037 -209.761783) (xy 14.139821 -209.743776) (xy 14.194664 -209.733646)
			(xy 14.250398 -209.731609) (xy 14.305835 -209.737709) (xy 14.359792 -209.751815) (xy 14.411121 -209.773627)
			(xy 14.458727 -209.802681) (xy 14.501595 -209.838356) (xy 14.538812 -209.879893) (xy 14.569585 -209.926406)
			(xy 14.593257 -209.976903) (xy 14.609325 -210.03031) (xy 14.617445 -210.085486) (xy 14.617954 -210.113372)
			(xy 14.617445 -210.141258) (xy 14.609325 -210.196434) (xy 14.593257 -210.249841) (xy 14.569585 -210.300338)
			(xy 14.538812 -210.346851) (xy 14.501595 -210.388388) (xy 14.458727 -210.424063) (xy 14.411121 -210.453117)
			(xy 14.359792 -210.474929) (xy 14.305835 -210.489035) (xy 14.250398 -210.495135) (xy 14.194664 -210.493098)
			(xy 14.139821 -210.482968) (xy 14.087037 -210.464961) (xy 14.037437 -210.43946) (xy 13.992079 -210.407009)
			(xy 13.95193 -210.3683) (xy 13.917844 -210.324157) (xy 13.890548 -210.275522) (xy 13.870625 -210.223431)
			(xy 13.858499 -210.168994) (xy 13.854428 -210.113372) (xy 5.720842 -210.113372) (xy 5.720842 -210.7057)
			(xy 16.776192 -210.7057) (xy 16.776192 -207.362044) (xy 16.776616 -207.351974) (xy 16.784335 -207.333375)
			(xy 16.791178 -207.325976) (xy 17.16405 -206.95285) (xy 17.171479 -206.946046) (xy 17.190056 -206.938304)
			(xy 17.200118 -206.937864) (xy 19.400774 -206.937864) (xy 19.410844 -206.938286) (xy 19.429443 -206.946007)
			(xy 19.436842 -206.95285) (xy 19.809714 -207.325976) (xy 19.816538 -207.333389) (xy 19.824266 -207.351978)
			(xy 19.8247 -207.362044) (xy 19.8247 -208.810352) (xy 21.535388 -208.810352) (xy 21.539459 -208.75473)
			(xy 21.551585 -208.700293) (xy 21.571508 -208.648202) (xy 21.598804 -208.599567) (xy 21.63289 -208.555424)
			(xy 21.673039 -208.516715) (xy 21.718397 -208.484264) (xy 21.767997 -208.458763) (xy 21.820781 -208.440756)
			(xy 21.875624 -208.430626) (xy 21.931358 -208.428589) (xy 21.986795 -208.434689) (xy 22.040752 -208.448795)
			(xy 22.092081 -208.470607) (xy 22.139687 -208.499661) (xy 22.182555 -208.535336) (xy 22.219772 -208.576873)
			(xy 22.250545 -208.623386) (xy 22.274217 -208.673883) (xy 22.290285 -208.72729) (xy 22.298405 -208.782466)
			(xy 22.298914 -208.810352) (xy 22.298405 -208.838238) (xy 22.290285 -208.893414) (xy 22.274217 -208.946821)
			(xy 22.250545 -208.997318) (xy 22.219772 -209.043831) (xy 22.182555 -209.085368) (xy 22.139687 -209.121043)
			(xy 22.092081 -209.150097) (xy 22.040752 -209.171909) (xy 21.986795 -209.186015) (xy 21.931358 -209.192115)
			(xy 21.875624 -209.190078) (xy 21.820781 -209.179948) (xy 21.767997 -209.161941) (xy 21.718397 -209.13644)
			(xy 21.673039 -209.103989) (xy 21.63289 -209.06528) (xy 21.598804 -209.021137) (xy 21.571508 -208.972502)
			(xy 21.551585 -208.920411) (xy 21.539459 -208.865974) (xy 21.535388 -208.810352) (xy 19.8247 -208.810352)
			(xy 19.8247 -210.4517) (xy 19.824301 -210.461773) (xy 19.816565 -210.480372) (xy 19.809714 -210.487768)
			(xy 19.309842 -210.987894) (xy 19.302421 -210.994707) (xy 19.283838 -211.002443) (xy 19.273774 -211.00288)
			(xy 17.073118 -211.00288) (xy 17.063049 -211.00245) (xy 17.044451 -210.994733) (xy 17.03705 -210.987894)
			(xy 16.791178 -210.741768) (xy 16.784328 -210.734376) (xy 16.776615 -210.71577) (xy 16.776192 -210.7057)
			(xy 5.720842 -210.7057) (xy 5.720842 -212.807621) (xy 11.31543 -212.807621) (xy 11.31543 -212.753119)
			(xy 11.323186 -212.699172) (xy 11.338541 -212.646878) (xy 11.361182 -212.597301) (xy 11.390647 -212.551451)
			(xy 11.426338 -212.510261) (xy 11.467528 -212.47457) (xy 11.513378 -212.445104) (xy 11.562954 -212.422462)
			(xy 11.615248 -212.407107) (xy 11.669195 -212.39935) (xy 11.696446 -212.398864) (xy 11.723692 -212.399293)
			(xy 11.777628 -212.407058) (xy 11.82991 -212.422422) (xy 11.879471 -212.445072) (xy 11.925303 -212.474548)
			(xy 11.966472 -212.510248) (xy 12.002139 -212.551446) (xy 12.017248 -212.574124) (xy 12.022086 -212.581157)
			(xy 12.035497 -212.591704) (xy 12.051641 -212.597224) (xy 12.060174 -212.597492) (xy 12.145518 -212.597492)
			(xy 12.154038 -212.597173) (xy 12.17015 -212.591625) (xy 12.18356 -212.581112) (xy 12.188444 -212.574124)
			(xy 12.203523 -212.551427) (xy 12.239196 -212.510233) (xy 12.280371 -212.474539) (xy 12.326209 -212.445071)
			(xy 12.375776 -212.42243) (xy 12.428061 -212.407077) (xy 12.482 -212.399324) (xy 12.509246 -212.398864)
			(xy 12.535223 -212.399266) (xy 12.586696 -212.406315) (xy 12.636734 -212.42029) (xy 12.684411 -212.440933)
			(xy 12.728842 -212.467859) (xy 12.769204 -212.500572) (xy 12.804749 -212.538463) (xy 12.820142 -212.559392)
			(xy 12.827792 -212.568866) (xy 12.84939 -212.580023) (xy 12.861544 -212.580728) (xy 12.944348 -212.580728)
			(xy 12.956512 -212.580046) (xy 12.978134 -212.568901) (xy 12.98575 -212.559392) (xy 13.001177 -212.538491)
			(xy 13.036724 -212.500612) (xy 13.077084 -212.467909) (xy 13.121509 -212.440987) (xy 13.169179 -212.420345)
			(xy 13.219208 -212.406366) (xy 13.270673 -212.399307) (xy 13.296646 -212.398864) (xy 13.323899 -212.399323)
			(xy 13.377851 -212.40708) (xy 13.430149 -212.422435) (xy 13.47973 -212.445078) (xy 13.525584 -212.474546)
			(xy 13.566778 -212.51024) (xy 13.602472 -212.551433) (xy 13.63194 -212.597286) (xy 13.654583 -212.646867)
			(xy 13.66994 -212.699165) (xy 13.677697 -212.753117) (xy 13.677697 -212.807623) (xy 13.66994 -212.861575)
			(xy 13.654583 -212.913873) (xy 13.63194 -212.963454) (xy 13.602472 -213.009307) (xy 13.566778 -213.0505)
			(xy 13.525584 -213.086194) (xy 13.47973 -213.115662) (xy 13.430149 -213.138305) (xy 13.377851 -213.15366)
			(xy 13.323899 -213.161417) (xy 13.296646 -213.16188) (xy 13.27067 -213.161466) (xy 13.219198 -213.154416)
			(xy 13.169161 -213.140442) (xy 13.121485 -213.119801) (xy 13.077054 -213.092877) (xy 13.036691 -213.060167)
			(xy 13.001144 -213.02228) (xy 12.98575 -213.001352) (xy 12.978115 -212.991864) (xy 12.956505 -212.980717)
			(xy 12.944348 -212.980016) (xy 12.861544 -212.980016) (xy 12.849383 -212.980715) (xy 12.827762 -212.99185)
			(xy 12.820142 -213.001352) (xy 12.804733 -213.022266) (xy 12.769182 -213.060143) (xy 12.728818 -213.092844)
			(xy 12.684389 -213.119763) (xy 12.636718 -213.140403) (xy 12.586686 -213.154381) (xy 12.53522 -213.161438)
			(xy 12.509246 -213.16188) (xy 12.482001 -213.161437) (xy 12.428066 -213.153672) (xy 12.375786 -213.138309)
			(xy 12.326225 -213.115661) (xy 12.280393 -213.086187) (xy 12.239223 -213.05049) (xy 12.203555 -213.009296)
			(xy 12.188444 -212.98662) (xy 12.183567 -212.979618) (xy 12.170172 -212.96907) (xy 12.154045 -212.963533)
			(xy 12.145518 -212.963252) (xy 12.060174 -212.963252) (xy 12.051656 -212.96359) (xy 12.035548 -212.969134)
			(xy 12.022136 -212.979637) (xy 12.017248 -212.98662) (xy 12.002156 -213.009308) (xy 11.966487 -213.050504)
			(xy 11.925315 -213.086201) (xy 11.879479 -213.115671) (xy 11.829914 -213.138314) (xy 11.77763 -213.153668)
			(xy 11.723692 -213.16142) (xy 11.696446 -213.16188) (xy 11.669195 -213.16139) (xy 11.615248 -213.153633)
			(xy 11.562954 -213.138278) (xy 11.513378 -213.115636) (xy 11.467528 -213.08617) (xy 11.426338 -213.050479)
			(xy 11.390647 -213.009289) (xy 11.361182 -212.963439) (xy 11.338541 -212.913862) (xy 11.323186 -212.861568)
			(xy 11.31543 -212.807621) (xy 5.720842 -212.807621) (xy 5.720842 -214.151972) (xy 13.219428 -214.151972)
			(xy 13.223499 -214.09635) (xy 13.235625 -214.041913) (xy 13.255548 -213.989822) (xy 13.282844 -213.941187)
			(xy 13.31693 -213.897044) (xy 13.357079 -213.858335) (xy 13.402437 -213.825884) (xy 13.452037 -213.800383)
			(xy 13.504821 -213.782376) (xy 13.559664 -213.772246) (xy 13.615398 -213.770209) (xy 13.670835 -213.776309)
			(xy 13.724792 -213.790415) (xy 13.776121 -213.812227) (xy 13.823727 -213.841281) (xy 13.866595 -213.876956)
			(xy 13.903812 -213.918493) (xy 13.934585 -213.965006) (xy 13.958257 -214.015503) (xy 13.974325 -214.06891)
			(xy 13.978026 -214.09406) (xy 18.591782 -214.09406) (xy 18.595853 -214.038438) (xy 18.607979 -213.984001)
			(xy 18.627902 -213.93191) (xy 18.655198 -213.883275) (xy 18.689284 -213.839132) (xy 18.729433 -213.800423)
			(xy 18.774791 -213.767972) (xy 18.824391 -213.742471) (xy 18.877175 -213.724464) (xy 18.932018 -213.714334)
			(xy 18.987752 -213.712297) (xy 19.043189 -213.718397) (xy 19.097146 -213.732503) (xy 19.148475 -213.754315)
			(xy 19.196081 -213.783369) (xy 19.238949 -213.819044) (xy 19.276166 -213.860581) (xy 19.306939 -213.907094)
			(xy 19.330611 -213.957591) (xy 19.346679 -214.010998) (xy 19.354799 -214.066174) (xy 19.355308 -214.09406)
			(xy 19.354799 -214.121946) (xy 19.346679 -214.177122) (xy 19.330611 -214.230529) (xy 19.306939 -214.281026)
			(xy 19.276166 -214.327539) (xy 19.238949 -214.369076) (xy 19.196081 -214.404751) (xy 19.148475 -214.433805)
			(xy 19.097146 -214.455617) (xy 19.043189 -214.469723) (xy 18.987752 -214.475823) (xy 18.932018 -214.473786)
			(xy 18.877175 -214.463656) (xy 18.824391 -214.445649) (xy 18.774791 -214.420148) (xy 18.729433 -214.387697)
			(xy 18.689284 -214.348988) (xy 18.655198 -214.304845) (xy 18.627902 -214.25621) (xy 18.607979 -214.204119)
			(xy 18.595853 -214.149682) (xy 18.591782 -214.09406) (xy 13.978026 -214.09406) (xy 13.982445 -214.124086)
			(xy 13.982954 -214.151972) (xy 13.982445 -214.179858) (xy 13.974325 -214.235034) (xy 13.958257 -214.288441)
			(xy 13.934585 -214.338938) (xy 13.903812 -214.385451) (xy 13.866595 -214.426988) (xy 13.823727 -214.462663)
			(xy 13.776121 -214.491717) (xy 13.724792 -214.513529) (xy 13.670835 -214.527635) (xy 13.615398 -214.533735)
			(xy 13.559664 -214.531698) (xy 13.504821 -214.521568) (xy 13.452037 -214.503561) (xy 13.402437 -214.47806)
			(xy 13.357079 -214.445609) (xy 13.31693 -214.4069) (xy 13.282844 -214.362757) (xy 13.255548 -214.314122)
			(xy 13.235625 -214.262031) (xy 13.223499 -214.207594) (xy 13.219428 -214.151972) (xy 5.720842 -214.151972)
			(xy 5.720842 -215.320372) (xy 17.156428 -215.320372) (xy 17.160499 -215.26475) (xy 17.172625 -215.210313)
			(xy 17.192548 -215.158222) (xy 17.219844 -215.109587) (xy 17.25393 -215.065444) (xy 17.294079 -215.026735)
			(xy 17.339437 -214.994284) (xy 17.389037 -214.968783) (xy 17.441821 -214.950776) (xy 17.496664 -214.940646)
			(xy 17.552398 -214.938609) (xy 17.607835 -214.944709) (xy 17.661792 -214.958815) (xy 17.713121 -214.980627)
			(xy 17.760727 -215.009681) (xy 17.803595 -215.045356) (xy 17.840812 -215.086893) (xy 17.871585 -215.133406)
			(xy 17.895257 -215.183903) (xy 17.911325 -215.23731) (xy 17.919445 -215.292486) (xy 17.919954 -215.320372)
			(xy 17.919445 -215.348258) (xy 17.911325 -215.403434) (xy 17.908193 -215.413844) (xy 21.5552 -215.413844)
			(xy 21.559271 -215.358222) (xy 21.571397 -215.303785) (xy 21.59132 -215.251694) (xy 21.618616 -215.203059)
			(xy 21.652702 -215.158916) (xy 21.692851 -215.120207) (xy 21.738209 -215.087756) (xy 21.787809 -215.062255)
			(xy 21.840593 -215.044248) (xy 21.895436 -215.034118) (xy 21.95117 -215.032081) (xy 22.006607 -215.038181)
			(xy 22.060564 -215.052287) (xy 22.111893 -215.074099) (xy 22.159499 -215.103153) (xy 22.202367 -215.138828)
			(xy 22.239584 -215.180365) (xy 22.270357 -215.226878) (xy 22.294029 -215.277375) (xy 22.310097 -215.330782)
			(xy 22.318217 -215.385958) (xy 22.318726 -215.413844) (xy 22.318217 -215.44173) (xy 22.310097 -215.496906)
			(xy 22.294029 -215.550313) (xy 22.270357 -215.60081) (xy 22.239584 -215.647323) (xy 22.202367 -215.68886)
			(xy 22.159499 -215.724535) (xy 22.111893 -215.753589) (xy 22.060564 -215.775401) (xy 22.006607 -215.789507)
			(xy 21.95117 -215.795607) (xy 21.895436 -215.79357) (xy 21.840593 -215.78344) (xy 21.787809 -215.765433)
			(xy 21.738209 -215.739932) (xy 21.692851 -215.707481) (xy 21.652702 -215.668772) (xy 21.618616 -215.624629)
			(xy 21.59132 -215.575994) (xy 21.571397 -215.523903) (xy 21.559271 -215.469466) (xy 21.5552 -215.413844)
			(xy 17.908193 -215.413844) (xy 17.895257 -215.456841) (xy 17.871585 -215.507338) (xy 17.840812 -215.553851)
			(xy 17.803595 -215.595388) (xy 17.760727 -215.631063) (xy 17.713121 -215.660117) (xy 17.661792 -215.681929)
			(xy 17.607835 -215.696035) (xy 17.552398 -215.702135) (xy 17.496664 -215.700098) (xy 17.441821 -215.689968)
			(xy 17.389037 -215.671961) (xy 17.339437 -215.64646) (xy 17.294079 -215.614009) (xy 17.25393 -215.5753)
			(xy 17.219844 -215.531157) (xy 17.192548 -215.482522) (xy 17.172625 -215.430431) (xy 17.160499 -215.375994)
			(xy 17.156428 -215.320372) (xy 5.720842 -215.320372) (xy 5.720842 -216.082372) (xy 16.267428 -216.082372)
			(xy 16.271499 -216.02675) (xy 16.283625 -215.972313) (xy 16.303548 -215.920222) (xy 16.330844 -215.871587)
			(xy 16.36493 -215.827444) (xy 16.405079 -215.788735) (xy 16.450437 -215.756284) (xy 16.500037 -215.730783)
			(xy 16.552821 -215.712776) (xy 16.607664 -215.702646) (xy 16.663398 -215.700609) (xy 16.718835 -215.706709)
			(xy 16.772792 -215.720815) (xy 16.824121 -215.742627) (xy 16.871727 -215.771681) (xy 16.914595 -215.807356)
			(xy 16.951812 -215.848893) (xy 16.982585 -215.895406) (xy 17.006257 -215.945903) (xy 17.022325 -215.99931)
			(xy 17.030445 -216.054486) (xy 17.030954 -216.082372) (xy 17.030445 -216.110258) (xy 17.022325 -216.165434)
			(xy 17.006257 -216.218841) (xy 16.982585 -216.269338) (xy 16.951812 -216.315851) (xy 16.914595 -216.357388)
			(xy 16.871727 -216.393063) (xy 16.824121 -216.422117) (xy 16.772792 -216.443929) (xy 16.718835 -216.458035)
			(xy 16.663398 -216.464135) (xy 16.607664 -216.462098) (xy 16.552821 -216.451968) (xy 16.500037 -216.433961)
			(xy 16.450437 -216.40846) (xy 16.405079 -216.376009) (xy 16.36493 -216.3373) (xy 16.330844 -216.293157)
			(xy 16.303548 -216.244522) (xy 16.283625 -216.192431) (xy 16.271499 -216.137994) (xy 16.267428 -216.082372)
			(xy 5.720842 -216.082372) (xy 5.720842 -217.81516) (xy 30.71622 -217.81516) (xy 30.716641 -217.787906)
			(xy 30.724403 -217.733955) (xy 30.739765 -217.681657) (xy 30.762413 -217.632078) (xy 30.791886 -217.586227)
			(xy 30.827584 -217.545036) (xy 30.868781 -217.509345) (xy 30.914638 -217.47988) (xy 30.964221 -217.457241)
			(xy 31.016522 -217.441889) (xy 31.070474 -217.434136) (xy 31.097728 -217.433652) (xy 31.125673 -217.434113)
			(xy 31.180965 -217.442279) (xy 31.234476 -217.458416) (xy 31.285063 -217.482181) (xy 31.331646 -217.513066)
			(xy 31.373229 -217.55041) (xy 31.408925 -217.593418) (xy 31.423864 -217.61704) (xy 31.428709 -217.624326)
			(xy 31.442307 -217.63532) (xy 31.458807 -217.64111) (xy 31.467552 -217.641424) (xy 31.554928 -217.640916)
			(xy 31.563671 -217.640477) (xy 31.580114 -217.634513) (xy 31.593587 -217.623359) (xy 31.598362 -217.616024)
			(xy 31.598362 -217.61577) (xy 31.613144 -217.591569) (xy 31.648752 -217.547435) (xy 31.690503 -217.509062)
			(xy 31.737477 -217.477295) (xy 31.788638 -217.452835) (xy 31.842857 -217.436222) (xy 31.898938 -217.427822)
			(xy 31.927292 -217.427302) (xy 31.954546 -217.427744) (xy 32.008499 -217.435501) (xy 32.060799 -217.450856)
			(xy 32.110382 -217.473499) (xy 32.156237 -217.502968) (xy 32.197432 -217.538662) (xy 32.233128 -217.579856)
			(xy 32.262597 -217.625711) (xy 32.285241 -217.675293) (xy 32.300598 -217.727593) (xy 32.308355 -217.781546)
			(xy 32.308355 -217.808556) (xy 32.553146 -217.808556) (xy 32.557217 -217.752934) (xy 32.569343 -217.698497)
			(xy 32.589266 -217.646406) (xy 32.616562 -217.597771) (xy 32.650648 -217.553628) (xy 32.690797 -217.514919)
			(xy 32.736155 -217.482468) (xy 32.785755 -217.456967) (xy 32.838539 -217.43896) (xy 32.893382 -217.42883)
			(xy 32.949116 -217.426793) (xy 33.004553 -217.432893) (xy 33.05851 -217.446999) (xy 33.109839 -217.468811)
			(xy 33.157445 -217.497865) (xy 33.200313 -217.53354) (xy 33.23753 -217.575077) (xy 33.268303 -217.62159)
			(xy 33.291975 -217.672087) (xy 33.308043 -217.725494) (xy 33.31238 -217.754962) (xy 33.507678 -217.754962)
			(xy 33.511749 -217.69934) (xy 33.523875 -217.644903) (xy 33.543798 -217.592812) (xy 33.571094 -217.544177)
			(xy 33.60518 -217.500034) (xy 33.645329 -217.461325) (xy 33.690687 -217.428874) (xy 33.740287 -217.403373)
			(xy 33.793071 -217.385366) (xy 33.847914 -217.375236) (xy 33.903648 -217.373199) (xy 33.959085 -217.379299)
			(xy 34.013042 -217.393405) (xy 34.064371 -217.415217) (xy 34.111977 -217.444271) (xy 34.154845 -217.479946)
			(xy 34.192062 -217.521483) (xy 34.222835 -217.567996) (xy 34.246507 -217.618493) (xy 34.262575 -217.6719)
			(xy 34.270695 -217.727076) (xy 34.27093 -217.739976) (xy 34.38093 -217.739976) (xy 34.385001 -217.684354)
			(xy 34.397127 -217.629917) (xy 34.41705 -217.577826) (xy 34.444346 -217.529191) (xy 34.478432 -217.485048)
			(xy 34.518581 -217.446339) (xy 34.563939 -217.413888) (xy 34.613539 -217.388387) (xy 34.666323 -217.37038)
			(xy 34.721166 -217.36025) (xy 34.7769 -217.358213) (xy 34.832337 -217.364313) (xy 34.886294 -217.378419)
			(xy 34.937623 -217.400231) (xy 34.985229 -217.429285) (xy 35.028097 -217.46496) (xy 35.065314 -217.506497)
			(xy 35.096087 -217.55301) (xy 35.119759 -217.603507) (xy 35.135827 -217.656914) (xy 35.143947 -217.71209)
			(xy 35.144456 -217.739976) (xy 35.143947 -217.767862) (xy 35.135827 -217.823038) (xy 35.119759 -217.876445)
			(xy 35.096087 -217.926942) (xy 35.065314 -217.973455) (xy 35.028097 -218.014992) (xy 34.985229 -218.050667)
			(xy 34.937623 -218.079721) (xy 34.886294 -218.101533) (xy 34.832337 -218.115639) (xy 34.7769 -218.121739)
			(xy 34.721166 -218.119702) (xy 34.666323 -218.109572) (xy 34.613539 -218.091565) (xy 34.563939 -218.066064)
			(xy 34.518581 -218.033613) (xy 34.478432 -217.994904) (xy 34.444346 -217.950761) (xy 34.41705 -217.902126)
			(xy 34.397127 -217.850035) (xy 34.385001 -217.795598) (xy 34.38093 -217.739976) (xy 34.27093 -217.739976)
			(xy 34.271204 -217.754962) (xy 34.270695 -217.782848) (xy 34.262575 -217.838024) (xy 34.246507 -217.891431)
			(xy 34.222835 -217.941928) (xy 34.192062 -217.988441) (xy 34.154845 -218.029978) (xy 34.111977 -218.065653)
			(xy 34.064371 -218.094707) (xy 34.013042 -218.116519) (xy 33.959085 -218.130625) (xy 33.903648 -218.136725)
			(xy 33.847914 -218.134688) (xy 33.793071 -218.124558) (xy 33.740287 -218.106551) (xy 33.690687 -218.08105)
			(xy 33.645329 -218.048599) (xy 33.60518 -218.00989) (xy 33.571094 -217.965747) (xy 33.543798 -217.917112)
			(xy 33.523875 -217.865021) (xy 33.511749 -217.810584) (xy 33.507678 -217.754962) (xy 33.31238 -217.754962)
			(xy 33.316163 -217.78067) (xy 33.316672 -217.808556) (xy 33.316163 -217.836442) (xy 33.308043 -217.891618)
			(xy 33.291975 -217.945025) (xy 33.268303 -217.995522) (xy 33.23753 -218.042035) (xy 33.200313 -218.083572)
			(xy 33.157445 -218.119247) (xy 33.109839 -218.148301) (xy 33.05851 -218.170113) (xy 33.004553 -218.184219)
			(xy 32.949116 -218.190319) (xy 32.893382 -218.188282) (xy 32.838539 -218.178152) (xy 32.785755 -218.160145)
			(xy 32.736155 -218.134644) (xy 32.690797 -218.102193) (xy 32.650648 -218.063484) (xy 32.616562 -218.019341)
			(xy 32.589266 -217.970706) (xy 32.569343 -217.918615) (xy 32.557217 -217.864178) (xy 32.553146 -217.808556)
			(xy 32.308355 -217.808556) (xy 32.308355 -217.836054) (xy 32.300598 -217.890007) (xy 32.285241 -217.942307)
			(xy 32.262597 -217.991889) (xy 32.233128 -218.037744) (xy 32.197432 -218.078938) (xy 32.156237 -218.114632)
			(xy 32.110382 -218.144101) (xy 32.060799 -218.166744) (xy 32.008499 -218.182099) (xy 31.954546 -218.189856)
			(xy 31.927292 -218.190318) (xy 31.899346 -218.189855) (xy 31.844054 -218.181692) (xy 31.790543 -218.165556)
			(xy 31.739955 -218.141792) (xy 31.693372 -218.110907) (xy 31.651789 -218.073561) (xy 31.616094 -218.030553)
			(xy 31.601156 -218.00693) (xy 31.596308 -217.999647) (xy 31.58271 -217.988655) (xy 31.566212 -217.982863)
			(xy 31.557468 -217.982546) (xy 31.470092 -217.983054) (xy 31.461345 -217.983451) (xy 31.444903 -217.989437)
			(xy 31.431432 -218.000605) (xy 31.426658 -218.007946) (xy 31.426658 -218.0082) (xy 31.410572 -218.034504)
			(xy 31.371249 -218.08199) (xy 31.32478 -218.12251) (xy 31.298896 -218.139264) (xy 31.291714 -218.144076)
			(xy 31.280856 -218.157514) (xy 31.275105 -218.173805) (xy 31.274766 -218.182444) (xy 31.27502 -218.282266)
			(xy 31.28772 -218.305126) (xy 31.29915 -218.311984) (xy 31.322518 -218.327) (xy 31.365081 -218.362688)
			(xy 31.402018 -218.404171) (xy 31.432549 -218.450571) (xy 31.456029 -218.500909) (xy 31.471961 -218.554119)
			(xy 31.480009 -218.609078) (xy 31.480506 -218.63685) (xy 31.48002 -218.664101) (xy 31.472264 -218.718049)
			(xy 31.456909 -218.770344) (xy 31.434267 -218.819921) (xy 31.404801 -218.865771) (xy 31.36911 -218.906962)
			(xy 31.327919 -218.942653) (xy 31.282069 -218.972119) (xy 31.232492 -218.994761) (xy 31.180197 -219.010116)
			(xy 31.126249 -219.017872) (xy 31.071747 -219.017872) (xy 31.017799 -219.010116) (xy 30.965504 -218.994761)
			(xy 30.915927 -218.972119) (xy 30.870077 -218.942653) (xy 30.828886 -218.906962) (xy 30.793195 -218.865771)
			(xy 30.763729 -218.819921) (xy 30.741087 -218.770344) (xy 30.725732 -218.718049) (xy 30.717976 -218.664101)
			(xy 30.71749 -218.63685) (xy 30.717963 -218.609171) (xy 30.725982 -218.554398) (xy 30.741831 -218.501358)
			(xy 30.765176 -218.451164) (xy 30.795529 -218.404869) (xy 30.832251 -218.363446) (xy 30.874573 -218.327762)
			(xy 30.89783 -218.312746) (xy 30.905013 -218.307936) (xy 30.915869 -218.294496) (xy 30.921621 -218.278205)
			(xy 30.92196 -218.269566) (xy 30.921706 -218.169744) (xy 30.909006 -218.146884) (xy 30.897576 -218.140026)
			(xy 30.874195 -218.125029) (xy 30.831636 -218.089335) (xy 30.794702 -218.047848) (xy 30.764174 -218.001444)
			(xy 30.740696 -217.951104) (xy 30.724765 -217.897892) (xy 30.716717 -217.842933) (xy 30.71622 -217.81516)
			(xy 5.720842 -217.81516) (xy 5.720842 -218.29141) (xy 17.041874 -218.29141) (xy 17.045945 -218.235788)
			(xy 17.058071 -218.181351) (xy 17.077994 -218.12926) (xy 17.10529 -218.080625) (xy 17.139376 -218.036482)
			(xy 17.179525 -217.997773) (xy 17.224883 -217.965322) (xy 17.274483 -217.939821) (xy 17.327267 -217.921814)
			(xy 17.38211 -217.911684) (xy 17.437844 -217.909647) (xy 17.493281 -217.915747) (xy 17.547238 -217.929853)
			(xy 17.598567 -217.951665) (xy 17.646173 -217.980719) (xy 17.689041 -218.016394) (xy 17.726258 -218.057931)
			(xy 17.757031 -218.104444) (xy 17.780703 -218.154941) (xy 17.796771 -218.208348) (xy 17.804891 -218.263524)
			(xy 17.8054 -218.29141) (xy 17.804891 -218.319296) (xy 17.796771 -218.374472) (xy 17.780703 -218.427879)
			(xy 17.757031 -218.478376) (xy 17.726258 -218.524889) (xy 17.689041 -218.566426) (xy 17.646173 -218.602101)
			(xy 17.598567 -218.631155) (xy 17.547238 -218.652967) (xy 17.493281 -218.667073) (xy 17.437844 -218.673173)
			(xy 17.38211 -218.671136) (xy 17.327267 -218.661006) (xy 17.274483 -218.642999) (xy 17.224883 -218.617498)
			(xy 17.179525 -218.585047) (xy 17.139376 -218.546338) (xy 17.10529 -218.502195) (xy 17.077994 -218.45356)
			(xy 17.058071 -218.401469) (xy 17.045945 -218.347032) (xy 17.041874 -218.29141) (xy 5.720842 -218.29141)
			(xy 5.720842 -229.94493) (xy 12.84554 -229.94493) (xy 12.849611 -229.889308) (xy 12.861737 -229.834871)
			(xy 12.88166 -229.78278) (xy 12.908956 -229.734145) (xy 12.943042 -229.690002) (xy 12.983191 -229.651293)
			(xy 13.028549 -229.618842) (xy 13.078149 -229.593341) (xy 13.130933 -229.575334) (xy 13.185776 -229.565204)
			(xy 13.24151 -229.563167) (xy 13.296947 -229.569267) (xy 13.350904 -229.583373) (xy 13.402233 -229.605185)
			(xy 13.449839 -229.634239) (xy 13.492707 -229.669914) (xy 13.529924 -229.711451) (xy 13.560697 -229.757964)
			(xy 13.584369 -229.808461) (xy 13.600437 -229.861868) (xy 13.608557 -229.917044) (xy 13.609066 -229.94493)
			(xy 13.608557 -229.972816) (xy 13.600437 -230.027992) (xy 13.584369 -230.081399) (xy 13.560697 -230.131896)
			(xy 13.529924 -230.178409) (xy 13.492707 -230.219946) (xy 13.449839 -230.255621) (xy 13.402233 -230.284675)
			(xy 13.350904 -230.306487) (xy 13.296947 -230.320593) (xy 13.24151 -230.326693) (xy 13.185776 -230.324656)
			(xy 13.130933 -230.314526) (xy 13.078149 -230.296519) (xy 13.028549 -230.271018) (xy 12.983191 -230.238567)
			(xy 12.943042 -230.199858) (xy 12.908956 -230.155715) (xy 12.88166 -230.10708) (xy 12.861737 -230.054989)
			(xy 12.849611 -230.000552) (xy 12.84554 -229.94493) (xy 5.720842 -229.94493) (xy 5.720842 -232.77322)
			(xy 11.918948 -232.77322) (xy 11.923019 -232.717598) (xy 11.935145 -232.663161) (xy 11.955068 -232.61107)
			(xy 11.982364 -232.562435) (xy 12.01645 -232.518292) (xy 12.056599 -232.479583) (xy 12.101957 -232.447132)
			(xy 12.151557 -232.421631) (xy 12.204341 -232.403624) (xy 12.259184 -232.393494) (xy 12.314918 -232.391457)
			(xy 12.370355 -232.397557) (xy 12.424312 -232.411663) (xy 12.475641 -232.433475) (xy 12.523247 -232.462529)
			(xy 12.566115 -232.498204) (xy 12.603332 -232.539741) (xy 12.634105 -232.586254) (xy 12.657777 -232.636751)
			(xy 12.673845 -232.690158) (xy 12.681965 -232.745334) (xy 12.682474 -232.77322) (xy 12.681965 -232.801106)
			(xy 12.673845 -232.856282) (xy 12.657777 -232.909689) (xy 12.634105 -232.960186) (xy 12.603332 -233.006699)
			(xy 12.566115 -233.048236) (xy 12.523247 -233.083911) (xy 12.475641 -233.112965) (xy 12.424312 -233.134777)
			(xy 12.370355 -233.148883) (xy 12.314918 -233.154983) (xy 12.259184 -233.152946) (xy 12.204341 -233.142816)
			(xy 12.151557 -233.124809) (xy 12.101957 -233.099308) (xy 12.056599 -233.066857) (xy 12.01645 -233.028148)
			(xy 11.982364 -232.984005) (xy 11.955068 -232.93537) (xy 11.935145 -232.883279) (xy 11.923019 -232.828842)
			(xy 11.918948 -232.77322) (xy 5.720842 -232.77322) (xy 5.720842 -233.590846) (xy 11.623038 -233.590846)
			(xy 11.627109 -233.535224) (xy 11.639235 -233.480787) (xy 11.659158 -233.428696) (xy 11.686454 -233.380061)
			(xy 11.72054 -233.335918) (xy 11.760689 -233.297209) (xy 11.806047 -233.264758) (xy 11.855647 -233.239257)
			(xy 11.908431 -233.22125) (xy 11.963274 -233.21112) (xy 12.019008 -233.209083) (xy 12.074445 -233.215183)
			(xy 12.128402 -233.229289) (xy 12.179731 -233.251101) (xy 12.227337 -233.280155) (xy 12.270205 -233.31583)
			(xy 12.307422 -233.357367) (xy 12.338195 -233.40388) (xy 12.361867 -233.454377) (xy 12.377935 -233.507784)
			(xy 12.386055 -233.56296) (xy 12.386564 -233.590846) (xy 12.386055 -233.618732) (xy 12.377935 -233.673908)
			(xy 12.361867 -233.727315) (xy 12.338195 -233.777812) (xy 12.307422 -233.824325) (xy 12.270205 -233.865862)
			(xy 12.227337 -233.901537) (xy 12.179731 -233.930591) (xy 12.128402 -233.952403) (xy 12.074445 -233.966509)
			(xy 12.019008 -233.972609) (xy 11.963274 -233.970572) (xy 11.908431 -233.960442) (xy 11.855647 -233.942435)
			(xy 11.806047 -233.916934) (xy 11.760689 -233.884483) (xy 11.72054 -233.845774) (xy 11.686454 -233.801631)
			(xy 11.659158 -233.752996) (xy 11.639235 -233.700905) (xy 11.627109 -233.646468) (xy 11.623038 -233.590846)
			(xy 5.720842 -233.590846) (xy 5.720842 -251.156216) (xy 5.721604 -251.164344) (xy 5.721604 -251.164852)
			(xy 5.723208 -251.172369) (xy 5.730188 -251.186053) (xy 5.73532 -251.191776) (xy 7.104634 -252.56109)
			(xy 7.110313 -252.566282) (xy 7.12402 -252.573258) (xy 7.131558 -252.574806) (xy 7.132066 -252.574806)
			(xy 7.140194 -252.575568) (xy 13.401548 -252.575568) (xy 13.409676 -252.574806) (xy 13.410184 -252.574806)
			(xy 13.417706 -252.573211) (xy 13.431404 -252.566245) (xy 13.437108 -252.56109) (xy 15.142718 -250.85548)
			(xy 15.14791 -250.849801) (xy 15.154886 -250.836094) (xy 15.156434 -250.828556) (xy 15.156434 -250.828048)
			(xy 15.157196 -250.81992) (xy 15.157196 -231.615488) (xy 15.156022 -231.603757) (xy 15.144511 -231.583215)
			(xy 15.135098 -231.576118) (xy 15.132015 -231.57411) (xy 15.125385 -231.570918) (xy 15.12189 -231.569768)
			(xy 15.110206 -231.565958) (xy 15.083403 -231.556519) (xy 15.032717 -231.530833) (xy 14.986401 -231.497914)
			(xy 14.945479 -231.458489) (xy 14.910857 -231.413432) (xy 14.8833 -231.363739) (xy 14.863417 -231.310508)
			(xy 14.851649 -231.254917) (xy 14.848255 -231.198195) (xy 14.853311 -231.141597) (xy 14.866705 -231.086375)
			(xy 14.888141 -231.033751) (xy 14.917144 -230.984887) (xy 14.953073 -230.940865) (xy 14.995134 -230.902658)
			(xy 15.042396 -230.871112) (xy 15.093814 -230.846923) (xy 15.120874 -230.838248) (xy 15.124938 -230.836978)
			(xy 15.131492 -230.834166) (xy 15.142836 -230.825531) (xy 15.14729 -230.81996) (xy 15.152116 -230.81361)
			(xy 15.154656 -230.805736) (xy 15.155819 -230.801902) (xy 15.1571 -230.793993) (xy 15.157196 -230.789988)
			(xy 15.157196 -221.967806) (xy 15.157618 -221.957735) (xy 15.16533 -221.939129) (xy 15.172182 -221.931738)
			(xy 15.948406 -221.155514) (xy 15.955541 -221.147549) (xy 15.963171 -221.127598) (xy 15.963138 -221.116906)
			(xy 15.962884 -221.109032) (xy 15.960598 -221.102936) (xy 15.954502 -221.091252) (xy 15.951708 -221.087696)
			(xy 15.9356 -221.067194) (xy 15.908507 -221.022647) (xy 15.887729 -220.974827) (xy 15.873654 -220.924625)
			(xy 15.866543 -220.872973) (xy 15.86611 -220.846904) (xy 15.86611 -220.84665) (xy 15.8666 -220.819365)
			(xy 15.874373 -220.765353) (xy 15.889753 -220.712996) (xy 15.912427 -220.663361) (xy 15.941935 -220.617457)
			(xy 15.977674 -220.57622) (xy 16.018918 -220.540489) (xy 16.064827 -220.510991) (xy 16.114467 -220.488326)
			(xy 16.166827 -220.472957) (xy 16.220841 -220.465195) (xy 16.248126 -220.464634) (xy 16.24838 -220.464634)
			(xy 16.273383 -220.46502) (xy 16.32296 -220.471545) (xy 16.371259 -220.484498) (xy 16.417448 -220.503657)
			(xy 16.460734 -220.528693) (xy 16.48079 -220.543628) (xy 16.482314 -220.544898) (xy 16.484092 -220.546168)
			(xy 16.485616 -220.54693) (xy 16.492728 -220.550994) (xy 16.499586 -220.554042) (xy 16.50873 -220.557598)
			(xy 16.516447 -220.559576) (xy 16.532363 -220.559195) (xy 16.539972 -220.556836) (xy 16.542766 -220.55582)
			(xy 16.546108 -220.554318) (xy 16.552359 -220.550498) (xy 16.555212 -220.5482) (xy 16.55953 -220.54439)
			(xy 16.771112 -220.332808) (xy 16.778511 -220.325963) (xy 16.797109 -220.318231) (xy 16.80718 -220.317822)
			(xy 26.007568 -220.317822) (xy 26.011978 -220.317732) (xy 26.020664 -220.316195) (xy 26.02484 -220.314774)
			(xy 26.033222 -220.311726) (xy 26.04008 -220.306138) (xy 26.049732 -220.29801) (xy 26.053288 -220.293438)
			(xy 26.069845 -220.272382) (xy 26.107884 -220.234672) (xy 26.150821 -220.202649) (xy 26.197813 -220.176943)
			(xy 26.247937 -220.158059) (xy 26.300209 -220.146367) (xy 26.353602 -220.142097) (xy 26.407068 -220.145333)
			(xy 26.459556 -220.156011) (xy 26.510036 -220.173922) (xy 26.557517 -220.198714) (xy 26.601066 -220.2299)
			(xy 26.639827 -220.266868) (xy 26.656792 -220.287596) (xy 26.658824 -220.290136) (xy 26.659078 -220.29039)
			(xy 26.660856 -220.292676) (xy 26.66111 -220.29293) (xy 26.664412 -220.297248) (xy 26.677112 -220.307916)
			(xy 26.680118 -220.310038) (xy 26.686621 -220.31348) (xy 26.690066 -220.314774) (xy 26.690574 -220.314774)
			(xy 26.694631 -220.31615) (xy 26.703057 -220.317691) (xy 26.707338 -220.317822) (xy 34.479484 -220.317822)
			(xy 34.487612 -220.31706) (xy 34.48812 -220.31706) (xy 34.495638 -220.315459) (xy 34.509325 -220.308481)
			(xy 34.515044 -220.303344) (xy 36.489386 -218.329002) (xy 36.497564 -218.319704) (xy 36.504861 -218.296082)
			(xy 36.503356 -218.28379) (xy 36.503356 -218.283536) (xy 27.99715 -173.366684) (xy 22.70633 -145.429478)
			(xy 22.697186 -145.372074) (xy 22.612096 -144.713452) (xy 20.2692 -126.900686) (xy 20.266673 -126.891998)
			(xy 20.256498 -126.877051) (xy 20.241764 -126.866569) (xy 20.233132 -126.863856) (xy 20.22983 -126.863094)
			(xy 20.19427 -126.854204) (xy 20.185126 -126.853188) (xy 20.184872 -126.853188) (xy 20.182078 -126.853442)
			(xy 20.177252 -126.853696) (xy 20.175474 -126.853696) (xy 20.171393 -126.854269) (xy 20.163481 -126.856569)
			(xy 20.159726 -126.858268) (xy 20.132294 -126.872238) (xy 20.126452 -126.881128) (xy 20.125944 -126.881636)
			(xy 20.123658 -126.88443) (xy 20.102655 -126.910655) (xy 20.053092 -126.956009) (xy 20.025106 -126.9746)
			(xy 20.001923 -126.98885) (xy 19.952353 -127.011303) (xy 19.900091 -127.026472) (xy 19.873214 -127.030734)
			(xy 19.862028 -127.032209) (xy 19.839534 -127.033987) (xy 19.828256 -127.03429) (xy 19.820382 -127.03429)
			(xy 19.793349 -127.033819) (xy 19.739823 -127.026184) (xy 19.687912 -127.011071) (xy 19.638653 -126.988782)
			(xy 19.593034 -126.959763) (xy 19.551967 -126.924595) (xy 19.516276 -126.883983) (xy 19.486675 -126.838739)
			(xy 19.463756 -126.78977) (xy 19.447979 -126.738057) (xy 19.439659 -126.684634) (xy 19.438874 -126.657608)
			(xy 19.438874 -126.652782) (xy 19.43989 -126.623318) (xy 19.440652 -126.612396) (xy 19.436842 -126.601982)
			(xy 19.434837 -126.596884) (xy 19.428949 -126.587648) (xy 19.425158 -126.583694) (xy 19.422872 -126.581408)
			(xy 19.421856 -126.562358) (xy 19.421785 -126.553188) (xy 19.427391 -126.535744) (xy 19.432778 -126.528322)
			(xy 19.51736 -126.42088) (xy 19.517614 -126.420372) (xy 19.517868 -126.420118) (xy 19.519392 -126.41834)
			(xy 19.520662 -126.416562) (xy 19.520916 -126.416308) (xy 19.521932 -126.415038) (xy 19.52244 -126.414276)
			(xy 19.525742 -126.409704) (xy 19.529298 -126.40183) (xy 19.530924 -126.397366) (xy 19.532713 -126.388037)
			(xy 19.532854 -126.383288) (xy 19.532854 -126.361952) (xy 19.532999 -126.356513) (xy 19.535312 -126.345884)
			(xy 19.537426 -126.34087) (xy 19.543522 -126.327408) (xy 19.547143 -126.318746) (xy 19.548374 -126.300026)
			(xy 19.542745 -126.28213) (xy 19.537172 -126.274576) (xy 19.531584 -126.267464) (xy 19.528028 -126.262892)
			(xy 19.52752 -126.26213) (xy 19.527012 -126.261622) (xy 19.52625 -126.260606) (xy 19.510061 -126.240343)
			(xy 19.482734 -126.196261) (xy 19.461638 -126.148881) (xy 19.44716 -126.099078) (xy 19.439569 -126.047772)
			(xy 19.438874 -126.021846) (xy 19.438874 -126.018798) (xy 19.43921 -125.993414) (xy 19.445778 -125.943076)
			(xy 19.458956 -125.894051) (xy 19.468338 -125.870462) (xy 19.478876 -125.846316) (xy 19.505637 -125.800936)
			(xy 19.521678 -125.780038) (xy 19.525488 -125.775212) (xy 19.528028 -125.769878) (xy 19.530271 -125.764764)
			(xy 19.532714 -125.75387) (xy 19.532854 -125.748288) (xy 19.532854 -125.726952) (xy 19.532999 -125.721513)
			(xy 19.535312 -125.710884) (xy 19.537426 -125.70587) (xy 19.543522 -125.692408) (xy 19.547143 -125.683746)
			(xy 19.548374 -125.665026) (xy 19.542745 -125.64713) (xy 19.537172 -125.639576) (xy 19.531584 -125.632464)
			(xy 19.528028 -125.627892) (xy 19.52752 -125.62713) (xy 19.527012 -125.626622) (xy 19.52625 -125.625606)
			(xy 19.510061 -125.605343) (xy 19.482734 -125.561261) (xy 19.461638 -125.513881) (xy 19.44716 -125.464078)
			(xy 19.439569 -125.412772) (xy 19.438874 -125.386846) (xy 19.438874 -125.383798) (xy 19.43921 -125.358414)
			(xy 19.445778 -125.308076) (xy 19.458956 -125.259051) (xy 19.468338 -125.235462) (xy 19.478876 -125.211316)
			(xy 19.505637 -125.165936) (xy 19.521678 -125.145038) (xy 19.525488 -125.140212) (xy 19.528028 -125.134878)
			(xy 19.530271 -125.129764) (xy 19.532714 -125.11887) (xy 19.532854 -125.113288) (xy 19.532854 -125.091952)
			(xy 19.532999 -125.086513) (xy 19.535312 -125.075884) (xy 19.537426 -125.07087) (xy 19.543522 -125.057408)
			(xy 19.547143 -125.048746) (xy 19.548374 -125.030026) (xy 19.542745 -125.01213) (xy 19.537172 -125.004576)
			(xy 19.531584 -124.997464) (xy 19.528028 -124.992892) (xy 19.52752 -124.99213) (xy 19.525996 -124.990352)
			(xy 19.507101 -124.966485) (xy 19.47634 -124.91396) (xy 19.454299 -124.857221) (xy 19.441536 -124.797704)
			(xy 19.439382 -124.76734) (xy 19.438874 -124.748798) (xy 19.438874 -124.747782) (xy 19.439361 -124.720531)
			(xy 19.447119 -124.666584) (xy 19.462476 -124.614291) (xy 19.485118 -124.564715) (xy 19.514584 -124.518865)
			(xy 19.550276 -124.477676) (xy 19.591465 -124.441984) (xy 19.637315 -124.412518) (xy 19.686891 -124.389876)
			(xy 19.739184 -124.374519) (xy 19.793131 -124.366761) (xy 19.820382 -124.366274) (xy 19.830179 -124.366343)
			(xy 19.849747 -124.367358) (xy 19.859498 -124.368306) (xy 19.862292 -124.36856) (xy 19.86661 -124.36856)
			(xy 19.876768 -124.368116) (xy 19.895502 -124.36026) (xy 19.902932 -124.35332) (xy 19.921728 -124.334016)
			(xy 19.926046 -124.329444) (xy 19.930618 -124.324872) (xy 19.788886 -123.248674) (xy 19.787584 -123.24081)
			(xy 19.780728 -123.226429) (xy 19.775424 -123.22048) (xy 19.770344 -123.214892) (xy 19.756374 -123.207272)
			(xy 19.748246 -123.205748) (xy 19.722013 -123.200235) (xy 19.671312 -123.182834) (xy 19.623544 -123.158509)
			(xy 19.579651 -123.127739) (xy 19.540495 -123.09113) (xy 19.506847 -123.049402) (xy 19.47937 -123.003375)
			(xy 19.458604 -122.953956) (xy 19.444958 -122.902118) (xy 19.441414 -122.875548) (xy 19.440398 -122.86615)
			(xy 19.439128 -122.846592) (xy 19.438874 -122.830844) (xy 19.438874 -122.830336) (xy 19.438874 -122.830082)
			(xy 19.43989 -122.80138) (xy 19.440652 -122.790458) (xy 19.436842 -122.780044) (xy 19.434834 -122.774948)
			(xy 19.428941 -122.765717) (xy 19.425158 -122.761756) (xy 19.422872 -122.75947) (xy 19.421856 -122.74042)
			(xy 19.421774 -122.731246) (xy 19.427363 -122.713788) (xy 19.432778 -122.706384) (xy 19.51736 -122.598942)
			(xy 19.517614 -122.598434) (xy 19.517868 -122.59818) (xy 19.519392 -122.596402) (xy 19.520662 -122.594624)
			(xy 19.520916 -122.59437) (xy 19.521932 -122.5931) (xy 19.52244 -122.592338) (xy 19.525742 -122.587766)
			(xy 19.529298 -122.579892) (xy 19.530921 -122.575428) (xy 19.532703 -122.566098) (xy 19.532854 -122.56135)
			(xy 19.532854 -122.539252) (xy 19.532972 -122.534156) (xy 19.535028 -122.524174) (xy 19.536918 -122.51944)
			(xy 19.543776 -122.503692) (xy 19.54403 -122.50293) (xy 19.54657 -122.497342) (xy 19.547586 -122.489722)
			(xy 19.547586 -122.477022) (xy 19.546316 -122.467878) (xy 19.54022 -122.455178) (xy 19.534886 -122.449082)
			(xy 19.533362 -122.447304) (xy 19.532092 -122.44578) (xy 19.530568 -122.444256) (xy 19.528282 -122.441462)
			(xy 19.521932 -122.433588) (xy 19.517614 -122.428) (xy 19.513804 -122.42292) (xy 19.496174 -122.398123)
			(xy 19.468183 -122.344107) (xy 19.449121 -122.286332) (xy 19.439472 -122.226263) (xy 19.438874 -122.195844)
			(xy 19.438874 -122.19305) (xy 19.438874 -122.185938) (xy 19.43989 -122.166634) (xy 19.440144 -122.163586)
			(xy 19.441114 -122.153235) (xy 19.444035 -122.132649) (xy 19.445986 -122.122438) (xy 19.452763 -122.091155)
			(xy 19.475365 -122.031274) (xy 19.490944 -122.003312) (xy 19.49958 -121.989342) (xy 19.49958 -121.988834)
			(xy 19.518884 -121.96191) (xy 19.519646 -121.961148) (xy 19.525234 -121.952766) (xy 19.528696 -121.946711)
			(xy 19.53257 -121.933318) (xy 19.532854 -121.92635) (xy 19.532854 -121.905014) (xy 19.532993 -121.899574)
			(xy 19.535294 -121.888939) (xy 19.537426 -121.883932) (xy 19.543522 -121.87047) (xy 19.547135 -121.86181)
			(xy 19.548354 -121.843096) (xy 19.542717 -121.825211) (xy 19.537172 -121.817638) (xy 19.531584 -121.810526)
			(xy 19.528028 -121.805954) (xy 19.52752 -121.805192) (xy 19.527012 -121.804684) (xy 19.52625 -121.803668)
			(xy 19.510063 -121.783404) (xy 19.482741 -121.739322) (xy 19.461649 -121.691941) (xy 19.447176 -121.642139)
			(xy 19.43959 -121.590833) (xy 19.438874 -121.564908) (xy 19.438874 -121.56186) (xy 19.43917 -121.538116)
			(xy 19.444935 -121.490981) (xy 19.456509 -121.444926) (xy 19.464782 -121.422668) (xy 19.464782 -121.42216)
			(xy 19.468338 -121.413778) (xy 19.468338 -121.41327) (xy 19.471386 -121.406666) (xy 19.472402 -121.404634)
			(xy 19.47545 -121.397268) (xy 19.475958 -121.39676) (xy 19.485278 -121.37768) (xy 19.507556 -121.341528)
			(xy 19.520408 -121.324624) (xy 19.525488 -121.31802) (xy 19.528028 -121.31294) (xy 19.529605 -121.309421)
			(xy 19.531768 -121.302021) (xy 19.532346 -121.298208) (xy 19.519646 -121.201688) (xy 19.513296 -121.152412)
			(xy 19.507962 -121.144792) (xy 19.505422 -121.140982) (xy 19.50466 -121.139966) (xy 19.486301 -121.111541)
			(xy 19.45883 -121.049709) (xy 19.45005 -121.01703) (xy 19.445979 -120.999939) (xy 19.440639 -120.965212)
			(xy 19.439382 -120.947688) (xy 19.439382 -120.94718) (xy 19.438874 -120.92813) (xy 19.438874 -120.923812)
			(xy 19.438984 -120.912543) (xy 19.440381 -120.890049) (xy 19.441668 -120.878854) (xy 19.444539 -120.85818)
			(xy 19.454209 -120.817574) (xy 19.460972 -120.797828) (xy 19.463004 -120.791986) (xy 19.464274 -120.780556)
			(xy 19.417538 -120.425718) (xy 19.38655 -120.189244) (xy 19.384772 -120.181116) (xy 19.272504 -119.810784)
			(xy 19.198844 -119.567706) (xy 18.852896 -118.426738) (xy 18.849745 -118.41769) (xy 18.837861 -118.402679)
			(xy 18.829782 -118.397528) (xy 18.8214 -118.392956) (xy 18.80235 -118.390162) (xy 18.792698 -118.392448)
			(xy 18.775172 -118.396258) (xy 18.757068 -118.39959) (xy 18.720427 -118.403157) (xy 18.70202 -118.40337)
			(xy 18.701512 -118.40337) (xy 18.680117 -118.40304) (xy 18.6376 -118.398198) (xy 18.616676 -118.393718)
			(xy 18.611088 -118.392448) (xy 18.607532 -118.391686) (xy 18.607024 -118.391432) (xy 18.605754 -118.391178)
			(xy 18.605246 -118.391178) (xy 18.601436 -118.390162) (xy 18.58772 -118.385844) (xy 18.564335 -118.378119)
			(xy 18.519616 -118.35748) (xy 18.498566 -118.344696) (xy 18.489707 -118.339013) (xy 18.472552 -118.326814)
			(xy 18.464276 -118.320312) (xy 18.463768 -118.320058) (xy 18.461736 -118.31828) (xy 18.455953 -118.314503)
			(xy 18.44295 -118.309861) (xy 18.436082 -118.309136) (xy 18.41119 -118.309136) (xy 18.40575 -118.308994)
			(xy 18.395118 -118.306689) (xy 18.390108 -118.304564) (xy 18.376646 -118.298468) (xy 18.367983 -118.294841)
			(xy 18.349257 -118.293597) (xy 18.331349 -118.299216) (xy 18.323814 -118.304818) (xy 18.316702 -118.310406)
			(xy 18.31213 -118.313962) (xy 18.311368 -118.31447) (xy 18.290726 -118.331108) (xy 18.245712 -118.35912)
			(xy 18.197253 -118.380628) (xy 18.146282 -118.39522) (xy 18.093782 -118.402613) (xy 18.067274 -118.403116)
			(xy 18.06702 -118.403116) (xy 18.05305 -118.402862) (xy 18.049748 -118.402862) (xy 18.020917 -118.401032)
			(xy 17.964259 -118.389762) (xy 17.909948 -118.370077) (xy 17.859226 -118.342428) (xy 17.813253 -118.307447)
			(xy 17.773081 -118.265934) (xy 17.739628 -118.218838) (xy 17.713658 -118.167236) (xy 17.695767 -118.112308)
			(xy 17.686363 -118.05531) (xy 17.685512 -118.026434) (xy 17.685512 -118.021608) (xy 17.686528 -117.992144)
			(xy 17.68729 -117.981222) (xy 17.68348 -117.970808) (xy 17.681466 -117.965716) (xy 17.675564 -117.956495)
			(xy 17.671796 -117.95252) (xy 17.66951 -117.950234) (xy 17.668494 -117.931184) (xy 17.668419 -117.922013)
			(xy 17.674022 -117.904565) (xy 17.679416 -117.897148) (xy 17.763998 -117.789706) (xy 17.764252 -117.789198)
			(xy 17.764506 -117.788944) (xy 17.76603 -117.787166) (xy 17.7673 -117.785388) (xy 17.767554 -117.785134)
			(xy 17.76857 -117.783864) (xy 17.769078 -117.783102) (xy 17.77238 -117.77853) (xy 17.775936 -117.770656)
			(xy 17.777566 -117.766193) (xy 17.779362 -117.756863) (xy 17.779492 -117.752114) (xy 17.779492 -117.730778)
			(xy 17.779634 -117.725338) (xy 17.781939 -117.714706) (xy 17.784064 -117.709696) (xy 17.79016 -117.696234)
			(xy 17.793784 -117.687571) (xy 17.795023 -117.668847) (xy 17.789404 -117.650942) (xy 17.78381 -117.643402)
			(xy 17.778222 -117.63629) (xy 17.774666 -117.631718) (xy 17.774158 -117.630956) (xy 17.77365 -117.630448)
			(xy 17.772888 -117.629432) (xy 17.7567 -117.609168) (xy 17.729375 -117.565086) (xy 17.708278 -117.517706)
			(xy 17.6938 -117.467904) (xy 17.686206 -117.416598) (xy 17.685512 -117.390672) (xy 17.685512 -117.387624)
			(xy 17.685846 -117.36224) (xy 17.69241 -117.3119) (xy 17.705583 -117.262873) (xy 17.714976 -117.239288)
			(xy 17.725519 -117.215145) (xy 17.752289 -117.169772) (xy 17.768316 -117.148864) (xy 17.772126 -117.144038)
			(xy 17.774666 -117.138704) (xy 17.776901 -117.133589) (xy 17.779325 -117.122694) (xy 17.779492 -117.117114)
			(xy 17.779492 -117.095778) (xy 17.779634 -117.090338) (xy 17.781939 -117.079706) (xy 17.784064 -117.074696)
			(xy 17.79016 -117.061234) (xy 17.793784 -117.052571) (xy 17.795023 -117.033847) (xy 17.789404 -117.015942)
			(xy 17.78381 -117.008402) (xy 17.778222 -117.00129) (xy 17.774666 -116.996718) (xy 17.774158 -116.995956)
			(xy 17.772634 -116.994178) (xy 17.75374 -116.970311) (xy 17.72298 -116.917785) (xy 17.700939 -116.861046)
			(xy 17.688174 -116.80153) (xy 17.68602 -116.771166) (xy 17.685512 -116.752624) (xy 17.685512 -116.751608)
			(xy 17.685975 -116.724355) (xy 17.693731 -116.670405) (xy 17.709087 -116.618107) (xy 17.731729 -116.568527)
			(xy 17.761197 -116.522674) (xy 17.796891 -116.481482) (xy 17.838084 -116.44579) (xy 17.883938 -116.416323)
			(xy 17.933518 -116.393682) (xy 17.985816 -116.378328) (xy 18.039767 -116.370574) (xy 18.06702 -116.3701)
			(xy 18.075402 -116.3701) (xy 18.091404 -116.370862) (xy 18.093436 -116.370862) (xy 18.10004 -116.371116)
			(xy 18.110708 -116.36629) (xy 18.11635 -116.363642) (xy 18.126241 -116.356063) (xy 18.130266 -116.351304)
			(xy 18.181574 -116.285772) (xy 18.188113 -116.276538) (xy 18.193128 -116.254507) (xy 18.191226 -116.243354)
			(xy 17.518126 -114.022124) (xy 17.51522 -114.013788) (xy 17.504691 -113.999633) (xy 17.497552 -113.994438)
			(xy 17.490186 -113.989612) (xy 17.473422 -113.985548) (xy 17.464532 -113.98631) (xy 17.42948 -113.987834)
			(xy 17.429226 -113.987834) (xy 17.401973 -113.98735) (xy 17.348021 -113.979597) (xy 17.295722 -113.964244)
			(xy 17.246139 -113.941605) (xy 17.200284 -113.91214) (xy 17.159088 -113.876448) (xy 17.123392 -113.835258)
			(xy 17.09392 -113.789406) (xy 17.071274 -113.739827) (xy 17.055914 -113.68753) (xy 17.048154 -113.633579)
			(xy 17.047718 -113.606326) (xy 17.047718 -113.59896) (xy 17.047972 -113.585244) (xy 17.03451 -113.561114)
			(xy 16.933418 -113.502694) (xy 16.905732 -113.502948) (xy 16.893794 -113.51006) (xy 16.871442 -113.523014)
			(xy 16.82399 -113.543438) (xy 16.774215 -113.55727) (xy 16.723028 -113.564257) (xy 16.697198 -113.56467)
			(xy 16.669945 -113.564207) (xy 16.615994 -113.556449) (xy 16.563696 -113.541093) (xy 16.514116 -113.51845)
			(xy 16.468262 -113.488982) (xy 16.42707 -113.453288) (xy 16.391376 -113.412094) (xy 16.361908 -113.366241)
			(xy 16.339266 -113.31666) (xy 16.32391 -113.264362) (xy 16.316153 -113.210411) (xy 16.316153 -113.155905)
			(xy 16.323911 -113.101954) (xy 16.339267 -113.049656) (xy 16.36191 -113.000076) (xy 16.391378 -112.954222)
			(xy 16.427072 -112.91303) (xy 16.468266 -112.877336) (xy 16.514119 -112.847868) (xy 16.5637 -112.825226)
			(xy 16.615998 -112.80987) (xy 16.669949 -112.802113) (xy 16.724455 -112.802113) (xy 16.778406 -112.809871)
			(xy 16.830704 -112.825227) (xy 16.880284 -112.84787) (xy 16.926138 -112.877338) (xy 16.96733 -112.913032)
			(xy 17.003024 -112.954226) (xy 17.032492 -113.000079) (xy 17.055134 -113.04966) (xy 17.07049 -113.101958)
			(xy 17.078247 -113.155909) (xy 17.078706 -113.183162) (xy 17.078706 -113.190528) (xy 17.078452 -113.204244)
			(xy 17.091914 -113.228374) (xy 17.193006 -113.286794) (xy 17.220692 -113.28654) (xy 17.23263 -113.279428)
			(xy 17.247616 -113.270792) (xy 17.248378 -113.270538) (xy 17.255744 -113.266083) (xy 17.267187 -113.253236)
			(xy 17.27073 -113.245392) (xy 17.274032 -113.237772) (xy 17.274794 -113.220246) (xy 16.966184 -112.202214)
			(xy 16.76654 -111.5441) (xy 16.763803 -111.536191) (xy 16.754086 -111.522579) (xy 16.74749 -111.51743)
			(xy 16.740886 -111.512858) (xy 16.725138 -111.508032) (xy 16.716502 -111.508286) (xy 16.707612 -111.50854)
			(xy 16.702786 -111.50854) (xy 16.675535 -111.508053) (xy 16.621587 -111.500295) (xy 16.569292 -111.484939)
			(xy 16.519714 -111.462298) (xy 16.473863 -111.432832) (xy 16.432672 -111.397141) (xy 16.396979 -111.355951)
			(xy 16.367511 -111.310102) (xy 16.344867 -111.260525) (xy 16.329509 -111.208231) (xy 16.321748 -111.154283)
			(xy 16.321278 -111.127032) (xy 16.321737 -111.100113) (xy 16.329295 -111.046808) (xy 16.344267 -110.995094)
			(xy 16.366354 -110.945996) (xy 16.395119 -110.900487) (xy 16.429992 -110.859469) (xy 16.470281 -110.823758)
			(xy 16.492474 -110.808516) (xy 16.497554 -110.805214) (xy 16.505936 -110.796324) (xy 16.526764 -110.758986)
			(xy 16.525494 -110.74781) (xy 14.21384 -103.121714) (xy 14.213078 -103.119174) (xy 14.212824 -103.118412)
			(xy 14.211808 -103.115364) (xy 8.994902 -85.904578) (xy 8.98131 -85.857744) (xy 8.962246 -85.7621)
			(xy 8.952619 -85.66505) (xy 8.951976 -85.616288) (xy 8.951976 -85.614256) (xy 8.95223 -85.607652)
			(xy 8.95223 -85.60689) (xy 9.028176 -76.396596) (xy 9.031732 -75.980798) (xy 9.043162 -74.581512)
			(xy 9.042659 -74.570184) (xy 9.033166 -74.549623) (xy 9.024874 -74.541888) (xy 8.964676 -74.491342)
			(xy 8.960218 -74.487821) (xy 8.950086 -74.482691) (xy 8.94461 -74.481182) (xy 8.934196 -74.478388)
			(xy 8.922766 -74.480674) (xy 8.90497 -74.483893) (xy 8.868967 -74.487327) (xy 8.850884 -74.487532)
			(xy 8.85063 -74.487532) (xy 8.823378 -74.487046) (xy 8.76943 -74.47929) (xy 8.717135 -74.463934)
			(xy 8.667557 -74.441293) (xy 8.621706 -74.411826) (xy 8.580516 -74.376134) (xy 8.544824 -74.334944)
			(xy 8.515357 -74.289093) (xy 8.492716 -74.239515) (xy 8.47736 -74.18722) (xy 8.469604 -74.133272)
			(xy 8.469604 -74.078768) (xy 8.47736 -74.02482) (xy 8.492716 -73.972525) (xy 8.515357 -73.922947)
			(xy 8.544824 -73.877096) (xy 8.580516 -73.835906) (xy 8.621706 -73.800214) (xy 8.667557 -73.770747)
			(xy 8.717135 -73.748106) (xy 8.76943 -73.73275) (xy 8.823378 -73.724994) (xy 8.85063 -73.724516)
			(xy 8.87027 -73.72477) (xy 8.909338 -73.728841) (xy 8.928608 -73.732644) (xy 8.928862 -73.732644)
			(xy 8.939677 -73.734311) (xy 8.960988 -73.729439) (xy 8.97001 -73.723246) (xy 9.03351 -73.671684)
			(xy 9.040927 -73.664635) (xy 9.049971 -73.6463) (xy 9.051036 -73.636124) (xy 9.05256 -73.43521) (xy 9.070594 -71.25208)
			(xy 9.0678 -71.243952) (xy 9.067546 -71.243698) (xy 9.057591 -71.213158) (xy 9.046871 -71.149829)
			(xy 9.04621 -71.117714) (xy 9.04621 -71.11746) (xy 9.046931 -71.083716) (xy 9.058817 -71.017284)
			(xy 9.069832 -70.98538) (xy 9.07288 -70.976998) (xy 9.141968 -62.603634) (xy 9.141968 -61.016388)
			(xy 9.137142 -61.01334) (xy 9.13384 -61.011562) (xy 9.10336 -61.003942) (xy 9.076224 -60.996699)
			(xy 9.024283 -60.975337) (xy 8.976031 -60.946596) (xy 8.93251 -60.911097) (xy 8.89466 -60.869605)
			(xy 8.863296 -60.823015) (xy 8.839097 -60.772333) (xy 8.822583 -60.718653) (xy 8.814111 -60.663133)
			(xy 8.813865 -60.606971) (xy 8.821849 -60.551378) (xy 8.837892 -60.497556) (xy 8.861646 -60.446664)
			(xy 8.8926 -60.399801) (xy 8.930085 -60.357978) (xy 8.973293 -60.322098) (xy 9.02129 -60.292936)
			(xy 9.046972 -60.281566) (xy 9.081008 -60.26912) (xy 9.090406 -60.266326) (xy 9.097772 -60.260484)
			(xy 9.106938 -60.25235) (xy 9.117043 -60.230064) (xy 9.117076 -60.217812) (xy 9.092692 -59.783726)
			(xy 9.088374 -59.70778) (xy 9.088374 -59.707526) (xy 9.00684 -58.808112) (xy 9.006193 -58.802344)
			(xy 9.002605 -58.791309) (xy 8.999728 -58.786268) (xy 8.99414 -58.777124) (xy 8.98398 -58.77052)
			(xy 8.961393 -58.755341) (xy 8.920354 -58.719602) (xy 8.884805 -58.678399) (xy 8.855466 -58.632566)
			(xy 8.832932 -58.583031) (xy 8.81766 -58.530799) (xy 8.809959 -58.476928) (xy 8.809482 -58.449718)
			(xy 8.809482 -58.449464) (xy 8.80994 -58.423442) (xy 8.817047 -58.371886) (xy 8.831096 -58.321774)
			(xy 8.851827 -58.274037) (xy 8.878854 -58.229561) (xy 8.911677 -58.189172) (xy 8.930386 -58.17108)
			(xy 8.934196 -58.167524) (xy 8.940546 -58.157872) (xy 8.942578 -58.152538) (xy 8.944421 -58.147151)
			(xy 8.945956 -58.135871) (xy 8.945626 -58.130186) (xy 8.942578 -58.097166) (xy 8.933688 -58.000138)
			(xy 8.874252 -57.343548) (xy 8.872354 -57.321181) (xy 8.870323 -57.276333) (xy 8.870188 -57.253886)
			(xy 8.870188 -57.253378) (xy 8.870442 -57.238392) (xy 8.870442 -57.238138) (xy 8.887714 -56.129428)
			(xy 8.887714 -56.125872) (xy 8.808974 -54.722776) (xy 8.640572 -51.719734) (xy 8.638794 -51.709574)
			(xy 8.638794 -51.709066) (xy 8.635481 -51.698833) (xy 8.621791 -51.682269) (xy 8.612378 -51.677062)
			(xy 8.549386 -51.645566) (xy 8.544061 -51.6431) (xy 8.532645 -51.640397) (xy 8.52678 -51.640232)
			(xy 8.498332 -51.640232) (xy 8.485124 -51.64201) (xy 8.478774 -51.643788) (xy 8.472678 -51.647344)
			(xy 8.450405 -51.660227) (xy 8.40313 -51.680542) (xy 8.353551 -51.69431) (xy 8.302571 -51.701281)
			(xy 8.276844 -51.7017) (xy 8.27659 -51.7017) (xy 8.250015 -51.701239) (xy 8.197381 -51.693858) (xy 8.146281 -51.67924)
			(xy 8.097705 -51.657669) (xy 8.052596 -51.629563) (xy 8.011825 -51.595465) (xy 7.976184 -51.556037)
			(xy 7.960868 -51.534314) (xy 7.958074 -51.53025) (xy 7.948168 -51.520344) (xy 7.94004 -51.51374)
			(xy 7.91464 -51.497738) (xy 7.902448 -51.496722) (xy 7.874762 -51.493928) (xy 7.874254 -51.493928)
			(xy 7.835138 -51.489864) (xy 7.830796 -51.489512) (xy 7.82211 -51.490155) (xy 7.817866 -51.491134)
			(xy 7.815834 -51.491642) (xy 7.814564 -51.49215) (xy 7.812786 -51.492658) (xy 7.806436 -51.494944)
			(xy 7.796276 -51.501548) (xy 7.792212 -51.505866) (xy 7.784949 -51.513472) (xy 7.769701 -51.527959)
			(xy 7.761732 -51.534822) (xy 7.738203 -51.554048) (xy 7.686256 -51.585562) (xy 7.62997 -51.608442)
			(xy 7.570769 -51.62211) (xy 7.540498 -51.624738) (xy 7.52094 -51.6255) (xy 7.514082 -51.6255) (xy 7.512812 -51.6255)
			(xy 7.512558 -51.6255) (xy 7.493762 -51.624992) (xy 7.490206 -51.624738) (xy 7.489952 -51.624738)
			(xy 7.46353 -51.622573) (xy 7.411612 -51.61186) (xy 7.361675 -51.594064) (xy 7.314683 -51.569529)
			(xy 7.271538 -51.538725) (xy 7.233072 -51.502247) (xy 7.200025 -51.460795) (xy 7.173033 -51.415169)
			(xy 7.152616 -51.366246) (xy 7.139166 -51.314968) (xy 7.135622 -51.288696) (xy 7.134606 -51.279298)
			(xy 7.133336 -51.25974) (xy 7.133082 -51.243992) (xy 7.133082 -51.243484) (xy 7.133082 -51.24323)
			(xy 7.134098 -51.214528) (xy 7.13486 -51.203606) (xy 7.13105 -51.193192) (xy 7.129046 -51.188093)
			(xy 7.12316 -51.178855) (xy 7.119366 -51.174904) (xy 7.11708 -51.172618) (xy 7.116064 -51.153568)
			(xy 7.115991 -51.144398) (xy 7.121595 -51.126952) (xy 7.126986 -51.119532) (xy 7.211568 -51.01209)
			(xy 7.211822 -51.011582) (xy 7.212076 -51.011328) (xy 7.2136 -51.00955) (xy 7.21487 -51.007772) (xy 7.215124 -51.007518)
			(xy 7.21614 -51.006248) (xy 7.216648 -51.005486) (xy 7.21995 -51.000914) (xy 7.223506 -50.99304)
			(xy 7.225133 -50.988576) (xy 7.226923 -50.979247) (xy 7.227062 -50.974498) (xy 7.227062 -50.953162)
			(xy 7.227206 -50.947723) (xy 7.229518 -50.937093) (xy 7.231634 -50.93208) (xy 7.23773 -50.918618)
			(xy 7.241352 -50.909956) (xy 7.242586 -50.891234) (xy 7.236961 -50.873335) (xy 7.23138 -50.865786)
			(xy 7.225792 -50.858674) (xy 7.222236 -50.854102) (xy 7.220204 -50.851562) (xy 7.201759 -50.82831)
			(xy 7.17154 -50.777229) (xy 7.149592 -50.722087) (xy 7.136442 -50.664213) (xy 7.133844 -50.634646)
			(xy 7.13359 -50.630328) (xy 7.13359 -50.62855) (xy 7.133082 -50.610008) (xy 7.133082 -50.608484)
			(xy 7.133601 -50.58128) (xy 7.141404 -50.527432) (xy 7.156778 -50.475239) (xy 7.179411 -50.42576)
			(xy 7.208844 -50.379998) (xy 7.24448 -50.338882) (xy 7.285596 -50.303246) (xy 7.331358 -50.273812)
			(xy 7.380837 -50.251179) (xy 7.43303 -50.235805) (xy 7.486878 -50.228001) (xy 7.514082 -50.227484)
			(xy 7.526274 -50.227484) (xy 7.553091 -50.228747) (xy 7.605996 -50.237861) (xy 7.657103 -50.254297)
			(xy 7.705403 -50.277731) (xy 7.749944 -50.3077) (xy 7.789848 -50.343613) (xy 7.807452 -50.363882)
			(xy 7.811516 -50.369724) (xy 7.817866 -50.37455) (xy 7.822692 -50.37836) (xy 7.84733 -50.389536)
			(xy 7.847584 -50.389536) (xy 7.852179 -50.391501) (xy 7.8619 -50.393814) (xy 7.866888 -50.394108)
			(xy 7.918704 -50.394108) (xy 7.930896 -50.392584) (xy 7.947152 -50.38852) (xy 7.951978 -50.386234)
			(xy 7.963154 -50.3809) (xy 7.96798 -50.378614) (xy 7.977378 -50.371502) (xy 7.981442 -50.366676)
			(xy 7.981696 -50.366422) (xy 7.984744 -50.362866) (xy 7.992697 -50.353641) (xy 8.009598 -50.336099)
			(xy 8.018526 -50.327814) (xy 8.039753 -50.308999) (xy 8.086731 -50.277214) (xy 8.137901 -50.252743)
			(xy 8.192133 -50.236127) (xy 8.24823 -50.227733) (xy 8.27659 -50.22723) (xy 8.279892 -50.22723) (xy 8.292846 -50.227738)
			(xy 8.321927 -50.229545) (xy 8.379075 -50.240896) (xy 8.406638 -50.250344) (xy 8.415274 -50.253392)
			(xy 8.441944 -50.253392) (xy 8.450072 -50.25263) (xy 8.45058 -50.25263) (xy 8.458103 -50.251037)
			(xy 8.471803 -50.244073) (xy 8.477504 -50.238914) (xy 8.48487 -50.231548) (xy 8.490966 -50.226468)
			(xy 8.534654 -50.194972) (xy 8.538805 -50.191327) (xy 8.545599 -50.182618) (xy 8.548116 -50.1777)
			(xy 8.550148 -50.172366) (xy 8.551306 -50.168531) (xy 8.552576 -50.160622) (xy 8.552688 -50.156618)
			(xy 8.552688 -50.153316) (xy 8.550656 -50.120804) (xy 8.550656 -50.120042) (xy 8.54837 -50.080926)
			(xy 8.546338 -50.046128) (xy 8.545733 -50.041702) (xy 8.543179 -50.033143) (xy 8.541258 -50.02911)
			(xy 8.53694 -50.020474) (xy 8.53186 -50.016156) (xy 8.528812 -50.013616) (xy 8.50646 -49.994566)
			(xy 8.503186 -49.991629) (xy 8.497572 -49.98486) (xy 8.495284 -49.981104) (xy 8.49503 -49.980596)
			(xy 8.494268 -49.979326) (xy 8.494014 -49.979072) (xy 8.490582 -49.973599) (xy 8.481457 -49.964462)
			(xy 8.47598 -49.961038) (xy 8.469884 -49.957736) (xy 8.46455 -49.956212) (xy 8.464042 -49.956212)
			(xy 8.450326 -49.95418) (xy 8.440674 -49.954434) (xy 8.43661 -49.954688) (xy 8.43407 -49.954942)
			(xy 8.433054 -49.954942) (xy 8.43026 -49.955196) (xy 8.429244 -49.95545) (xy 8.428228 -49.95545)
			(xy 8.42645 -49.955704) (xy 8.424672 -49.955704) (xy 8.399018 -49.956466) (xy 8.376971 -49.956155)
			(xy 8.333172 -49.951062) (xy 8.311642 -49.946306) (xy 8.311388 -49.946306) (xy 8.310626 -49.946052)
			(xy 8.310372 -49.946052) (xy 8.308594 -49.945544) (xy 8.284972 -49.93894) (xy 8.267709 -49.933306)
			(xy 8.234249 -49.919186) (xy 8.21817 -49.910746) (xy 8.217662 -49.910746) (xy 8.215122 -49.909222)
			(xy 8.213852 -49.90846) (xy 8.213598 -49.908206) (xy 8.212582 -49.907698) (xy 8.21182 -49.907444)
			(xy 8.198537 -49.899838) (xy 8.173108 -49.882797) (xy 8.16102 -49.873408) (xy 8.160512 -49.8729)
			(xy 8.157464 -49.870614) (xy 8.152638 -49.86782) (xy 8.146288 -49.864772) (xy 8.135366 -49.862232)
			(xy 8.108188 -49.862232) (xy 8.102748 -49.86209) (xy 8.092116 -49.859784) (xy 8.087106 -49.85766)
			(xy 8.073644 -49.851564) (xy 8.064981 -49.847937) (xy 8.046255 -49.846694) (xy 8.028348 -49.852313)
			(xy 8.020812 -49.857914) (xy 8.0137 -49.863502) (xy 8.009128 -49.867058) (xy 8.008366 -49.867566)
			(xy 7.987724 -49.884204) (xy 7.94271 -49.912216) (xy 7.894251 -49.933724) (xy 7.84328 -49.948316)
			(xy 7.79078 -49.955708) (xy 7.764272 -49.956212) (xy 7.754366 -49.956212) (xy 7.725646 -49.954969)
			(xy 7.669049 -49.944909) (xy 7.614606 -49.926457) (xy 7.563555 -49.900033) (xy 7.53999 -49.883568)
			(xy 7.531354 -49.877472) (xy 7.526274 -49.873154) (xy 7.518908 -49.868582) (xy 7.516876 -49.867566)
			(xy 7.511551 -49.865101) (xy 7.500135 -49.862401) (xy 7.49427 -49.862232) (xy 7.473188 -49.862232)
			(xy 7.467748 -49.86209) (xy 7.457116 -49.859784) (xy 7.452106 -49.85766) (xy 7.438644 -49.851564)
			(xy 7.429981 -49.847937) (xy 7.411255 -49.846694) (xy 7.393348 -49.852313) (xy 7.385812 -49.857914)
			(xy 7.3787 -49.863502) (xy 7.374128 -49.867058) (xy 7.373366 -49.867566) (xy 7.352724 -49.884204)
			(xy 7.30771 -49.912216) (xy 7.259251 -49.933724) (xy 7.20828 -49.948316) (xy 7.15578 -49.955708)
			(xy 7.129272 -49.956212) (xy 7.119366 -49.956212) (xy 7.090646 -49.954969) (xy 7.034049 -49.944909)
			(xy 6.979606 -49.926457) (xy 6.928555 -49.900033) (xy 6.90499 -49.883568) (xy 6.896354 -49.877472)
			(xy 6.891274 -49.873154) (xy 6.883908 -49.868582) (xy 6.881876 -49.867566) (xy 6.876551 -49.865101)
			(xy 6.865135 -49.862401) (xy 6.85927 -49.862232) (xy 6.838188 -49.862232) (xy 6.832748 -49.86209)
			(xy 6.822116 -49.859784) (xy 6.817106 -49.85766) (xy 6.803644 -49.851564) (xy 6.794981 -49.847937)
			(xy 6.776255 -49.846694) (xy 6.758348 -49.852313) (xy 6.750812 -49.857914) (xy 6.7437 -49.863502)
			(xy 6.739128 -49.867058) (xy 6.738366 -49.867566) (xy 6.717724 -49.884204) (xy 6.67271 -49.912216)
			(xy 6.624251 -49.933724) (xy 6.57328 -49.948316) (xy 6.52078 -49.955708) (xy 6.494272 -49.956212)
			(xy 6.494018 -49.956212) (xy 6.466767 -49.955726) (xy 6.412818 -49.947969) (xy 6.360523 -49.932614)
			(xy 6.310946 -49.909972) (xy 6.265095 -49.880506) (xy 6.223905 -49.844814) (xy 6.188213 -49.803623)
			(xy 6.158747 -49.757772) (xy 6.136106 -49.708195) (xy 6.12075 -49.6559) (xy 6.112994 -49.601951)
			(xy 6.112994 -49.547449) (xy 6.12075 -49.4935) (xy 6.136106 -49.441205) (xy 6.158747 -49.391628)
			(xy 6.188213 -49.345777) (xy 6.223905 -49.304586) (xy 6.265095 -49.268894) (xy 6.310946 -49.239428)
			(xy 6.360523 -49.216786) (xy 6.412818 -49.201431) (xy 6.466767 -49.193674) (xy 6.494018 -49.193196)
			(xy 6.494272 -49.193196) (xy 6.51989 -49.193604) (xy 6.570666 -49.200453) (xy 6.620066 -49.214045)
			(xy 6.667199 -49.234135) (xy 6.711214 -49.260361) (xy 6.731508 -49.276) (xy 6.736334 -49.27981) (xy 6.7437 -49.283112)
			(xy 6.748439 -49.284982) (xy 6.758419 -49.287027) (xy 6.763512 -49.287176) (xy 6.784848 -49.287176)
			(xy 6.790287 -49.287321) (xy 6.800918 -49.28963) (xy 6.80593 -49.291748) (xy 6.819392 -49.297844)
			(xy 6.828054 -49.301464) (xy 6.846774 -49.302695) (xy 6.864671 -49.297068) (xy 6.872224 -49.291494)
			(xy 6.879336 -49.285906) (xy 6.883908 -49.28235) (xy 6.88467 -49.281842) (xy 6.905311 -49.2652) (xy 6.950323 -49.23718)
			(xy 6.998782 -49.215663) (xy 7.049753 -49.201063) (xy 7.102254 -49.193661) (xy 7.128764 -49.193196)
			(xy 7.13867 -49.193196) (xy 7.169458 -49.194565) (xy 7.230013 -49.205999) (xy 7.287947 -49.22701)
			(xy 7.341753 -49.257052) (xy 7.366254 -49.275746) (xy 7.371334 -49.27981) (xy 7.379208 -49.283366)
			(xy 7.383836 -49.285139) (xy 7.393558 -49.287056) (xy 7.398512 -49.287176) (xy 7.419848 -49.287176)
			(xy 7.425287 -49.287321) (xy 7.435918 -49.28963) (xy 7.44093 -49.291748) (xy 7.454392 -49.297844)
			(xy 7.463054 -49.301464) (xy 7.481774 -49.302695) (xy 7.499671 -49.297068) (xy 7.507224 -49.291494)
			(xy 7.514336 -49.285906) (xy 7.518908 -49.28235) (xy 7.51967 -49.281842) (xy 7.540311 -49.2652) (xy 7.585323 -49.23718)
			(xy 7.633782 -49.215663) (xy 7.684753 -49.201063) (xy 7.737254 -49.193661) (xy 7.763764 -49.193196)
			(xy 7.77367 -49.193196) (xy 7.804458 -49.194565) (xy 7.865013 -49.205999) (xy 7.922947 -49.22701)
			(xy 7.976753 -49.257052) (xy 8.001254 -49.275746) (xy 8.006334 -49.27981) (xy 8.014208 -49.283366)
			(xy 8.018836 -49.285139) (xy 8.028558 -49.287056) (xy 8.033512 -49.287176) (xy 8.054848 -49.287176)
			(xy 8.060287 -49.287321) (xy 8.070918 -49.28963) (xy 8.07593 -49.291748) (xy 8.08736 -49.297082)
			(xy 8.087868 -49.297082) (xy 8.097012 -49.301654) (xy 8.108442 -49.301908) (xy 8.113946 -49.301789)
			(xy 8.124711 -49.299489) (xy 8.129778 -49.297336) (xy 8.134858 -49.29505) (xy 8.143748 -49.290478)
			(xy 8.14832 -49.286414) (xy 8.172058 -49.266695) (xy 8.224643 -49.234402) (xy 8.252968 -49.222152)
			(xy 8.275328 -49.213254) (xy 8.321736 -49.200513) (xy 8.369376 -49.1937) (xy 8.39343 -49.192942)
			(xy 8.404098 -49.192688) (xy 8.412734 -49.189132) (xy 8.4171 -49.187077) (xy 8.425028 -49.18158)
			(xy 8.428482 -49.17821) (xy 8.447532 -49.15789) (xy 8.479282 -49.1236) (xy 8.485901 -49.115773) (xy 8.492855 -49.096511)
			(xy 8.492744 -49.086262) (xy 8.434324 -48.047402) (xy 8.33501 -46.28007) (xy 8.334074 -46.270461)
			(xy 8.325993 -46.252943) (xy 8.312012 -46.239651) (xy 8.294108 -46.232466) (xy 8.284464 -46.232064)
			(xy 8.279384 -46.232064) (xy 8.256778 -46.232826) (xy 8.256524 -46.232826) (xy 8.229285 -46.232321)
			(xy 8.175366 -46.224533) (xy 8.123104 -46.209154) (xy 8.07356 -46.186498) (xy 8.027743 -46.157024)
			(xy 7.986584 -46.121333) (xy 7.950921 -46.08015) (xy 7.921478 -46.034313) (xy 7.898855 -45.984754)
			(xy 7.883512 -45.932481) (xy 7.87576 -45.878557) (xy 7.87527 -45.851318) (xy 7.875716 -45.8249) (xy 7.883003 -45.772569)
			(xy 7.897444 -45.721745) (xy 7.918762 -45.6734) (xy 7.94655 -45.628461) (xy 7.980274 -45.587789)
			(xy 8.019291 -45.55216) (xy 8.062852 -45.522259) (xy 8.110123 -45.498657) (xy 8.1602 -45.481806)
			(xy 8.212124 -45.472029) (xy 8.23849 -45.470318) (xy 8.238744 -45.470318) (xy 8.244332 -45.470064)
			(xy 8.245094 -45.46981) (xy 8.254522 -45.467759) (xy 8.270975 -45.457709) (xy 8.277098 -45.450252)
			(xy 8.277098 -45.449998) (xy 8.28187 -45.443035) (xy 8.286939 -45.426943) (xy 8.287004 -45.418502)
			(xy 8.250174 -44.759626) (xy 8.224266 -44.306236) (xy 8.224012 -44.302172) (xy 8.097774 -43.367198)
			(xy 7.69366 -40.375586) (xy 7.68989 -40.346131) (xy 7.685441 -40.28691) (xy 7.68477 -40.257222) (xy 7.678674 -39.8653)
			(xy 7.676642 -39.725346) (xy 7.676158 -39.720384) (xy 7.673476 -39.710785) (xy 7.671308 -39.706296)
			(xy 7.671308 -39.706042) (xy 7.652074 -39.666102) (xy 7.619952 -39.583472) (xy 7.595294 -39.498315)
			(xy 7.578297 -39.411305) (xy 7.569095 -39.323129) (xy 7.56793 -39.278814) (xy 7.56666 -39.196518)
			(xy 7.56031 -38.783514) (xy 7.56031 -38.78326) (xy 7.560056 -38.768528) (xy 7.560056 -38.76802) (xy 7.560464 -38.727689)
			(xy 7.567001 -38.647291) (xy 7.580016 -38.567685) (xy 7.599424 -38.489393) (xy 7.611872 -38.451028)
			(xy 7.614047 -38.443578) (xy 7.614298 -38.428068) (xy 7.61238 -38.420548) (xy 7.611364 -38.417246)
			(xy 7.597017 -38.377312) (xy 7.57436 -38.295531) (xy 7.558725 -38.212122) (xy 7.550223 -38.127687)
			(xy 7.549134 -38.085268) (xy 7.546594 -37.927534) (xy 7.545578 -37.854128) (xy 7.541514 -37.589714)
			(xy 7.541514 -37.58946) (xy 7.54126 -37.574728) (xy 7.54126 -37.57422) (xy 7.541962 -37.522073) (xy 7.552903 -37.418354)
			(xy 7.563104 -37.36721) (xy 7.568692 -37.342572) (xy 7.570724 -37.334444) (xy 7.563358 -37.260276)
			(xy 7.558024 -37.250878) (xy 7.537109 -37.213073) (xy 7.501201 -37.134483) (xy 7.472287 -37.053059)
			(xy 7.460996 -37.011356) (xy 7.460996 -37.010848) (xy 7.455408 -36.99002) (xy 7.453884 -36.981638)
			(xy 7.453884 -36.981384) (xy 7.45363 -36.980622) (xy 7.453376 -36.979352) (xy 7.453122 -36.977828)
			(xy 7.452614 -36.976558) (xy 7.45236 -36.975034) (xy 7.451852 -36.973002) (xy 7.446065 -36.945236)
			(xy 7.437296 -36.889195) (xy 7.434326 -36.860988) (xy 7.390892 -36.42106) (xy 7.388702 -36.396863)
			(xy 7.386414 -36.348327) (xy 7.38632 -36.324032) (xy 7.386931 -36.274089) (xy 7.396979 -36.174711)
			(xy 7.406386 -36.125658) (xy 7.408418 -36.115752) (xy 7.403846 -36.093654) (xy 7.401814 -36.089082)
			(xy 7.383397 -36.043479) (xy 7.354636 -35.949423) (xy 7.335353 -35.852976) (xy 7.329932 -35.804094)
			(xy 7.329932 -35.80384) (xy 7.328154 -35.786822) (xy 7.328154 -35.786314) (xy 7.305294 -35.553142)
			(xy 7.303945 -35.546237) (xy 7.298011 -35.533486) (xy 7.29361 -35.527996) (xy 7.29107 -35.525202)
			(xy 7.290816 -35.524948) (xy 7.281418 -35.517582) (xy 7.253478 -35.518852) (xy 7.215632 -35.519868)
			(xy 7.203186 -35.519868) (xy 7.156791 -35.518987) (xy 7.064459 -35.509664) (xy 6.973393 -35.491798)
			(xy 6.884383 -35.465545) (xy 6.798198 -35.431131) (xy 6.715585 -35.388855) (xy 6.676136 -35.36442)
			(xy 6.674104 -35.364928) (xy 6.67004 -35.36569) (xy 6.653041 -35.368564) (xy 6.618699 -35.371616)
			(xy 6.60146 -35.371786) (xy 6.600952 -35.371786) (xy 6.573874 -35.371309) (xy 6.520263 -35.363646)
			(xy 6.468274 -35.348479) (xy 6.418951 -35.326114) (xy 6.373286 -35.297) (xy 6.332196 -35.261723)
			(xy 6.296507 -35.22099) (xy 6.266935 -35.17562) (xy 6.244075 -35.126525) (xy 6.228386 -35.074691)
			(xy 6.220183 -35.02116) (xy 6.219444 -34.994088) (xy 6.219444 -34.990024) (xy 6.219953 -34.96277)
			(xy 6.227743 -34.908821) (xy 6.243112 -34.856523) (xy 6.253988 -34.831528) (xy 6.256274 -34.826448)
			(xy 6.258052 -34.81832) (xy 6.24384 -34.770385) (xy 6.223947 -34.672397) (xy 6.213949 -34.572911)
			(xy 6.213348 -34.522918) (xy 6.213348 -34.52241) (xy 6.213782 -34.479823) (xy 6.221021 -34.394958)
			(xy 6.235472 -34.31102) (xy 6.257031 -34.22862) (xy 6.285539 -34.14836) (xy 6.302756 -34.109406)
			(xy 6.305939 -34.100273) (xy 6.305943 -34.080946) (xy 6.302756 -34.071814) (xy 6.285547 -34.032858)
			(xy 6.257052 -33.952594) (xy 6.235499 -33.870195) (xy 6.221045 -33.786258) (xy 6.213796 -33.701396)
			(xy 6.213348 -33.65881) (xy 6.213348 -33.657794) (xy 6.213976 -33.607927) (xy 6.223983 -33.508696)
			(xy 6.243856 -33.410962) (xy 6.258052 -33.363154) (xy 6.257036 -33.358582) (xy 6.25348 -33.348168)
			(xy 6.252464 -33.345882) (xy 6.24226 -33.321857) (xy 6.227723 -33.271726) (xy 6.220139 -33.220083)
			(xy 6.219444 -33.19399) (xy 6.219444 -33.188656) (xy 6.220035 -33.161478) (xy 6.22797 -33.1077) (xy 6.243459 -33.055594)
			(xy 6.266188 -33.006214) (xy 6.295698 -32.960561) (xy 6.331389 -32.919559) (xy 6.372539 -32.884039)
			(xy 6.418316 -32.854721) (xy 6.46779 -32.832199) (xy 6.519961 -32.816928) (xy 6.573772 -32.809218)
			(xy 6.600952 -32.808672) (xy 6.605524 -32.808672) (xy 6.621617 -32.809012) (xy 6.653663 -32.812067)
			(xy 6.669532 -32.814768) (xy 6.676898 -32.816038) (xy 6.716238 -32.791745) (xy 6.798603 -32.749718)
			(xy 6.884506 -32.715498) (xy 6.973207 -32.689377) (xy 7.063946 -32.67158) (xy 7.155942 -32.662259)
			(xy 7.20217 -32.661352) (xy 7.214362 -32.661352) (xy 7.260979 -32.662083) (xy 7.353775 -32.671165)
			(xy 7.445317 -32.68887) (xy 7.534807 -32.715044) (xy 7.621464 -32.749457) (xy 7.704529 -32.791809)
			(xy 7.744206 -32.816292) (xy 7.745222 -32.816038) (xy 7.750556 -32.815022) (xy 7.75335 -32.814514)
			(xy 7.76605 -32.812482) (xy 7.766558 -32.812482) (xy 7.7807 -32.810528) (xy 7.809178 -32.808493)
			(xy 7.823454 -32.808418) (xy 7.825232 -32.808418) (xy 7.85368 -32.809942) (xy 7.854188 -32.809942)
			(xy 7.876305 -32.812146) (xy 7.919851 -32.82106) (xy 7.941056 -32.827722) (xy 7.944104 -32.828738)
			(xy 7.958074 -32.831278) (xy 7.969739 -32.832342) (xy 7.991978 -32.825073) (xy 8.000746 -32.817308)
			(xy 8.012938 -32.804608) (xy 8.016748 -32.801052) (xy 8.057388 -32.771334) (xy 8.062468 -32.766508)
			(xy 8.068056 -32.759396) (xy 8.067548 -32.737298) (xy 8.067548 -32.722312) (xy 8.067982 -32.679725)
			(xy 8.075221 -32.59486) (xy 8.089672 -32.510922) (xy 8.11123 -32.428522) (xy 8.139739 -32.348262)
			(xy 8.156956 -32.309308) (xy 8.16014 -32.300174) (xy 8.160144 -32.280848) (xy 8.156956 -32.271716)
			(xy 8.139766 -32.232807) (xy 8.111296 -32.152642) (xy 8.089752 -32.070345) (xy 8.07529 -31.986513)
			(xy 8.068015 -31.901755) (xy 8.067548 -31.85922) (xy 8.067548 -31.82239) (xy 8.065415 -31.818856)
			(xy 8.060183 -31.812472) (xy 8.057134 -31.80969) (xy 8.055356 -31.808166) (xy 8.052054 -31.805118)
			(xy 7.988554 -31.759144) (xy 7.988046 -31.759144) (xy 7.979664 -31.75254) (xy 7.967472 -31.750254)
			(xy 7.961501 -31.749302) (xy 7.94943 -31.749938) (xy 7.943596 -31.751524) (xy 7.939532 -31.752794)
			(xy 7.911417 -31.76146) (xy 7.853371 -31.771024) (xy 7.823962 -31.771844) (xy 7.822438 -31.771844)
			(xy 7.818628 -31.772098) (xy 7.81304 -31.772098) (xy 7.79907 -31.771336) (xy 7.798816 -31.771336)
			(xy 7.778242 -31.769812) (xy 7.777734 -31.769812) (xy 7.76605 -31.768542) (xy 7.759446 -31.76778)
			(xy 7.755128 -31.767526) (xy 7.728712 -31.774892) (xy 7.72287 -31.778448) (xy 7.689459 -31.797998)
			(xy 7.620132 -31.832454) (xy 7.548341 -31.86143) (xy 7.511542 -31.873444) (xy 7.4632 -31.888057)
			(xy 7.364305 -31.908561) (xy 7.263844 -31.918955) (xy 7.213346 -31.919672) (xy 7.206488 -31.919672)
			(xy 7.206234 -31.919926) (xy 7.161874 -31.919235) (xy 7.073538 -31.910945) (xy 6.986287 -31.894844)
			(xy 6.900809 -31.871061) (xy 6.817781 -31.839782) (xy 6.737858 -31.801255) (xy 6.699504 -31.778956)
			(xy 6.695948 -31.77667) (xy 6.690773 -31.774409) (xy 6.679749 -31.771973) (xy 6.674104 -31.771844)
			(xy 6.600952 -31.771844) (xy 6.573806 -31.771362) (xy 6.520063 -31.763659) (xy 6.467954 -31.748416)
			(xy 6.418533 -31.725939) (xy 6.372796 -31.696684) (xy 6.331669 -31.661241) (xy 6.295981 -31.620326)
			(xy 6.266454 -31.574764) (xy 6.243684 -31.525478) (xy 6.22813 -31.473461) (xy 6.220106 -31.419765)
			(xy 6.219444 -31.392622) (xy 6.219444 -31.389828) (xy 6.219936 -31.361597) (xy 6.228223 -31.305748)
			(xy 6.24465 -31.25173) (xy 6.256274 -31.225998) (xy 6.258052 -31.218632) (xy 6.244014 -31.171265)
			(xy 6.224251 -31.074463) (xy 6.214138 -30.976183) (xy 6.213348 -30.926786) (xy 6.213348 -30.922468)
			(xy 6.213782 -30.879881) (xy 6.22102 -30.795016) (xy 6.235471 -30.711078) (xy 6.257029 -30.628678)
			(xy 6.285537 -30.548417) (xy 6.302756 -30.509464) (xy 6.305932 -30.500331) (xy 6.30592 -30.48101)
			(xy 6.302756 -30.471872) (xy 6.285544 -30.432916) (xy 6.257045 -30.352653) (xy 6.235487 -30.270254)
			(xy 6.221029 -30.186317) (xy 6.213774 -30.101454) (xy 6.213348 -30.058868) (xy 6.213348 -30.05836)
			(xy 6.213992 -30.008319) (xy 6.224066 -29.908744) (xy 6.244048 -29.810676) (xy 6.258306 -29.762704)
			(xy 6.256528 -29.755084) (xy 6.254242 -29.750258) (xy 6.243234 -29.725168) (xy 6.227722 -29.672622)
			(xy 6.2199 -29.618394) (xy 6.219444 -29.591) (xy 6.219444 -29.590238) (xy 6.21993 -29.562987) (xy 6.227687 -29.509039)
			(xy 6.243042 -29.456745) (xy 6.265683 -29.407168) (xy 6.29515 -29.361318) (xy 6.330841 -29.320128)
			(xy 6.372031 -29.284437) (xy 6.417882 -29.254971) (xy 6.467459 -29.232331) (xy 6.519753 -29.216976)
			(xy 6.573701 -29.20922) (xy 6.600952 -29.20873) (xy 6.601968 -29.20873) (xy 6.618434 -29.208882)
			(xy 6.651246 -29.211681) (xy 6.6675 -29.214318) (xy 6.677152 -29.216096) (xy 6.71708 -29.191468)
			(xy 6.800718 -29.148966) (xy 6.887976 -29.114499) (xy 6.978082 -29.088371) (xy 7.070242 -29.070812)
			(xy 7.163643 -29.061977) (xy 7.210552 -29.06141) (xy 7.257464 -29.061942) (xy 7.350874 -29.070747)
			(xy 7.443042 -29.088291) (xy 7.533154 -29.114421) (xy 7.620411 -29.148904) (xy 7.704041 -29.191436)
			(xy 7.743952 -29.216096) (xy 7.750302 -29.214826) (xy 7.767612 -29.211885) (xy 7.802594 -29.208835)
			(xy 7.820152 -29.20873) (xy 7.824216 -29.20873) (xy 7.853421 -29.209561) (xy 7.911077 -29.219004)
			(xy 7.939024 -29.227526) (xy 7.939532 -29.22778) (xy 7.942834 -29.228796) (xy 7.948676 -29.230066)
			(xy 7.959518 -29.231686) (xy 7.980842 -29.226697) (xy 7.989824 -29.220414) (xy 7.990078 -29.22016)
			(xy 7.991094 -29.219652) (xy 8.057134 -29.1719) (xy 8.060275 -29.169319) (xy 8.065757 -29.163316)
			(xy 8.068056 -29.159962) (xy 8.067548 -29.14142) (xy 8.067548 -29.12237) (xy 8.067982 -29.079783)
			(xy 8.07522 -28.994918) (xy 8.08967 -28.910979) (xy 8.111228 -28.828579) (xy 8.139737 -28.748319)
			(xy 8.156956 -28.709366) (xy 8.160132 -28.700233) (xy 8.160121 -28.680912) (xy 8.156956 -28.671774)
			(xy 8.139744 -28.632818) (xy 8.111244 -28.552555) (xy 8.089687 -28.470156) (xy 8.075228 -28.38622)
			(xy 8.067974 -28.301356) (xy 8.067548 -28.25877) (xy 8.068036 -28.211623) (xy 8.07681 -28.117738)
			(xy 8.085074 -28.071318) (xy 8.088721 -28.052831) (xy 8.097231 -28.016118) (xy 8.102092 -27.997912)
			(xy 8.112252 -27.96286) (xy 8.112252 -27.962606) (xy 8.110474 -27.954224) (xy 8.108188 -27.949144)
			(xy 8.107934 -27.948636) (xy 8.097391 -27.924428) (xy 8.082334 -27.873818) (xy 8.074416 -27.821614)
			(xy 8.073644 -27.79522) (xy 8.073644 -27.789886) (xy 8.074147 -27.762647) (xy 8.081933 -27.708727)
			(xy 8.09731 -27.656462) (xy 8.119966 -27.606917) (xy 8.149439 -27.561099) (xy 8.18513 -27.519939)
			(xy 8.226314 -27.484275) (xy 8.272152 -27.454833) (xy 8.321713 -27.43221) (xy 8.373987 -27.416868)
			(xy 8.427912 -27.409119) (xy 8.455152 -27.408632) (xy 8.472709 -27.408753) (xy 8.507689 -27.41181)
			(xy 8.525002 -27.414728) (xy 8.527034 -27.415236) (xy 8.529574 -27.415744) (xy 8.530336 -27.415744)
			(xy 8.531606 -27.415998) (xy 8.574532 -27.39009) (xy 8.575548 -27.389582) (xy 8.57885 -27.387804)
			(xy 8.596376 -27.378152) (xy 8.599424 -27.370786) (xy 8.619744 -27.295348) (xy 8.61949 -27.281632)
			(xy 8.617712 -27.275028) (xy 8.613394 -27.259534) (xy 8.610346 -27.2542) (xy 8.598652 -27.232664)
			(xy 8.580235 -27.187249) (xy 8.567776 -27.139852) (xy 8.561478 -27.091251) (xy 8.56107 -27.066748)
			(xy 8.56107 -27.057604) (xy 8.561324 -27.05354) (xy 8.561324 -27.052778) (xy 8.56361 -27.022552)
			(xy 8.566714 -26.998918) (xy 8.57806 -26.952619) (xy 8.595103 -26.908102) (xy 8.606028 -26.886916)
			(xy 8.618859 -26.8638) (xy 8.649931 -26.821026) (xy 8.686613 -26.782953) (xy 8.70712 -26.766266)
			(xy 8.709152 -26.764742) (xy 8.716264 -26.757884) (xy 8.729218 -26.742136) (xy 8.731758 -26.736802)
			(xy 8.734298 -26.725118) (xy 8.730234 -26.647394) (xy 8.729726 -26.634948) (xy 8.711438 -26.603452)
			(xy 8.706866 -26.59888) (xy 8.69569 -26.58745) (xy 8.68934 -26.583132) (xy 8.667443 -26.567858) (xy 8.627735 -26.532169)
			(xy 8.593388 -26.491296) (xy 8.565069 -26.446037) (xy 8.543333 -26.397273) (xy 8.528602 -26.345957)
			(xy 8.521165 -26.293088) (xy 8.520684 -26.266394) (xy 8.52117 -26.239143) (xy 8.528926 -26.185195)
			(xy 8.544281 -26.1329) (xy 8.566923 -26.083323) (xy 8.596389 -26.037473) (xy 8.63208 -25.996282)
			(xy 8.673271 -25.960591) (xy 8.719121 -25.931125) (xy 8.768698 -25.908483) (xy 8.820993 -25.893128)
			(xy 8.874941 -25.885372) (xy 8.929443 -25.885372) (xy 8.983391 -25.893128) (xy 9.035686 -25.908483)
			(xy 9.085263 -25.931125) (xy 9.131113 -25.960591) (xy 9.172304 -25.996282) (xy 9.207995 -26.037473)
			(xy 9.237461 -26.083323) (xy 9.260103 -26.1329) (xy 9.275458 -26.185195) (xy 9.283214 -26.239143)
			(xy 9.2837 -26.266394) (xy 9.283148 -26.295552) (xy 9.274276 -26.353189) (xy 9.256738 -26.408805)
			(xy 9.230942 -26.461105) (xy 9.19749 -26.508872) (xy 9.157158 -26.550992) (xy 9.134348 -26.569162)
			(xy 9.131554 -26.571194) (xy 9.12495 -26.577798) (xy 9.120378 -26.58364) (xy 9.116304 -26.589981)
			(xy 9.111651 -26.604309) (xy 9.111234 -26.611834) (xy 9.115044 -26.69667) (xy 9.11987 -26.706068)
			(xy 9.120886 -26.708354) (xy 9.133586 -26.72969) (xy 9.137904 -26.734008) (xy 9.14908 -26.745438)
			(xy 9.15543 -26.749756) (xy 9.177287 -26.764969) (xy 9.216933 -26.800525) (xy 9.251244 -26.841253)
			(xy 9.279552 -26.88636) (xy 9.301307 -26.934968) (xy 9.316084 -26.98613) (xy 9.323596 -27.038852)
			(xy 9.324086 -27.065478) (xy 9.324086 -27.07132) (xy 9.323859 -27.083298) (xy 9.322079 -27.107192)
			(xy 9.32053 -27.119072) (xy 9.32053 -27.11958) (xy 9.320022 -27.122628) (xy 9.320022 -27.122882)
			(xy 9.31926 -27.1272) (xy 9.31926 -27.127454) (xy 9.318752 -27.130502) (xy 9.317736 -27.13609) (xy 9.317736 -27.136598)
			(xy 9.316974 -27.140408) (xy 9.315958 -27.14498) (xy 9.313546 -27.156051) (xy 9.307571 -27.177909)
			(xy 9.30402 -27.188668) (xy 9.300718 -27.19832) (xy 9.301734 -27.217116) (xy 9.304782 -27.223974)
			(xy 9.33577 -27.28595) (xy 9.338818 -27.290776) (xy 9.344914 -27.297634) (xy 9.351772 -27.303476)
			(xy 9.36371 -27.307286) (xy 9.403509 -27.320228) (xy 9.458836 -27.342846) (xy 16.523716 -27.342846)
			(xy 16.523716 -26.479246) (xy 16.524206 -26.449278) (xy 16.532029 -26.389856) (xy 16.547542 -26.331963)
			(xy 16.570478 -26.27659) (xy 16.600445 -26.224684) (xy 16.636932 -26.177134) (xy 16.679312 -26.134754)
			(xy 16.726862 -26.098267) (xy 16.778768 -26.0683) (xy 16.834141 -26.045364) (xy 16.892034 -26.029851)
			(xy 16.951456 -26.022028) (xy 17.011392 -26.022028) (xy 17.070814 -26.029851) (xy 17.128707 -26.045364)
			(xy 17.18408 -26.0683) (xy 17.235986 -26.098267) (xy 17.283536 -26.134754) (xy 17.325916 -26.177134)
			(xy 17.362403 -26.224684) (xy 17.39237 -26.27659) (xy 17.415306 -26.331963) (xy 17.423055 -26.360882)
			(xy 19.089622 -26.360882) (xy 19.093693 -26.30526) (xy 19.105819 -26.250823) (xy 19.125742 -26.198732)
			(xy 19.153038 -26.150097) (xy 19.187124 -26.105954) (xy 19.227273 -26.067245) (xy 19.272631 -26.034794)
			(xy 19.322231 -26.009293) (xy 19.375015 -25.991286) (xy 19.429858 -25.981156) (xy 19.485592 -25.979119)
			(xy 19.541029 -25.985219) (xy 19.594986 -25.999325) (xy 19.646315 -26.021137) (xy 19.666949 -26.03373)
			(xy 31.267906 -26.03373) (xy 31.271977 -25.978108) (xy 31.284103 -25.923671) (xy 31.304026 -25.87158)
			(xy 31.331322 -25.822945) (xy 31.365408 -25.778802) (xy 31.405557 -25.740093) (xy 31.450915 -25.707642)
			(xy 31.500515 -25.682141) (xy 31.553299 -25.664134) (xy 31.608142 -25.654004) (xy 31.663876 -25.651967)
			(xy 31.719313 -25.658067) (xy 31.77327 -25.672173) (xy 31.824599 -25.693985) (xy 31.872205 -25.723039)
			(xy 31.915073 -25.758714) (xy 31.95229 -25.800251) (xy 31.983063 -25.846764) (xy 32.006735 -25.897261)
			(xy 32.022803 -25.950668) (xy 32.030923 -26.005844) (xy 32.031432 -26.03373) (xy 32.030923 -26.061616)
			(xy 32.022803 -26.116792) (xy 32.006735 -26.170199) (xy 31.983063 -26.220696) (xy 31.95229 -26.267209)
			(xy 31.915073 -26.308746) (xy 31.872205 -26.344421) (xy 31.824599 -26.373475) (xy 31.77327 -26.395287)
			(xy 31.719313 -26.409393) (xy 31.663876 -26.415493) (xy 31.608142 -26.413456) (xy 31.553299 -26.403326)
			(xy 31.500515 -26.385319) (xy 31.450915 -26.359818) (xy 31.405557 -26.327367) (xy 31.365408 -26.288658)
			(xy 31.331322 -26.244515) (xy 31.304026 -26.19588) (xy 31.284103 -26.143789) (xy 31.271977 -26.089352)
			(xy 31.267906 -26.03373) (xy 19.666949 -26.03373) (xy 19.693921 -26.050191) (xy 19.736789 -26.085866)
			(xy 19.774006 -26.127403) (xy 19.804779 -26.173916) (xy 19.828451 -26.224413) (xy 19.844519 -26.27782)
			(xy 19.852639 -26.332996) (xy 19.853148 -26.360882) (xy 19.852639 -26.388768) (xy 19.844519 -26.443944)
			(xy 19.828451 -26.497351) (xy 19.804779 -26.547848) (xy 19.774006 -26.594361) (xy 19.736789 -26.635898)
			(xy 19.693921 -26.671573) (xy 19.646315 -26.700627) (xy 19.594986 -26.722439) (xy 19.541029 -26.736545)
			(xy 19.485592 -26.742645) (xy 19.429858 -26.740608) (xy 19.375015 -26.730478) (xy 19.322231 -26.712471)
			(xy 19.272631 -26.68697) (xy 19.227273 -26.654519) (xy 19.187124 -26.61581) (xy 19.153038 -26.571667)
			(xy 19.125742 -26.523032) (xy 19.105819 -26.470941) (xy 19.093693 -26.416504) (xy 19.089622 -26.360882)
			(xy 17.423055 -26.360882) (xy 17.430819 -26.389856) (xy 17.438642 -26.449278) (xy 17.439132 -26.479246)
			(xy 17.439132 -27.342846) (xy 17.438642 -27.372814) (xy 17.430819 -27.432236) (xy 17.415306 -27.490129)
			(xy 17.39237 -27.545502) (xy 17.362403 -27.597408) (xy 17.325916 -27.644958) (xy 17.283536 -27.687338)
			(xy 17.235986 -27.723825) (xy 17.18408 -27.753792) (xy 17.128707 -27.776728) (xy 17.070814 -27.792241)
			(xy 17.011392 -27.800064) (xy 16.951456 -27.800064) (xy 16.892034 -27.792241) (xy 16.834141 -27.776728)
			(xy 16.778768 -27.753792) (xy 16.726862 -27.723825) (xy 16.679312 -27.687338) (xy 16.636932 -27.644958)
			(xy 16.600445 -27.597408) (xy 16.570478 -27.545502) (xy 16.547542 -27.490129) (xy 16.532029 -27.432236)
			(xy 16.524206 -27.372814) (xy 16.523716 -27.342846) (xy 9.458836 -27.342846) (xy 9.480981 -27.351899)
			(xy 9.555525 -27.389954) (xy 9.591294 -27.41168) (xy 9.59993 -27.41168) (xy 9.61213 -27.410168) (xy 9.63666 -27.408515)
			(xy 9.648952 -27.408378) (xy 9.668256 -27.408886) (xy 9.677908 -27.409648) (xy 9.704915 -27.412184)
			(xy 9.757871 -27.423923) (xy 9.808633 -27.443041) (xy 9.856176 -27.469154) (xy 9.899543 -27.501735)
			(xy 9.93786 -27.540128) (xy 9.954514 -27.56154) (xy 9.956546 -27.56408) (xy 10.000941 -27.571476)
			(xy 10.088279 -27.59324) (xy 10.173301 -27.622784) (xy 10.255316 -27.659867) (xy 10.333657 -27.704187)
			(xy 10.407687 -27.755384) (xy 10.476804 -27.813042) (xy 10.508996 -27.844496) (xy 11.420094 -28.755594)
			(xy 11.454353 -28.790557) (xy 11.516572 -28.866132) (xy 11.5443 -28.90647) (xy 11.574272 -28.951428)
			(xy 11.580114 -28.95854) (xy 11.735816 -29.114242) (xy 18.847308 -29.114242) (xy 18.847308 -28.250642)
			(xy 18.847798 -28.220658) (xy 18.855626 -28.161202) (xy 18.871147 -28.103277) (xy 18.894096 -28.047873)
			(xy 18.92408 -27.995939) (xy 18.960586 -27.948363) (xy 19.002991 -27.905958) (xy 19.050567 -27.869452)
			(xy 19.102501 -27.839468) (xy 19.157905 -27.816519) (xy 19.21583 -27.800998) (xy 19.275286 -27.79317)
			(xy 19.335254 -27.79317) (xy 19.39471 -27.800998) (xy 19.452635 -27.816519) (xy 19.508039 -27.839468)
			(xy 19.559973 -27.869452) (xy 19.607549 -27.905958) (xy 19.649954 -27.948363) (xy 19.68646 -27.995939)
			(xy 19.716444 -28.047873) (xy 19.739393 -28.103277) (xy 19.749001 -28.139136) (xy 28.39796 -28.139136)
			(xy 28.402031 -28.083514) (xy 28.414157 -28.029077) (xy 28.43408 -27.976986) (xy 28.461376 -27.928351)
			(xy 28.495462 -27.884208) (xy 28.535611 -27.845499) (xy 28.580969 -27.813048) (xy 28.630569 -27.787547)
			(xy 28.683353 -27.76954) (xy 28.738196 -27.75941) (xy 28.79393 -27.757373) (xy 28.849367 -27.763473)
			(xy 28.903324 -27.777579) (xy 28.954653 -27.799391) (xy 29.002259 -27.828445) (xy 29.045127 -27.86412)
			(xy 29.082344 -27.905657) (xy 29.113117 -27.95217) (xy 29.136789 -28.002667) (xy 29.152857 -28.056074)
			(xy 29.160977 -28.11125) (xy 29.161486 -28.139136) (xy 29.66796 -28.139136) (xy 29.672031 -28.083514)
			(xy 29.684157 -28.029077) (xy 29.70408 -27.976986) (xy 29.731376 -27.928351) (xy 29.765462 -27.884208)
			(xy 29.805611 -27.845499) (xy 29.850969 -27.813048) (xy 29.900569 -27.787547) (xy 29.953353 -27.76954)
			(xy 30.008196 -27.75941) (xy 30.06393 -27.757373) (xy 30.119367 -27.763473) (xy 30.173324 -27.777579)
			(xy 30.224653 -27.799391) (xy 30.272259 -27.828445) (xy 30.315127 -27.86412) (xy 30.352344 -27.905657)
			(xy 30.383117 -27.95217) (xy 30.406789 -28.002667) (xy 30.422857 -28.056074) (xy 30.430977 -28.11125)
			(xy 30.431486 -28.139136) (xy 30.430977 -28.167022) (xy 30.422857 -28.222198) (xy 30.406789 -28.275605)
			(xy 30.383117 -28.326102) (xy 30.352344 -28.372615) (xy 30.315127 -28.414152) (xy 30.272259 -28.449827)
			(xy 30.224653 -28.478881) (xy 30.173324 -28.500693) (xy 30.119367 -28.514799) (xy 30.06393 -28.520899)
			(xy 30.008196 -28.518862) (xy 29.953353 -28.508732) (xy 29.900569 -28.490725) (xy 29.850969 -28.465224)
			(xy 29.805611 -28.432773) (xy 29.765462 -28.394064) (xy 29.731376 -28.349921) (xy 29.70408 -28.301286)
			(xy 29.684157 -28.249195) (xy 29.672031 -28.194758) (xy 29.66796 -28.139136) (xy 29.161486 -28.139136)
			(xy 29.160977 -28.167022) (xy 29.152857 -28.222198) (xy 29.136789 -28.275605) (xy 29.113117 -28.326102)
			(xy 29.082344 -28.372615) (xy 29.045127 -28.414152) (xy 29.002259 -28.449827) (xy 28.954653 -28.478881)
			(xy 28.903324 -28.500693) (xy 28.849367 -28.514799) (xy 28.79393 -28.520899) (xy 28.738196 -28.518862)
			(xy 28.683353 -28.508732) (xy 28.630569 -28.490725) (xy 28.580969 -28.465224) (xy 28.535611 -28.432773)
			(xy 28.495462 -28.394064) (xy 28.461376 -28.349921) (xy 28.43408 -28.301286) (xy 28.414157 -28.249195)
			(xy 28.402031 -28.194758) (xy 28.39796 -28.139136) (xy 19.749001 -28.139136) (xy 19.754914 -28.161202)
			(xy 19.762742 -28.220658) (xy 19.763232 -28.250642) (xy 19.763232 -29.114242) (xy 19.762742 -29.144226)
			(xy 19.754914 -29.203682) (xy 19.739393 -29.261607) (xy 19.716444 -29.317011) (xy 19.68646 -29.368945)
			(xy 19.649954 -29.416521) (xy 19.607549 -29.458926) (xy 19.559973 -29.495432) (xy 19.508039 -29.525416)
			(xy 19.452635 -29.548365) (xy 19.39471 -29.563886) (xy 19.335254 -29.571714) (xy 19.275286 -29.571714)
			(xy 19.21583 -29.563886) (xy 19.157905 -29.548365) (xy 19.102501 -29.525416) (xy 19.050567 -29.495432)
			(xy 19.002991 -29.458926) (xy 18.960586 -29.416521) (xy 18.92408 -29.368945) (xy 18.894096 -29.317011)
			(xy 18.871147 -29.261607) (xy 18.855626 -29.203682) (xy 18.847798 -29.144226) (xy 18.847308 -29.114242)
			(xy 11.735816 -29.114242) (xy 11.834368 -29.212794) (xy 11.837162 -29.215334) (xy 11.848846 -29.222446)
			(xy 11.853672 -29.224224) (xy 11.854434 -29.224478) (xy 11.854688 -29.224478) (xy 11.855196 -29.224732)
			(xy 11.85672 -29.22524) (xy 11.856974 -29.22524) (xy 11.857228 -29.22524) (xy 11.858244 -29.225748)
			(xy 11.876532 -29.231844) (xy 11.87704 -29.231844) (xy 11.90371 -29.24302) (xy 11.9126 -29.247084)
			(xy 11.924488 -29.253047) (xy 11.947496 -29.266394) (xy 11.958574 -29.273754) (xy 11.961876 -29.27604)
			(xy 11.985912 -29.293316) (xy 12.028836 -29.334074) (xy 12.064944 -29.380977) (xy 12.093367 -29.432898)
			(xy 12.113422 -29.488588) (xy 12.124627 -29.54671) (xy 12.126214 -29.576268) (xy 12.126722 -29.590492)
			(xy 12.126722 -29.590746) (xy 12.52855 -30.192218) (xy 12.5349 -30.199838) (xy 12.635484 -30.300422)
			(xy 13.255596 -30.92069) (xy 21.489416 -30.92069) (xy 21.489416 -30.05709) (xy 21.489906 -30.027106)
			(xy 21.497734 -29.96765) (xy 21.513255 -29.909725) (xy 21.536204 -29.854321) (xy 21.566188 -29.802387)
			(xy 21.602694 -29.754811) (xy 21.645099 -29.712406) (xy 21.692675 -29.6759) (xy 21.744609 -29.645916)
			(xy 21.800013 -29.622967) (xy 21.857938 -29.607446) (xy 21.917394 -29.599618) (xy 21.977362 -29.599618)
			(xy 22.036818 -29.607446) (xy 22.094743 -29.622967) (xy 22.150147 -29.645916) (xy 22.202081 -29.6759)
			(xy 22.249657 -29.712406) (xy 22.292062 -29.754811) (xy 22.328568 -29.802387) (xy 22.358552 -29.854321)
			(xy 22.381501 -29.909725) (xy 22.397022 -29.96765) (xy 22.40485 -30.027106) (xy 22.40534 -30.05709)
			(xy 22.40534 -30.376876) (xy 26.888948 -30.376876) (xy 26.889503 -30.34796) (xy 26.898222 -30.29079)
			(xy 26.915471 -30.235591) (xy 26.940856 -30.183629) (xy 26.973794 -30.136094) (xy 27.013531 -30.094077)
			(xy 27.036014 -30.075886) (xy 27.04482 -30.068277) (xy 27.055003 -30.047378) (xy 27.055572 -30.035754)
			(xy 27.055572 -29.955998) (xy 27.055029 -29.944366) (xy 27.044844 -29.923456) (xy 27.036014 -29.915866)
			(xy 27.013517 -29.897691) (xy 26.973782 -29.855668) (xy 26.940844 -29.80813) (xy 26.915458 -29.756166)
			(xy 26.898205 -29.700965) (xy 26.88948 -29.643793) (xy 26.888948 -29.614876) (xy 26.889434 -29.587625)
			(xy 26.89719 -29.533677) (xy 26.912545 -29.481382) (xy 26.935187 -29.431805) (xy 26.964653 -29.385955)
			(xy 27.000344 -29.344764) (xy 27.041535 -29.309073) (xy 27.087385 -29.279607) (xy 27.136962 -29.256965)
			(xy 27.189257 -29.24161) (xy 27.243205 -29.233854) (xy 27.297707 -29.233854) (xy 27.351655 -29.24161)
			(xy 27.40395 -29.256965) (xy 27.453527 -29.279607) (xy 27.499377 -29.309073) (xy 27.540568 -29.344764)
			(xy 27.576259 -29.385955) (xy 27.605725 -29.431805) (xy 27.628367 -29.481382) (xy 27.643722 -29.533677)
			(xy 27.651478 -29.587625) (xy 27.651964 -29.614876) (xy 27.651442 -29.643793) (xy 27.642716 -29.700965)
			(xy 27.625459 -29.756164) (xy 27.600069 -29.808126) (xy 27.567125 -29.85566) (xy 27.527384 -29.897676)
			(xy 27.504898 -29.915866) (xy 27.496116 -29.923497) (xy 27.485919 -29.94438) (xy 27.48534 -29.955998)
			(xy 27.48534 -30.035754) (xy 27.485848 -30.04739) (xy 27.496058 -30.0683) (xy 27.504898 -30.075886)
			(xy 27.527374 -30.094085) (xy 27.56711 -30.136103) (xy 27.60005 -30.183637) (xy 27.62544 -30.235596)
			(xy 27.642697 -30.290792) (xy 27.651428 -30.34796) (xy 27.651964 -30.376876) (xy 29.929074 -30.376876)
			(xy 29.929619 -30.34796) (xy 29.938339 -30.290789) (xy 29.955589 -30.235589) (xy 29.980976 -30.183627)
			(xy 30.013916 -30.136092) (xy 30.053655 -30.094076) (xy 30.07614 -30.075886) (xy 30.08495 -30.068282)
			(xy 30.09513 -30.047379) (xy 30.095698 -30.035754) (xy 30.095698 -29.955998) (xy 30.095147 -29.944368)
			(xy 30.084967 -29.923458) (xy 30.07614 -29.915866) (xy 30.053649 -29.897684) (xy 30.013912 -29.855664)
			(xy 29.980973 -29.808127) (xy 29.955585 -29.756164) (xy 29.938332 -29.700964) (xy 29.929606 -29.643793)
			(xy 29.929074 -29.614876) (xy 29.92956 -29.587625) (xy 29.937316 -29.533677) (xy 29.952671 -29.481382)
			(xy 29.975313 -29.431805) (xy 30.004779 -29.385955) (xy 30.04047 -29.344764) (xy 30.081661 -29.309073)
			(xy 30.127511 -29.279607) (xy 30.177088 -29.256965) (xy 30.229383 -29.24161) (xy 30.283331 -29.233854)
			(xy 30.337833 -29.233854) (xy 30.391781 -29.24161) (xy 30.444076 -29.256965) (xy 30.493653 -29.279607)
			(xy 30.539503 -29.309073) (xy 30.580694 -29.344764) (xy 30.616385 -29.385955) (xy 30.645851 -29.431805)
			(xy 30.668493 -29.481382) (xy 30.683848 -29.533677) (xy 30.691604 -29.587625) (xy 30.69209 -29.614876)
			(xy 30.691558 -29.643792) (xy 30.682832 -29.700963) (xy 30.665577 -29.756162) (xy 30.640188 -29.808124)
			(xy 30.607247 -29.855658) (xy 30.567508 -29.897675) (xy 30.545024 -29.915866) (xy 30.53623 -29.923485)
			(xy 30.526042 -29.944377) (xy 30.525466 -29.955998) (xy 30.525466 -30.035754) (xy 30.525965 -30.047392)
			(xy 30.53618 -30.068302) (xy 30.545024 -30.075886) (xy 30.567506 -30.094079) (xy 30.60724 -30.136099)
			(xy 30.640178 -30.183634) (xy 30.665567 -30.235594) (xy 30.682824 -30.290791) (xy 30.691554 -30.34796)
			(xy 30.69209 -30.376876) (xy 30.691604 -30.404127) (xy 30.683848 -30.458075) (xy 30.668493 -30.51037)
			(xy 30.645851 -30.559947) (xy 30.616385 -30.605797) (xy 30.580694 -30.646988) (xy 30.539503 -30.682679)
			(xy 30.493653 -30.712145) (xy 30.444076 -30.734787) (xy 30.391781 -30.750142) (xy 30.337833 -30.757898)
			(xy 30.283331 -30.757898) (xy 30.229383 -30.750142) (xy 30.177088 -30.734787) (xy 30.127511 -30.712145)
			(xy 30.081661 -30.682679) (xy 30.04047 -30.646988) (xy 30.004779 -30.605797) (xy 29.975313 -30.559947)
			(xy 29.952671 -30.51037) (xy 29.937316 -30.458075) (xy 29.92956 -30.404127) (xy 29.929074 -30.376876)
			(xy 27.651964 -30.376876) (xy 27.651478 -30.404127) (xy 27.643722 -30.458075) (xy 27.628367 -30.51037)
			(xy 27.605725 -30.559947) (xy 27.576259 -30.605797) (xy 27.540568 -30.646988) (xy 27.499377 -30.682679)
			(xy 27.453527 -30.712145) (xy 27.40395 -30.734787) (xy 27.351655 -30.750142) (xy 27.297707 -30.757898)
			(xy 27.243205 -30.757898) (xy 27.189257 -30.750142) (xy 27.136962 -30.734787) (xy 27.087385 -30.712145)
			(xy 27.041535 -30.682679) (xy 27.000344 -30.646988) (xy 26.964653 -30.605797) (xy 26.935187 -30.559947)
			(xy 26.912545 -30.51037) (xy 26.89719 -30.458075) (xy 26.889434 -30.404127) (xy 26.888948 -30.376876)
			(xy 22.40534 -30.376876) (xy 22.40534 -30.92069) (xy 22.40485 -30.950674) (xy 22.397022 -31.01013)
			(xy 22.381501 -31.068055) (xy 22.358552 -31.123459) (xy 22.328568 -31.175393) (xy 22.292062 -31.222969)
			(xy 22.249657 -31.265374) (xy 22.202081 -31.30188) (xy 22.150147 -31.331864) (xy 22.094743 -31.354813)
			(xy 22.036818 -31.370334) (xy 21.977362 -31.378162) (xy 21.917394 -31.378162) (xy 21.857938 -31.370334)
			(xy 21.800013 -31.354813) (xy 21.744609 -31.331864) (xy 21.692675 -31.30188) (xy 21.645099 -31.265374)
			(xy 21.602694 -31.222969) (xy 21.566188 -31.175393) (xy 21.536204 -31.123459) (xy 21.513255 -31.068055)
			(xy 21.497734 -31.01013) (xy 21.489906 -30.950674) (xy 21.489416 -30.92069) (xy 13.255596 -30.92069)
			(xy 13.647928 -31.31312) (xy 13.681621 -31.347612) (xy 13.742904 -31.422062) (xy 13.796715 -31.50208)
			(xy 13.842552 -31.586917) (xy 13.861796 -31.631128) (xy 14.166342 -32.353504) (xy 14.243304 -32.536384)
			(xy 14.318238 -32.714184) (xy 18.847308 -32.714184) (xy 18.847308 -31.850584) (xy 18.847798 -31.8206)
			(xy 18.855626 -31.761144) (xy 18.871147 -31.703219) (xy 18.894096 -31.647815) (xy 18.92408 -31.595881)
			(xy 18.960586 -31.548305) (xy 19.002991 -31.5059) (xy 19.050567 -31.469394) (xy 19.102501 -31.43941)
			(xy 19.157905 -31.416461) (xy 19.21583 -31.40094) (xy 19.275286 -31.393112) (xy 19.335254 -31.393112)
			(xy 19.39471 -31.40094) (xy 19.452635 -31.416461) (xy 19.508039 -31.43941) (xy 19.559973 -31.469394)
			(xy 19.607549 -31.5059) (xy 19.649954 -31.548305) (xy 19.664976 -31.567882) (xy 26.998674 -31.567882)
			(xy 27.002745 -31.51226) (xy 27.014871 -31.457823) (xy 27.034794 -31.405732) (xy 27.06209 -31.357097)
			(xy 27.096176 -31.312954) (xy 27.136325 -31.274245) (xy 27.181683 -31.241794) (xy 27.231283 -31.216293)
			(xy 27.284067 -31.198286) (xy 27.33891 -31.188156) (xy 27.394644 -31.186119) (xy 27.450081 -31.192219)
			(xy 27.504038 -31.206325) (xy 27.555367 -31.228137) (xy 27.602973 -31.257191) (xy 27.645841 -31.292866)
			(xy 27.683058 -31.334403) (xy 27.713831 -31.380916) (xy 27.737503 -31.431413) (xy 27.753571 -31.48482)
			(xy 27.761691 -31.539996) (xy 27.7622 -31.567882) (xy 27.761691 -31.595768) (xy 27.753571 -31.650944)
			(xy 27.737503 -31.704351) (xy 27.730511 -31.719266) (xy 28.285438 -31.719266) (xy 28.289509 -31.663644)
			(xy 28.301635 -31.609207) (xy 28.321558 -31.557116) (xy 28.348854 -31.508481) (xy 28.38294 -31.464338)
			(xy 28.423089 -31.425629) (xy 28.468447 -31.393178) (xy 28.518047 -31.367677) (xy 28.570831 -31.34967)
			(xy 28.625674 -31.33954) (xy 28.681408 -31.337503) (xy 28.736845 -31.343603) (xy 28.790802 -31.357709)
			(xy 28.842131 -31.379521) (xy 28.889737 -31.408575) (xy 28.932605 -31.44425) (xy 28.969822 -31.485787)
			(xy 29.000595 -31.5323) (xy 29.024267 -31.582797) (xy 29.040335 -31.636204) (xy 29.044485 -31.664402)
			(xy 29.561026 -31.664402) (xy 29.565097 -31.60878) (xy 29.577223 -31.554343) (xy 29.597146 -31.502252)
			(xy 29.624442 -31.453617) (xy 29.658528 -31.409474) (xy 29.698677 -31.370765) (xy 29.744035 -31.338314)
			(xy 29.793635 -31.312813) (xy 29.846419 -31.294806) (xy 29.901262 -31.284676) (xy 29.956996 -31.282639)
			(xy 30.012433 -31.288739) (xy 30.06639 -31.302845) (xy 30.117719 -31.324657) (xy 30.165325 -31.353711)
			(xy 30.208193 -31.389386) (xy 30.24541 -31.430923) (xy 30.276183 -31.477436) (xy 30.299855 -31.527933)
			(xy 30.315923 -31.58134) (xy 30.324043 -31.636516) (xy 30.324552 -31.664402) (xy 30.324043 -31.692288)
			(xy 30.315923 -31.747464) (xy 30.306983 -31.777178) (xy 30.8262 -31.777178) (xy 30.830271 -31.721556)
			(xy 30.842397 -31.667119) (xy 30.86232 -31.615028) (xy 30.889616 -31.566393) (xy 30.923702 -31.52225)
			(xy 30.963851 -31.483541) (xy 31.009209 -31.45109) (xy 31.058809 -31.425589) (xy 31.111593 -31.407582)
			(xy 31.166436 -31.397452) (xy 31.22217 -31.395415) (xy 31.277607 -31.401515) (xy 31.331564 -31.415621)
			(xy 31.382893 -31.437433) (xy 31.430499 -31.466487) (xy 31.473367 -31.502162) (xy 31.510584 -31.543699)
			(xy 31.541357 -31.590212) (xy 31.565029 -31.640709) (xy 31.581097 -31.694116) (xy 31.589217 -31.749292)
			(xy 31.589726 -31.777178) (xy 31.589217 -31.805064) (xy 31.581097 -31.86024) (xy 31.565029 -31.913647)
			(xy 31.541357 -31.964144) (xy 31.510584 -32.010657) (xy 31.473367 -32.052194) (xy 31.430499 -32.087869)
			(xy 31.382893 -32.116923) (xy 31.331564 -32.138735) (xy 31.277607 -32.152841) (xy 31.22217 -32.158941)
			(xy 31.166436 -32.156904) (xy 31.111593 -32.146774) (xy 31.058809 -32.128767) (xy 31.009209 -32.103266)
			(xy 30.963851 -32.070815) (xy 30.923702 -32.032106) (xy 30.889616 -31.987963) (xy 30.86232 -31.939328)
			(xy 30.842397 -31.887237) (xy 30.830271 -31.8328) (xy 30.8262 -31.777178) (xy 30.306983 -31.777178)
			(xy 30.299855 -31.800871) (xy 30.276183 -31.851368) (xy 30.24541 -31.897881) (xy 30.208193 -31.939418)
			(xy 30.165325 -31.975093) (xy 30.117719 -32.004147) (xy 30.06639 -32.025959) (xy 30.012433 -32.040065)
			(xy 29.956996 -32.046165) (xy 29.901262 -32.044128) (xy 29.846419 -32.033998) (xy 29.793635 -32.015991)
			(xy 29.744035 -31.99049) (xy 29.698677 -31.958039) (xy 29.658528 -31.91933) (xy 29.624442 -31.875187)
			(xy 29.597146 -31.826552) (xy 29.577223 -31.774461) (xy 29.565097 -31.720024) (xy 29.561026 -31.664402)
			(xy 29.044485 -31.664402) (xy 29.048455 -31.69138) (xy 29.048964 -31.719266) (xy 29.048455 -31.747152)
			(xy 29.040335 -31.802328) (xy 29.024267 -31.855735) (xy 29.000595 -31.906232) (xy 28.969822 -31.952745)
			(xy 28.932605 -31.994282) (xy 28.889737 -32.029957) (xy 28.842131 -32.059011) (xy 28.790802 -32.080823)
			(xy 28.736845 -32.094929) (xy 28.681408 -32.101029) (xy 28.625674 -32.098992) (xy 28.570831 -32.088862)
			(xy 28.518047 -32.070855) (xy 28.468447 -32.045354) (xy 28.423089 -32.012903) (xy 28.38294 -31.974194)
			(xy 28.348854 -31.930051) (xy 28.321558 -31.881416) (xy 28.301635 -31.829325) (xy 28.289509 -31.774888)
			(xy 28.285438 -31.719266) (xy 27.730511 -31.719266) (xy 27.713831 -31.754848) (xy 27.683058 -31.801361)
			(xy 27.645841 -31.842898) (xy 27.602973 -31.878573) (xy 27.555367 -31.907627) (xy 27.504038 -31.929439)
			(xy 27.450081 -31.943545) (xy 27.394644 -31.949645) (xy 27.33891 -31.947608) (xy 27.284067 -31.937478)
			(xy 27.231283 -31.919471) (xy 27.181683 -31.89397) (xy 27.136325 -31.861519) (xy 27.096176 -31.82281)
			(xy 27.06209 -31.778667) (xy 27.034794 -31.730032) (xy 27.014871 -31.677941) (xy 27.002745 -31.623504)
			(xy 26.998674 -31.567882) (xy 19.664976 -31.567882) (xy 19.68646 -31.595881) (xy 19.716444 -31.647815)
			(xy 19.739393 -31.703219) (xy 19.754914 -31.761144) (xy 19.762742 -31.8206) (xy 19.763232 -31.850584)
			(xy 19.763232 -32.714184) (xy 19.762742 -32.744168) (xy 19.754914 -32.803624) (xy 19.739393 -32.861549)
			(xy 19.716444 -32.916953) (xy 19.68646 -32.968887) (xy 19.649954 -33.016463) (xy 19.607549 -33.058868)
			(xy 19.559973 -33.095374) (xy 19.508039 -33.125358) (xy 19.452635 -33.148307) (xy 19.39471 -33.163828)
			(xy 19.335254 -33.171656) (xy 19.275286 -33.171656) (xy 19.21583 -33.163828) (xy 19.157905 -33.148307)
			(xy 19.102501 -33.125358) (xy 19.050567 -33.095374) (xy 19.002991 -33.058868) (xy 18.960586 -33.016463)
			(xy 18.92408 -32.968887) (xy 18.894096 -32.916953) (xy 18.871147 -32.861549) (xy 18.855626 -32.803624)
			(xy 18.847798 -32.744168) (xy 18.847308 -32.714184) (xy 14.318238 -32.714184) (xy 14.357096 -32.806386)
			(xy 14.359202 -32.810987) (xy 14.364962 -32.819304) (xy 14.368526 -32.822896) (xy 14.375638 -32.830008)
			(xy 14.385798 -32.833818) (xy 14.409839 -32.843539) (xy 14.455268 -32.868547) (xy 14.496894 -32.899473)
			(xy 14.533953 -32.935748) (xy 14.565762 -32.976704) (xy 14.591736 -33.021587) (xy 14.611397 -33.069573)
			(xy 14.624383 -33.119778) (xy 14.62786 -33.145476) (xy 14.629384 -33.160208) (xy 14.630654 -33.19018)
			(xy 14.630654 -33.190688) (xy 14.63026 -33.21659) (xy 14.623325 -33.267927) (xy 14.609498 -33.317851)
			(xy 14.599666 -33.341818) (xy 14.599666 -33.342072) (xy 14.596042 -33.351641) (xy 14.595906 -33.372084)
			(xy 14.599412 -33.381696) (xy 15.079304 -34.520886) (xy 21.489416 -34.520886) (xy 21.489416 -33.657286)
			(xy 21.489906 -33.627302) (xy 21.497734 -33.567846) (xy 21.513255 -33.509921) (xy 21.536204 -33.454517)
			(xy 21.566188 -33.402583) (xy 21.602694 -33.355007) (xy 21.645099 -33.312602) (xy 21.692675 -33.276096)
			(xy 21.744609 -33.246112) (xy 21.800013 -33.223163) (xy 21.857938 -33.207642) (xy 21.917394 -33.199814)
			(xy 21.977362 -33.199814) (xy 22.036818 -33.207642) (xy 22.094743 -33.223163) (xy 22.150147 -33.246112)
			(xy 22.202081 -33.276096) (xy 22.249657 -33.312602) (xy 22.292062 -33.355007) (xy 22.328568 -33.402583)
			(xy 22.358552 -33.454517) (xy 22.381501 -33.509921) (xy 22.397022 -33.567846) (xy 22.40485 -33.627302)
			(xy 22.40534 -33.657286) (xy 22.40534 -34.520886) (xy 22.40485 -34.55087) (xy 22.397022 -34.610326)
			(xy 22.381501 -34.668251) (xy 22.358552 -34.723655) (xy 22.328568 -34.775589) (xy 22.292062 -34.823165)
			(xy 22.249657 -34.86557) (xy 22.202081 -34.902076) (xy 22.150147 -34.93206) (xy 22.094743 -34.955009)
			(xy 22.036818 -34.97053) (xy 21.977362 -34.978358) (xy 21.917394 -34.978358) (xy 21.857938 -34.97053)
			(xy 21.800013 -34.955009) (xy 21.744609 -34.93206) (xy 21.692675 -34.902076) (xy 21.645099 -34.86557)
			(xy 21.602694 -34.823165) (xy 21.566188 -34.775589) (xy 21.536204 -34.723655) (xy 21.513255 -34.668251)
			(xy 21.497734 -34.610326) (xy 21.489906 -34.55087) (xy 21.489416 -34.520886) (xy 15.079304 -34.520886)
			(xy 15.392705 -35.264852) (xy 29.902402 -35.264852) (xy 29.906473 -35.20923) (xy 29.918599 -35.154793)
			(xy 29.938522 -35.102702) (xy 29.965818 -35.054067) (xy 29.999904 -35.009924) (xy 30.040053 -34.971215)
			(xy 30.085411 -34.938764) (xy 30.135011 -34.913263) (xy 30.187795 -34.895256) (xy 30.242638 -34.885126)
			(xy 30.298372 -34.883089) (xy 30.353809 -34.889189) (xy 30.407766 -34.903295) (xy 30.459095 -34.925107)
			(xy 30.506701 -34.954161) (xy 30.549569 -34.989836) (xy 30.586786 -35.031373) (xy 30.617559 -35.077886)
			(xy 30.641231 -35.128383) (xy 30.657299 -35.18179) (xy 30.665419 -35.236966) (xy 30.665928 -35.264852)
			(xy 30.665419 -35.292738) (xy 30.657299 -35.347914) (xy 30.641231 -35.401321) (xy 30.617559 -35.451818)
			(xy 30.586786 -35.498331) (xy 30.549569 -35.539868) (xy 30.506701 -35.575543) (xy 30.459095 -35.604597)
			(xy 30.407766 -35.626409) (xy 30.353809 -35.640515) (xy 30.298372 -35.646615) (xy 30.242638 -35.644578)
			(xy 30.187795 -35.634448) (xy 30.135011 -35.616441) (xy 30.085411 -35.59094) (xy 30.040053 -35.558489)
			(xy 29.999904 -35.51978) (xy 29.965818 -35.475637) (xy 29.938522 -35.427002) (xy 29.918599 -35.374911)
			(xy 29.906473 -35.320474) (xy 29.902402 -35.264852) (xy 15.392705 -35.264852) (xy 15.650467 -35.876738)
			(xy 18.717258 -35.876738) (xy 18.721329 -35.821116) (xy 18.733455 -35.766679) (xy 18.753378 -35.714588)
			(xy 18.780674 -35.665953) (xy 18.81476 -35.62181) (xy 18.854909 -35.583101) (xy 18.900267 -35.55065)
			(xy 18.949867 -35.525149) (xy 19.002651 -35.507142) (xy 19.057494 -35.497012) (xy 19.113228 -35.494975)
			(xy 19.168665 -35.501075) (xy 19.222622 -35.515181) (xy 19.273951 -35.536993) (xy 19.321557 -35.566047)
			(xy 19.364425 -35.601722) (xy 19.401642 -35.643259) (xy 19.432415 -35.689772) (xy 19.456087 -35.740269)
			(xy 19.472155 -35.793676) (xy 19.480275 -35.848852) (xy 19.480784 -35.876738) (xy 22.789388 -35.876738)
			(xy 22.789874 -35.849487) (xy 22.79763 -35.795539) (xy 22.812985 -35.743244) (xy 22.835627 -35.693667)
			(xy 22.865093 -35.647817) (xy 22.900784 -35.606626) (xy 22.941975 -35.570935) (xy 22.987825 -35.541469)
			(xy 23.037402 -35.518827) (xy 23.089697 -35.503472) (xy 23.143645 -35.495716) (xy 23.198147 -35.495716)
			(xy 23.252095 -35.503472) (xy 23.30439 -35.518827) (xy 23.353967 -35.541469) (xy 23.399817 -35.570935)
			(xy 23.441008 -35.606626) (xy 23.476699 -35.647817) (xy 23.506165 -35.693667) (xy 23.528807 -35.743244)
			(xy 23.544162 -35.795539) (xy 23.551918 -35.849487) (xy 23.552404 -35.876738) (xy 23.551879 -35.905485)
			(xy 23.543214 -35.962323) (xy 23.526116 -36.017217) (xy 23.500973 -36.068923) (xy 23.485094 -36.092892)
			(xy 23.477483 -36.104722) (xy 23.468486 -36.131366) (xy 23.467098 -36.159453) (xy 23.473425 -36.186853)
			(xy 23.486986 -36.211489) (xy 23.506754 -36.23149) (xy 23.531228 -36.24534) (xy 23.544784 -36.249102)
			(xy 23.57205 -36.256313) (xy 23.624227 -36.277717) (xy 23.672687 -36.306568) (xy 23.716372 -36.342237)
			(xy 23.754332 -36.383948) (xy 23.785739 -36.43079) (xy 23.796546 -36.453572) (xy 23.928576 -36.453572)
			(xy 23.932647 -36.39795) (xy 23.944773 -36.343513) (xy 23.964696 -36.291422) (xy 23.991992 -36.242787)
			(xy 24.026078 -36.198644) (xy 24.066227 -36.159935) (xy 24.111585 -36.127484) (xy 24.161185 -36.101983)
			(xy 24.213969 -36.083976) (xy 24.268812 -36.073846) (xy 24.324546 -36.071809) (xy 24.379983 -36.077909)
			(xy 24.43394 -36.092015) (xy 24.485269 -36.113827) (xy 24.532875 -36.142881) (xy 24.575743 -36.178556)
			(xy 24.61296 -36.220093) (xy 24.643733 -36.266606) (xy 24.653269 -36.286948) (xy 31.200342 -36.286948)
			(xy 31.204413 -36.231326) (xy 31.216539 -36.176889) (xy 31.236462 -36.124798) (xy 31.263758 -36.076163)
			(xy 31.297844 -36.03202) (xy 31.337993 -35.993311) (xy 31.383351 -35.96086) (xy 31.432951 -35.935359)
			(xy 31.485735 -35.917352) (xy 31.540578 -35.907222) (xy 31.596312 -35.905185) (xy 31.651749 -35.911285)
			(xy 31.705706 -35.925391) (xy 31.757035 -35.947203) (xy 31.804641 -35.976257) (xy 31.847509 -36.011932)
			(xy 31.884726 -36.053469) (xy 31.915499 -36.099982) (xy 31.939171 -36.150479) (xy 31.955239 -36.203886)
			(xy 31.963359 -36.259062) (xy 31.963868 -36.286948) (xy 31.963359 -36.314834) (xy 31.955239 -36.37001)
			(xy 31.939171 -36.423417) (xy 31.915499 -36.473914) (xy 31.884726 -36.520427) (xy 31.847509 -36.561964)
			(xy 31.804641 -36.597639) (xy 31.757035 -36.626693) (xy 31.705706 -36.648505) (xy 31.651749 -36.662611)
			(xy 31.596312 -36.668711) (xy 31.540578 -36.666674) (xy 31.485735 -36.656544) (xy 31.432951 -36.638537)
			(xy 31.383351 -36.613036) (xy 31.337993 -36.580585) (xy 31.297844 -36.541876) (xy 31.263758 -36.497733)
			(xy 31.236462 -36.449098) (xy 31.216539 -36.397007) (xy 31.204413 -36.34257) (xy 31.200342 -36.286948)
			(xy 24.653269 -36.286948) (xy 24.667405 -36.317103) (xy 24.683473 -36.37051) (xy 24.691593 -36.425686)
			(xy 24.692102 -36.453572) (xy 24.691593 -36.481458) (xy 24.683473 -36.536634) (xy 24.667405 -36.590041)
			(xy 24.643733 -36.640538) (xy 24.61296 -36.687051) (xy 24.575743 -36.728588) (xy 24.532875 -36.764263)
			(xy 24.485269 -36.793317) (xy 24.43394 -36.815129) (xy 24.379983 -36.829235) (xy 24.324546 -36.835335)
			(xy 24.268812 -36.833298) (xy 24.213969 -36.823168) (xy 24.161185 -36.805161) (xy 24.111585 -36.77966)
			(xy 24.066227 -36.747209) (xy 24.026078 -36.7085) (xy 23.991992 -36.664357) (xy 23.964696 -36.615722)
			(xy 23.944773 -36.563631) (xy 23.932647 -36.509194) (xy 23.928576 -36.453572) (xy 23.796546 -36.453572)
			(xy 23.80991 -36.481746) (xy 23.826318 -36.535704) (xy 23.834606 -36.591489) (xy 23.835106 -36.619688)
			(xy 23.83462 -36.646939) (xy 23.826864 -36.700887) (xy 23.811509 -36.753182) (xy 23.788867 -36.802759)
			(xy 23.759401 -36.848609) (xy 23.72371 -36.8898) (xy 23.682519 -36.925491) (xy 23.636669 -36.954957)
			(xy 23.587092 -36.977599) (xy 23.534797 -36.992954) (xy 23.480849 -37.00071) (xy 23.426347 -37.00071)
			(xy 23.372399 -36.992954) (xy 23.320104 -36.977599) (xy 23.270527 -36.954957) (xy 23.224677 -36.925491)
			(xy 23.183486 -36.8898) (xy 23.147795 -36.848609) (xy 23.118329 -36.802759) (xy 23.095687 -36.753182)
			(xy 23.080332 -36.700887) (xy 23.072576 -36.646939) (xy 23.07209 -36.619688) (xy 23.072629 -36.590941)
			(xy 23.08129 -36.534104) (xy 23.098384 -36.47921) (xy 23.123523 -36.427504) (xy 23.1394 -36.403534)
			(xy 23.146982 -36.391686) (xy 23.155984 -36.365049) (xy 23.157376 -36.336966) (xy 23.151054 -36.309568)
			(xy 23.137497 -36.284935) (xy 23.117734 -36.264935) (xy 23.093264 -36.251086) (xy 23.07971 -36.247324)
			(xy 23.05245 -36.240094) (xy 23.000274 -36.21869) (xy 22.951816 -36.189841) (xy 22.908131 -36.154174)
			(xy 22.870172 -36.112467) (xy 22.838764 -36.065626) (xy 22.814591 -36.014674) (xy 22.798181 -35.960719)
			(xy 22.78989 -35.904936) (xy 22.789388 -35.876738) (xy 19.480784 -35.876738) (xy 19.480275 -35.904624)
			(xy 19.472155 -35.9598) (xy 19.456087 -36.013207) (xy 19.432415 -36.063704) (xy 19.401642 -36.110217)
			(xy 19.364425 -36.151754) (xy 19.321557 -36.187429) (xy 19.273951 -36.216483) (xy 19.222622 -36.238295)
			(xy 19.168665 -36.252401) (xy 19.113228 -36.258501) (xy 19.057494 -36.256464) (xy 19.002651 -36.246334)
			(xy 18.949867 -36.228327) (xy 18.900267 -36.202826) (xy 18.854909 -36.170375) (xy 18.81476 -36.131666)
			(xy 18.780674 -36.087523) (xy 18.753378 -36.038888) (xy 18.733455 -35.986797) (xy 18.721329 -35.93236)
			(xy 18.717258 -35.876738) (xy 15.650467 -35.876738) (xy 15.917216 -36.50996) (xy 20.613876 -36.50996)
			(xy 20.617947 -36.454338) (xy 20.630073 -36.399901) (xy 20.649996 -36.34781) (xy 20.677292 -36.299175)
			(xy 20.711378 -36.255032) (xy 20.751527 -36.216323) (xy 20.796885 -36.183872) (xy 20.846485 -36.158371)
			(xy 20.899269 -36.140364) (xy 20.954112 -36.130234) (xy 21.009846 -36.128197) (xy 21.065283 -36.134297)
			(xy 21.11924 -36.148403) (xy 21.170569 -36.170215) (xy 21.218175 -36.199269) (xy 21.261043 -36.234944)
			(xy 21.29826 -36.276481) (xy 21.329033 -36.322994) (xy 21.352705 -36.373491) (xy 21.368773 -36.426898)
			(xy 21.376893 -36.482074) (xy 21.377402 -36.50996) (xy 21.376893 -36.537846) (xy 21.368773 -36.593022)
			(xy 21.352705 -36.646429) (xy 21.329033 -36.696926) (xy 21.29826 -36.743439) (xy 21.261043 -36.784976)
			(xy 21.218175 -36.820651) (xy 21.170569 -36.849705) (xy 21.11924 -36.871517) (xy 21.065283 -36.885623)
			(xy 21.009846 -36.891723) (xy 20.954112 -36.889686) (xy 20.899269 -36.879556) (xy 20.846485 -36.861549)
			(xy 20.796885 -36.836048) (xy 20.751527 -36.803597) (xy 20.711378 -36.764888) (xy 20.677292 -36.720745)
			(xy 20.649996 -36.67211) (xy 20.630073 -36.620019) (xy 20.617947 -36.565582) (xy 20.613876 -36.50996)
			(xy 15.917216 -36.50996) (xy 16.250412 -37.300916) (xy 16.269133 -37.346963) (xy 16.298411 -37.44196)
			(xy 16.305119 -37.47516) (xy 17.75917 -37.47516) (xy 17.763241 -37.419538) (xy 17.775367 -37.365101)
			(xy 17.79529 -37.31301) (xy 17.822586 -37.264375) (xy 17.856672 -37.220232) (xy 17.896821 -37.181523)
			(xy 17.942179 -37.149072) (xy 17.991779 -37.123571) (xy 18.044563 -37.105564) (xy 18.099406 -37.095434)
			(xy 18.15514 -37.093397) (xy 18.210577 -37.099497) (xy 18.264534 -37.113603) (xy 18.315863 -37.135415)
			(xy 18.363469 -37.164469) (xy 18.406337 -37.200144) (xy 18.443554 -37.241681) (xy 18.474327 -37.288194)
			(xy 18.497999 -37.338691) (xy 18.514067 -37.392098) (xy 18.522187 -37.447274) (xy 18.522696 -37.47516)
			(xy 18.522187 -37.503046) (xy 18.514067 -37.558222) (xy 18.497999 -37.611629) (xy 18.474327 -37.662126)
			(xy 18.474174 -37.662358) (xy 19.948396 -37.662358) (xy 19.952467 -37.606736) (xy 19.964593 -37.552299)
			(xy 19.984516 -37.500208) (xy 20.011812 -37.451573) (xy 20.045898 -37.40743) (xy 20.086047 -37.368721)
			(xy 20.131405 -37.33627) (xy 20.181005 -37.310769) (xy 20.233789 -37.292762) (xy 20.288632 -37.282632)
			(xy 20.344366 -37.280595) (xy 20.399803 -37.286695) (xy 20.45376 -37.300801) (xy 20.505089 -37.322613)
			(xy 20.552695 -37.351667) (xy 20.595563 -37.387342) (xy 20.63278 -37.428879) (xy 20.663553 -37.475392)
			(xy 20.687225 -37.525889) (xy 20.703293 -37.579296) (xy 20.711413 -37.634472) (xy 20.711922 -37.662358)
			(xy 20.711413 -37.690244) (xy 20.703293 -37.74542) (xy 20.694659 -37.774118) (xy 31.464756 -37.774118)
			(xy 31.468827 -37.718496) (xy 31.480953 -37.664059) (xy 31.500876 -37.611968) (xy 31.528172 -37.563333)
			(xy 31.562258 -37.51919) (xy 31.602407 -37.480481) (xy 31.647765 -37.44803) (xy 31.697365 -37.422529)
			(xy 31.750149 -37.404522) (xy 31.804992 -37.394392) (xy 31.860726 -37.392355) (xy 31.916163 -37.398455)
			(xy 31.97012 -37.412561) (xy 32.021449 -37.434373) (xy 32.069055 -37.463427) (xy 32.111923 -37.499102)
			(xy 32.14914 -37.540639) (xy 32.179913 -37.587152) (xy 32.203585 -37.637649) (xy 32.219653 -37.691056)
			(xy 32.227773 -37.746232) (xy 32.228282 -37.774118) (xy 32.227773 -37.802004) (xy 32.219653 -37.85718)
			(xy 32.203585 -37.910587) (xy 32.179913 -37.961084) (xy 32.14914 -38.007597) (xy 32.111923 -38.049134)
			(xy 32.069055 -38.084809) (xy 32.021449 -38.113863) (xy 31.97012 -38.135675) (xy 31.916163 -38.149781)
			(xy 31.860726 -38.155881) (xy 31.804992 -38.153844) (xy 31.750149 -38.143714) (xy 31.697365 -38.125707)
			(xy 31.647765 -38.100206) (xy 31.602407 -38.067755) (xy 31.562258 -38.029046) (xy 31.528172 -37.984903)
			(xy 31.500876 -37.936268) (xy 31.480953 -37.884177) (xy 31.468827 -37.82974) (xy 31.464756 -37.774118)
			(xy 20.694659 -37.774118) (xy 20.687225 -37.798827) (xy 20.663553 -37.849324) (xy 20.63278 -37.895837)
			(xy 20.595563 -37.937374) (xy 20.552695 -37.973049) (xy 20.505089 -38.002103) (xy 20.45376 -38.023915)
			(xy 20.399803 -38.038021) (xy 20.344366 -38.044121) (xy 20.288632 -38.042084) (xy 20.233789 -38.031954)
			(xy 20.181005 -38.013947) (xy 20.131405 -37.988446) (xy 20.086047 -37.955995) (xy 20.045898 -37.917286)
			(xy 20.011812 -37.873143) (xy 19.984516 -37.824508) (xy 19.964593 -37.772417) (xy 19.952467 -37.71798)
			(xy 19.948396 -37.662358) (xy 18.474174 -37.662358) (xy 18.443554 -37.708639) (xy 18.406337 -37.750176)
			(xy 18.363469 -37.785851) (xy 18.315863 -37.814905) (xy 18.264534 -37.836717) (xy 18.210577 -37.850823)
			(xy 18.15514 -37.856923) (xy 18.099406 -37.854886) (xy 18.044563 -37.844756) (xy 17.991779 -37.826749)
			(xy 17.942179 -37.801248) (xy 17.896821 -37.768797) (xy 17.856672 -37.730088) (xy 17.822586 -37.685945)
			(xy 17.79529 -37.63731) (xy 17.775367 -37.585219) (xy 17.763241 -37.530782) (xy 17.75917 -37.47516)
			(xy 16.305119 -37.47516) (xy 16.318099 -37.539397) (xy 16.328001 -37.638309) (xy 16.328644 -37.688012)
			(xy 16.328644 -37.704522) (xy 16.328644 -37.705538) (xy 16.311644 -38.729948) (xy 23.70102 -38.729948)
			(xy 23.70102 -38.675452) (xy 23.708776 -38.621511) (xy 23.724129 -38.569222) (xy 23.746767 -38.519651)
			(xy 23.776229 -38.473806) (xy 23.811916 -38.432621) (xy 23.853101 -38.396933) (xy 23.898946 -38.36747)
			(xy 23.948517 -38.344831) (xy 24.000805 -38.329477) (xy 24.054746 -38.321721) (xy 24.081994 -38.321234)
			(xy 24.110299 -38.321713) (xy 24.166288 -38.330064) (xy 24.220429 -38.3466) (xy 24.27153 -38.370957)
			(xy 24.31847 -38.4026) (xy 24.360216 -38.440834) (xy 24.395854 -38.484818) (xy 24.41067 -38.50894)
			(xy 24.41834 -38.520924) (xy 24.438944 -38.540523) (xy 24.46416 -38.553667) (xy 24.492027 -38.559332)
			(xy 24.520374 -38.557078) (xy 24.546994 -38.54708) (xy 24.569817 -38.530116) (xy 24.578818 -38.5191)
			(xy 24.596999 -38.49622) (xy 24.639163 -38.455756) (xy 24.687 -38.422189) (xy 24.739393 -38.396303)
			(xy 24.795118 -38.378701) (xy 24.852875 -38.369796) (xy 24.882094 -38.36924) (xy 24.909345 -38.36973)
			(xy 24.963292 -38.377487) (xy 25.015586 -38.392842) (xy 25.065162 -38.415484) (xy 25.111012 -38.44495)
			(xy 25.152202 -38.480641) (xy 25.187893 -38.521831) (xy 25.217358 -38.567681) (xy 25.239999 -38.617258)
			(xy 25.255354 -38.669552) (xy 25.26311 -38.723499) (xy 25.26311 -38.778001) (xy 25.255354 -38.831948)
			(xy 25.239999 -38.884242) (xy 25.217358 -38.933819) (xy 25.187893 -38.979669) (xy 25.152202 -39.020859)
			(xy 25.111012 -39.05655) (xy 25.065162 -39.086016) (xy 25.015586 -39.108658) (xy 24.963292 -39.124013)
			(xy 24.909345 -39.13177) (xy 24.882094 -39.132256) (xy 24.853789 -39.131792) (xy 24.797798 -39.123438)
			(xy 24.743657 -39.1069) (xy 24.692556 -39.08254) (xy 24.645616 -39.050895) (xy 24.60387 -39.01266)
			(xy 24.568234 -38.968673) (xy 24.553418 -38.94455) (xy 24.545763 -38.932555) (xy 24.525156 -38.912957)
			(xy 24.499936 -38.899815) (xy 24.472067 -38.894152) (xy 24.443718 -38.896408) (xy 24.417096 -38.906408)
			(xy 24.394272 -38.923373) (xy 24.38527 -38.93439) (xy 24.367093 -38.957274) (xy 24.324929 -38.997738)
			(xy 24.277091 -39.031305) (xy 24.224697 -39.057191) (xy 24.168971 -39.074791) (xy 24.111214 -39.083694)
			(xy 24.081994 -39.08425) (xy 24.054746 -39.083679) (xy 24.000805 -39.075923) (xy 23.948517 -39.060569)
			(xy 23.898946 -39.03793) (xy 23.853101 -39.008467) (xy 23.811916 -38.972779) (xy 23.776229 -38.931594)
			(xy 23.746767 -38.885749) (xy 23.724129 -38.836178) (xy 23.708776 -38.783889) (xy 23.70102 -38.729948)
			(xy 16.311644 -38.729948) (xy 16.309086 -38.884098) (xy 16.304006 -39.18585) (xy 16.302651 -39.233199)
			(xy 16.292095 -39.327338) (xy 16.282924 -39.37381) (xy 16.157788 -39.97198) (xy 25.895806 -39.97198)
			(xy 25.899877 -39.916358) (xy 25.912003 -39.861921) (xy 25.931926 -39.80983) (xy 25.959222 -39.761195)
			(xy 25.993308 -39.717052) (xy 26.033457 -39.678343) (xy 26.078815 -39.645892) (xy 26.128415 -39.620391)
			(xy 26.181199 -39.602384) (xy 26.236042 -39.592254) (xy 26.291776 -39.590217) (xy 26.347213 -39.596317)
			(xy 26.40117 -39.610423) (xy 26.452499 -39.632235) (xy 26.500105 -39.661289) (xy 26.542973 -39.696964)
			(xy 26.58019 -39.738501) (xy 26.610963 -39.785014) (xy 26.634635 -39.835511) (xy 26.650703 -39.888918)
			(xy 26.658823 -39.944094) (xy 26.659332 -39.97198) (xy 26.658823 -39.999866) (xy 26.650703 -40.055042)
			(xy 26.634635 -40.108449) (xy 26.610963 -40.158946) (xy 26.58019 -40.205459) (xy 26.542973 -40.246996)
			(xy 26.500105 -40.282671) (xy 26.452499 -40.311725) (xy 26.40117 -40.333537) (xy 26.347213 -40.347643)
			(xy 26.291776 -40.353743) (xy 26.236042 -40.351706) (xy 26.181199 -40.341576) (xy 26.128415 -40.323569)
			(xy 26.078815 -40.298068) (xy 26.033457 -40.265617) (xy 25.993308 -40.226908) (xy 25.959222 -40.182765)
			(xy 25.931926 -40.13413) (xy 25.912003 -40.082039) (xy 25.899877 -40.027602) (xy 25.895806 -39.97198)
			(xy 16.157788 -39.97198) (xy 16.103854 -40.22979) (xy 15.993618 -40.756078) (xy 15.99301 -40.760903)
			(xy 15.9934 -40.770619) (xy 15.99438 -40.775382) (xy 15.994634 -40.776398) (xy 15.996592 -40.783451)
			(xy 16.003955 -40.796095) (xy 16.009112 -40.80129) (xy 16.072104 -40.860218) (xy 16.081756 -40.86733)
			(xy 16.090765 -40.871874) (xy 16.110769 -40.874352) (xy 16.120618 -40.872156) (xy 16.126968 -40.870378)
			(xy 16.150923 -40.864512) (xy 16.199844 -40.858265) (xy 16.224504 -40.857932) (xy 16.225266 -40.857932)
			(xy 16.254 -40.858481) (xy 16.310824 -40.867069) (xy 16.365734 -40.884028) (xy 16.417504 -40.908979)
			(xy 16.464978 -40.941366) (xy 16.486378 -40.960548) (xy 16.490442 -40.964358) (xy 16.500094 -40.969946)
			(xy 16.51127 -40.974264) (xy 16.518382 -40.976042) (xy 16.525494 -40.976804) (xy 16.590772 -40.976804)
			(xy 16.596614 -40.97655) (xy 16.61525 -40.956912) (xy 16.656991 -40.922436) (xy 16.703079 -40.894031)
			(xy 16.752636 -40.872237) (xy 16.804721 -40.857469) (xy 16.858343 -40.850008) (xy 16.885412 -40.84955)
			(xy 16.913409 -40.85005) (xy 16.968831 -40.85802) (xy 17.022556 -40.873797) (xy 17.073489 -40.897058)
			(xy 17.120593 -40.927331) (xy 17.162909 -40.964) (xy 17.199576 -41.006317) (xy 17.229847 -41.053422)
			(xy 17.253107 -41.104355) (xy 17.268882 -41.15808) (xy 17.276851 -41.213503) (xy 17.276851 -41.269497)
			(xy 17.268882 -41.32492) (xy 17.253107 -41.378645) (xy 17.229847 -41.429578) (xy 17.199576 -41.476683)
			(xy 17.162909 -41.519) (xy 17.120593 -41.555669) (xy 17.073489 -41.585942) (xy 17.022556 -41.609203)
			(xy 16.968831 -41.62498) (xy 16.913409 -41.63295) (xy 16.885412 -41.633394) (xy 16.858342 -41.632938)
			(xy 16.804719 -41.625486) (xy 16.752632 -41.610721) (xy 16.703074 -41.588925) (xy 16.656989 -41.560514)
			(xy 16.615255 -41.526028) (xy 16.596614 -41.506394) (xy 16.590772 -41.50614) (xy 16.527272 -41.50614)
			(xy 16.515334 -41.507664) (xy 16.509238 -41.509188) (xy 16.497046 -41.514268) (xy 16.49222 -41.517062)
			(xy 16.487902 -41.520872) (xy 16.48714 -41.521634) (xy 16.465687 -41.540955) (xy 16.41807 -41.573597)
			(xy 16.366104 -41.598745) (xy 16.310959 -41.615833) (xy 16.253878 -41.624474) (xy 16.225012 -41.625012)
			(xy 16.224758 -41.625012) (xy 16.198419 -41.624579) (xy 16.146237 -41.617374) (xy 16.095532 -41.60309)
			(xy 16.047262 -41.581998) (xy 16.002334 -41.554495) (xy 15.98168 -41.538144) (xy 15.981172 -41.537636)
			(xy 15.975949 -41.533659) (xy 15.963986 -41.528262) (xy 15.95755 -41.526968) (xy 15.945358 -41.524936)
			(xy 15.850616 -41.55821) (xy 15.842552 -41.561431) (xy 15.82906 -41.572344) (xy 15.819977 -41.58713)
			(xy 15.81785 -41.595548) (xy 15.734538 -41.993566) (xy 15.68958 -42.207942) (xy 15.459706 -43.305222)
			(xy 18.307304 -43.305222) (xy 18.307782 -43.277852) (xy 18.315597 -43.223674) (xy 18.331083 -43.171171)
			(xy 18.353922 -43.121424) (xy 18.383644 -43.075456) (xy 18.401284 -43.054524) (xy 18.401538 -43.05427)
			(xy 18.407106 -43.047171) (xy 18.413363 -43.030264) (xy 18.41373 -43.02125) (xy 18.41373 -42.954194)
			(xy 18.413369 -42.945178) (xy 18.407123 -42.928261) (xy 18.401538 -42.921174) (xy 18.401284 -42.921174)
			(xy 18.401284 -42.92092) (xy 18.383638 -42.899993) (xy 18.353928 -42.854019) (xy 18.331094 -42.80427)
			(xy 18.315604 -42.751768) (xy 18.307777 -42.697591) (xy 18.307304 -42.670222) (xy 18.30784 -42.641484)
			(xy 18.316459 -42.584657) (xy 18.333507 -42.529766) (xy 18.358595 -42.478054) (xy 18.391158 -42.430691)
			(xy 18.410428 -42.409364) (xy 18.417032 -42.402506) (xy 18.424144 -42.384472) (xy 18.424144 -42.295572)
			(xy 18.417032 -42.277538) (xy 18.410428 -42.27068) (xy 18.391179 -42.249334) (xy 18.358613 -42.201975)
			(xy 18.333519 -42.150267) (xy 18.316468 -42.095379) (xy 18.307843 -42.038554) (xy 18.30784 -41.981078)
			(xy 18.31646 -41.924253) (xy 18.333508 -41.869363) (xy 18.358596 -41.817653) (xy 18.391159 -41.770291)
			(xy 18.410428 -41.748964) (xy 18.417032 -41.742106) (xy 18.424144 -41.724072) (xy 18.424144 -41.635172)
			(xy 18.417032 -41.617138) (xy 18.410428 -41.61028) (xy 18.391166 -41.588945) (xy 18.358599 -41.541585)
			(xy 18.333505 -41.489876) (xy 18.316452 -41.434987) (xy 18.307827 -41.37816) (xy 18.307304 -41.349422)
			(xy 18.30779 -41.322171) (xy 18.315546 -41.268223) (xy 18.330901 -41.215928) (xy 18.353543 -41.166351)
			(xy 18.383009 -41.120501) (xy 18.4187 -41.07931) (xy 18.459891 -41.043619) (xy 18.505741 -41.014153)
			(xy 18.555318 -40.991511) (xy 18.607613 -40.976156) (xy 18.661561 -40.9684) (xy 18.716063 -40.9684)
			(xy 18.739184 -40.971724) (xy 26.594052 -40.971724) (xy 26.598123 -40.916102) (xy 26.610249 -40.861665)
			(xy 26.630172 -40.809574) (xy 26.657468 -40.760939) (xy 26.691554 -40.716796) (xy 26.731703 -40.678087)
			(xy 26.777061 -40.645636) (xy 26.826661 -40.620135) (xy 26.879445 -40.602128) (xy 26.934288 -40.591998)
			(xy 26.990022 -40.589961) (xy 27.045459 -40.596061) (xy 27.099416 -40.610167) (xy 27.150745 -40.631979)
			(xy 27.198351 -40.661033) (xy 27.241219 -40.696708) (xy 27.278436 -40.738245) (xy 27.309209 -40.784758)
			(xy 27.332881 -40.835255) (xy 27.348949 -40.888662) (xy 27.357069 -40.943838) (xy 27.357578 -40.971724)
			(xy 27.357069 -40.99961) (xy 27.348949 -41.054786) (xy 27.332881 -41.108193) (xy 27.309209 -41.15869)
			(xy 27.278436 -41.205203) (xy 27.241219 -41.24674) (xy 27.198351 -41.282415) (xy 27.150745 -41.311469)
			(xy 27.099416 -41.333281) (xy 27.045459 -41.347387) (xy 26.990022 -41.353487) (xy 26.934288 -41.35145)
			(xy 26.879445 -41.34132) (xy 26.826661 -41.323313) (xy 26.777061 -41.297812) (xy 26.731703 -41.265361)
			(xy 26.691554 -41.226652) (xy 26.657468 -41.182509) (xy 26.630172 -41.133874) (xy 26.610249 -41.081783)
			(xy 26.598123 -41.027346) (xy 26.594052 -40.971724) (xy 18.739184 -40.971724) (xy 18.770011 -40.976156)
			(xy 18.822306 -40.991511) (xy 18.871883 -41.014153) (xy 18.917733 -41.043619) (xy 18.958924 -41.07931)
			(xy 18.994615 -41.120501) (xy 19.024081 -41.166351) (xy 19.046723 -41.215928) (xy 19.062078 -41.268223)
			(xy 19.069834 -41.322171) (xy 19.07032 -41.349422) (xy 19.069804 -41.378161) (xy 19.061179 -41.434989)
			(xy 19.044127 -41.489879) (xy 19.019033 -41.541591) (xy 18.986467 -41.588953) (xy 18.967196 -41.61028)
			(xy 18.960592 -41.617138) (xy 18.95348 -41.635172) (xy 18.95348 -41.724072) (xy 18.960592 -41.742106)
			(xy 18.967196 -41.748964) (xy 18.986488 -41.770272) (xy 19.019051 -41.817639) (xy 19.04414 -41.869353)
			(xy 19.061187 -41.924247) (xy 19.069807 -41.981076) (xy 19.069805 -42.038556) (xy 19.06118 -42.095385)
			(xy 19.044128 -42.150276) (xy 19.019034 -42.201989) (xy 18.986468 -42.249353) (xy 18.967196 -42.27068)
			(xy 18.960592 -42.277538) (xy 18.95348 -42.295572) (xy 18.95348 -42.384472) (xy 18.960592 -42.402506)
			(xy 18.967196 -42.409364) (xy 18.986466 -42.430692) (xy 19.019035 -42.478053) (xy 19.044128 -42.529764)
			(xy 19.061179 -42.584655) (xy 19.0698 -42.641483) (xy 19.07032 -42.670222) (xy 19.069886 -42.697594)
			(xy 19.062064 -42.751775) (xy 19.046568 -42.804279) (xy 19.02601 -42.849038) (xy 20.892006 -42.849038)
			(xy 20.896077 -42.793416) (xy 20.908203 -42.738979) (xy 20.928126 -42.686888) (xy 20.955422 -42.638253)
			(xy 20.989508 -42.59411) (xy 21.029657 -42.555401) (xy 21.075015 -42.52295) (xy 21.124615 -42.497449)
			(xy 21.177399 -42.479442) (xy 21.232242 -42.469312) (xy 21.287976 -42.467275) (xy 21.343413 -42.473375)
			(xy 21.39737 -42.487481) (xy 21.448699 -42.509293) (xy 21.496305 -42.538347) (xy 21.539173 -42.574022)
			(xy 21.57639 -42.615559) (xy 21.607163 -42.662072) (xy 21.630835 -42.712569) (xy 21.646903 -42.765976)
			(xy 21.655023 -42.821152) (xy 21.655384 -42.84091) (xy 26.933142 -42.84091) (xy 26.937213 -42.785288)
			(xy 26.949339 -42.730851) (xy 26.969262 -42.67876) (xy 26.996558 -42.630125) (xy 27.030644 -42.585982)
			(xy 27.070793 -42.547273) (xy 27.116151 -42.514822) (xy 27.165751 -42.489321) (xy 27.218535 -42.471314)
			(xy 27.273378 -42.461184) (xy 27.329112 -42.459147) (xy 27.384549 -42.465247) (xy 27.438506 -42.479353)
			(xy 27.489835 -42.501165) (xy 27.537441 -42.530219) (xy 27.580309 -42.565894) (xy 27.617526 -42.607431)
			(xy 27.648299 -42.653944) (xy 27.671971 -42.704441) (xy 27.688039 -42.757848) (xy 27.696159 -42.813024)
			(xy 27.696668 -42.84091) (xy 27.696159 -42.868796) (xy 27.688039 -42.923972) (xy 27.671971 -42.977379)
			(xy 27.648299 -43.027876) (xy 27.617526 -43.074389) (xy 27.580309 -43.115926) (xy 27.537441 -43.151601)
			(xy 27.489835 -43.180655) (xy 27.438506 -43.202467) (xy 27.384549 -43.216573) (xy 27.329112 -43.222673)
			(xy 27.273378 -43.220636) (xy 27.218535 -43.210506) (xy 27.165751 -43.192499) (xy 27.116151 -43.166998)
			(xy 27.070793 -43.134547) (xy 27.030644 -43.095838) (xy 26.996558 -43.051695) (xy 26.969262 -43.00306)
			(xy 26.949339 -42.950969) (xy 26.937213 -42.896532) (xy 26.933142 -42.84091) (xy 21.655384 -42.84091)
			(xy 21.655532 -42.849038) (xy 21.655023 -42.876924) (xy 21.646903 -42.9321) (xy 21.630835 -42.985507)
			(xy 21.607163 -43.036004) (xy 21.57639 -43.082517) (xy 21.539173 -43.124054) (xy 21.496305 -43.159729)
			(xy 21.448699 -43.188783) (xy 21.39737 -43.210595) (xy 21.343413 -43.224701) (xy 21.287976 -43.230801)
			(xy 21.232242 -43.228764) (xy 21.177399 -43.218634) (xy 21.124615 -43.200627) (xy 21.075015 -43.175126)
			(xy 21.029657 -43.142675) (xy 20.989508 -43.103966) (xy 20.955422 -43.059823) (xy 20.928126 -43.011188)
			(xy 20.908203 -42.959097) (xy 20.896077 -42.90466) (xy 20.892006 -42.849038) (xy 19.02601 -42.849038)
			(xy 19.023719 -42.854026) (xy 18.993986 -42.89999) (xy 18.97634 -42.92092) (xy 18.976086 -42.921174)
			(xy 18.970503 -42.928263) (xy 18.964254 -42.945178) (xy 18.963894 -42.954194) (xy 18.963894 -43.02125)
			(xy 18.964277 -43.030264) (xy 18.970507 -43.047181) (xy 18.976086 -43.05427) (xy 18.97634 -43.05427)
			(xy 18.97634 -43.054524) (xy 18.993964 -43.075468) (xy 19.023676 -43.121438) (xy 19.046515 -43.171183)
			(xy 19.06201 -43.223681) (xy 19.069843 -43.277854) (xy 19.07032 -43.305222) (xy 19.069834 -43.332473)
			(xy 19.062078 -43.386421) (xy 19.046723 -43.438716) (xy 19.024081 -43.488293) (xy 18.994615 -43.534143)
			(xy 18.958924 -43.575334) (xy 18.917733 -43.611025) (xy 18.871883 -43.640491) (xy 18.822306 -43.663133)
			(xy 18.770011 -43.678488) (xy 18.716063 -43.686244) (xy 18.661561 -43.686244) (xy 18.607613 -43.678488)
			(xy 18.555318 -43.663133) (xy 18.505741 -43.640491) (xy 18.459891 -43.611025) (xy 18.4187 -43.575334)
			(xy 18.383009 -43.534143) (xy 18.353543 -43.488293) (xy 18.330901 -43.438716) (xy 18.315546 -43.386421)
			(xy 18.30779 -43.332473) (xy 18.307304 -43.305222) (xy 15.459706 -43.305222) (xy 15.445232 -43.37431)
			(xy 15.444724 -43.37685) (xy 15.390053 -43.73626) (xy 20.213064 -43.73626) (xy 20.217135 -43.680638)
			(xy 20.229261 -43.626201) (xy 20.249184 -43.57411) (xy 20.27648 -43.525475) (xy 20.310566 -43.481332)
			(xy 20.350715 -43.442623) (xy 20.396073 -43.410172) (xy 20.445673 -43.384671) (xy 20.498457 -43.366664)
			(xy 20.5533 -43.356534) (xy 20.609034 -43.354497) (xy 20.664471 -43.360597) (xy 20.718428 -43.374703)
			(xy 20.769757 -43.396515) (xy 20.817363 -43.425569) (xy 20.860231 -43.461244) (xy 20.897448 -43.502781)
			(xy 20.928221 -43.549294) (xy 20.951893 -43.599791) (xy 20.967961 -43.653198) (xy 20.976081 -43.708374)
			(xy 20.97659 -43.73626) (xy 20.976081 -43.764146) (xy 20.967961 -43.819322) (xy 20.956652 -43.85691)
			(xy 24.719786 -43.85691) (xy 24.723857 -43.801288) (xy 24.735983 -43.746851) (xy 24.755906 -43.69476)
			(xy 24.783202 -43.646125) (xy 24.817288 -43.601982) (xy 24.857437 -43.563273) (xy 24.902795 -43.530822)
			(xy 24.952395 -43.505321) (xy 25.005179 -43.487314) (xy 25.060022 -43.477184) (xy 25.115756 -43.475147)
			(xy 25.171193 -43.481247) (xy 25.22515 -43.495353) (xy 25.276479 -43.517165) (xy 25.324085 -43.546219)
			(xy 25.366953 -43.581894) (xy 25.40417 -43.623431) (xy 25.434943 -43.669944) (xy 25.458615 -43.720441)
			(xy 25.474683 -43.773848) (xy 25.482803 -43.829024) (xy 25.483312 -43.85691) (xy 25.482803 -43.884796)
			(xy 25.474683 -43.939972) (xy 25.458615 -43.993379) (xy 25.434943 -44.043876) (xy 25.40417 -44.090389)
			(xy 25.366953 -44.131926) (xy 25.324085 -44.167601) (xy 25.276479 -44.196655) (xy 25.22515 -44.218467)
			(xy 25.171193 -44.232573) (xy 25.115756 -44.238673) (xy 25.060022 -44.236636) (xy 25.005179 -44.226506)
			(xy 24.952395 -44.208499) (xy 24.902795 -44.182998) (xy 24.857437 -44.150547) (xy 24.817288 -44.111838)
			(xy 24.783202 -44.067695) (xy 24.755906 -44.01906) (xy 24.735983 -43.966969) (xy 24.723857 -43.912532)
			(xy 24.719786 -43.85691) (xy 20.956652 -43.85691) (xy 20.951893 -43.872729) (xy 20.928221 -43.923226)
			(xy 20.897448 -43.969739) (xy 20.860231 -44.011276) (xy 20.817363 -44.046951) (xy 20.769757 -44.076005)
			(xy 20.718428 -44.097817) (xy 20.664471 -44.111923) (xy 20.609034 -44.118023) (xy 20.5533 -44.115986)
			(xy 20.498457 -44.105856) (xy 20.445673 -44.087849) (xy 20.396073 -44.062348) (xy 20.350715 -44.029897)
			(xy 20.310566 -43.991188) (xy 20.27648 -43.947045) (xy 20.249184 -43.89841) (xy 20.229261 -43.846319)
			(xy 20.217135 -43.791882) (xy 20.213064 -43.73626) (xy 15.390053 -43.73626) (xy 15.180411 -45.114464)
			(xy 20.06549 -45.114464) (xy 20.069561 -45.058842) (xy 20.081687 -45.004405) (xy 20.10161 -44.952314)
			(xy 20.128906 -44.903679) (xy 20.162992 -44.859536) (xy 20.203141 -44.820827) (xy 20.248499 -44.788376)
			(xy 20.298099 -44.762875) (xy 20.350883 -44.744868) (xy 20.405726 -44.734738) (xy 20.46146 -44.732701)
			(xy 20.516897 -44.738801) (xy 20.570854 -44.752907) (xy 20.622183 -44.774719) (xy 20.669789 -44.803773)
			(xy 20.712657 -44.839448) (xy 20.742639 -44.87291) (xy 26.933142 -44.87291) (xy 26.937213 -44.817288)
			(xy 26.949339 -44.762851) (xy 26.969262 -44.71076) (xy 26.996558 -44.662125) (xy 27.030644 -44.617982)
			(xy 27.070793 -44.579273) (xy 27.116151 -44.546822) (xy 27.165751 -44.521321) (xy 27.218535 -44.503314)
			(xy 27.273378 -44.493184) (xy 27.329112 -44.491147) (xy 27.384549 -44.497247) (xy 27.438506 -44.511353)
			(xy 27.489835 -44.533165) (xy 27.537441 -44.562219) (xy 27.580309 -44.597894) (xy 27.617526 -44.639431)
			(xy 27.648299 -44.685944) (xy 27.671971 -44.736441) (xy 27.688039 -44.789848) (xy 27.696159 -44.845024)
			(xy 27.696668 -44.87291) (xy 27.696159 -44.900796) (xy 27.688039 -44.955972) (xy 27.671971 -45.009379)
			(xy 27.648299 -45.059876) (xy 27.617526 -45.106389) (xy 27.580309 -45.147926) (xy 27.537441 -45.183601)
			(xy 27.489835 -45.212655) (xy 27.438506 -45.234467) (xy 27.384549 -45.248573) (xy 27.329112 -45.254673)
			(xy 27.273378 -45.252636) (xy 27.218535 -45.242506) (xy 27.165751 -45.224499) (xy 27.116151 -45.198998)
			(xy 27.070793 -45.166547) (xy 27.030644 -45.127838) (xy 26.996558 -45.083695) (xy 26.969262 -45.03506)
			(xy 26.949339 -44.982969) (xy 26.937213 -44.928532) (xy 26.933142 -44.87291) (xy 20.742639 -44.87291)
			(xy 20.749874 -44.880985) (xy 20.780647 -44.927498) (xy 20.804319 -44.977995) (xy 20.820387 -45.031402)
			(xy 20.828507 -45.086578) (xy 20.829016 -45.114464) (xy 20.828507 -45.14235) (xy 20.820387 -45.197526)
			(xy 20.804319 -45.250933) (xy 20.780647 -45.30143) (xy 20.749874 -45.347943) (xy 20.744232 -45.35424)
			(xy 24.703784 -45.35424) (xy 24.707855 -45.298618) (xy 24.719981 -45.244181) (xy 24.739904 -45.19209)
			(xy 24.7672 -45.143455) (xy 24.801286 -45.099312) (xy 24.841435 -45.060603) (xy 24.886793 -45.028152)
			(xy 24.936393 -45.002651) (xy 24.989177 -44.984644) (xy 25.04402 -44.974514) (xy 25.099754 -44.972477)
			(xy 25.155191 -44.978577) (xy 25.209148 -44.992683) (xy 25.260477 -45.014495) (xy 25.308083 -45.043549)
			(xy 25.350951 -45.079224) (xy 25.388168 -45.120761) (xy 25.418941 -45.167274) (xy 25.442613 -45.217771)
			(xy 25.458681 -45.271178) (xy 25.466801 -45.326354) (xy 25.46731 -45.35424) (xy 25.466801 -45.382126)
			(xy 25.458681 -45.437302) (xy 25.442613 -45.490709) (xy 25.418941 -45.541206) (xy 25.388168 -45.587719)
			(xy 25.350951 -45.629256) (xy 25.308083 -45.664931) (xy 25.260477 -45.693985) (xy 25.209148 -45.715797)
			(xy 25.155191 -45.729903) (xy 25.099754 -45.736003) (xy 25.04402 -45.733966) (xy 24.989177 -45.723836)
			(xy 24.936393 -45.705829) (xy 24.886793 -45.680328) (xy 24.841435 -45.647877) (xy 24.801286 -45.609168)
			(xy 24.7672 -45.565025) (xy 24.739904 -45.51639) (xy 24.719981 -45.464299) (xy 24.707855 -45.409862)
			(xy 24.703784 -45.35424) (xy 20.744232 -45.35424) (xy 20.712657 -45.38948) (xy 20.669789 -45.425155)
			(xy 20.622183 -45.454209) (xy 20.570854 -45.476021) (xy 20.516897 -45.490127) (xy 20.46146 -45.496227)
			(xy 20.405726 -45.49419) (xy 20.350883 -45.48406) (xy 20.298099 -45.466053) (xy 20.248499 -45.440552)
			(xy 20.203141 -45.408101) (xy 20.162992 -45.369392) (xy 20.128906 -45.325249) (xy 20.10161 -45.276614)
			(xy 20.081687 -45.224523) (xy 20.069561 -45.170086) (xy 20.06549 -45.114464) (xy 15.180411 -45.114464)
			(xy 15.033206 -46.082204) (xy 18.052542 -46.082204) (xy 18.052959 -46.054949) (xy 18.060717 -46.000994)
			(xy 18.076075 -45.948692) (xy 18.098721 -45.899109) (xy 18.128193 -45.853253) (xy 18.163892 -45.812059)
			(xy 18.20509 -45.776365) (xy 18.250949 -45.746899) (xy 18.300535 -45.724259) (xy 18.352839 -45.708907)
			(xy 18.406795 -45.701156) (xy 18.43405 -45.700696) (xy 18.460954 -45.70112) (xy 18.514226 -45.708699)
			(xy 18.565905 -45.723685) (xy 18.614967 -45.745781) (xy 18.660438 -45.774549) (xy 18.701419 -45.80942)
			(xy 18.737095 -45.8497) (xy 18.752312 -45.871892) (xy 18.759424 -45.882814) (xy 18.782284 -45.894752)
			(xy 18.894552 -45.89272) (xy 18.916904 -45.879766) (xy 18.923762 -45.86859) (xy 18.938655 -45.844969)
			(xy 18.974339 -45.802018) (xy 19.015902 -45.764726) (xy 19.062457 -45.733891) (xy 19.113009 -45.710171)
			(xy 19.166479 -45.694072) (xy 19.221724 -45.685939) (xy 19.249644 -45.685456) (xy 19.276638 -45.685892)
			(xy 19.330087 -45.693504) (xy 19.381931 -45.70857) (xy 19.431135 -45.730789) (xy 19.476718 -45.759719)
			(xy 19.497548 -45.776896) (xy 19.505676 -45.784008) (xy 19.52625 -45.790104) (xy 19.611594 -45.779182)
			(xy 19.62214 -45.777415) (xy 19.640422 -45.766355) (xy 19.6469 -45.757846) (xy 19.66226 -45.73662)
			(xy 19.697846 -45.698167) (xy 19.738362 -45.664948) (xy 19.783044 -45.637589) (xy 19.831051 -45.616605)
			(xy 19.881479 -45.602391) (xy 19.933378 -45.595214) (xy 19.959574 -45.594778) (xy 19.986827 -45.595268)
			(xy 20.040779 -45.603021) (xy 20.093078 -45.618374) (xy 20.142659 -45.641015) (xy 20.188514 -45.670481)
			(xy 20.229708 -45.706173) (xy 20.265404 -45.747365) (xy 20.294873 -45.793218) (xy 20.317516 -45.842798)
			(xy 20.332873 -45.895096) (xy 20.340631 -45.949047) (xy 20.340631 -46.003553) (xy 20.332873 -46.057504)
			(xy 20.317516 -46.109802) (xy 20.294873 -46.159382) (xy 20.265404 -46.205235) (xy 20.229708 -46.246427)
			(xy 20.188514 -46.282119) (xy 20.142659 -46.311585) (xy 20.093078 -46.334226) (xy 20.040779 -46.349579)
			(xy 19.986827 -46.357332) (xy 19.959574 -46.357794) (xy 19.932581 -46.357336) (xy 19.879133 -46.349728)
			(xy 19.82729 -46.334666) (xy 19.778085 -46.312452) (xy 19.732501 -46.283528) (xy 19.71167 -46.266354)
			(xy 19.703542 -46.259242) (xy 19.682968 -46.253146) (xy 19.597624 -46.264068) (xy 19.587085 -46.265862)
			(xy 19.568801 -46.276903) (xy 19.562318 -46.285404) (xy 19.544699 -46.3097) (xy 19.503108 -46.352962)
			(xy 19.479514 -46.37151) (xy 19.47164 -46.377352) (xy 19.461226 -46.394878) (xy 19.448018 -46.485302)
			(xy 19.452844 -46.504606) (xy 19.458686 -46.51248) (xy 19.458686 -46.512734) (xy 19.47619 -46.537477)
			(xy 19.503992 -46.59133) (xy 19.522928 -46.648903) (xy 19.530131 -46.693836) (xy 24.676354 -46.693836)
			(xy 24.67684 -46.666585) (xy 24.684596 -46.612637) (xy 24.699951 -46.560342) (xy 24.722593 -46.510765)
			(xy 24.752059 -46.464915) (xy 24.78775 -46.423724) (xy 24.828941 -46.388033) (xy 24.874791 -46.358567)
			(xy 24.924368 -46.335925) (xy 24.976663 -46.32057) (xy 25.030611 -46.312814) (xy 25.085113 -46.312814)
			(xy 25.139061 -46.32057) (xy 25.191356 -46.335925) (xy 25.240933 -46.358567) (xy 25.286783 -46.388033)
			(xy 25.327974 -46.423724) (xy 25.363665 -46.464915) (xy 25.393131 -46.510765) (xy 25.415773 -46.560342)
			(xy 25.431128 -46.612637) (xy 25.438884 -46.666585) (xy 25.43937 -46.693836) (xy 25.438901 -46.720264)
			(xy 25.431591 -46.772611) (xy 25.417117 -46.823446) (xy 25.395755 -46.871793) (xy 25.38222 -46.894496)
			(xy 25.381966 -46.89475) (xy 25.37663 -46.904768) (xy 25.374372 -46.927318) (xy 25.377648 -46.938184)
			(xy 25.40381 -47.01286) (xy 25.408168 -47.023389) (xy 25.424274 -47.039472) (xy 25.434798 -47.043848)
			(xy 25.435052 -47.043848) (xy 25.459562 -47.052914) (xy 25.506014 -47.076857) (xy 25.548766 -47.106914)
			(xy 25.587018 -47.142522) (xy 25.620054 -47.183015) (xy 25.647258 -47.227636) (xy 25.668119 -47.275552)
			(xy 25.682249 -47.325865) (xy 25.689383 -47.377636) (xy 25.689814 -47.403766) (xy 25.689328 -47.431017)
			(xy 25.687805 -47.441612) (xy 26.961844 -47.441612) (xy 26.965915 -47.38599) (xy 26.978041 -47.331553)
			(xy 26.997964 -47.279462) (xy 27.02526 -47.230827) (xy 27.059346 -47.186684) (xy 27.099495 -47.147975)
			(xy 27.144853 -47.115524) (xy 27.194453 -47.090023) (xy 27.247237 -47.072016) (xy 27.30208 -47.061886)
			(xy 27.357814 -47.059849) (xy 27.413251 -47.065949) (xy 27.467208 -47.080055) (xy 27.518537 -47.101867)
			(xy 27.566143 -47.130921) (xy 27.609011 -47.166596) (xy 27.646228 -47.208133) (xy 27.677001 -47.254646)
			(xy 27.700673 -47.305143) (xy 27.716741 -47.35855) (xy 27.724861 -47.413726) (xy 27.72537 -47.441612)
			(xy 27.724861 -47.469498) (xy 27.716741 -47.524674) (xy 27.700673 -47.578081) (xy 27.677001 -47.628578)
			(xy 27.646228 -47.675091) (xy 27.609011 -47.716628) (xy 27.566143 -47.752303) (xy 27.518537 -47.781357)
			(xy 27.467208 -47.803169) (xy 27.413251 -47.817275) (xy 27.357814 -47.823375) (xy 27.30208 -47.821338)
			(xy 27.247237 -47.811208) (xy 27.194453 -47.793201) (xy 27.144853 -47.7677) (xy 27.099495 -47.735249)
			(xy 27.059346 -47.69654) (xy 27.02526 -47.652397) (xy 26.997964 -47.603762) (xy 26.978041 -47.551671)
			(xy 26.965915 -47.497234) (xy 26.961844 -47.441612) (xy 25.687805 -47.441612) (xy 25.681572 -47.484965)
			(xy 25.666217 -47.53726) (xy 25.643575 -47.586837) (xy 25.614109 -47.632687) (xy 25.578418 -47.673878)
			(xy 25.537227 -47.709569) (xy 25.491377 -47.739035) (xy 25.4418 -47.761677) (xy 25.389505 -47.777032)
			(xy 25.335557 -47.784788) (xy 25.281055 -47.784788) (xy 25.227107 -47.777032) (xy 25.174812 -47.761677)
			(xy 25.125235 -47.739035) (xy 25.079385 -47.709569) (xy 25.038194 -47.673878) (xy 25.002503 -47.632687)
			(xy 24.973037 -47.586837) (xy 24.950395 -47.53726) (xy 24.93504 -47.484965) (xy 24.927284 -47.431017)
			(xy 24.926798 -47.403766) (xy 24.927272 -47.377338) (xy 24.934581 -47.324991) (xy 24.949054 -47.274156)
			(xy 24.970413 -47.225809) (xy 24.983948 -47.203106) (xy 24.984202 -47.202852) (xy 24.989537 -47.192833)
			(xy 24.991798 -47.170283) (xy 24.98852 -47.159418) (xy 24.962358 -47.084742) (xy 24.958014 -47.074206)
			(xy 24.941898 -47.058126) (xy 24.93137 -47.053754) (xy 24.931116 -47.053754) (xy 24.9066 -47.044704)
			(xy 24.860148 -47.020757) (xy 24.817398 -46.990698) (xy 24.779147 -46.955088) (xy 24.746112 -46.914592)
			(xy 24.718909 -46.869969) (xy 24.698048 -46.822053) (xy 24.683919 -46.771738) (xy 24.676785 -46.719966)
			(xy 24.676354 -46.693836) (xy 19.530131 -46.693836) (xy 19.532521 -46.708745) (xy 19.533108 -46.739048)
			(xy 19.532667 -46.7663) (xy 19.524904 -46.82025) (xy 19.509543 -46.872545) (xy 19.486896 -46.922123)
			(xy 19.457425 -46.967973) (xy 19.421729 -47.009163) (xy 19.380534 -47.044853) (xy 19.334681 -47.074319)
			(xy 19.2851 -47.096959) (xy 19.232803 -47.112314) (xy 19.178852 -47.12007) (xy 19.1516 -47.120556)
			(xy 19.125567 -47.120101) (xy 19.073984 -47.113015) (xy 19.023843 -47.098987) (xy 18.976072 -47.078278)
			(xy 18.931557 -47.051271) (xy 18.911062 -47.035212) (xy 18.903294 -47.029488) (xy 18.884892 -47.023736)
			(xy 18.875248 -47.024036) (xy 18.795492 -47.030386) (xy 18.777712 -47.039022) (xy 18.771362 -47.046388)
			(xy 18.753173 -47.066026) (xy 18.712267 -47.100549) (xy 18.66694 -47.129019) (xy 18.61808 -47.150878)
			(xy 18.566645 -47.165697) (xy 18.513645 -47.173186) (xy 18.486882 -47.173642) (xy 18.459632 -47.173139)
			(xy 18.405687 -47.165381) (xy 18.353394 -47.150025) (xy 18.303819 -47.127385) (xy 18.25797 -47.09792)
			(xy 18.216781 -47.06223) (xy 18.18109 -47.021042) (xy 18.151623 -46.975195) (xy 18.12898 -46.925621)
			(xy 18.113622 -46.873329) (xy 18.105862 -46.819384) (xy 18.105374 -46.792134) (xy 18.105905 -46.76336)
			(xy 18.114556 -46.706467) (xy 18.131651 -46.651517) (xy 18.156803 -46.599756) (xy 18.189441 -46.55236)
			(xy 18.208752 -46.531022) (xy 18.216118 -46.523148) (xy 18.22323 -46.503336) (xy 18.215864 -46.40707)
			(xy 18.205958 -46.388274) (xy 18.197576 -46.38167) (xy 18.175382 -46.363456) (xy 18.136175 -46.321517)
			(xy 18.103692 -46.274179) (xy 18.078665 -46.222509) (xy 18.06166 -46.167674) (xy 18.05306 -46.11091)
			(xy 18.052542 -46.082204) (xy 15.033206 -46.082204) (xy 14.694788 -48.30699) (xy 24.553924 -48.30699)
			(xy 24.557995 -48.251368) (xy 24.570121 -48.196931) (xy 24.590044 -48.14484) (xy 24.61734 -48.096205)
			(xy 24.651426 -48.052062) (xy 24.691575 -48.013353) (xy 24.736933 -47.980902) (xy 24.786533 -47.955401)
			(xy 24.839317 -47.937394) (xy 24.89416 -47.927264) (xy 24.949894 -47.925227) (xy 25.005331 -47.931327)
			(xy 25.059288 -47.945433) (xy 25.110617 -47.967245) (xy 25.158223 -47.996299) (xy 25.201091 -48.031974)
			(xy 25.238308 -48.073511) (xy 25.269081 -48.120024) (xy 25.292753 -48.170521) (xy 25.308821 -48.223928)
			(xy 25.316941 -48.279104) (xy 25.31745 -48.30699) (xy 25.316941 -48.334876) (xy 25.308821 -48.390052)
			(xy 25.292753 -48.443459) (xy 25.269081 -48.493956) (xy 25.238308 -48.540469) (xy 25.201091 -48.582006)
			(xy 25.158223 -48.617681) (xy 25.110617 -48.646735) (xy 25.059288 -48.668547) (xy 25.005331 -48.682653)
			(xy 24.949894 -48.688753) (xy 24.89416 -48.686716) (xy 24.839317 -48.676586) (xy 24.786533 -48.658579)
			(xy 24.736933 -48.633078) (xy 24.691575 -48.600627) (xy 24.651426 -48.561918) (xy 24.61734 -48.517775)
			(xy 24.590044 -48.46914) (xy 24.570121 -48.417049) (xy 24.557995 -48.362612) (xy 24.553924 -48.30699)
			(xy 14.694788 -48.30699) (xy 14.626942 -48.753014) (xy 21.168358 -48.753014) (xy 21.172429 -48.697392)
			(xy 21.184555 -48.642955) (xy 21.204478 -48.590864) (xy 21.231774 -48.542229) (xy 21.26586 -48.498086)
			(xy 21.306009 -48.459377) (xy 21.351367 -48.426926) (xy 21.400967 -48.401425) (xy 21.453751 -48.383418)
			(xy 21.508594 -48.373288) (xy 21.564328 -48.371251) (xy 21.619765 -48.377351) (xy 21.673722 -48.391457)
			(xy 21.725051 -48.413269) (xy 21.772657 -48.442323) (xy 21.815525 -48.477998) (xy 21.852742 -48.519535)
			(xy 21.883515 -48.566048) (xy 21.907187 -48.616545) (xy 21.923255 -48.669952) (xy 21.931375 -48.725128)
			(xy 21.931884 -48.753014) (xy 21.931375 -48.7809) (xy 21.923255 -48.836076) (xy 21.907187 -48.889483)
			(xy 21.905791 -48.89246) (xy 23.214074 -48.89246) (xy 23.218145 -48.836838) (xy 23.230271 -48.782401)
			(xy 23.250194 -48.73031) (xy 23.27749 -48.681675) (xy 23.311576 -48.637532) (xy 23.351725 -48.598823)
			(xy 23.397083 -48.566372) (xy 23.446683 -48.540871) (xy 23.499467 -48.522864) (xy 23.55431 -48.512734)
			(xy 23.610044 -48.510697) (xy 23.665481 -48.516797) (xy 23.719438 -48.530903) (xy 23.770767 -48.552715)
			(xy 23.818373 -48.581769) (xy 23.861241 -48.617444) (xy 23.898458 -48.658981) (xy 23.929231 -48.705494)
			(xy 23.952903 -48.755991) (xy 23.968971 -48.809398) (xy 23.977091 -48.864574) (xy 23.9776 -48.89246)
			(xy 23.977091 -48.920346) (xy 23.974653 -48.93691) (xy 26.933142 -48.93691) (xy 26.937213 -48.881288)
			(xy 26.949339 -48.826851) (xy 26.969262 -48.77476) (xy 26.996558 -48.726125) (xy 27.030644 -48.681982)
			(xy 27.070793 -48.643273) (xy 27.116151 -48.610822) (xy 27.165751 -48.585321) (xy 27.218535 -48.567314)
			(xy 27.273378 -48.557184) (xy 27.329112 -48.555147) (xy 27.384549 -48.561247) (xy 27.438506 -48.575353)
			(xy 27.489835 -48.597165) (xy 27.537441 -48.626219) (xy 27.580309 -48.661894) (xy 27.617526 -48.703431)
			(xy 27.648299 -48.749944) (xy 27.671971 -48.800441) (xy 27.688039 -48.853848) (xy 27.696159 -48.909024)
			(xy 27.696668 -48.93691) (xy 27.696159 -48.964796) (xy 27.688039 -49.019972) (xy 27.671971 -49.073379)
			(xy 27.648299 -49.123876) (xy 27.617526 -49.170389) (xy 27.580309 -49.211926) (xy 27.537441 -49.247601)
			(xy 27.489835 -49.276655) (xy 27.438506 -49.298467) (xy 27.384549 -49.312573) (xy 27.329112 -49.318673)
			(xy 27.273378 -49.316636) (xy 27.218535 -49.306506) (xy 27.165751 -49.288499) (xy 27.116151 -49.262998)
			(xy 27.070793 -49.230547) (xy 27.030644 -49.191838) (xy 26.996558 -49.147695) (xy 26.969262 -49.09906)
			(xy 26.949339 -49.046969) (xy 26.937213 -48.992532) (xy 26.933142 -48.93691) (xy 23.974653 -48.93691)
			(xy 23.968971 -48.975522) (xy 23.952903 -49.028929) (xy 23.929231 -49.079426) (xy 23.898458 -49.125939)
			(xy 23.861241 -49.167476) (xy 23.818373 -49.203151) (xy 23.770767 -49.232205) (xy 23.719438 -49.254017)
			(xy 23.665481 -49.268123) (xy 23.610044 -49.274223) (xy 23.55431 -49.272186) (xy 23.499467 -49.262056)
			(xy 23.446683 -49.244049) (xy 23.397083 -49.218548) (xy 23.351725 -49.186097) (xy 23.311576 -49.147388)
			(xy 23.27749 -49.103245) (xy 23.250194 -49.05461) (xy 23.230271 -49.002519) (xy 23.218145 -48.948082)
			(xy 23.214074 -48.89246) (xy 21.905791 -48.89246) (xy 21.883515 -48.93998) (xy 21.852742 -48.986493)
			(xy 21.815525 -49.02803) (xy 21.772657 -49.063705) (xy 21.725051 -49.092759) (xy 21.673722 -49.114571)
			(xy 21.619765 -49.128677) (xy 21.564328 -49.134777) (xy 21.508594 -49.13274) (xy 21.453751 -49.12261)
			(xy 21.400967 -49.104603) (xy 21.351367 -49.079102) (xy 21.306009 -49.046651) (xy 21.26586 -49.007942)
			(xy 21.231774 -48.963799) (xy 21.204478 -48.915164) (xy 21.184555 -48.863073) (xy 21.172429 -48.808636)
			(xy 21.168358 -48.753014) (xy 14.626942 -48.753014) (xy 14.444423 -49.95291) (xy 26.933142 -49.95291)
			(xy 26.937213 -49.897288) (xy 26.949339 -49.842851) (xy 26.969262 -49.79076) (xy 26.996558 -49.742125)
			(xy 27.030644 -49.697982) (xy 27.070793 -49.659273) (xy 27.116151 -49.626822) (xy 27.165751 -49.601321)
			(xy 27.218535 -49.583314) (xy 27.273378 -49.573184) (xy 27.329112 -49.571147) (xy 27.384549 -49.577247)
			(xy 27.438506 -49.591353) (xy 27.489835 -49.613165) (xy 27.537441 -49.642219) (xy 27.580309 -49.677894)
			(xy 27.617526 -49.719431) (xy 27.648299 -49.765944) (xy 27.671971 -49.816441) (xy 27.688039 -49.869848)
			(xy 27.696159 -49.925024) (xy 27.696668 -49.95291) (xy 27.696159 -49.980796) (xy 27.688039 -50.035972)
			(xy 27.671971 -50.089379) (xy 27.648299 -50.139876) (xy 27.617526 -50.186389) (xy 27.580309 -50.227926)
			(xy 27.537441 -50.263601) (xy 27.489835 -50.292655) (xy 27.438506 -50.314467) (xy 27.384549 -50.328573)
			(xy 27.329112 -50.334673) (xy 27.273378 -50.332636) (xy 27.218535 -50.322506) (xy 27.165751 -50.304499)
			(xy 27.116151 -50.278998) (xy 27.070793 -50.246547) (xy 27.030644 -50.207838) (xy 26.996558 -50.163695)
			(xy 26.969262 -50.11506) (xy 26.949339 -50.062969) (xy 26.937213 -50.008532) (xy 26.933142 -49.95291)
			(xy 14.444423 -49.95291) (xy 14.431518 -50.037746) (xy 14.431518 -50.038254) (xy 14.427708 -50.06213)
			(xy 14.427454 -50.063908) (xy 14.426692 -50.068988) (xy 14.282125 -51.019456) (xy 24.749504 -51.019456)
			(xy 24.753575 -50.963834) (xy 24.765701 -50.909397) (xy 24.785624 -50.857306) (xy 24.81292 -50.808671)
			(xy 24.847006 -50.764528) (xy 24.887155 -50.725819) (xy 24.932513 -50.693368) (xy 24.982113 -50.667867)
			(xy 25.034897 -50.64986) (xy 25.08974 -50.63973) (xy 25.145474 -50.637693) (xy 25.200911 -50.643793)
			(xy 25.254868 -50.657899) (xy 25.306197 -50.679711) (xy 25.353803 -50.708765) (xy 25.396671 -50.74444)
			(xy 25.433888 -50.785977) (xy 25.464661 -50.83249) (xy 25.488333 -50.882987) (xy 25.504401 -50.936394)
			(xy 25.512521 -50.99157) (xy 25.51303 -51.019456) (xy 25.512521 -51.047342) (xy 25.504401 -51.102518)
			(xy 25.488333 -51.155925) (xy 25.464661 -51.206422) (xy 25.439805 -51.243992) (xy 33.13303 -51.243992)
			(xy 33.133484 -51.216621) (xy 33.141304 -51.162441) (xy 33.156795 -51.109938) (xy 33.17964 -51.060191)
			(xy 33.209367 -51.014225) (xy 33.22701 -50.993294) (xy 33.227264 -50.99304) (xy 33.232848 -50.985952)
			(xy 33.239094 -50.969036) (xy 33.239456 -50.96002) (xy 33.239456 -50.892964) (xy 33.239126 -50.883944)
			(xy 33.232861 -50.867027) (xy 33.227264 -50.859944) (xy 33.22701 -50.859944) (xy 33.22701 -50.85969)
			(xy 33.209354 -50.838771) (xy 33.179645 -50.792795) (xy 33.156812 -50.743044) (xy 33.141325 -50.69054)
			(xy 33.133501 -50.636362) (xy 33.13303 -50.608992) (xy 33.133448 -50.581737) (xy 33.141207 -50.527783)
			(xy 33.156566 -50.475482) (xy 33.179212 -50.425899) (xy 33.208685 -50.380044) (xy 33.244383 -50.338851)
			(xy 33.285581 -50.303157) (xy 33.331439 -50.27369) (xy 33.381025 -50.25105) (xy 33.433328 -50.235697)
			(xy 33.487283 -50.227945) (xy 33.514538 -50.227484) (xy 33.543455 -50.228015) (xy 33.600627 -50.236737)
			(xy 33.655827 -50.25399) (xy 33.707789 -50.27938) (xy 33.755323 -50.312322) (xy 33.797339 -50.352064)
			(xy 33.815528 -50.37455) (xy 33.823124 -50.383368) (xy 33.844033 -50.393544) (xy 33.85566 -50.394108)
			(xy 33.935416 -50.394108) (xy 33.947047 -50.393561) (xy 33.967956 -50.383377) (xy 33.975548 -50.37455)
			(xy 33.993756 -50.352081) (xy 34.035774 -50.312347) (xy 34.083305 -50.279408) (xy 34.135263 -50.254018)
			(xy 34.190457 -50.236757) (xy 34.247623 -50.228023) (xy 34.276538 -50.227484) (xy 34.30379 -50.227942)
			(xy 34.357738 -50.235704) (xy 34.410033 -50.251063) (xy 34.45961 -50.273708) (xy 34.50546 -50.303178)
			(xy 34.546649 -50.338872) (xy 34.58234 -50.380065) (xy 34.611806 -50.425917) (xy 34.634447 -50.475495)
			(xy 34.649802 -50.527791) (xy 34.65756 -50.58174) (xy 34.658046 -50.608992) (xy 34.657591 -50.635307)
			(xy 34.650356 -50.687436) (xy 34.636035 -50.73808) (xy 34.614901 -50.786279) (xy 34.587352 -50.831122)
			(xy 34.553909 -50.871761) (xy 34.534856 -50.889916) (xy 34.527454 -50.897437) (xy 34.518928 -50.916717)
			(xy 34.518346 -50.927254) (xy 34.518346 -51.00193) (xy 34.518886 -51.012479) (xy 34.527412 -51.031775)
			(xy 34.534856 -51.039268) (xy 34.553948 -51.057386) (xy 34.5874 -51.098025) (xy 34.614953 -51.142874)
			(xy 34.636084 -51.191082) (xy 34.650394 -51.241735) (xy 34.657611 -51.293874) (xy 34.658046 -51.320192)
			(xy 34.657515 -51.347441) (xy 34.64976 -51.401385) (xy 34.634408 -51.453677) (xy 34.611771 -51.503252)
			(xy 34.582309 -51.5491) (xy 34.546622 -51.59029) (xy 34.505437 -51.625981) (xy 34.459592 -51.655449)
			(xy 34.41002 -51.678092) (xy 34.35773 -51.693451) (xy 34.303787 -51.701212) (xy 34.276538 -51.7017)
			(xy 34.248874 -51.701158) (xy 34.194126 -51.693164) (xy 34.141105 -51.677353) (xy 34.090921 -51.654055)
			(xy 34.044625 -51.623758) (xy 34.003186 -51.587097) (xy 33.967472 -51.544839) (xy 33.952434 -51.521614)
			(xy 33.945791 -51.511943) (xy 33.925934 -51.499497) (xy 33.914334 -51.497738) (xy 33.834324 -51.489864)
			(xy 33.822686 -51.48925) (xy 33.80085 -51.497317) (xy 33.792414 -51.505358) (xy 33.79216 -51.505612)
			(xy 33.774083 -51.524197) (xy 33.73375 -51.556775) (xy 33.689375 -51.583587) (xy 33.641776 -51.604139)
			(xy 33.591831 -51.618052) (xy 33.540461 -51.625069) (xy 33.514538 -51.6255) (xy 33.487286 -51.625009)
			(xy 33.433335 -51.617257) (xy 33.381038 -51.601906) (xy 33.331457 -51.579267) (xy 33.285603 -51.549802)
			(xy 33.24441 -51.514111) (xy 33.208716 -51.472921) (xy 33.179247 -51.427069) (xy 33.156605 -51.377491)
			(xy 33.141249 -51.325194) (xy 33.133493 -51.271244) (xy 33.13303 -51.243992) (xy 25.439805 -51.243992)
			(xy 25.433888 -51.252935) (xy 25.396671 -51.294472) (xy 25.353803 -51.330147) (xy 25.306197 -51.359201)
			(xy 25.254868 -51.381013) (xy 25.200911 -51.395119) (xy 25.145474 -51.401219) (xy 25.08974 -51.399182)
			(xy 25.034897 -51.389052) (xy 24.982113 -51.371045) (xy 24.932513 -51.345544) (xy 24.887155 -51.313093)
			(xy 24.847006 -51.274384) (xy 24.81292 -51.230241) (xy 24.785624 -51.181606) (xy 24.765701 -51.129515)
			(xy 24.753575 -51.075078) (xy 24.749504 -51.019456) (xy 14.282125 -51.019456) (xy 14.127591 -52.035456)
			(xy 26.94127 -52.035456) (xy 26.945341 -51.979834) (xy 26.957467 -51.925397) (xy 26.97739 -51.873306)
			(xy 27.004686 -51.824671) (xy 27.038772 -51.780528) (xy 27.078921 -51.741819) (xy 27.124279 -51.709368)
			(xy 27.173879 -51.683867) (xy 27.226663 -51.66586) (xy 27.281506 -51.65573) (xy 27.33724 -51.653693)
			(xy 27.392677 -51.659793) (xy 27.446634 -51.673899) (xy 27.497963 -51.695711) (xy 27.545569 -51.724765)
			(xy 27.588437 -51.76044) (xy 27.625654 -51.801977) (xy 27.656427 -51.84849) (xy 27.680099 -51.898987)
			(xy 27.696167 -51.952394) (xy 27.704287 -52.00757) (xy 27.704796 -52.035456) (xy 27.704287 -52.063342)
			(xy 27.696167 -52.118518) (xy 27.680099 -52.171925) (xy 27.656427 -52.222422) (xy 27.625654 -52.268935)
			(xy 27.588437 -52.310472) (xy 27.545569 -52.346147) (xy 27.497963 -52.375201) (xy 27.446634 -52.397013)
			(xy 27.392677 -52.411119) (xy 27.33724 -52.417219) (xy 27.281506 -52.415182) (xy 27.226663 -52.405052)
			(xy 27.173879 -52.387045) (xy 27.124279 -52.361544) (xy 27.078921 -52.329093) (xy 27.038772 -52.290384)
			(xy 27.004686 -52.246241) (xy 26.97739 -52.197606) (xy 26.957467 -52.145515) (xy 26.945341 -52.091078)
			(xy 26.94127 -52.035456) (xy 14.127591 -52.035456) (xy 14.116812 -52.106322) (xy 14.116304 -52.11318)
			(xy 14.110462 -52.479194) (xy 14.110502 -52.485178) (xy 14.113062 -52.496863) (xy 14.115542 -52.502308)
			(xy 14.118082 -52.507642) (xy 14.125702 -52.516786) (xy 14.130782 -52.520596) (xy 14.15412 -52.538758)
			(xy 14.195436 -52.581064) (xy 14.229745 -52.629228) (xy 14.256227 -52.682101) (xy 14.27425 -52.738421)
			(xy 14.283386 -52.796845) (xy 14.283944 -52.826412) (xy 14.282928 -52.855876) (xy 14.28115 -52.871116)
			(xy 14.28115 -52.87137) (xy 14.279228 -52.886157) (xy 14.273378 -52.9154) (xy 14.269466 -52.92979)
			(xy 14.26229 -52.953812) (xy 14.242502 -52.999876) (xy 14.21686 -53.042958) (xy 14.201648 -53.062886)
			(xy 14.198854 -53.066442) (xy 14.19225 -53.078888) (xy 14.18971 -53.090064) (xy 14.18971 -53.117242)
			(xy 14.189566 -53.122681) (xy 14.187257 -53.133312) (xy 14.185138 -53.138324) (xy 14.179042 -53.151786)
			(xy 14.175422 -53.160448) (xy 14.17419 -53.179169) (xy 14.179813 -53.197068) (xy 14.185392 -53.204618)
			(xy 14.19098 -53.21173) (xy 14.194536 -53.216302) (xy 14.195044 -53.217064) (xy 14.195552 -53.217572)
			(xy 14.196314 -53.218588) (xy 14.212501 -53.238852) (xy 14.239824 -53.282935) (xy 14.260918 -53.330315)
			(xy 14.275394 -53.380117) (xy 14.282984 -53.431422) (xy 14.28369 -53.457348) (xy 14.28369 -53.460396)
			(xy 14.283354 -53.48578) (xy 14.276789 -53.536119) (xy 14.263613 -53.585145) (xy 14.254226 -53.608732)
			(xy 14.254226 -53.608986) (xy 14.253972 -53.609494) (xy 14.252702 -53.612288) (xy 14.252194 -53.613304)
			(xy 14.249654 -53.619146) (xy 14.245082 -53.628798) (xy 14.240002 -53.63845) (xy 14.240002 -53.638958)
			(xy 14.234922 -53.648356) (xy 14.234414 -53.648864) (xy 14.224762 -53.66512) (xy 14.224254 -53.665628)
			(xy 14.211046 -53.68544) (xy 14.20495 -53.693822) (xy 14.200378 -53.699664) (xy 14.19606 -53.706522)
			(xy 14.195044 -53.708554) (xy 14.192583 -53.71388) (xy 14.189891 -53.725296) (xy 14.18971 -53.73116)
			(xy 14.18971 -53.752242) (xy 14.189566 -53.757681) (xy 14.187257 -53.768312) (xy 14.185138 -53.773324)
			(xy 14.179042 -53.786786) (xy 14.175422 -53.795448) (xy 14.17419 -53.814169) (xy 14.179813 -53.832068)
			(xy 14.185392 -53.839618) (xy 14.19098 -53.84673) (xy 14.194536 -53.851302) (xy 14.195044 -53.852064)
			(xy 14.195552 -53.852572) (xy 14.196314 -53.853588) (xy 14.212501 -53.873852) (xy 14.239824 -53.917935)
			(xy 14.260918 -53.965315) (xy 14.275394 -54.015117) (xy 14.282984 -54.066422) (xy 14.28369 -54.092348)
			(xy 14.28369 -54.095396) (xy 14.283354 -54.12078) (xy 14.276789 -54.171119) (xy 14.263613 -54.220145)
			(xy 14.254226 -54.243732) (xy 14.254226 -54.243986) (xy 14.253972 -54.244494) (xy 14.252702 -54.247288)
			(xy 14.252194 -54.248304) (xy 14.249654 -54.254146) (xy 14.245082 -54.263798) (xy 14.240002 -54.27345)
			(xy 14.240002 -54.273958) (xy 14.234922 -54.283356) (xy 14.234414 -54.283864) (xy 14.224762 -54.30012)
			(xy 14.224254 -54.300628) (xy 14.211046 -54.32044) (xy 14.20495 -54.328822) (xy 14.200378 -54.334664)
			(xy 14.19606 -54.341522) (xy 14.195044 -54.343554) (xy 14.192583 -54.34888) (xy 14.189891 -54.360296)
			(xy 14.18971 -54.36616) (xy 14.18971 -54.387242) (xy 14.189566 -54.392681) (xy 14.187257 -54.403312)
			(xy 14.185138 -54.408324) (xy 14.179042 -54.421786) (xy 14.175422 -54.430448) (xy 14.17419 -54.449169)
			(xy 14.179813 -54.467068) (xy 14.185392 -54.474618) (xy 14.19098 -54.48173) (xy 14.194536 -54.486302)
			(xy 14.195044 -54.487064) (xy 14.196568 -54.488842) (xy 14.215461 -54.51271) (xy 14.246217 -54.565236)
			(xy 14.268255 -54.621975) (xy 14.281017 -54.681491) (xy 14.283182 -54.711854) (xy 14.28369 -54.730396)
			(xy 14.28369 -54.731412) (xy 14.283611 -54.74415) (xy 14.281957 -54.769571) (xy 14.280388 -54.782212)
			(xy 14.279033 -54.791102) (xy 16.176498 -54.791102) (xy 16.176966 -54.763732) (xy 16.184783 -54.709553)
			(xy 16.200272 -54.65705) (xy 16.223113 -54.607303) (xy 16.252837 -54.561336) (xy 16.270478 -54.540404)
			(xy 16.270732 -54.54015) (xy 16.276307 -54.533056) (xy 16.28256 -54.516145) (xy 16.282924 -54.50713)
			(xy 16.282924 -54.440074) (xy 16.282574 -54.431056) (xy 16.276321 -54.41414) (xy 16.270732 -54.407054)
			(xy 16.270478 -54.407054) (xy 16.270478 -54.4068) (xy 16.252841 -54.385865) (xy 16.22312 -54.339896)
			(xy 16.200278 -54.29015) (xy 16.184783 -54.237649) (xy 16.176956 -54.183471) (xy 16.176955 -54.128732)
			(xy 16.184783 -54.074554) (xy 16.200277 -54.022053) (xy 16.223119 -53.972307) (xy 16.252839 -53.926338)
			(xy 16.270478 -53.905404) (xy 16.270732 -53.90515) (xy 16.276307 -53.898056) (xy 16.28256 -53.881145)
			(xy 16.282924 -53.87213) (xy 16.282924 -53.805074) (xy 16.282574 -53.796056) (xy 16.276321 -53.77914)
			(xy 16.270732 -53.772054) (xy 16.270478 -53.772054) (xy 16.270478 -53.7718) (xy 16.252841 -53.750865)
			(xy 16.22312 -53.704896) (xy 16.200278 -53.65515) (xy 16.184783 -53.602649) (xy 16.176956 -53.548471)
			(xy 16.176955 -53.493732) (xy 16.184783 -53.439554) (xy 16.200277 -53.387053) (xy 16.223119 -53.337307)
			(xy 16.252839 -53.291338) (xy 16.270478 -53.270404) (xy 16.270732 -53.27015) (xy 16.276307 -53.263056)
			(xy 16.28256 -53.246145) (xy 16.282924 -53.23713) (xy 16.282924 -53.170074) (xy 16.282574 -53.161056)
			(xy 16.276321 -53.14414) (xy 16.270732 -53.137054) (xy 16.270478 -53.137054) (xy 16.270478 -53.1368)
			(xy 16.252822 -53.115882) (xy 16.223113 -53.069905) (xy 16.200281 -53.020154) (xy 16.184794 -52.96765)
			(xy 16.17697 -52.913472) (xy 16.176498 -52.886102) (xy 16.176984 -52.858851) (xy 16.18474 -52.804903)
			(xy 16.200095 -52.752608) (xy 16.222737 -52.703031) (xy 16.252203 -52.657181) (xy 16.287894 -52.61599)
			(xy 16.329085 -52.580299) (xy 16.374935 -52.550833) (xy 16.424512 -52.528191) (xy 16.476807 -52.512836)
			(xy 16.530755 -52.50508) (xy 16.585257 -52.50508) (xy 16.639205 -52.512836) (xy 16.6915 -52.528191)
			(xy 16.7306 -52.546048) (xy 21.679696 -52.546048) (xy 21.679696 -52.491552) (xy 21.687451 -52.43761)
			(xy 21.702804 -52.385321) (xy 21.725441 -52.335749) (xy 21.754902 -52.289902) (xy 21.790588 -52.248715)
			(xy 21.831772 -52.213025) (xy 21.877615 -52.183559) (xy 21.927185 -52.160917) (xy 21.979473 -52.145559)
			(xy 22.033414 -52.137799) (xy 22.060662 -52.13731) (xy 22.088032 -52.137796) (xy 22.14221 -52.145609)
			(xy 22.194713 -52.161093) (xy 22.24446 -52.18393) (xy 22.290428 -52.213651) (xy 22.31136 -52.23129)
			(xy 22.311614 -52.231544) (xy 22.318689 -52.237148) (xy 22.335615 -52.243383) (xy 22.344634 -52.243736)
			(xy 22.41169 -52.243736) (xy 22.420705 -52.243366) (xy 22.437622 -52.237127) (xy 22.44471 -52.231544)
			(xy 22.44471 -52.23129) (xy 22.444964 -52.23129) (xy 22.465897 -52.213649) (xy 22.511865 -52.183925)
			(xy 22.561611 -52.161079) (xy 22.614113 -52.145583) (xy 22.668291 -52.137754) (xy 22.723033 -52.137754)
			(xy 22.777211 -52.145583) (xy 22.829713 -52.161079) (xy 22.879459 -52.183925) (xy 22.925427 -52.213649)
			(xy 22.94636 -52.23129) (xy 22.946614 -52.231544) (xy 22.953689 -52.237148) (xy 22.970615 -52.243383)
			(xy 22.979634 -52.243736) (xy 23.04669 -52.243736) (xy 23.055705 -52.243366) (xy 23.072622 -52.237127)
			(xy 23.07971 -52.231544) (xy 23.07971 -52.23129) (xy 23.079964 -52.23129) (xy 23.100898 -52.213653)
			(xy 23.14687 -52.183941) (xy 23.196617 -52.161105) (xy 23.249118 -52.145613) (xy 23.303293 -52.137784)
			(xy 23.330662 -52.13731) (xy 23.357918 -52.137734) (xy 23.411876 -52.145487) (xy 23.464181 -52.160841)
			(xy 23.513768 -52.183482) (xy 23.559628 -52.212951) (xy 23.600827 -52.248646) (xy 23.636527 -52.289842)
			(xy 23.666 -52.335699) (xy 23.688646 -52.385284) (xy 23.704005 -52.437587) (xy 23.711763 -52.491544)
			(xy 23.711763 -52.546056) (xy 23.705819 -52.587398) (xy 24.755346 -52.587398) (xy 24.759417 -52.531776)
			(xy 24.771543 -52.477339) (xy 24.791466 -52.425248) (xy 24.818762 -52.376613) (xy 24.852848 -52.33247)
			(xy 24.892997 -52.293761) (xy 24.938355 -52.26131) (xy 24.987955 -52.235809) (xy 25.040739 -52.217802)
			(xy 25.095582 -52.207672) (xy 25.151316 -52.205635) (xy 25.206753 -52.211735) (xy 25.26071 -52.225841)
			(xy 25.312039 -52.247653) (xy 25.359645 -52.276707) (xy 25.402513 -52.312382) (xy 25.43973 -52.353919)
			(xy 25.470503 -52.400432) (xy 25.494175 -52.450929) (xy 25.510243 -52.504336) (xy 25.517839 -52.555949)
			(xy 32.583902 -52.555949) (xy 32.583902 -52.501451) (xy 32.591658 -52.447509) (xy 32.607011 -52.395219)
			(xy 32.629649 -52.345646) (xy 32.659112 -52.299799) (xy 32.694799 -52.258612) (xy 32.735985 -52.222923)
			(xy 32.78183 -52.193458) (xy 32.831402 -52.170817) (xy 32.883691 -52.155462) (xy 32.937633 -52.147703)
			(xy 32.964882 -52.147216) (xy 32.992252 -52.147689) (xy 33.046431 -52.155504) (xy 33.098934 -52.170992)
			(xy 33.148681 -52.193832) (xy 33.194648 -52.223555) (xy 33.21558 -52.241196) (xy 33.215834 -52.24145)
			(xy 33.222931 -52.247021) (xy 33.23984 -52.253276) (xy 33.248854 -52.253642) (xy 33.31591 -52.253642)
			(xy 33.324929 -52.253302) (xy 33.341846 -52.247044) (xy 33.34893 -52.24145) (xy 33.34893 -52.241196)
			(xy 33.349184 -52.241196) (xy 33.370111 -52.22355) (xy 33.416085 -52.19384) (xy 33.465834 -52.171005)
			(xy 33.518336 -52.155515) (xy 33.572512 -52.147689) (xy 33.599882 -52.147216) (xy 33.627137 -52.14763)
			(xy 33.681094 -52.155385) (xy 33.733397 -52.170741) (xy 33.782983 -52.193383) (xy 33.828841 -52.222853)
			(xy 33.870038 -52.258549) (xy 33.905736 -52.299745) (xy 33.935208 -52.345601) (xy 33.957853 -52.395186)
			(xy 33.973211 -52.447489) (xy 33.980969 -52.501445) (xy 33.980969 -52.555955) (xy 33.973211 -52.609911)
			(xy 33.957853 -52.662214) (xy 33.935208 -52.711799) (xy 33.905736 -52.757655) (xy 33.870038 -52.798851)
			(xy 33.828841 -52.834547) (xy 33.782983 -52.864017) (xy 33.733397 -52.886659) (xy 33.681094 -52.902015)
			(xy 33.627137 -52.90977) (xy 33.599882 -52.910232) (xy 33.572511 -52.909793) (xy 33.51833 -52.901971)
			(xy 33.465826 -52.886477) (xy 33.416079 -52.863629) (xy 33.370114 -52.833897) (xy 33.349184 -52.816252)
			(xy 33.34893 -52.815998) (xy 33.341839 -52.810418) (xy 33.324926 -52.804167) (xy 33.31591 -52.803806)
			(xy 33.248854 -52.803806) (xy 33.23984 -52.804188) (xy 33.222922 -52.810418) (xy 33.215834 -52.815998)
			(xy 33.215834 -52.816252) (xy 33.21558 -52.816252) (xy 33.194622 -52.83386) (xy 33.148657 -52.863578)
			(xy 33.098916 -52.886421) (xy 33.046421 -52.901919) (xy 32.99225 -52.909754) (xy 32.964882 -52.910232)
			(xy 32.937633 -52.909697) (xy 32.883691 -52.901938) (xy 32.831402 -52.886583) (xy 32.78183 -52.863942)
			(xy 32.735985 -52.834477) (xy 32.694799 -52.798788) (xy 32.659112 -52.757601) (xy 32.629649 -52.711754)
			(xy 32.607011 -52.662181) (xy 32.591658 -52.609891) (xy 32.583902 -52.555949) (xy 25.517839 -52.555949)
			(xy 25.518363 -52.559512) (xy 25.518872 -52.587398) (xy 25.518363 -52.615284) (xy 25.510243 -52.67046)
			(xy 25.494175 -52.723867) (xy 25.470503 -52.774364) (xy 25.43973 -52.820877) (xy 25.402513 -52.862414)
			(xy 25.359645 -52.898089) (xy 25.312039 -52.927143) (xy 25.26071 -52.948955) (xy 25.206753 -52.963061)
			(xy 25.151316 -52.969161) (xy 25.095582 -52.967124) (xy 25.040739 -52.956994) (xy 24.987955 -52.938987)
			(xy 24.938355 -52.913486) (xy 24.892997 -52.881035) (xy 24.852848 -52.842326) (xy 24.818762 -52.798183)
			(xy 24.791466 -52.749548) (xy 24.771543 -52.697457) (xy 24.759417 -52.64302) (xy 24.755346 -52.587398)
			(xy 23.705819 -52.587398) (xy 23.704005 -52.600013) (xy 23.688646 -52.652316) (xy 23.666 -52.701901)
			(xy 23.636527 -52.747758) (xy 23.600827 -52.788954) (xy 23.559628 -52.824649) (xy 23.513768 -52.854118)
			(xy 23.464181 -52.876759) (xy 23.411876 -52.892113) (xy 23.357918 -52.899866) (xy 23.330662 -52.900326)
			(xy 23.303292 -52.899842) (xy 23.249113 -52.892031) (xy 23.19661 -52.876547) (xy 23.146862 -52.853709)
			(xy 23.100895 -52.823987) (xy 23.079964 -52.806346) (xy 23.07971 -52.806092) (xy 23.072625 -52.800503)
			(xy 23.055707 -52.794258) (xy 23.04669 -52.7939) (xy 22.979634 -52.7939) (xy 22.970619 -52.794273)
			(xy 22.953702 -52.800509) (xy 22.946614 -52.806092) (xy 22.94636 -52.806346) (xy 22.925427 -52.823987)
			(xy 22.879459 -52.853711) (xy 22.829713 -52.876557) (xy 22.777211 -52.892053) (xy 22.723033 -52.899882)
			(xy 22.668291 -52.899882) (xy 22.614113 -52.892053) (xy 22.561611 -52.876557) (xy 22.511865 -52.853711)
			(xy 22.465897 -52.823987) (xy 22.444964 -52.806346) (xy 22.44471 -52.806092) (xy 22.437625 -52.800503)
			(xy 22.420707 -52.794258) (xy 22.41169 -52.7939) (xy 22.344634 -52.7939) (xy 22.335619 -52.794273)
			(xy 22.318702 -52.800509) (xy 22.311614 -52.806092) (xy 22.311614 -52.806346) (xy 22.31136 -52.806346)
			(xy 22.290409 -52.823962) (xy 22.244442 -52.853679) (xy 22.1947 -52.87652) (xy 22.142203 -52.892017)
			(xy 22.08803 -52.89985) (xy 22.060662 -52.900326) (xy 22.033414 -52.899801) (xy 21.979473 -52.892041)
			(xy 21.927185 -52.876683) (xy 21.877615 -52.854041) (xy 21.831772 -52.824575) (xy 21.790588 -52.788885)
			(xy 21.754902 -52.747698) (xy 21.725441 -52.701851) (xy 21.702804 -52.652279) (xy 21.687451 -52.59999)
			(xy 21.679696 -52.546048) (xy 16.7306 -52.546048) (xy 16.741077 -52.550833) (xy 16.786927 -52.580299)
			(xy 16.828118 -52.61599) (xy 16.863809 -52.657181) (xy 16.893275 -52.703031) (xy 16.915917 -52.752608)
			(xy 16.931272 -52.804903) (xy 16.939028 -52.858851) (xy 16.939514 -52.886102) (xy 16.939046 -52.913472)
			(xy 16.931228 -52.967651) (xy 16.915739 -53.020154) (xy 16.892898 -53.069901) (xy 16.863175 -53.115868)
			(xy 16.845534 -53.1368) (xy 16.84528 -53.137054) (xy 16.839704 -53.144148) (xy 16.833452 -53.161059)
			(xy 16.833088 -53.170074) (xy 16.833088 -53.23713) (xy 16.833434 -53.246148) (xy 16.839689 -53.263065)
			(xy 16.84528 -53.27015) (xy 16.845534 -53.27015) (xy 16.845534 -53.270404) (xy 16.863178 -53.291334)
			(xy 16.892906 -53.337302) (xy 16.915754 -53.387048) (xy 16.931251 -53.439551) (xy 16.939081 -53.49373)
			(xy 16.93908 -53.548473) (xy 16.931251 -53.602652) (xy 16.915753 -53.655155) (xy 16.892905 -53.704901)
			(xy 16.863176 -53.750868) (xy 16.846604 -53.77053) (xy 17.210786 -53.77053) (xy 17.211293 -53.741612)
			(xy 17.22002 -53.684439) (xy 17.237278 -53.629239) (xy 17.262671 -53.577276) (xy 17.295619 -53.529743)
			(xy 17.335364 -53.487728) (xy 17.357852 -53.46954) (xy 17.36664 -53.461915) (xy 17.376832 -53.441027)
			(xy 17.37741 -53.429408) (xy 17.37741 -53.349652) (xy 17.376881 -53.338019) (xy 17.366685 -53.31711)
			(xy 17.357852 -53.30952) (xy 17.335368 -53.29133) (xy 17.295635 -53.249308) (xy 17.262698 -53.201773)
			(xy 17.23731 -53.149812) (xy 17.220053 -53.094615) (xy 17.211322 -53.037446) (xy 17.210786 -53.00853)
			(xy 17.211283 -52.981278) (xy 17.219036 -52.927329) (xy 17.234388 -52.875032) (xy 17.257026 -52.825452)
			(xy 17.286491 -52.779599) (xy 17.322181 -52.738406) (xy 17.36337 -52.702712) (xy 17.409221 -52.673244)
			(xy 17.458798 -52.6506) (xy 17.511094 -52.635244) (xy 17.565042 -52.627486) (xy 17.592294 -52.627022)
			(xy 17.618608 -52.627486) (xy 17.670737 -52.634721) (xy 17.72138 -52.64904) (xy 17.769579 -52.670173)
			(xy 17.814423 -52.69772) (xy 17.855062 -52.73116) (xy 17.873218 -52.750212) (xy 17.880729 -52.757625)
			(xy 17.900017 -52.766143) (xy 17.910556 -52.766722) (xy 17.985232 -52.766722) (xy 17.995778 -52.766163)
			(xy 18.015073 -52.757648) (xy 18.02257 -52.750212) (xy 18.04075 -52.73118) (xy 18.081374 -52.697721)
			(xy 18.126209 -52.670158) (xy 18.174405 -52.649015) (xy 18.225049 -52.634693) (xy 18.277179 -52.627463)
			(xy 18.303494 -52.627022) (xy 18.330748 -52.627461) (xy 18.384701 -52.635218) (xy 18.437002 -52.650575)
			(xy 18.486584 -52.673219) (xy 18.532438 -52.702689) (xy 18.573632 -52.738385) (xy 18.609326 -52.779581)
			(xy 18.638793 -52.825437) (xy 18.661434 -52.875021) (xy 18.676787 -52.927322) (xy 18.684541 -52.981276)
			(xy 18.685002 -53.00853) (xy 18.684512 -53.036196) (xy 18.682281 -53.051456) (xy 26.94127 -53.051456)
			(xy 26.945341 -52.995834) (xy 26.957467 -52.941397) (xy 26.97739 -52.889306) (xy 27.004686 -52.840671)
			(xy 27.038772 -52.796528) (xy 27.078921 -52.757819) (xy 27.124279 -52.725368) (xy 27.173879 -52.699867)
			(xy 27.226663 -52.68186) (xy 27.281506 -52.67173) (xy 27.33724 -52.669693) (xy 27.392677 -52.675793)
			(xy 27.446634 -52.689899) (xy 27.497963 -52.711711) (xy 27.545569 -52.740765) (xy 27.588437 -52.77644)
			(xy 27.625654 -52.817977) (xy 27.656427 -52.86449) (xy 27.680099 -52.914987) (xy 27.696167 -52.968394)
			(xy 27.704287 -53.02357) (xy 27.704796 -53.051456) (xy 27.704287 -53.079342) (xy 27.696167 -53.134518)
			(xy 27.680099 -53.187925) (xy 27.656427 -53.238422) (xy 27.625654 -53.284935) (xy 27.588437 -53.326472)
			(xy 27.545569 -53.362147) (xy 27.497963 -53.391201) (xy 27.446634 -53.413013) (xy 27.392677 -53.427119)
			(xy 27.33724 -53.433219) (xy 27.281506 -53.431182) (xy 27.226663 -53.421052) (xy 27.173879 -53.403045)
			(xy 27.124279 -53.377544) (xy 27.078921 -53.345093) (xy 27.038772 -53.306384) (xy 27.004686 -53.262241)
			(xy 26.97739 -53.213606) (xy 26.957467 -53.161515) (xy 26.945341 -53.107078) (xy 26.94127 -53.051456)
			(xy 18.682281 -53.051456) (xy 18.676509 -53.090946) (xy 18.660688 -53.143968) (xy 18.637381 -53.194152)
			(xy 18.607077 -53.240448) (xy 18.570409 -53.281885) (xy 18.528144 -53.317597) (xy 18.504916 -53.332634)
			(xy 18.495219 -53.339246) (xy 18.482787 -53.359126) (xy 18.48104 -53.370734) (xy 18.473166 -53.450744)
			(xy 18.47251 -53.462383) (xy 18.480606 -53.484222) (xy 18.48866 -53.492654) (xy 18.488914 -53.492908)
			(xy 18.507484 -53.511) (xy 18.540063 -53.55133) (xy 18.566877 -53.595702) (xy 18.587432 -53.643298)
			(xy 18.601348 -53.69324) (xy 18.608368 -53.744608) (xy 18.608802 -53.77053) (xy 18.60835 -53.797782)
			(xy 18.600589 -53.851732) (xy 18.58523 -53.904027) (xy 18.562585 -53.953605) (xy 18.533115 -53.999456)
			(xy 18.49742 -54.040646) (xy 18.456227 -54.076337) (xy 18.410373 -54.105802) (xy 18.360793 -54.128443)
			(xy 18.308496 -54.143797) (xy 18.254546 -54.151553) (xy 18.227294 -54.152038) (xy 18.199923 -54.151591)
			(xy 18.145742 -54.143771) (xy 18.093239 -54.128278) (xy 18.043492 -54.105432) (xy 17.997526 -54.075702)
			(xy 17.976596 -54.058058) (xy 17.976342 -54.057804) (xy 17.969247 -54.052229) (xy 17.952337 -54.045975)
			(xy 17.943322 -54.045612) (xy 17.876266 -54.045612) (xy 17.867247 -54.04595) (xy 17.85033 -54.052211)
			(xy 17.843246 -54.057804) (xy 17.843246 -54.058058) (xy 17.842992 -54.058058) (xy 17.822068 -54.075708)
			(xy 17.776094 -54.105419) (xy 17.726344 -54.128254) (xy 17.673842 -54.143742) (xy 17.619664 -54.151567)
			(xy 17.592294 -54.152038) (xy 17.565044 -54.151528) (xy 17.511099 -54.143771) (xy 17.458806 -54.128417)
			(xy 17.409231 -54.105777) (xy 17.363382 -54.076313) (xy 17.322193 -54.040624) (xy 17.286501 -53.999437)
			(xy 17.257034 -53.95359) (xy 17.234391 -53.904016) (xy 17.219034 -53.851725) (xy 17.211274 -53.79778)
			(xy 17.210786 -53.77053) (xy 16.846604 -53.77053) (xy 16.845534 -53.7718) (xy 16.84528 -53.772054)
			(xy 16.839704 -53.779148) (xy 16.833452 -53.796059) (xy 16.833088 -53.805074) (xy 16.833088 -53.87213)
			(xy 16.833434 -53.881148) (xy 16.839689 -53.898065) (xy 16.84528 -53.90515) (xy 16.845534 -53.90515)
			(xy 16.845534 -53.905404) (xy 16.863178 -53.926334) (xy 16.892906 -53.972302) (xy 16.915754 -54.022048)
			(xy 16.931251 -54.074551) (xy 16.939081 -54.12873) (xy 16.93908 -54.183473) (xy 16.931251 -54.237652)
			(xy 16.915753 -54.290155) (xy 16.90196 -54.320186) (xy 19.130518 -54.320186) (xy 19.130971 -54.292815)
			(xy 19.138792 -54.238635) (xy 19.154283 -54.186132) (xy 19.177128 -54.136385) (xy 19.206855 -54.090419)
			(xy 19.224498 -54.069488) (xy 19.224752 -54.069234) (xy 19.230337 -54.062146) (xy 19.236583 -54.04523)
			(xy 19.236944 -54.036214) (xy 19.236944 -53.969158) (xy 19.236572 -53.960142) (xy 19.230336 -53.943225)
			(xy 19.224752 -53.936138) (xy 19.224498 -53.936138) (xy 19.224498 -53.935884) (xy 19.206885 -53.914931)
			(xy 19.177169 -53.868964) (xy 19.154328 -53.819222) (xy 19.138831 -53.766726) (xy 19.130996 -53.712554)
			(xy 19.130518 -53.685186) (xy 19.131004 -53.657935) (xy 19.13876 -53.603987) (xy 19.154115 -53.551692)
			(xy 19.176757 -53.502115) (xy 19.206223 -53.456265) (xy 19.241914 -53.415074) (xy 19.283105 -53.379383)
			(xy 19.328955 -53.349917) (xy 19.378532 -53.327275) (xy 19.430827 -53.31192) (xy 19.484775 -53.304164)
			(xy 19.539277 -53.304164) (xy 19.593225 -53.31192) (xy 19.64552 -53.327275) (xy 19.695097 -53.349917)
			(xy 19.740947 -53.379383) (xy 19.782138 -53.415074) (xy 19.817829 -53.456265) (xy 19.843722 -53.496556)
			(xy 32.133441 -53.496556) (xy 32.133441 -53.442044) (xy 32.141199 -53.388088) (xy 32.156558 -53.335785)
			(xy 32.179204 -53.2862) (xy 32.208677 -53.240343) (xy 32.244376 -53.199148) (xy 32.285575 -53.163453)
			(xy 32.331435 -53.133985) (xy 32.381022 -53.111344) (xy 32.433327 -53.095991) (xy 32.487284 -53.088238)
			(xy 32.51454 -53.087778) (xy 32.54191 -53.08826) (xy 32.596089 -53.096071) (xy 32.648593 -53.111555)
			(xy 32.69834 -53.134394) (xy 32.744307 -53.164117) (xy 32.765238 -53.181758) (xy 32.765492 -53.182012)
			(xy 32.772576 -53.187603) (xy 32.789495 -53.193847) (xy 32.798512 -53.194204) (xy 32.865568 -53.194204)
			(xy 32.874583 -53.193831) (xy 32.8915 -53.187594) (xy 32.898588 -53.182012) (xy 32.898588 -53.181758)
			(xy 32.898842 -53.181758) (xy 32.919779 -53.164126) (xy 32.965751 -53.134414) (xy 33.015498 -53.111578)
			(xy 33.067997 -53.096085) (xy 33.122171 -53.088253) (xy 33.14954 -53.087778) (xy 33.176788 -53.088295)
			(xy 33.23073 -53.096056) (xy 33.283018 -53.111414) (xy 33.332588 -53.134056) (xy 33.378432 -53.163523)
			(xy 33.419616 -53.199213) (xy 33.455301 -53.2404) (xy 33.484763 -53.286247) (xy 33.5074 -53.33582)
			(xy 33.522753 -53.388109) (xy 33.530508 -53.442052) (xy 33.530508 -53.496548) (xy 33.522753 -53.550491)
			(xy 33.5074 -53.60278) (xy 33.484763 -53.652353) (xy 33.455301 -53.6982) (xy 33.419616 -53.739387)
			(xy 33.378432 -53.775077) (xy 33.332588 -53.804544) (xy 33.283018 -53.827186) (xy 33.23073 -53.842544)
			(xy 33.176788 -53.850305) (xy 33.14954 -53.850794) (xy 33.122171 -53.850306) (xy 33.067992 -53.842494)
			(xy 33.015489 -53.82701) (xy 32.965742 -53.804173) (xy 32.919774 -53.774453) (xy 32.898842 -53.756814)
			(xy 32.898588 -53.75656) (xy 32.891513 -53.750957) (xy 32.874587 -53.744721) (xy 32.865568 -53.744368)
			(xy 32.798512 -53.744368) (xy 32.789497 -53.744738) (xy 32.77258 -53.750977) (xy 32.765492 -53.75656)
			(xy 32.765492 -53.756814) (xy 32.765238 -53.756814) (xy 32.744304 -53.774451) (xy 32.698332 -53.804163)
			(xy 32.648585 -53.826999) (xy 32.596084 -53.84249) (xy 32.541909 -53.850319) (xy 32.51454 -53.850794)
			(xy 32.487284 -53.850362) (xy 32.433327 -53.842609) (xy 32.381022 -53.827256) (xy 32.331435 -53.804615)
			(xy 32.285575 -53.775147) (xy 32.244376 -53.739452) (xy 32.208677 -53.698257) (xy 32.179204 -53.6524)
			(xy 32.156558 -53.602815) (xy 32.141199 -53.550512) (xy 32.133441 -53.496556) (xy 19.843722 -53.496556)
			(xy 19.847295 -53.502115) (xy 19.869937 -53.551692) (xy 19.885292 -53.603987) (xy 19.893048 -53.657935)
			(xy 19.893534 -53.685186) (xy 19.893076 -53.712557) (xy 19.885259 -53.766737) (xy 19.869769 -53.819241)
			(xy 19.846925 -53.868987) (xy 19.817197 -53.914953) (xy 19.799554 -53.935884) (xy 19.7993 -53.936138)
			(xy 19.793733 -53.943238) (xy 19.787475 -53.960145) (xy 19.787108 -53.969158) (xy 19.787108 -54.036214)
			(xy 19.787457 -54.045232) (xy 19.79371 -54.062149) (xy 19.7993 -54.069234) (xy 19.799554 -54.069234)
			(xy 19.799554 -54.069488) (xy 19.817194 -54.09042) (xy 19.846907 -54.136392) (xy 19.869744 -54.186139)
			(xy 19.885234 -54.23864) (xy 19.893061 -54.292817) (xy 19.893534 -54.320186) (xy 19.893048 -54.347437)
			(xy 19.885292 -54.401385) (xy 19.869937 -54.45368) (xy 19.847295 -54.503257) (xy 19.817829 -54.549107)
			(xy 19.782138 -54.590298) (xy 19.740947 -54.625989) (xy 19.695097 -54.655455) (xy 19.64552 -54.678097)
			(xy 19.593225 -54.693452) (xy 19.539277 -54.701208) (xy 19.484775 -54.701208) (xy 19.430827 -54.693452)
			(xy 19.378532 -54.678097) (xy 19.328955 -54.655455) (xy 19.283105 -54.625989) (xy 19.241914 -54.590298)
			(xy 19.206223 -54.549107) (xy 19.176757 -54.503257) (xy 19.154115 -54.45368) (xy 19.13876 -54.401385)
			(xy 19.131004 -54.347437) (xy 19.130518 -54.320186) (xy 16.90196 -54.320186) (xy 16.892905 -54.339901)
			(xy 16.863176 -54.385868) (xy 16.845534 -54.4068) (xy 16.84528 -54.407054) (xy 16.839704 -54.414148)
			(xy 16.833452 -54.431059) (xy 16.833088 -54.440074) (xy 16.833088 -54.50713) (xy 16.833434 -54.516148)
			(xy 16.839689 -54.533065) (xy 16.84528 -54.54015) (xy 16.845534 -54.54015) (xy 16.845534 -54.540404)
			(xy 16.863194 -54.561319) (xy 16.892901 -54.607297) (xy 16.915733 -54.657049) (xy 16.931219 -54.709553)
			(xy 16.939042 -54.763732) (xy 16.939159 -54.770528) (xy 20.07108 -54.770528) (xy 20.071543 -54.743157)
			(xy 20.079359 -54.688977) (xy 20.094847 -54.636474) (xy 20.11769 -54.586727) (xy 20.147417 -54.540761)
			(xy 20.16506 -54.51983) (xy 20.165314 -54.519576) (xy 20.170918 -54.512502) (xy 20.177154 -54.495575)
			(xy 20.177506 -54.486556) (xy 20.177506 -54.4195) (xy 20.177148 -54.410483) (xy 20.170901 -54.393566)
			(xy 20.165314 -54.38648) (xy 20.16506 -54.38648) (xy 20.16506 -54.386226) (xy 20.147413 -54.3653)
			(xy 20.117704 -54.319325) (xy 20.09487 -54.269576) (xy 20.07938 -54.217074) (xy 20.071553 -54.162898)
			(xy 20.07108 -54.135528) (xy 20.071566 -54.108277) (xy 20.079322 -54.054329) (xy 20.094677 -54.002034)
			(xy 20.117319 -53.952457) (xy 20.146785 -53.906607) (xy 20.182476 -53.865416) (xy 20.223667 -53.829725)
			(xy 20.269517 -53.800259) (xy 20.319094 -53.777617) (xy 20.371389 -53.762262) (xy 20.425337 -53.754506)
			(xy 20.479839 -53.754506) (xy 20.533787 -53.762262) (xy 20.586082 -53.777617) (xy 20.635659 -53.800259)
			(xy 20.681509 -53.829725) (xy 20.7227 -53.865416) (xy 20.758391 -53.906607) (xy 20.787857 -53.952457)
			(xy 20.792932 -53.96357) (xy 24.77211 -53.96357) (xy 24.776181 -53.907948) (xy 24.788307 -53.853511)
			(xy 24.80823 -53.80142) (xy 24.835526 -53.752785) (xy 24.869612 -53.708642) (xy 24.909761 -53.669933)
			(xy 24.955119 -53.637482) (xy 25.004719 -53.611981) (xy 25.057503 -53.593974) (xy 25.112346 -53.583844)
			(xy 25.16808 -53.581807) (xy 25.223517 -53.587907) (xy 25.277474 -53.602013) (xy 25.328803 -53.623825)
			(xy 25.376409 -53.652879) (xy 25.419277 -53.688554) (xy 25.456494 -53.730091) (xy 25.487267 -53.776604)
			(xy 25.510939 -53.827101) (xy 25.527007 -53.880508) (xy 25.535127 -53.935684) (xy 25.535636 -53.96357)
			(xy 25.535127 -53.991456) (xy 25.527007 -54.046632) (xy 25.510939 -54.100039) (xy 25.487267 -54.150536)
			(xy 25.456494 -54.197049) (xy 25.419277 -54.238586) (xy 25.376409 -54.274261) (xy 25.328803 -54.303315)
			(xy 25.277474 -54.325127) (xy 25.223517 -54.339233) (xy 25.16808 -54.345333) (xy 25.112346 -54.343296)
			(xy 25.057503 -54.333166) (xy 25.004719 -54.315159) (xy 24.955119 -54.289658) (xy 24.909761 -54.257207)
			(xy 24.869612 -54.218498) (xy 24.835526 -54.174355) (xy 24.80823 -54.12572) (xy 24.788307 -54.073629)
			(xy 24.776181 -54.019192) (xy 24.77211 -53.96357) (xy 20.792932 -53.96357) (xy 20.810499 -54.002034)
			(xy 20.825854 -54.054329) (xy 20.83361 -54.108277) (xy 20.834096 -54.135528) (xy 20.833647 -54.162899)
			(xy 20.825825 -54.217079) (xy 20.810332 -54.269582) (xy 20.787487 -54.319329) (xy 20.757759 -54.365295)
			(xy 20.740116 -54.386226) (xy 20.739862 -54.38648) (xy 20.734273 -54.393565) (xy 20.728029 -54.410483)
			(xy 20.72767 -54.4195) (xy 20.72767 -54.486556) (xy 20.728055 -54.49557) (xy 20.734284 -54.512487)
			(xy 20.739862 -54.519576) (xy 20.740116 -54.519576) (xy 20.740116 -54.51983) (xy 20.757738 -54.540776)
			(xy 20.787452 -54.586745) (xy 20.810291 -54.636489) (xy 20.825786 -54.688987) (xy 20.833619 -54.74316)
			(xy 20.834096 -54.770528) (xy 20.83361 -54.797779) (xy 20.825854 -54.851727) (xy 20.810499 -54.904022)
			(xy 20.787857 -54.953599) (xy 20.765071 -54.989055) (xy 29.901045 -54.989055) (xy 29.901045 -54.934545)
			(xy 29.908803 -54.880589) (xy 29.924161 -54.828287) (xy 29.946807 -54.778704) (xy 29.976279 -54.732848)
			(xy 30.011977 -54.691653) (xy 30.053175 -54.655958) (xy 30.099034 -54.62649) (xy 30.148619 -54.603849)
			(xy 30.200923 -54.588496) (xy 30.254879 -54.580743) (xy 30.282134 -54.580282) (xy 30.310226 -54.58075)
			(xy 30.365805 -54.588982) (xy 30.419575 -54.605278) (xy 30.470372 -54.629285) (xy 30.517098 -54.660484)
			(xy 30.558743 -54.698199) (xy 30.594404 -54.741616) (xy 30.609286 -54.765448) (xy 30.61462 -54.774338)
			(xy 30.631638 -54.78653) (xy 30.724856 -54.80685) (xy 30.74543 -54.802532) (xy 30.754066 -54.79669)
			(xy 30.778137 -54.780701) (xy 30.830066 -54.755356) (xy 30.885222 -54.738127) (xy 30.942344 -54.729409)
			(xy 30.971236 -54.728872) (xy 30.998487 -54.729344) (xy 31.052434 -54.737105) (xy 31.104728 -54.752464)
			(xy 31.154304 -54.775108) (xy 31.200153 -54.804576) (xy 31.241343 -54.840269) (xy 31.277034 -54.881459)
			(xy 31.3065 -54.92731) (xy 31.329142 -54.976887) (xy 31.344498 -55.029181) (xy 31.352257 -55.083129)
			(xy 31.352744 -55.11038) (xy 31.35228 -55.13775) (xy 31.344464 -55.19193) (xy 31.328975 -55.244434)
			(xy 31.306132 -55.294181) (xy 31.276406 -55.340147) (xy 31.258764 -55.361078) (xy 31.25851 -55.361332)
			(xy 31.252947 -55.368435) (xy 31.246686 -55.385339) (xy 31.246318 -55.394352) (xy 31.246318 -55.461408)
			(xy 31.246667 -55.470426) (xy 31.25292 -55.487343) (xy 31.25851 -55.494428) (xy 31.258764 -55.494428)
			(xy 31.258764 -55.494682) (xy 31.276385 -55.51563) (xy 31.306112 -55.561595) (xy 31.328959 -55.611339)
			(xy 31.344457 -55.663839) (xy 31.352288 -55.718015) (xy 31.35229 -55.772755) (xy 31.344463 -55.826932)
			(xy 31.328969 -55.879433) (xy 31.306126 -55.929178) (xy 31.276404 -55.975145) (xy 31.258764 -55.996078)
			(xy 31.25851 -55.996332) (xy 31.252947 -56.003435) (xy 31.246686 -56.020339) (xy 31.246318 -56.029352)
			(xy 31.246318 -56.096408) (xy 31.246667 -56.105426) (xy 31.25292 -56.122343) (xy 31.25851 -56.129428)
			(xy 31.258764 -56.129428) (xy 31.258764 -56.129682) (xy 31.276403 -56.150615) (xy 31.306116 -56.196587)
			(xy 31.328952 -56.246334) (xy 31.344443 -56.298835) (xy 31.352271 -56.353011) (xy 31.352744 -56.38038)
			(xy 31.352258 -56.407631) (xy 31.344502 -56.461579) (xy 31.329147 -56.513874) (xy 31.306505 -56.563451)
			(xy 31.277039 -56.609301) (xy 31.241348 -56.650492) (xy 31.200157 -56.686183) (xy 31.154307 -56.715649)
			(xy 31.10473 -56.738291) (xy 31.052435 -56.753646) (xy 30.998487 -56.761402) (xy 30.943985 -56.761402)
			(xy 30.890037 -56.753646) (xy 30.837742 -56.738291) (xy 30.788165 -56.715649) (xy 30.742315 -56.686183)
			(xy 30.701124 -56.650492) (xy 30.665433 -56.609301) (xy 30.635967 -56.563451) (xy 30.613325 -56.513874)
			(xy 30.59797 -56.461579) (xy 30.590214 -56.407631) (xy 30.589728 -56.38038) (xy 30.590176 -56.353009)
			(xy 30.597997 -56.298829) (xy 30.61349 -56.246325) (xy 30.636336 -56.196579) (xy 30.666065 -56.150613)
			(xy 30.683708 -56.129682) (xy 30.683962 -56.129428) (xy 30.68955 -56.122343) (xy 30.695794 -56.105425)
			(xy 30.696154 -56.096408) (xy 30.696154 -56.029352) (xy 30.695782 -56.020336) (xy 30.689546 -56.003419)
			(xy 30.683962 -55.996332) (xy 30.683708 -55.996332) (xy 30.683708 -55.996078) (xy 30.666049 -55.975161)
			(xy 30.636326 -55.92919) (xy 30.613483 -55.879441) (xy 30.597989 -55.826937) (xy 30.590163 -55.772756)
			(xy 30.590165 -55.718014) (xy 30.597995 -55.663834) (xy 30.613494 -55.611331) (xy 30.63634 -55.561584)
			(xy 30.666067 -55.515615) (xy 30.683708 -55.494682) (xy 30.683962 -55.494428) (xy 30.68955 -55.487343)
			(xy 30.695794 -55.470425) (xy 30.696154 -55.461408) (xy 30.696154 -55.394352) (xy 30.695782 -55.385336)
			(xy 30.689546 -55.368419) (xy 30.683962 -55.361332) (xy 30.683708 -55.360824) (xy 30.672765 -55.348089)
			(xy 30.652923 -55.320998) (xy 30.644084 -55.306722) (xy 30.63875 -55.297832) (xy 30.621732 -55.28564)
			(xy 30.528514 -55.26532) (xy 30.50794 -55.269638) (xy 30.499304 -55.27548) (xy 30.475239 -55.291478)
			(xy 30.423308 -55.316822) (xy 30.368151 -55.334048) (xy 30.311026 -55.342763) (xy 30.282134 -55.343298)
			(xy 30.254879 -55.342857) (xy 30.200923 -55.335104) (xy 30.148619 -55.319751) (xy 30.099034 -55.29711)
			(xy 30.053175 -55.267642) (xy 30.011977 -55.231947) (xy 29.976279 -55.190752) (xy 29.946807 -55.144896)
			(xy 29.924161 -55.095313) (xy 29.908803 -55.043011) (xy 29.901045 -54.989055) (xy 20.765071 -54.989055)
			(xy 20.758391 -54.999449) (xy 20.7227 -55.04064) (xy 20.681509 -55.076331) (xy 20.635659 -55.105797)
			(xy 20.586082 -55.128439) (xy 20.533787 -55.143794) (xy 20.479839 -55.15155) (xy 20.425337 -55.15155)
			(xy 20.371389 -55.143794) (xy 20.319094 -55.128439) (xy 20.269517 -55.105797) (xy 20.223667 -55.076331)
			(xy 20.182476 -55.04064) (xy 20.146785 -54.999449) (xy 20.117319 -54.953599) (xy 20.094677 -54.904022)
			(xy 20.079322 -54.851727) (xy 20.071566 -54.797779) (xy 20.07108 -54.770528) (xy 16.939159 -54.770528)
			(xy 16.939514 -54.791102) (xy 16.939028 -54.818353) (xy 16.931272 -54.872301) (xy 16.915917 -54.924596)
			(xy 16.893275 -54.974173) (xy 16.863809 -55.020023) (xy 16.828118 -55.061214) (xy 16.786927 -55.096905)
			(xy 16.741077 -55.126371) (xy 16.6915 -55.149013) (xy 16.639205 -55.164368) (xy 16.585257 -55.172124)
			(xy 16.530755 -55.172124) (xy 16.476807 -55.164368) (xy 16.424512 -55.149013) (xy 16.374935 -55.126371)
			(xy 16.329085 -55.096905) (xy 16.287894 -55.061214) (xy 16.252203 -55.020023) (xy 16.222737 -54.974173)
			(xy 16.200095 -54.924596) (xy 16.18474 -54.872301) (xy 16.176984 -54.818353) (xy 16.176498 -54.791102)
			(xy 14.279033 -54.791102) (xy 14.276029 -54.810808) (xy 14.259806 -54.866328) (xy 14.235387 -54.918763)
			(xy 14.203334 -54.966912) (xy 14.164381 -55.00967) (xy 14.11942 -55.04606) (xy 14.094714 -55.061104)
			(xy 14.08811 -55.064914) (xy 14.086332 -55.06593) (xy 14.08303 -55.067708) (xy 14.076426 -55.078884)
			(xy 14.073231 -55.084683) (xy 14.069622 -55.097417) (xy 14.069314 -55.10403) (xy 14.059682 -55.722266)
			(xy 25.834084 -55.722266) (xy 25.838155 -55.666644) (xy 25.850281 -55.612207) (xy 25.870204 -55.560116)
			(xy 25.8975 -55.511481) (xy 25.931586 -55.467338) (xy 25.971735 -55.428629) (xy 26.017093 -55.396178)
			(xy 26.066693 -55.370677) (xy 26.119477 -55.35267) (xy 26.17432 -55.34254) (xy 26.230054 -55.340503)
			(xy 26.285491 -55.346603) (xy 26.339448 -55.360709) (xy 26.390777 -55.382521) (xy 26.438383 -55.411575)
			(xy 26.449534 -55.420855) (xy 28.224645 -55.420855) (xy 28.224645 -55.366345) (xy 28.232403 -55.312389)
			(xy 28.247761 -55.260087) (xy 28.270407 -55.210504) (xy 28.299879 -55.164648) (xy 28.335577 -55.123453)
			(xy 28.376775 -55.087758) (xy 28.422634 -55.05829) (xy 28.472219 -55.035649) (xy 28.524523 -55.020296)
			(xy 28.578479 -55.012543) (xy 28.605734 -55.012082) (xy 28.632048 -55.012533) (xy 28.684177 -55.019772)
			(xy 28.73482 -55.034094) (xy 28.783019 -55.05523) (xy 28.827862 -55.082779) (xy 28.868502 -55.11622)
			(xy 28.886658 -55.135272) (xy 28.894197 -55.142653) (xy 28.913464 -55.15119) (xy 28.923996 -55.151782)
			(xy 28.998672 -55.151782) (xy 29.009222 -55.151257) (xy 29.028518 -55.142719) (xy 29.03601 -55.135272)
			(xy 29.054162 -55.116213) (xy 29.094793 -55.082757) (xy 29.139634 -55.0552) (xy 29.187836 -55.034062)
			(xy 29.238484 -55.019745) (xy 29.290618 -55.012521) (xy 29.316934 -55.012082) (xy 29.344183 -55.012591)
			(xy 29.398125 -55.020351) (xy 29.450415 -55.035708) (xy 29.499986 -55.058351) (xy 29.545831 -55.087817)
			(xy 29.587016 -55.123508) (xy 29.622703 -55.164696) (xy 29.652165 -55.210544) (xy 29.674803 -55.260117)
			(xy 29.690156 -55.312408) (xy 29.697912 -55.366351) (xy 29.697912 -55.420849) (xy 29.690156 -55.474792)
			(xy 29.674803 -55.527083) (xy 29.652165 -55.576656) (xy 29.622703 -55.622504) (xy 29.587016 -55.663692)
			(xy 29.545831 -55.699383) (xy 29.499986 -55.728849) (xy 29.450415 -55.751492) (xy 29.398125 -55.766849)
			(xy 29.344183 -55.774609) (xy 29.316934 -55.775098) (xy 29.290619 -55.774675) (xy 29.238488 -55.767431)
			(xy 29.187844 -55.753104) (xy 29.139646 -55.731963) (xy 29.094803 -55.704409) (xy 29.054165 -55.670963)
			(xy 29.03601 -55.651908) (xy 29.028485 -55.64451) (xy 29.009208 -55.635983) (xy 28.998672 -55.635398)
			(xy 28.923996 -55.635398) (xy 28.913445 -55.635912) (xy 28.894149 -55.644458) (xy 28.886658 -55.651908)
			(xy 28.868517 -55.670978) (xy 28.827884 -55.704434) (xy 28.783041 -55.731991) (xy 28.734837 -55.753127)
			(xy 28.684187 -55.767441) (xy 28.632051 -55.774662) (xy 28.605734 -55.775098) (xy 28.578479 -55.774657)
			(xy 28.524523 -55.766904) (xy 28.472219 -55.751551) (xy 28.422634 -55.72891) (xy 28.376775 -55.699442)
			(xy 28.335577 -55.663747) (xy 28.299879 -55.622552) (xy 28.270407 -55.576696) (xy 28.247761 -55.527113)
			(xy 28.232403 -55.474811) (xy 28.224645 -55.420855) (xy 26.449534 -55.420855) (xy 26.481251 -55.44725)
			(xy 26.518468 -55.488787) (xy 26.549241 -55.5353) (xy 26.572913 -55.585797) (xy 26.588981 -55.639204)
			(xy 26.597101 -55.69438) (xy 26.59761 -55.722266) (xy 26.597101 -55.750152) (xy 26.588981 -55.805328)
			(xy 26.572913 -55.858735) (xy 26.549241 -55.909232) (xy 26.518468 -55.955745) (xy 26.481251 -55.997282)
			(xy 26.438383 -56.032957) (xy 26.390777 -56.062011) (xy 26.339448 -56.083823) (xy 26.285491 -56.097929)
			(xy 26.230054 -56.104029) (xy 26.17432 -56.101992) (xy 26.119477 -56.091862) (xy 26.066693 -56.073855)
			(xy 26.017093 -56.048354) (xy 25.971735 -56.015903) (xy 25.931586 -55.977194) (xy 25.8975 -55.933051)
			(xy 25.870204 -55.884416) (xy 25.850281 -55.832325) (xy 25.838155 -55.777888) (xy 25.834084 -55.722266)
			(xy 14.059682 -55.722266) (xy 14.048486 -56.440832) (xy 14.048647 -56.447916) (xy 14.052382 -56.461578)
			(xy 14.055852 -56.467756) (xy 14.063218 -56.480202) (xy 14.07033 -56.483758) (xy 14.093993 -56.495899)
			(xy 14.138006 -56.525755) (xy 14.177448 -56.561433) (xy 14.211554 -56.602241) (xy 14.239664 -56.64739)
			(xy 14.261233 -56.696003) (xy 14.275845 -56.747141) (xy 14.283214 -56.799812) (xy 14.28369 -56.826404)
			(xy 14.283281 -56.851951) (xy 14.276464 -56.902589) (xy 14.262952 -56.951864) (xy 14.242988 -56.998897)
			(xy 14.240594 -57.002934) (xy 21.563584 -57.002934) (xy 21.564105 -56.974843) (xy 21.572327 -56.919267)
			(xy 21.588614 -56.865499) (xy 21.612612 -56.814702) (xy 21.643803 -56.767974) (xy 21.681511 -56.726329)
			(xy 21.724921 -56.690665) (xy 21.74875 -56.675782) (xy 21.75764 -56.670448) (xy 21.769832 -56.65343)
			(xy 21.790152 -56.560212) (xy 21.785834 -56.539638) (xy 21.779992 -56.531002) (xy 21.76399 -56.50694)
			(xy 21.738648 -56.455008) (xy 21.721423 -56.399849) (xy 21.712708 -56.342725) (xy 21.712174 -56.313832)
			(xy 21.712685 -56.286581) (xy 21.720437 -56.232632) (xy 21.735788 -56.180337) (xy 21.758426 -56.130758)
			(xy 21.787889 -56.084905) (xy 21.823577 -56.043713) (xy 21.864765 -56.008019) (xy 21.910614 -55.97855)
			(xy 21.96019 -55.955906) (xy 22.012484 -55.940548) (xy 22.066431 -55.932789) (xy 22.093682 -55.932324)
			(xy 22.121052 -55.932795) (xy 22.175231 -55.940611) (xy 22.227735 -55.956098) (xy 22.277481 -55.978939)
			(xy 22.323448 -56.008663) (xy 22.34438 -56.026304) (xy 22.344634 -56.026558) (xy 22.35173 -56.03213)
			(xy 22.36864 -56.038384) (xy 22.377654 -56.03875) (xy 22.44471 -56.03875) (xy 22.453729 -56.038408)
			(xy 22.470646 -56.032151) (xy 22.47773 -56.026558) (xy 22.47773 -56.026304) (xy 22.477984 -56.026304)
			(xy 22.498917 -56.008663) (xy 22.544885 -55.978939) (xy 22.594631 -55.956093) (xy 22.647133 -55.940597)
			(xy 22.701311 -55.932768) (xy 22.756053 -55.932768) (xy 22.810231 -55.940597) (xy 22.862733 -55.956093)
			(xy 22.912479 -55.978939) (xy 22.958447 -56.008663) (xy 22.97938 -56.026304) (xy 22.979634 -56.026558)
			(xy 22.98673 -56.03213) (xy 23.00364 -56.038384) (xy 23.012654 -56.03875) (xy 23.07971 -56.03875)
			(xy 23.088729 -56.038408) (xy 23.105646 -56.032151) (xy 23.11273 -56.026558) (xy 23.11273 -56.026304)
			(xy 23.112984 -56.026304) (xy 23.133912 -56.00866) (xy 23.179886 -55.978948) (xy 23.229634 -55.956113)
			(xy 23.282136 -55.940624) (xy 23.336313 -55.932797) (xy 23.363682 -55.932324) (xy 23.390938 -55.932722)
			(xy 23.444895 -55.940477) (xy 23.4972 -55.955833) (xy 23.546787 -55.978476) (xy 23.592646 -56.007946)
			(xy 23.633844 -56.043643) (xy 23.669543 -56.08484) (xy 23.699015 -56.130698) (xy 23.721661 -56.180283)
			(xy 23.737019 -56.232587) (xy 23.744777 -56.286544) (xy 23.744777 -56.297068) (xy 24.086564 -56.297068)
			(xy 24.090635 -56.241446) (xy 24.102761 -56.187009) (xy 24.122684 -56.134918) (xy 24.14998 -56.086283)
			(xy 24.184066 -56.04214) (xy 24.224215 -56.003431) (xy 24.269573 -55.97098) (xy 24.319173 -55.945479)
			(xy 24.371957 -55.927472) (xy 24.4268 -55.917342) (xy 24.482534 -55.915305) (xy 24.537971 -55.921405)
			(xy 24.591928 -55.935511) (xy 24.643257 -55.957323) (xy 24.690863 -55.986377) (xy 24.733731 -56.022052)
			(xy 24.770948 -56.063589) (xy 24.801721 -56.110102) (xy 24.825393 -56.160599) (xy 24.841461 -56.214006)
			(xy 24.849581 -56.269182) (xy 24.85009 -56.297068) (xy 24.849581 -56.324954) (xy 24.841461 -56.38013)
			(xy 24.825393 -56.433537) (xy 24.801721 -56.484034) (xy 24.770948 -56.530547) (xy 24.733731 -56.572084)
			(xy 24.690863 -56.607759) (xy 24.643257 -56.636813) (xy 24.591928 -56.658625) (xy 24.537971 -56.672731)
			(xy 24.482534 -56.678831) (xy 24.4268 -56.676794) (xy 24.371957 -56.666664) (xy 24.319173 -56.648657)
			(xy 24.269573 -56.623156) (xy 24.224215 -56.590705) (xy 24.184066 -56.551996) (xy 24.14998 -56.507853)
			(xy 24.122684 -56.459218) (xy 24.102761 -56.407127) (xy 24.090635 -56.35269) (xy 24.086564 -56.297068)
			(xy 23.744777 -56.297068) (xy 23.744777 -56.341056) (xy 23.737019 -56.395013) (xy 23.721661 -56.447317)
			(xy 23.699015 -56.496902) (xy 23.669543 -56.54276) (xy 23.633844 -56.583957) (xy 23.592646 -56.619654)
			(xy 23.546787 -56.649124) (xy 23.4972 -56.671767) (xy 23.444895 -56.687123) (xy 23.390938 -56.694878)
			(xy 23.363682 -56.69534) (xy 23.336311 -56.694899) (xy 23.28213 -56.687077) (xy 23.229626 -56.671583)
			(xy 23.179879 -56.648736) (xy 23.133914 -56.619005) (xy 23.112984 -56.60136) (xy 23.11273 -56.601106)
			(xy 23.105639 -56.595527) (xy 23.088726 -56.589275) (xy 23.07971 -56.588914) (xy 23.012654 -56.588914)
			(xy 23.003639 -56.589294) (xy 22.986722 -56.595525) (xy 22.979634 -56.601106) (xy 22.979634 -56.60136)
			(xy 22.97938 -56.60136) (xy 22.958447 -56.619001) (xy 22.912479 -56.648725) (xy 22.862733 -56.671571)
			(xy 22.810231 -56.687067) (xy 22.756053 -56.694896) (xy 22.701311 -56.694896) (xy 22.647133 -56.687067)
			(xy 22.594631 -56.671571) (xy 22.544885 -56.648725) (xy 22.498917 -56.619001) (xy 22.477984 -56.60136)
			(xy 22.47773 -56.601106) (xy 22.470639 -56.595527) (xy 22.453726 -56.589275) (xy 22.44471 -56.588914)
			(xy 22.377654 -56.588914) (xy 22.368639 -56.589294) (xy 22.351722 -56.595525) (xy 22.344634 -56.601106)
			(xy 22.344126 -56.60136) (xy 22.331394 -56.612307) (xy 22.304301 -56.632146) (xy 22.290024 -56.640984)
			(xy 22.281134 -56.646318) (xy 22.268942 -56.663336) (xy 22.248622 -56.756554) (xy 22.25294 -56.777128)
			(xy 22.258782 -56.785764) (xy 22.274767 -56.809837) (xy 22.300113 -56.861765) (xy 22.317343 -56.91692)
			(xy 22.326063 -56.974042) (xy 22.3266 -57.002934) (xy 22.326114 -57.030185) (xy 22.318358 -57.084133)
			(xy 22.303003 -57.136428) (xy 22.280361 -57.186005) (xy 22.250895 -57.231855) (xy 22.215204 -57.273046)
			(xy 22.174013 -57.308737) (xy 22.128163 -57.338203) (xy 22.078586 -57.360845) (xy 22.026291 -57.3762)
			(xy 21.972343 -57.383956) (xy 21.917841 -57.383956) (xy 21.863893 -57.3762) (xy 21.811598 -57.360845)
			(xy 21.762021 -57.338203) (xy 21.716171 -57.308737) (xy 21.67498 -57.273046) (xy 21.639289 -57.231855)
			(xy 21.609823 -57.186005) (xy 21.587181 -57.136428) (xy 21.571826 -57.084133) (xy 21.56407 -57.030185)
			(xy 21.563584 -57.002934) (xy 14.240594 -57.002934) (xy 14.216927 -57.042846) (xy 14.201394 -57.063132)
			(xy 14.197584 -57.068212) (xy 14.195044 -57.073546) (xy 14.19225 -57.07888) (xy 14.18971 -57.090056)
			(xy 14.18971 -57.117996) (xy 14.189597 -57.123093) (xy 14.187548 -57.133078) (xy 14.185646 -57.137808)
			(xy 14.178788 -57.153556) (xy 14.178534 -57.154318) (xy 14.175994 -57.159906) (xy 14.174978 -57.167526)
			(xy 14.174978 -57.180226) (xy 14.176248 -57.18937) (xy 14.182344 -57.20207) (xy 14.187678 -57.208166)
			(xy 14.189202 -57.209944) (xy 14.190472 -57.211468) (xy 14.191996 -57.212992) (xy 14.194282 -57.215786)
			(xy 14.200632 -57.22366) (xy 14.201648 -57.224676) (xy 14.203172 -57.226708) (xy 14.221658 -57.251411)
			(xy 14.251243 -57.305551) (xy 14.271739 -57.363743) (xy 14.282613 -57.424473) (xy 14.28369 -57.455308)
			(xy 14.28369 -57.463436) (xy 14.28323 -57.48528) (xy 30.605982 -57.48528) (xy 30.610053 -57.429658)
			(xy 30.622179 -57.375221) (xy 30.642102 -57.32313) (xy 30.669398 -57.274495) (xy 30.703484 -57.230352)
			(xy 30.743633 -57.191643) (xy 30.788991 -57.159192) (xy 30.838591 -57.133691) (xy 30.891375 -57.115684)
			(xy 30.946218 -57.105554) (xy 31.001952 -57.103517) (xy 31.057389 -57.109617) (xy 31.111346 -57.123723)
			(xy 31.162675 -57.145535) (xy 31.210281 -57.174589) (xy 31.253149 -57.210264) (xy 31.290366 -57.251801)
			(xy 31.321139 -57.298314) (xy 31.344811 -57.348811) (xy 31.360879 -57.402218) (xy 31.368999 -57.457394)
			(xy 31.369508 -57.48528) (xy 31.368999 -57.513166) (xy 31.360879 -57.568342) (xy 31.344811 -57.621749)
			(xy 31.321139 -57.672246) (xy 31.290366 -57.718759) (xy 31.253149 -57.760296) (xy 31.210281 -57.795971)
			(xy 31.162675 -57.825025) (xy 31.111346 -57.846837) (xy 31.057389 -57.860943) (xy 31.001952 -57.867043)
			(xy 30.946218 -57.865006) (xy 30.891375 -57.854876) (xy 30.838591 -57.836869) (xy 30.788991 -57.811368)
			(xy 30.743633 -57.778917) (xy 30.703484 -57.740208) (xy 30.669398 -57.696065) (xy 30.642102 -57.64743)
			(xy 30.622179 -57.595339) (xy 30.610053 -57.540902) (xy 30.605982 -57.48528) (xy 14.28323 -57.48528)
			(xy 14.283156 -57.488768) (xy 14.276218 -57.538958) (xy 14.262708 -57.587791) (xy 14.242862 -57.63441)
			(xy 14.217028 -57.677998) (xy 14.201648 -57.698132) (xy 14.200378 -57.699656) (xy 14.19606 -57.705244)
			(xy 14.191234 -57.719722) (xy 14.18971 -57.73166) (xy 14.18971 -57.752996) (xy 14.189597 -57.758093)
			(xy 14.187548 -57.768078) (xy 14.185646 -57.772808) (xy 14.178788 -57.788556) (xy 14.178534 -57.789318)
			(xy 14.175994 -57.794906) (xy 14.174978 -57.802526) (xy 14.174978 -57.815226) (xy 14.176248 -57.82437)
			(xy 14.182344 -57.83707) (xy 14.187678 -57.843166) (xy 14.189202 -57.844944) (xy 14.190472 -57.846468)
			(xy 14.191996 -57.847992) (xy 14.194282 -57.850786) (xy 14.200632 -57.85866) (xy 14.201648 -57.859676)
			(xy 14.203172 -57.861708) (xy 14.221658 -57.886411) (xy 14.251243 -57.940551) (xy 14.271739 -57.998743)
			(xy 14.282613 -58.059473) (xy 14.28369 -58.090308) (xy 14.28369 -58.098436) (xy 14.283156 -58.123768)
			(xy 14.276218 -58.173958) (xy 14.262708 -58.222791) (xy 14.242862 -58.26941) (xy 14.217028 -58.312998)
			(xy 14.201648 -58.333132) (xy 14.200378 -58.334656) (xy 14.19606 -58.340244) (xy 14.191234 -58.354722)
			(xy 14.18971 -58.36666) (xy 14.18971 -58.387234) (xy 14.189567 -58.392673) (xy 14.187259 -58.403305)
			(xy 14.185138 -58.408316) (xy 14.179042 -58.421778) (xy 14.175421 -58.43044) (xy 14.174185 -58.449163)
			(xy 14.179807 -58.467064) (xy 14.185392 -58.47461) (xy 14.19098 -58.481722) (xy 14.194536 -58.486294)
			(xy 14.195044 -58.487056) (xy 14.212686 -58.508939) (xy 14.242018 -58.556887) (xy 14.253464 -58.58256)
			(xy 14.260702 -58.60019) (xy 14.272027 -58.63658) (xy 14.27607 -58.655204) (xy 14.279989 -58.679334)
			(xy 21.995384 -58.679334) (xy 21.995813 -58.653019) (xy 22.003056 -58.600889) (xy 22.017383 -58.550246)
			(xy 22.038523 -58.502047) (xy 22.066076 -58.457204) (xy 22.09952 -58.416566) (xy 22.118574 -58.39841)
			(xy 22.125969 -58.390883) (xy 22.134498 -58.371607) (xy 22.135084 -58.361072) (xy 22.135084 -58.286396)
			(xy 22.134575 -58.275844) (xy 22.126026 -58.256549) (xy 22.118574 -58.249058) (xy 22.0995 -58.230921)
			(xy 22.066046 -58.190287) (xy 22.03849 -58.145442) (xy 22.017355 -58.097238) (xy 22.003041 -58.046588)
			(xy 21.99582 -57.994451) (xy 21.995384 -57.968134) (xy 21.99587 -57.940883) (xy 22.003626 -57.886935)
			(xy 22.018981 -57.83464) (xy 22.041623 -57.785063) (xy 22.071089 -57.739213) (xy 22.10678 -57.698022)
			(xy 22.147971 -57.662331) (xy 22.193821 -57.632865) (xy 22.243398 -57.610223) (xy 22.295693 -57.594868)
			(xy 22.349641 -57.587112) (xy 22.404143 -57.587112) (xy 22.458091 -57.594868) (xy 22.510386 -57.610223)
			(xy 22.559963 -57.632865) (xy 22.605813 -57.662331) (xy 22.647004 -57.698022) (xy 22.682695 -57.739213)
			(xy 22.712161 -57.785063) (xy 22.734803 -57.83464) (xy 22.750158 -57.886935) (xy 22.757914 -57.940883)
			(xy 22.7584 -57.968134) (xy 22.757955 -57.994449) (xy 22.750716 -58.046578) (xy 22.743448 -58.072274)
			(xy 25.993596 -58.072274) (xy 25.997667 -58.016652) (xy 26.009793 -57.962215) (xy 26.029716 -57.910124)
			(xy 26.057012 -57.861489) (xy 26.091098 -57.817346) (xy 26.131247 -57.778637) (xy 26.176605 -57.746186)
			(xy 26.226205 -57.720685) (xy 26.278989 -57.702678) (xy 26.333832 -57.692548) (xy 26.389566 -57.690511)
			(xy 26.445003 -57.696611) (xy 26.49896 -57.710717) (xy 26.550289 -57.732529) (xy 26.597895 -57.761583)
			(xy 26.640763 -57.797258) (xy 26.67798 -57.838795) (xy 26.708753 -57.885308) (xy 26.732425 -57.935805)
			(xy 26.748493 -57.989212) (xy 26.756613 -58.044388) (xy 26.757122 -58.072274) (xy 26.757052 -58.076084)
			(xy 31.358076 -58.076084) (xy 31.362147 -58.020462) (xy 31.374273 -57.966025) (xy 31.394196 -57.913934)
			(xy 31.421492 -57.865299) (xy 31.455578 -57.821156) (xy 31.495727 -57.782447) (xy 31.541085 -57.749996)
			(xy 31.590685 -57.724495) (xy 31.643469 -57.706488) (xy 31.698312 -57.696358) (xy 31.754046 -57.694321)
			(xy 31.809483 -57.700421) (xy 31.86344 -57.714527) (xy 31.914769 -57.736339) (xy 31.962375 -57.765393)
			(xy 32.005243 -57.801068) (xy 32.04246 -57.842605) (xy 32.058796 -57.867296) (xy 33.64306 -57.867296)
			(xy 33.647131 -57.811674) (xy 33.659257 -57.757237) (xy 33.67918 -57.705146) (xy 33.706476 -57.656511)
			(xy 33.740562 -57.612368) (xy 33.780711 -57.573659) (xy 33.826069 -57.541208) (xy 33.875669 -57.515707)
			(xy 33.928453 -57.4977) (xy 33.983296 -57.48757) (xy 34.03903 -57.485533) (xy 34.094467 -57.491633)
			(xy 34.148424 -57.505739) (xy 34.199753 -57.527551) (xy 34.247359 -57.556605) (xy 34.290227 -57.59228)
			(xy 34.327444 -57.633817) (xy 34.358217 -57.68033) (xy 34.381889 -57.730827) (xy 34.397957 -57.784234)
			(xy 34.406077 -57.83941) (xy 34.406586 -57.867296) (xy 34.406077 -57.895182) (xy 34.397957 -57.950358)
			(xy 34.381889 -58.003765) (xy 34.358217 -58.054262) (xy 34.327444 -58.100775) (xy 34.290227 -58.142312)
			(xy 34.247359 -58.177987) (xy 34.199753 -58.207041) (xy 34.148424 -58.228853) (xy 34.094467 -58.242959)
			(xy 34.03903 -58.249059) (xy 33.983296 -58.247022) (xy 33.928453 -58.236892) (xy 33.875669 -58.218885)
			(xy 33.826069 -58.193384) (xy 33.780711 -58.160933) (xy 33.740562 -58.122224) (xy 33.706476 -58.078081)
			(xy 33.67918 -58.029446) (xy 33.659257 -57.977355) (xy 33.647131 -57.922918) (xy 33.64306 -57.867296)
			(xy 32.058796 -57.867296) (xy 32.073233 -57.889118) (xy 32.096905 -57.939615) (xy 32.112973 -57.993022)
			(xy 32.121093 -58.048198) (xy 32.121602 -58.076084) (xy 32.121093 -58.10397) (xy 32.112973 -58.159146)
			(xy 32.096905 -58.212553) (xy 32.073233 -58.26305) (xy 32.04246 -58.309563) (xy 32.005243 -58.3511)
			(xy 31.962375 -58.386775) (xy 31.914769 -58.415829) (xy 31.86344 -58.437641) (xy 31.809483 -58.451747)
			(xy 31.754046 -58.457847) (xy 31.698312 -58.45581) (xy 31.643469 -58.44568) (xy 31.590685 -58.427673)
			(xy 31.541085 -58.402172) (xy 31.495727 -58.369721) (xy 31.455578 -58.331012) (xy 31.421492 -58.286869)
			(xy 31.394196 -58.238234) (xy 31.374273 -58.186143) (xy 31.362147 -58.131706) (xy 31.358076 -58.076084)
			(xy 26.757052 -58.076084) (xy 26.756613 -58.10016) (xy 26.748493 -58.155336) (xy 26.732425 -58.208743)
			(xy 26.708753 -58.25924) (xy 26.67798 -58.305753) (xy 26.640763 -58.34729) (xy 26.597895 -58.382965)
			(xy 26.550289 -58.412019) (xy 26.49896 -58.433831) (xy 26.445003 -58.447937) (xy 26.389566 -58.454037)
			(xy 26.333832 -58.452) (xy 26.278989 -58.44187) (xy 26.226205 -58.423863) (xy 26.176605 -58.398362)
			(xy 26.131247 -58.365911) (xy 26.091098 -58.327202) (xy 26.057012 -58.283059) (xy 26.029716 -58.234424)
			(xy 26.009793 -58.182333) (xy 25.997667 -58.127896) (xy 25.993596 -58.072274) (xy 22.743448 -58.072274)
			(xy 22.736392 -58.097221) (xy 22.715256 -58.14542) (xy 22.687705 -58.190263) (xy 22.654263 -58.230902)
			(xy 22.63521 -58.249058) (xy 22.627826 -58.256595) (xy 22.619291 -58.275863) (xy 22.6187 -58.286396)
			(xy 22.6187 -58.361072) (xy 22.619231 -58.371621) (xy 22.627765 -58.390917) (xy 22.63521 -58.39841)
			(xy 22.654265 -58.416566) (xy 22.687722 -58.457196) (xy 22.715281 -58.502036) (xy 22.736419 -58.550237)
			(xy 22.739525 -58.561224) (xy 32.56229 -58.561224) (xy 32.566361 -58.505602) (xy 32.578487 -58.451165)
			(xy 32.59841 -58.399074) (xy 32.625706 -58.350439) (xy 32.659792 -58.306296) (xy 32.699941 -58.267587)
			(xy 32.745299 -58.235136) (xy 32.794899 -58.209635) (xy 32.847683 -58.191628) (xy 32.902526 -58.181498)
			(xy 32.95826 -58.179461) (xy 33.013697 -58.185561) (xy 33.067654 -58.199667) (xy 33.118983 -58.221479)
			(xy 33.166589 -58.250533) (xy 33.209457 -58.286208) (xy 33.246674 -58.327745) (xy 33.277447 -58.374258)
			(xy 33.301119 -58.424755) (xy 33.317187 -58.478162) (xy 33.325307 -58.533338) (xy 33.325816 -58.561224)
			(xy 33.325307 -58.58911) (xy 33.317187 -58.644286) (xy 33.301119 -58.697693) (xy 33.277447 -58.74819)
			(xy 33.246674 -58.794703) (xy 33.209457 -58.83624) (xy 33.166589 -58.871915) (xy 33.118983 -58.900969)
			(xy 33.067654 -58.922781) (xy 33.013697 -58.936887) (xy 32.95826 -58.942987) (xy 32.902526 -58.94095)
			(xy 32.847683 -58.93082) (xy 32.794899 -58.912813) (xy 32.745299 -58.887312) (xy 32.699941 -58.854861)
			(xy 32.659792 -58.816152) (xy 32.625706 -58.772009) (xy 32.59841 -58.723374) (xy 32.578487 -58.671283)
			(xy 32.566361 -58.616846) (xy 32.56229 -58.561224) (xy 22.739525 -58.561224) (xy 22.750737 -58.600884)
			(xy 22.757961 -58.653018) (xy 22.7584 -58.679334) (xy 22.757914 -58.706585) (xy 22.750158 -58.760533)
			(xy 22.734803 -58.812828) (xy 22.712161 -58.862405) (xy 22.682695 -58.908255) (xy 22.647004 -58.949446)
			(xy 22.605813 -58.985137) (xy 22.559963 -59.014603) (xy 22.510386 -59.037245) (xy 22.458091 -59.0526)
			(xy 22.404143 -59.060356) (xy 22.349641 -59.060356) (xy 22.295693 -59.0526) (xy 22.243398 -59.037245)
			(xy 22.193821 -59.014603) (xy 22.147971 -58.985137) (xy 22.10678 -58.949446) (xy 22.071089 -58.908255)
			(xy 22.041623 -58.862405) (xy 22.018981 -58.812828) (xy 22.003626 -58.760533) (xy 21.99587 -58.706585)
			(xy 21.995384 -58.679334) (xy 14.279989 -58.679334) (xy 14.280896 -58.684922) (xy 14.282057 -58.694918)
			(xy 14.283457 -58.714994) (xy 14.28369 -58.725054) (xy 14.28369 -58.740294) (xy 14.283436 -58.744358)
			(xy 14.283436 -58.748168) (xy 14.282674 -58.7629) (xy 14.282674 -58.763916) (xy 14.282166 -58.770266)
			(xy 14.279372 -58.789316) (xy 14.277455 -58.800939) (xy 14.272369 -58.823941) (xy 14.269212 -58.83529)
			(xy 14.269212 -58.836306) (xy 14.267688 -58.841386) (xy 14.263878 -58.854086) (xy 14.26083 -58.861452)
			(xy 14.250447 -58.888652) (xy 14.222642 -58.939803) (xy 14.205458 -58.963306) (xy 14.201394 -58.968894)
			(xy 14.221726 -59.174634) (xy 31.093154 -59.174634) (xy 31.097225 -59.119012) (xy 31.109351 -59.064575)
			(xy 31.129274 -59.012484) (xy 31.15657 -58.963849) (xy 31.190656 -58.919706) (xy 31.230805 -58.880997)
			(xy 31.276163 -58.848546) (xy 31.325763 -58.823045) (xy 31.378547 -58.805038) (xy 31.43339 -58.794908)
			(xy 31.489124 -58.792871) (xy 31.544561 -58.798971) (xy 31.598518 -58.813077) (xy 31.649847 -58.834889)
			(xy 31.697453 -58.863943) (xy 31.740321 -58.899618) (xy 31.777538 -58.941155) (xy 31.808311 -58.987668)
			(xy 31.831983 -59.038165) (xy 31.848051 -59.091572) (xy 31.856171 -59.146748) (xy 31.85668 -59.174634)
			(xy 31.856171 -59.20252) (xy 31.848051 -59.257696) (xy 31.831983 -59.311103) (xy 31.808311 -59.3616)
			(xy 31.777538 -59.408113) (xy 31.740321 -59.44965) (xy 31.697453 -59.485325) (xy 31.649847 -59.514379)
			(xy 31.598518 -59.536191) (xy 31.544561 -59.550297) (xy 31.489124 -59.556397) (xy 31.43339 -59.55436)
			(xy 31.378547 -59.54423) (xy 31.325763 -59.526223) (xy 31.276163 -59.500722) (xy 31.230805 -59.468271)
			(xy 31.190656 -59.429562) (xy 31.15657 -59.385419) (xy 31.129274 -59.336784) (xy 31.109351 -59.284693)
			(xy 31.097225 -59.230256) (xy 31.093154 -59.174634) (xy 14.221726 -59.174634) (xy 14.248384 -59.444382)
			(xy 14.299438 -59.96178) (xy 14.301699 -59.986164) (xy 14.303333 -60.019261) (xy 22.135824 -60.019261)
			(xy 22.135824 -59.964759) (xy 22.14358 -59.910811) (xy 22.158935 -59.858516) (xy 22.181576 -59.808938)
			(xy 22.211043 -59.763088) (xy 22.246734 -59.721897) (xy 22.287924 -59.686205) (xy 22.333775 -59.656738)
			(xy 22.383352 -59.634097) (xy 22.435647 -59.618741) (xy 22.489595 -59.610984) (xy 22.516846 -59.610498)
			(xy 22.544215 -59.610996) (xy 22.598393 -59.618806) (xy 22.650895 -59.634288) (xy 22.700643 -59.657123)
			(xy 22.746611 -59.68684) (xy 22.767544 -59.704478) (xy 22.767798 -59.704732) (xy 22.774878 -59.710327)
			(xy 22.7918 -59.716568) (xy 22.800818 -59.716924) (xy 22.867874 -59.716924) (xy 22.876889 -59.716549)
			(xy 22.893806 -59.710313) (xy 22.900894 -59.704732) (xy 22.900894 -59.704478) (xy 22.901148 -59.704478)
			(xy 22.922081 -59.686837) (xy 22.968049 -59.657113) (xy 23.017795 -59.634267) (xy 23.070297 -59.618771)
			(xy 23.124475 -59.610942) (xy 23.179217 -59.610942) (xy 23.233395 -59.618771) (xy 23.285897 -59.634267)
			(xy 23.335643 -59.657113) (xy 23.381611 -59.686837) (xy 23.402544 -59.704478) (xy 23.402798 -59.704732)
			(xy 23.409878 -59.710327) (xy 23.4268 -59.716568) (xy 23.435818 -59.716924) (xy 23.502874 -59.716924)
			(xy 23.511889 -59.716549) (xy 23.528806 -59.710313) (xy 23.535894 -59.704732) (xy 23.535894 -59.704478)
			(xy 23.536148 -59.704478) (xy 23.557086 -59.686846) (xy 23.603058 -59.657134) (xy 23.652804 -59.634297)
			(xy 23.705303 -59.618804) (xy 23.759477 -59.610974) (xy 23.786846 -59.610498) (xy 23.814099 -59.610969)
			(xy 23.86805 -59.618725) (xy 23.920347 -59.634081) (xy 23.969927 -59.656723) (xy 24.015781 -59.686191)
			(xy 24.056973 -59.721884) (xy 24.092667 -59.763076) (xy 24.122135 -59.808929) (xy 24.144778 -59.858509)
			(xy 24.160134 -59.910807) (xy 24.167891 -59.964757) (xy 24.167891 -60.019263) (xy 24.160134 -60.073213)
			(xy 24.144778 -60.125511) (xy 24.122135 -60.175091) (xy 24.092667 -60.220944) (xy 24.056973 -60.262136)
			(xy 24.015781 -60.297829) (xy 23.969927 -60.327297) (xy 23.920347 -60.349939) (xy 23.86805 -60.365295)
			(xy 23.814099 -60.373051) (xy 23.786846 -60.373514) (xy 23.759477 -60.373018) (xy 23.705299 -60.365207)
			(xy 23.652797 -60.349724) (xy 23.603049 -60.32689) (xy 23.557081 -60.297172) (xy 23.536148 -60.279534)
			(xy 23.535894 -60.27928) (xy 23.528815 -60.273683) (xy 23.511892 -60.267443) (xy 23.502874 -60.267088)
			(xy 23.435818 -60.267088) (xy 23.426802 -60.267456) (xy 23.409885 -60.273696) (xy 23.402798 -60.27928)
			(xy 23.402544 -60.279534) (xy 23.381611 -60.297175) (xy 23.335643 -60.326899) (xy 23.285897 -60.349745)
			(xy 23.233395 -60.365241) (xy 23.179217 -60.37307) (xy 23.124475 -60.37307) (xy 23.070297 -60.365241)
			(xy 23.017795 -60.349745) (xy 22.968049 -60.326899) (xy 22.922081 -60.297175) (xy 22.901148 -60.279534)
			(xy 22.900894 -60.27928) (xy 22.893815 -60.273683) (xy 22.876892 -60.267443) (xy 22.867874 -60.267088)
			(xy 22.800818 -60.267088) (xy 22.791802 -60.267456) (xy 22.774885 -60.273696) (xy 22.767798 -60.27928)
			(xy 22.767798 -60.279534) (xy 22.767544 -60.279534) (xy 22.746611 -60.297171) (xy 22.700638 -60.326882)
			(xy 22.65089 -60.349718) (xy 22.59839 -60.36521) (xy 22.544215 -60.373039) (xy 22.516846 -60.373514)
			(xy 22.489595 -60.373036) (xy 22.435647 -60.365279) (xy 22.383352 -60.349923) (xy 22.333775 -60.327282)
			(xy 22.287924 -60.297815) (xy 22.246734 -60.262123) (xy 22.211043 -60.220932) (xy 22.181576 -60.175082)
			(xy 22.158935 -60.125504) (xy 22.14358 -60.073209) (xy 22.135824 -60.019261) (xy 14.303333 -60.019261)
			(xy 14.304114 -60.035082) (xy 14.304264 -60.05957) (xy 14.304264 -60.633356) (xy 33.796984 -60.633356)
			(xy 33.801055 -60.577734) (xy 33.813181 -60.523297) (xy 33.833104 -60.471206) (xy 33.8604 -60.422571)
			(xy 33.894486 -60.378428) (xy 33.934635 -60.339719) (xy 33.979993 -60.307268) (xy 34.029593 -60.281767)
			(xy 34.082377 -60.26376) (xy 34.13722 -60.25363) (xy 34.192954 -60.251593) (xy 34.248391 -60.257693)
			(xy 34.302348 -60.271799) (xy 34.353677 -60.293611) (xy 34.401283 -60.322665) (xy 34.444151 -60.35834)
			(xy 34.481368 -60.399877) (xy 34.512141 -60.44639) (xy 34.535813 -60.496887) (xy 34.551881 -60.550294)
			(xy 34.560001 -60.60547) (xy 34.56051 -60.633356) (xy 34.560001 -60.661242) (xy 34.551881 -60.716418)
			(xy 34.535813 -60.769825) (xy 34.512141 -60.820322) (xy 34.481368 -60.866835) (xy 34.444151 -60.908372)
			(xy 34.401283 -60.944047) (xy 34.353677 -60.973101) (xy 34.302348 -60.994913) (xy 34.248391 -61.009019)
			(xy 34.192954 -61.015119) (xy 34.13722 -61.013082) (xy 34.082377 -61.002952) (xy 34.029593 -60.984945)
			(xy 33.979993 -60.959444) (xy 33.934635 -60.926993) (xy 33.894486 -60.888284) (xy 33.8604 -60.844141)
			(xy 33.833104 -60.795506) (xy 33.813181 -60.743415) (xy 33.801055 -60.688978) (xy 33.796984 -60.633356)
			(xy 14.304264 -60.633356) (xy 14.304264 -61.487812) (xy 32.30448 -61.487812) (xy 32.308551 -61.43219)
			(xy 32.320677 -61.377753) (xy 32.3406 -61.325662) (xy 32.367896 -61.277027) (xy 32.401982 -61.232884)
			(xy 32.442131 -61.194175) (xy 32.487489 -61.161724) (xy 32.537089 -61.136223) (xy 32.589873 -61.118216)
			(xy 32.644716 -61.108086) (xy 32.70045 -61.106049) (xy 32.755887 -61.112149) (xy 32.809844 -61.126255)
			(xy 32.861173 -61.148067) (xy 32.908779 -61.177121) (xy 32.951647 -61.212796) (xy 32.988864 -61.254333)
			(xy 33.019637 -61.300846) (xy 33.043309 -61.351343) (xy 33.059377 -61.40475) (xy 33.067497 -61.459926)
			(xy 33.068006 -61.487812) (xy 33.067497 -61.515698) (xy 33.059377 -61.570874) (xy 33.043309 -61.624281)
			(xy 33.019637 -61.674778) (xy 32.988864 -61.721291) (xy 32.951647 -61.762828) (xy 32.908779 -61.798503)
			(xy 32.861173 -61.827557) (xy 32.809844 -61.849369) (xy 32.755887 -61.863475) (xy 32.70045 -61.869575)
			(xy 32.644716 -61.867538) (xy 32.589873 -61.857408) (xy 32.537089 -61.839401) (xy 32.487489 -61.8139)
			(xy 32.442131 -61.781449) (xy 32.401982 -61.74274) (xy 32.367896 -61.698597) (xy 32.3406 -61.649962)
			(xy 32.320677 -61.597871) (xy 32.308551 -61.543434) (xy 32.30448 -61.487812) (xy 14.304264 -61.487812)
			(xy 14.304264 -61.851032) (xy 14.30401 -61.858398) (xy 14.30401 -61.85916) (xy 14.301904 -62.121034)
			(xy 30.242254 -62.121034) (xy 30.246325 -62.065412) (xy 30.258451 -62.010975) (xy 30.278374 -61.958884)
			(xy 30.30567 -61.910249) (xy 30.339756 -61.866106) (xy 30.379905 -61.827397) (xy 30.425263 -61.794946)
			(xy 30.474863 -61.769445) (xy 30.527647 -61.751438) (xy 30.58249 -61.741308) (xy 30.638224 -61.739271)
			(xy 30.693661 -61.745371) (xy 30.747618 -61.759477) (xy 30.798947 -61.781289) (xy 30.846553 -61.810343)
			(xy 30.889421 -61.846018) (xy 30.926638 -61.887555) (xy 30.957411 -61.934068) (xy 30.981083 -61.984565)
			(xy 30.997151 -62.037972) (xy 31.005271 -62.093148) (xy 31.00578 -62.121034) (xy 31.005271 -62.14892)
			(xy 30.997151 -62.204096) (xy 30.981083 -62.257503) (xy 30.957411 -62.308) (xy 30.926638 -62.354513)
			(xy 30.889421 -62.39605) (xy 30.846553 -62.431725) (xy 30.798947 -62.460779) (xy 30.747618 -62.482591)
			(xy 30.693661 -62.496697) (xy 30.638224 -62.502797) (xy 30.58249 -62.50076) (xy 30.527647 -62.49063)
			(xy 30.474863 -62.472623) (xy 30.425263 -62.447122) (xy 30.379905 -62.414671) (xy 30.339756 -62.375962)
			(xy 30.30567 -62.331819) (xy 30.278374 -62.283184) (xy 30.258451 -62.231093) (xy 30.246325 -62.176656)
			(xy 30.242254 -62.121034) (xy 14.301904 -62.121034) (xy 14.293119 -63.213549) (xy 22.120888 -63.213549)
			(xy 22.120888 -63.159051) (xy 22.128643 -63.105109) (xy 22.143996 -63.052818) (xy 22.166634 -63.003245)
			(xy 22.196095 -62.957398) (xy 22.231782 -62.91621) (xy 22.272966 -62.880519) (xy 22.31881 -62.851053)
			(xy 22.368381 -62.82841) (xy 22.420669 -62.813052) (xy 22.474611 -62.805291) (xy 22.50186 -62.804802)
			(xy 22.529229 -62.805291) (xy 22.583408 -62.813103) (xy 22.63591 -62.828587) (xy 22.685658 -62.851424)
			(xy 22.731626 -62.881143) (xy 22.752558 -62.898782) (xy 22.752812 -62.899036) (xy 22.759888 -62.904638)
			(xy 22.776813 -62.910874) (xy 22.785832 -62.911228) (xy 22.852888 -62.911228) (xy 22.861904 -62.910859)
			(xy 22.87882 -62.904619) (xy 22.885908 -62.899036) (xy 22.885908 -62.898782) (xy 22.886162 -62.898782)
			(xy 22.907095 -62.881141) (xy 22.953063 -62.851417) (xy 23.002809 -62.828571) (xy 23.055311 -62.813075)
			(xy 23.109489 -62.805246) (xy 23.164231 -62.805246) (xy 23.218409 -62.813075) (xy 23.270911 -62.828571)
			(xy 23.320657 -62.851417) (xy 23.366625 -62.881141) (xy 23.387558 -62.898782) (xy 23.387812 -62.899036)
			(xy 23.394888 -62.904638) (xy 23.411813 -62.910874) (xy 23.420832 -62.911228) (xy 23.487888 -62.911228)
			(xy 23.496904 -62.910859) (xy 23.51382 -62.904619) (xy 23.520908 -62.899036) (xy 23.520908 -62.898782)
			(xy 23.521162 -62.898782) (xy 23.542095 -62.881144) (xy 23.588068 -62.851433) (xy 23.637815 -62.828597)
			(xy 23.690316 -62.813106) (xy 23.744491 -62.805277) (xy 23.77186 -62.804802) (xy 23.799115 -62.805242)
			(xy 23.853072 -62.812995) (xy 23.905376 -62.828348) (xy 23.954963 -62.850989) (xy 24.000822 -62.880456)
			(xy 24.042021 -62.916151) (xy 24.07772 -62.957346) (xy 24.107192 -63.003202) (xy 24.129838 -63.052786)
			(xy 24.13966 -63.086234) (xy 27.387548 -63.086234) (xy 27.391619 -63.030612) (xy 27.403745 -62.976175)
			(xy 27.423668 -62.924084) (xy 27.450964 -62.875449) (xy 27.48505 -62.831306) (xy 27.525199 -62.792597)
			(xy 27.570557 -62.760146) (xy 27.620157 -62.734645) (xy 27.672941 -62.716638) (xy 27.727784 -62.706508)
			(xy 27.783518 -62.704471) (xy 27.797377 -62.705996) (xy 33.665158 -62.705996) (xy 33.669229 -62.650374)
			(xy 33.681355 -62.595937) (xy 33.701278 -62.543846) (xy 33.728574 -62.495211) (xy 33.76266 -62.451068)
			(xy 33.802809 -62.412359) (xy 33.848167 -62.379908) (xy 33.897767 -62.354407) (xy 33.950551 -62.3364)
			(xy 34.005394 -62.32627) (xy 34.061128 -62.324233) (xy 34.116565 -62.330333) (xy 34.170522 -62.344439)
			(xy 34.221851 -62.366251) (xy 34.269457 -62.395305) (xy 34.312325 -62.43098) (xy 34.349542 -62.472517)
			(xy 34.380315 -62.51903) (xy 34.403987 -62.569527) (xy 34.420055 -62.622934) (xy 34.428175 -62.67811)
			(xy 34.428684 -62.705996) (xy 34.428175 -62.733882) (xy 34.420055 -62.789058) (xy 34.403987 -62.842465)
			(xy 34.380315 -62.892962) (xy 34.349542 -62.939475) (xy 34.312325 -62.981012) (xy 34.269457 -63.016687)
			(xy 34.221851 -63.045741) (xy 34.170522 -63.067553) (xy 34.116565 -63.081659) (xy 34.061128 -63.087759)
			(xy 34.005394 -63.085722) (xy 33.950551 -63.075592) (xy 33.897767 -63.057585) (xy 33.848167 -63.032084)
			(xy 33.802809 -62.999633) (xy 33.76266 -62.960924) (xy 33.728574 -62.916781) (xy 33.701278 -62.868146)
			(xy 33.681355 -62.816055) (xy 33.669229 -62.761618) (xy 33.665158 -62.705996) (xy 27.797377 -62.705996)
			(xy 27.838955 -62.710571) (xy 27.892912 -62.724677) (xy 27.944241 -62.746489) (xy 27.991847 -62.775543)
			(xy 28.034715 -62.811218) (xy 28.071932 -62.852755) (xy 28.102705 -62.899268) (xy 28.126377 -62.949765)
			(xy 28.142445 -63.003172) (xy 28.150565 -63.058348) (xy 28.151074 -63.086234) (xy 28.150565 -63.11412)
			(xy 28.142445 -63.169296) (xy 28.126377 -63.222703) (xy 28.102705 -63.2732) (xy 28.102552 -63.273432)
			(xy 29.576774 -63.273432) (xy 29.580845 -63.21781) (xy 29.592971 -63.163373) (xy 29.612894 -63.111282)
			(xy 29.64019 -63.062647) (xy 29.674276 -63.018504) (xy 29.714425 -62.979795) (xy 29.759783 -62.947344)
			(xy 29.809383 -62.921843) (xy 29.862167 -62.903836) (xy 29.91701 -62.893706) (xy 29.972744 -62.891669)
			(xy 30.028181 -62.897769) (xy 30.082138 -62.911875) (xy 30.133467 -62.933687) (xy 30.181073 -62.962741)
			(xy 30.223941 -62.998416) (xy 30.261158 -63.039953) (xy 30.291931 -63.086466) (xy 30.315603 -63.136963)
			(xy 30.331671 -63.19037) (xy 30.339791 -63.245546) (xy 30.3403 -63.273432) (xy 30.339791 -63.301318)
			(xy 30.331671 -63.356494) (xy 30.315603 -63.409901) (xy 30.291931 -63.460398) (xy 30.261158 -63.506911)
			(xy 30.223941 -63.548448) (xy 30.181073 -63.584123) (xy 30.133467 -63.613177) (xy 30.082138 -63.634989)
			(xy 30.028181 -63.649095) (xy 29.972744 -63.655195) (xy 29.91701 -63.653158) (xy 29.862167 -63.643028)
			(xy 29.809383 -63.625021) (xy 29.759783 -63.59952) (xy 29.714425 -63.567069) (xy 29.674276 -63.52836)
			(xy 29.64019 -63.484217) (xy 29.612894 -63.435582) (xy 29.592971 -63.383491) (xy 29.580845 -63.329054)
			(xy 29.576774 -63.273432) (xy 28.102552 -63.273432) (xy 28.071932 -63.319713) (xy 28.034715 -63.36125)
			(xy 27.991847 -63.396925) (xy 27.944241 -63.425979) (xy 27.892912 -63.447791) (xy 27.838955 -63.461897)
			(xy 27.783518 -63.467997) (xy 27.727784 -63.46596) (xy 27.672941 -63.45583) (xy 27.620157 -63.437823)
			(xy 27.570557 -63.412322) (xy 27.525199 -63.379871) (xy 27.48505 -63.341162) (xy 27.450964 -63.297019)
			(xy 27.423668 -63.248384) (xy 27.403745 -63.196293) (xy 27.391619 -63.141856) (xy 27.387548 -63.086234)
			(xy 24.13966 -63.086234) (xy 24.145197 -63.105089) (xy 24.152955 -63.159045) (xy 24.152955 -63.213555)
			(xy 24.145197 -63.267511) (xy 24.129838 -63.319814) (xy 24.107192 -63.369398) (xy 24.07772 -63.415254)
			(xy 24.042021 -63.456449) (xy 24.000822 -63.492144) (xy 23.954963 -63.521611) (xy 23.905376 -63.544252)
			(xy 23.853072 -63.559605) (xy 23.799115 -63.567358) (xy 23.77186 -63.567818) (xy 23.74449 -63.567337)
			(xy 23.690311 -63.559526) (xy 23.637807 -63.544041) (xy 23.58806 -63.521202) (xy 23.542093 -63.491479)
			(xy 23.521162 -63.473838) (xy 23.520908 -63.473584) (xy 23.513825 -63.467993) (xy 23.496905 -63.461749)
			(xy 23.487888 -63.461392) (xy 23.420832 -63.461392) (xy 23.411817 -63.461766) (xy 23.3949 -63.468002)
			(xy 23.387812 -63.473584) (xy 23.387558 -63.473838) (xy 23.366625 -63.491479) (xy 23.320657 -63.521203)
			(xy 23.270911 -63.544049) (xy 23.218409 -63.559545) (xy 23.164231 -63.567374) (xy 23.109489 -63.567374)
			(xy 23.055311 -63.559545) (xy 23.002809 -63.544049) (xy 22.953063 -63.521203) (xy 22.907095 -63.491479)
			(xy 22.886162 -63.473838) (xy 22.885908 -63.473584) (xy 22.878825 -63.467993) (xy 22.861905 -63.461749)
			(xy 22.852888 -63.461392) (xy 22.785832 -63.461392) (xy 22.776817 -63.461766) (xy 22.7599 -63.468002)
			(xy 22.752812 -63.473584) (xy 22.752812 -63.473838) (xy 22.752558 -63.473838) (xy 22.73162 -63.49147)
			(xy 22.685648 -63.521181) (xy 22.635902 -63.544018) (xy 22.583403 -63.559511) (xy 22.529229 -63.567343)
			(xy 22.50186 -63.567818) (xy 22.474611 -63.567309) (xy 22.420669 -63.559548) (xy 22.368381 -63.54419)
			(xy 22.31881 -63.521547) (xy 22.272966 -63.492081) (xy 22.231782 -63.45639) (xy 22.196095 -63.415202)
			(xy 22.166634 -63.369355) (xy 22.143996 -63.319782) (xy 22.128643 -63.267491) (xy 22.120888 -63.213549)
			(xy 14.293119 -63.213549) (xy 14.292072 -63.34379) (xy 14.292072 -65.100962) (xy 20.132546 -65.100962)
			(xy 20.136617 -65.04534) (xy 20.148743 -64.990903) (xy 20.168666 -64.938812) (xy 20.195962 -64.890177)
			(xy 20.230048 -64.846034) (xy 20.270197 -64.807325) (xy 20.315555 -64.774874) (xy 20.365155 -64.749373)
			(xy 20.417939 -64.731366) (xy 20.472782 -64.721236) (xy 20.528516 -64.719199) (xy 20.583953 -64.725299)
			(xy 20.63791 -64.739405) (xy 20.689239 -64.761217) (xy 20.736845 -64.790271) (xy 20.779713 -64.825946)
			(xy 20.81693 -64.867483) (xy 20.847703 -64.913996) (xy 20.871375 -64.964493) (xy 20.887443 -65.0179)
			(xy 20.895563 -65.073076) (xy 20.896072 -65.100962) (xy 20.89565 -65.124076) (xy 32.107376 -65.124076)
			(xy 32.111447 -65.068454) (xy 32.123573 -65.014017) (xy 32.143496 -64.961926) (xy 32.170792 -64.913291)
			(xy 32.204878 -64.869148) (xy 32.245027 -64.830439) (xy 32.290385 -64.797988) (xy 32.339985 -64.772487)
			(xy 32.392769 -64.75448) (xy 32.447612 -64.74435) (xy 32.503346 -64.742313) (xy 32.558783 -64.748413)
			(xy 32.61274 -64.762519) (xy 32.664069 -64.784331) (xy 32.711675 -64.813385) (xy 32.754543 -64.84906)
			(xy 32.79176 -64.890597) (xy 32.822533 -64.93711) (xy 32.846205 -64.987607) (xy 32.862273 -65.041014)
			(xy 32.870393 -65.09619) (xy 32.870902 -65.124076) (xy 32.870393 -65.151962) (xy 32.862273 -65.207138)
			(xy 32.846205 -65.260545) (xy 32.822533 -65.311042) (xy 32.79176 -65.357555) (xy 32.754543 -65.399092)
			(xy 32.711675 -65.434767) (xy 32.664069 -65.463821) (xy 32.61274 -65.485633) (xy 32.558783 -65.499739)
			(xy 32.503346 -65.505839) (xy 32.447612 -65.503802) (xy 32.392769 -65.493672) (xy 32.339985 -65.475665)
			(xy 32.290385 -65.450164) (xy 32.245027 -65.417713) (xy 32.204878 -65.379004) (xy 32.170792 -65.334861)
			(xy 32.143496 -65.286226) (xy 32.123573 -65.234135) (xy 32.111447 -65.179698) (xy 32.107376 -65.124076)
			(xy 20.89565 -65.124076) (xy 20.895563 -65.128848) (xy 20.887443 -65.184024) (xy 20.871375 -65.237431)
			(xy 20.847703 -65.287928) (xy 20.81693 -65.334441) (xy 20.779713 -65.375978) (xy 20.736845 -65.411653)
			(xy 20.689239 -65.440707) (xy 20.63791 -65.462519) (xy 20.583953 -65.476625) (xy 20.528516 -65.482725)
			(xy 20.472782 -65.480688) (xy 20.417939 -65.470558) (xy 20.365155 -65.452551) (xy 20.315555 -65.42705)
			(xy 20.270197 -65.394599) (xy 20.230048 -65.35589) (xy 20.195962 -65.311747) (xy 20.168666 -65.263112)
			(xy 20.148743 -65.211021) (xy 20.136617 -65.156584) (xy 20.132546 -65.100962) (xy 14.292072 -65.100962)
			(xy 14.292072 -65.439036) (xy 14.291818 -65.444624) (xy 14.291818 -65.46469) (xy 14.291818 -65.465198)
			(xy 14.291564 -65.48247) (xy 14.291564 -65.482978) (xy 14.29131 -65.498472) (xy 14.29131 -65.49898)
			(xy 14.291056 -65.522094) (xy 14.291056 -65.522602) (xy 14.290802 -65.541906) (xy 14.290802 -65.54597)
			(xy 14.291334 -65.55596) (xy 14.29904 -65.5744) (xy 14.305788 -65.581784) (xy 14.313132 -65.588598)
			(xy 14.331594 -65.596338) (xy 14.341602 -65.59677) (xy 14.352778 -65.59677) (xy 14.356842 -65.596262)
			(xy 14.365526 -65.594609) (xy 14.381113 -65.586298) (xy 14.387322 -65.580006) (xy 14.391894 -65.574926)
			(xy 14.394688 -65.569846) (xy 14.409325 -65.544793) (xy 14.44498 -65.499021) (xy 14.487135 -65.459153)
			(xy 14.534824 -65.426105) (xy 14.586954 -65.400633) (xy 14.642331 -65.38332) (xy 14.699688 -65.374563)
			(xy 14.728698 -65.374012) (xy 14.75595 -65.374475) (xy 14.8099 -65.382232) (xy 14.862197 -65.397588)
			(xy 14.911777 -65.420231) (xy 14.957628 -65.449699) (xy 14.99882 -65.485393) (xy 15.034512 -65.526586)
			(xy 15.063978 -65.572439) (xy 15.086618 -65.622019) (xy 15.101972 -65.674317) (xy 15.109726 -65.728268)
			(xy 15.110206 -65.75552) (xy 15.109707 -65.78326) (xy 15.101672 -65.838155) (xy 15.085775 -65.891309)
			(xy 15.06235 -65.941601) (xy 15.031891 -65.987973) (xy 14.995039 -66.029446) (xy 14.952572 -66.065147)
			(xy 14.905384 -66.094324) (xy 14.854468 -66.116362) (xy 14.800899 -66.130797) (xy 14.773402 -66.134488)
			(xy 14.759686 -66.136012) (xy 14.732739 -66.137738) (xy 14.678841 -66.134492) (xy 14.625939 -66.123681)
			(xy 14.57509 -66.105519) (xy 14.527308 -66.08037) (xy 14.483549 -66.048737) (xy 14.463776 -66.030348)
			(xy 14.456664 -66.02349) (xy 14.441678 -66.017394) (xy 14.435074 -66.015362) (xy 14.4272 -66.01333)
			(xy 14.426692 -66.01333) (xy 14.415262 -66.011806) (xy 14.410182 -66.01206) (xy 14.401038 -66.013584)
			(xy 14.347952 -66.034666) (xy 14.347444 -66.034666) (xy 14.313662 -66.04889) (xy 14.305798 -66.052886)
			(xy 14.293187 -66.065202) (xy 14.285489 -66.081058) (xy 14.284198 -66.089784) (xy 14.28115 -66.315844)
			(xy 14.278356 -66.54292) (xy 14.277086 -66.646806) (xy 14.275562 -66.766186) (xy 14.275562 -66.789554)
			(xy 14.27607 -66.794126) (xy 14.276324 -66.796158) (xy 14.276832 -66.800476) (xy 14.279378 -66.81171)
			(xy 14.292868 -66.830354) (xy 14.30274 -66.83629) (xy 14.310868 -66.840354) (xy 14.318742 -66.843148)
			(xy 14.39418 -66.87058) (xy 14.398127 -66.871842) (xy 14.406294 -66.873243) (xy 14.410436 -66.873374)
			(xy 14.417294 -66.873374) (xy 14.438122 -66.868802) (xy 14.438884 -66.868548) (xy 14.44879 -66.863976)
			(xy 14.45133 -66.860928) (xy 14.457172 -66.85407) (xy 14.480043 -66.82852) (xy 14.533195 -66.785206)
			(xy 14.562836 -66.767964) (xy 14.575027 -66.761332) (xy 14.600196 -66.749633) (xy 14.613128 -66.744596)
			(xy 14.613382 -66.744596) (xy 14.617446 -66.743072) (xy 14.623034 -66.74104) (xy 14.63548 -66.736722)
			(xy 14.642338 -66.73469) (xy 14.666658 -66.728143) (xy 14.716479 -66.720756) (xy 14.741652 -66.719958)
			(xy 14.746732 -66.720212) (xy 14.749272 -66.720212) (xy 14.774761 -66.720698) (xy 14.825265 -66.727652)
			(xy 14.874391 -66.741279) (xy 14.921261 -66.761336) (xy 14.965038 -66.787464) (xy 14.985238 -66.803016)
			(xy 14.990064 -66.806826) (xy 14.99743 -66.810128) (xy 15.00217 -66.811994) (xy 15.01215 -66.814033)
			(xy 15.017242 -66.814192) (xy 15.038578 -66.814192) (xy 15.044019 -66.814329) (xy 15.054655 -66.816626)
			(xy 15.05966 -66.818764) (xy 15.073122 -66.82486) (xy 15.081783 -66.828473) (xy 15.100498 -66.829694)
			(xy 15.118386 -66.824062) (xy 15.125954 -66.81851) (xy 15.133066 -66.812922) (xy 15.137638 -66.809366)
			(xy 15.1384 -66.808858) (xy 15.159043 -66.792221) (xy 15.204058 -66.764211) (xy 15.252516 -66.742702)
			(xy 15.303486 -66.72811) (xy 15.355986 -66.720714) (xy 15.382494 -66.720212) (xy 15.382748 -66.720212)
			(xy 15.409996 -66.720702) (xy 15.463938 -66.728464) (xy 15.516226 -66.743823) (xy 15.565795 -66.766467)
			(xy 15.611638 -66.795935) (xy 15.652821 -66.831627) (xy 15.688506 -66.872816) (xy 15.717965 -66.918664)
			(xy 15.740601 -66.968238) (xy 15.755951 -67.020529) (xy 15.763703 -67.074471) (xy 15.764256 -67.10172)
			(xy 15.763781 -67.128799) (xy 15.756121 -67.182411) (xy 15.740956 -67.234402) (xy 15.718592 -67.283726)
			(xy 15.689479 -67.329393) (xy 15.654201 -67.370483) (xy 15.613467 -67.406173) (xy 15.568096 -67.435744)
			(xy 15.518999 -67.458603) (xy 15.467163 -67.47429) (xy 15.413631 -67.482489) (xy 15.386558 -67.483228)
			(xy 15.38224 -67.483228) (xy 15.352331 -67.482619) (xy 15.293251 -67.47324) (xy 15.236356 -67.454767)
			(xy 15.183035 -67.427652) (xy 15.158466 -67.410584) (xy 15.150084 -67.404234) (xy 15.145258 -67.400424)
			(xy 15.136622 -67.39509) (xy 15.135606 -67.394582) (xy 15.130281 -67.392117) (xy 15.118865 -67.389415)
			(xy 15.113 -67.389248) (xy 15.091918 -67.389248) (xy 15.086477 -67.389109) (xy 15.075842 -67.386809)
			(xy 15.070836 -67.384676) (xy 15.057374 -67.37858) (xy 15.048713 -67.374966) (xy 15.029999 -67.373746)
			(xy 15.012113 -67.379383) (xy 15.004542 -67.38493) (xy 14.99743 -67.390518) (xy 14.992858 -67.394074)
			(xy 14.992096 -67.394582) (xy 14.971454 -67.411221) (xy 14.926441 -67.439235) (xy 14.877982 -67.460747)
			(xy 14.827011 -67.475341) (xy 14.774511 -67.482738) (xy 14.748002 -67.483228) (xy 14.735556 -67.483228)
			(xy 14.70659 -67.481784) (xy 14.649568 -67.471218) (xy 14.594806 -67.452132) (xy 14.568932 -67.439032)
			(xy 14.546101 -67.426368) (xy 14.50379 -67.39578) (xy 14.484604 -67.378072) (xy 14.482572 -67.37604)
			(xy 14.475245 -67.369006) (xy 14.461266 -67.354267) (xy 14.454632 -67.346576) (xy 14.451076 -67.342258)
			(xy 14.447012 -67.338956) (xy 14.439138 -67.333876) (xy 14.42974 -67.329304) (xy 14.424682 -67.327098)
			(xy 14.413919 -67.324668) (xy 14.408404 -67.324478) (xy 14.394434 -67.324478) (xy 14.390554 -67.32458)
			(xy 14.382897 -67.325855) (xy 14.379194 -67.327018) (xy 14.35227 -67.335908) (xy 14.351762 -67.335908)
			(xy 14.300454 -67.353688) (xy 14.292391 -67.357109) (xy 14.27902 -67.368404) (xy 14.270181 -67.383511)
			(xy 14.268196 -67.392042) (xy 14.267688 -67.39509) (xy 14.266531 -67.488054) (xy 18.779234 -67.488054)
			(xy 18.783305 -67.432432) (xy 18.795431 -67.377995) (xy 18.815354 -67.325904) (xy 18.84265 -67.277269)
			(xy 18.876736 -67.233126) (xy 18.916885 -67.194417) (xy 18.962243 -67.161966) (xy 19.011843 -67.136465)
			(xy 19.064627 -67.118458) (xy 19.11947 -67.108328) (xy 19.175204 -67.106291) (xy 19.230641 -67.112391)
			(xy 19.284598 -67.126497) (xy 19.335927 -67.148309) (xy 19.383533 -67.177363) (xy 19.426401 -67.213038)
			(xy 19.463618 -67.254575) (xy 19.494391 -67.301088) (xy 19.518063 -67.351585) (xy 19.534131 -67.404992)
			(xy 19.542251 -67.460168) (xy 19.54276 -67.488054) (xy 19.542251 -67.51594) (xy 19.539066 -67.537584)
			(xy 20.071332 -67.537584) (xy 20.075403 -67.481962) (xy 20.087529 -67.427525) (xy 20.107452 -67.375434)
			(xy 20.134748 -67.326799) (xy 20.168834 -67.282656) (xy 20.208983 -67.243947) (xy 20.254341 -67.211496)
			(xy 20.303941 -67.185995) (xy 20.356725 -67.167988) (xy 20.411568 -67.157858) (xy 20.467302 -67.155821)
			(xy 20.522739 -67.161921) (xy 20.576696 -67.176027) (xy 20.628025 -67.197839) (xy 20.675631 -67.226893)
			(xy 20.718499 -67.262568) (xy 20.755716 -67.304105) (xy 20.786489 -67.350618) (xy 20.810161 -67.401115)
			(xy 20.826229 -67.454522) (xy 20.834349 -67.509698) (xy 20.834858 -67.537584) (xy 20.834349 -67.56547)
			(xy 20.830304 -67.592956) (xy 21.345396 -67.592956) (xy 21.349467 -67.537334) (xy 21.361593 -67.482897)
			(xy 21.381516 -67.430806) (xy 21.408812 -67.382171) (xy 21.442898 -67.338028) (xy 21.483047 -67.299319)
			(xy 21.528405 -67.266868) (xy 21.578005 -67.241367) (xy 21.630789 -67.22336) (xy 21.685632 -67.21323)
			(xy 21.741366 -67.211193) (xy 21.796803 -67.217293) (xy 21.85076 -67.231399) (xy 21.902089 -67.253211)
			(xy 21.949695 -67.282265) (xy 21.992563 -67.31794) (xy 22.02978 -67.359477) (xy 22.060553 -67.40599)
			(xy 22.084225 -67.456487) (xy 22.100293 -67.509894) (xy 22.10841 -67.565052) (xy 24.446693 -67.565052)
			(xy 24.446693 -67.510548) (xy 24.454451 -67.456599) (xy 24.469807 -67.404304) (xy 24.49245 -67.354726)
			(xy 24.521919 -67.308875) (xy 24.557613 -67.267686) (xy 24.598806 -67.231996) (xy 24.644659 -67.202532)
			(xy 24.694239 -67.179894) (xy 24.746536 -67.164542) (xy 24.800486 -67.156791) (xy 24.827738 -67.15633)
			(xy 24.855107 -67.156825) (xy 24.909285 -67.164635) (xy 24.961788 -67.180117) (xy 25.011536 -67.202952)
			(xy 25.057504 -67.232671) (xy 25.078436 -67.25031) (xy 25.07869 -67.250564) (xy 25.08577 -67.25616)
			(xy 25.102692 -67.262399) (xy 25.11171 -67.262756) (xy 25.178766 -67.262756) (xy 25.187782 -67.262392)
			(xy 25.2047 -67.25615) (xy 25.211786 -67.250564) (xy 25.211786 -67.25031) (xy 25.21204 -67.25031)
			(xy 25.232985 -67.232687) (xy 25.278954 -67.202973) (xy 25.328698 -67.180133) (xy 25.381196 -67.164638)
			(xy 25.43537 -67.156806) (xy 25.462738 -67.15633) (xy 25.48999 -67.156742) (xy 25.543939 -67.164504)
			(xy 25.596235 -67.179864) (xy 25.645812 -67.20251) (xy 25.691662 -67.23198) (xy 25.732852 -67.267675)
			(xy 25.768543 -67.308868) (xy 25.798009 -67.354721) (xy 25.820649 -67.404301) (xy 25.836004 -67.456598)
			(xy 25.84376 -67.510548) (xy 25.84376 -67.565052) (xy 25.836004 -67.619002) (xy 25.820649 -67.671299)
			(xy 25.798009 -67.720879) (xy 25.768543 -67.766732) (xy 25.732852 -67.807925) (xy 25.691662 -67.84362)
			(xy 25.645812 -67.87309) (xy 25.596235 -67.895736) (xy 25.543939 -67.911096) (xy 25.48999 -67.918858)
			(xy 25.462738 -67.919346) (xy 25.435368 -67.918871) (xy 25.381189 -67.911057) (xy 25.328685 -67.895571)
			(xy 25.278938 -67.872731) (xy 25.232971 -67.843007) (xy 25.21204 -67.825366) (xy 25.211786 -67.825112)
			(xy 25.204707 -67.819515) (xy 25.187784 -67.813274) (xy 25.178766 -67.81292) (xy 25.11171 -67.81292)
			(xy 25.102693 -67.813277) (xy 25.085776 -67.819524) (xy 25.07869 -67.825112) (xy 25.07869 -67.825366)
			(xy 25.078436 -67.825366) (xy 25.057497 -67.842996) (xy 25.011527 -67.872711) (xy 24.961781 -67.895549)
			(xy 24.909282 -67.911042) (xy 24.855107 -67.918871) (xy 24.827738 -67.919346) (xy 24.800486 -67.918809)
			(xy 24.746536 -67.911058) (xy 24.694239 -67.895706) (xy 24.644659 -67.873068) (xy 24.598806 -67.843604)
			(xy 24.557613 -67.807914) (xy 24.521919 -67.766725) (xy 24.49245 -67.720874) (xy 24.469807 -67.671296)
			(xy 24.454451 -67.619001) (xy 24.446693 -67.565052) (xy 22.10841 -67.565052) (xy 22.108413 -67.56507)
			(xy 22.108922 -67.592956) (xy 22.108413 -67.620842) (xy 22.100293 -67.676018) (xy 22.084225 -67.729425)
			(xy 22.060553 -67.779922) (xy 22.02978 -67.826435) (xy 21.992563 -67.867972) (xy 21.949695 -67.903647)
			(xy 21.902089 -67.932701) (xy 21.85076 -67.954513) (xy 21.796803 -67.968619) (xy 21.741366 -67.974719)
			(xy 21.685632 -67.972682) (xy 21.630789 -67.962552) (xy 21.578005 -67.944545) (xy 21.528405 -67.919044)
			(xy 21.483047 -67.886593) (xy 21.442898 -67.847884) (xy 21.408812 -67.803741) (xy 21.381516 -67.755106)
			(xy 21.361593 -67.703015) (xy 21.349467 -67.648578) (xy 21.345396 -67.592956) (xy 20.830304 -67.592956)
			(xy 20.826229 -67.620646) (xy 20.810161 -67.674053) (xy 20.786489 -67.72455) (xy 20.755716 -67.771063)
			(xy 20.718499 -67.8126) (xy 20.675631 -67.848275) (xy 20.628025 -67.877329) (xy 20.576696 -67.899141)
			(xy 20.522739 -67.913247) (xy 20.467302 -67.919347) (xy 20.411568 -67.91731) (xy 20.356725 -67.90718)
			(xy 20.303941 -67.889173) (xy 20.254341 -67.863672) (xy 20.208983 -67.831221) (xy 20.168834 -67.792512)
			(xy 20.134748 -67.748369) (xy 20.107452 -67.699734) (xy 20.087529 -67.647643) (xy 20.075403 -67.593206)
			(xy 20.071332 -67.537584) (xy 19.539066 -67.537584) (xy 19.534131 -67.571116) (xy 19.518063 -67.624523)
			(xy 19.494391 -67.67502) (xy 19.463618 -67.721533) (xy 19.426401 -67.76307) (xy 19.383533 -67.798745)
			(xy 19.335927 -67.827799) (xy 19.284598 -67.849611) (xy 19.230641 -67.863717) (xy 19.175204 -67.869817)
			(xy 19.11947 -67.86778) (xy 19.064627 -67.85765) (xy 19.011843 -67.839643) (xy 18.962243 -67.814142)
			(xy 18.916885 -67.781691) (xy 18.876736 -67.742982) (xy 18.84265 -67.698839) (xy 18.815354 -67.650204)
			(xy 18.795431 -67.598113) (xy 18.783305 -67.543676) (xy 18.779234 -67.488054) (xy 14.266531 -67.488054)
			(xy 14.252861 -68.586604) (xy 16.625316 -68.586604) (xy 16.625781 -68.559234) (xy 16.633598 -68.505054)
			(xy 16.649087 -68.452551) (xy 16.67193 -68.402804) (xy 16.701655 -68.356838) (xy 16.719296 -68.335906)
			(xy 16.71955 -68.335652) (xy 16.725127 -68.328559) (xy 16.731378 -68.311647) (xy 16.731742 -68.302632)
			(xy 16.731742 -68.235576) (xy 16.731409 -68.226556) (xy 16.725146 -68.209639) (xy 16.71955 -68.202556)
			(xy 16.719296 -68.202556) (xy 16.719296 -68.202302) (xy 16.701644 -68.181381) (xy 16.671934 -68.135405)
			(xy 16.649101 -68.085655) (xy 16.633613 -68.033152) (xy 16.625788 -67.978974) (xy 16.625316 -67.951604)
			(xy 16.625759 -67.92435) (xy 16.633516 -67.870397) (xy 16.648873 -67.818098) (xy 16.671517 -67.768516)
			(xy 16.700987 -67.722662) (xy 16.736682 -67.681468) (xy 16.777878 -67.645775) (xy 16.823733 -67.616307)
			(xy 16.873316 -67.593666) (xy 16.925617 -67.578312) (xy 16.97957 -67.570558) (xy 17.006824 -67.570096)
			(xy 17.033138 -67.570549) (xy 17.085268 -67.577787) (xy 17.13591 -67.592109) (xy 17.184109 -67.613244)
			(xy 17.228953 -67.640793) (xy 17.269592 -67.674233) (xy 17.287748 -67.693286) (xy 17.295252 -67.700709)
			(xy 17.314545 -67.709221) (xy 17.325086 -67.709796) (xy 17.399762 -67.709796) (xy 17.410311 -67.709261)
			(xy 17.429607 -67.70073) (xy 17.4371 -67.693286) (xy 17.45526 -67.674235) (xy 17.495889 -67.640778)
			(xy 17.540728 -67.613219) (xy 17.588928 -67.592079) (xy 17.639575 -67.577761) (xy 17.691708 -67.570535)
			(xy 17.718024 -67.570096) (xy 17.745395 -67.570549) (xy 17.799574 -67.57837) (xy 17.852078 -67.593862)
			(xy 17.901824 -67.616707) (xy 17.947791 -67.646434) (xy 17.968722 -67.664076) (xy 17.968976 -67.66433)
			(xy 17.976063 -67.669916) (xy 17.99298 -67.676162) (xy 18.001996 -67.676522) (xy 18.069052 -67.676522)
			(xy 18.078066 -67.676137) (xy 18.094983 -67.669908) (xy 18.102072 -67.66433) (xy 18.102072 -67.664076)
			(xy 18.102326 -67.664076) (xy 18.123272 -67.646454) (xy 18.169241 -67.616741) (xy 18.218985 -67.593902)
			(xy 18.271483 -67.578407) (xy 18.325656 -67.570573) (xy 18.353024 -67.570096) (xy 18.380276 -67.570555)
			(xy 18.434225 -67.578315) (xy 18.48652 -67.593674) (xy 18.536098 -67.616318) (xy 18.581948 -67.645787)
			(xy 18.623138 -67.681481) (xy 18.65883 -67.722674) (xy 18.688295 -67.768527) (xy 18.710936 -67.818106)
			(xy 18.726291 -67.870402) (xy 18.734047 -67.924352) (xy 18.734532 -67.951604) (xy 18.734085 -67.978975)
			(xy 18.726265 -68.033156) (xy 18.710772 -68.08566) (xy 18.687926 -68.135406) (xy 18.658196 -68.181372)
			(xy 18.640552 -68.202302) (xy 18.640298 -68.202556) (xy 18.634723 -68.209651) (xy 18.62847 -68.226561)
			(xy 18.628106 -68.235576) (xy 18.628106 -68.302632) (xy 18.628447 -68.311651) (xy 18.634705 -68.328567)
			(xy 18.640298 -68.335652) (xy 18.640552 -68.335652) (xy 18.640552 -68.335906) (xy 18.6582 -68.356831)
			(xy 18.687912 -68.402805) (xy 18.710747 -68.452554) (xy 18.726236 -68.505057) (xy 18.73406 -68.559234)
			(xy 18.734532 -68.586604) (xy 18.734026 -68.613854) (xy 18.72627 -68.6678) (xy 18.710915 -68.720093)
			(xy 18.694275 -68.75653) (xy 22.17039 -68.75653) (xy 22.170876 -68.729161) (xy 22.178689 -68.674982)
			(xy 22.194174 -68.62248) (xy 22.217011 -68.572732) (xy 22.246731 -68.526765) (xy 22.26437 -68.505832)
			(xy 22.264624 -68.505578) (xy 22.270229 -68.498504) (xy 22.276464 -68.481577) (xy 22.276816 -68.472558)
			(xy 22.276816 -68.405502) (xy 22.276454 -68.396486) (xy 22.27021 -68.379569) (xy 22.264624 -68.372482)
			(xy 22.26437 -68.372482) (xy 22.26437 -68.372228) (xy 22.246726 -68.3513) (xy 22.217016 -68.305326)
			(xy 22.194181 -68.255577) (xy 22.178691 -68.203076) (xy 22.170864 -68.148899) (xy 22.17039 -68.12153)
			(xy 22.170883 -68.094278) (xy 22.178636 -68.040328) (xy 22.193988 -67.988031) (xy 22.216627 -67.938451)
			(xy 22.246092 -67.892598) (xy 22.281782 -67.851405) (xy 22.322972 -67.815711) (xy 22.368823 -67.786242)
			(xy 22.418401 -67.763599) (xy 22.470697 -67.748243) (xy 22.524646 -67.740485) (xy 22.551898 -67.740022)
			(xy 22.579268 -67.740484) (xy 22.633448 -67.748302) (xy 22.685951 -67.763792) (xy 22.735698 -67.786634)
			(xy 22.781665 -67.81636) (xy 22.802596 -67.834002) (xy 22.80285 -67.834256) (xy 22.809942 -67.839834)
			(xy 22.826855 -67.846085) (xy 22.83587 -67.846448) (xy 22.902926 -67.846448) (xy 22.911946 -67.846115)
			(xy 22.928863 -67.839852) (xy 22.935946 -67.834256) (xy 22.935946 -67.834002) (xy 22.9362 -67.834002)
			(xy 22.957121 -67.81635) (xy 23.003097 -67.78664) (xy 23.052847 -67.763806) (xy 23.10535 -67.748318)
			(xy 23.159528 -67.740494) (xy 23.186898 -67.740022) (xy 23.213212 -67.740484) (xy 23.265341 -67.747719)
			(xy 23.315984 -67.762038) (xy 23.364184 -67.783172) (xy 23.409027 -67.810719) (xy 23.449666 -67.84416)
			(xy 23.467822 -67.863212) (xy 23.475332 -67.870627) (xy 23.494621 -67.879144) (xy 23.50516 -67.879722)
			(xy 23.579836 -67.879722) (xy 23.590382 -67.879165) (xy 23.609678 -67.870649) (xy 23.617174 -67.863212)
			(xy 23.635352 -67.844178) (xy 23.675976 -67.810719) (xy 23.720812 -67.783157) (xy 23.769008 -67.762014)
			(xy 23.819652 -67.747693) (xy 23.871783 -67.740463) (xy 23.898098 -67.740022) (xy 23.925352 -67.740457)
			(xy 23.979306 -67.748215) (xy 24.031606 -67.763572) (xy 24.081188 -67.786217) (xy 24.127043 -67.815687)
			(xy 24.168236 -67.851384) (xy 24.20393 -67.89258) (xy 24.233397 -67.938437) (xy 24.256038 -67.98802)
			(xy 24.271391 -68.040322) (xy 24.279145 -68.094276) (xy 24.279606 -68.12153) (xy 24.279156 -68.148901)
			(xy 24.271334 -68.203081) (xy 24.255841 -68.255584) (xy 24.232996 -68.30533) (xy 24.203268 -68.351297)
			(xy 24.185626 -68.372228) (xy 24.185372 -68.372482) (xy 24.179784 -68.379567) (xy 24.173539 -68.396485)
			(xy 24.17318 -68.405502) (xy 24.17318 -68.472558) (xy 24.173561 -68.481572) (xy 24.179792 -68.498489)
			(xy 24.185372 -68.505578) (xy 24.185626 -68.505578) (xy 24.185626 -68.505832) (xy 24.203251 -68.526776)
			(xy 24.232964 -68.572746) (xy 24.255802 -68.62249) (xy 24.271297 -68.674988) (xy 24.279129 -68.729162)
			(xy 24.279606 -68.75653) (xy 24.27915 -68.783782) (xy 24.271389 -68.837731) (xy 24.25603 -68.890026)
			(xy 24.233386 -68.939604) (xy 24.203916 -68.985454) (xy 24.168221 -69.026644) (xy 24.127029 -69.062335)
			(xy 24.081176 -69.091801) (xy 24.031596 -69.114442) (xy 23.9793 -69.129796) (xy 23.92535 -69.137552)
			(xy 23.898098 -69.138038) (xy 23.871783 -69.137592) (xy 23.819653 -69.130355) (xy 23.769009 -69.116033)
			(xy 23.72081 -69.094897) (xy 23.675967 -69.067346) (xy 23.635329 -69.033902) (xy 23.617174 -69.014848)
			(xy 23.609657 -69.00744) (xy 23.590374 -68.998918) (xy 23.579836 -68.998338) (xy 23.50516 -68.998338)
			(xy 23.494611 -68.998875) (xy 23.475315 -69.007403) (xy 23.467822 -69.014848) (xy 23.449658 -69.033895)
			(xy 23.409029 -69.067351) (xy 23.36419 -69.09491) (xy 23.315991 -69.11605) (xy 23.265346 -69.130369)
			(xy 23.213213 -69.137597) (xy 23.186898 -69.138038) (xy 23.159527 -69.137588) (xy 23.105347 -69.129769)
			(xy 23.052843 -69.114277) (xy 23.003096 -69.091431) (xy 22.957131 -69.061702) (xy 22.9362 -69.044058)
			(xy 22.935946 -69.043804) (xy 22.92885 -69.038231) (xy 22.911941 -69.031976) (xy 22.902926 -69.031612)
			(xy 22.83587 -69.031612) (xy 22.826851 -69.031952) (xy 22.809934 -69.038211) (xy 22.80285 -69.043804)
			(xy 22.80285 -69.044058) (xy 22.802596 -69.044058) (xy 22.781671 -69.061706) (xy 22.735697 -69.091418)
			(xy 22.685948 -69.114253) (xy 22.633445 -69.129742) (xy 22.579268 -69.137566) (xy 22.551898 -69.138038)
			(xy 22.524648 -69.137524) (xy 22.470703 -69.129768) (xy 22.418411 -69.114414) (xy 22.368835 -69.091775)
			(xy 22.322986 -69.062311) (xy 22.281797 -69.026623) (xy 22.246105 -68.985436) (xy 22.216638 -68.939589)
			(xy 22.193995 -68.890016) (xy 22.178638 -68.837724) (xy 22.170878 -68.78378) (xy 22.17039 -68.75653)
			(xy 18.694275 -68.75653) (xy 18.688275 -68.769669) (xy 18.658811 -68.815518) (xy 18.623122 -68.856707)
			(xy 18.581934 -68.892399) (xy 18.536086 -68.921866) (xy 18.486512 -68.944508) (xy 18.43422 -68.959865)
			(xy 18.380274 -68.967625) (xy 18.353024 -68.968112) (xy 18.325654 -68.967629) (xy 18.271476 -68.959815)
			(xy 18.218973 -68.944329) (xy 18.169226 -68.921492) (xy 18.123258 -68.891771) (xy 18.102326 -68.874132)
			(xy 18.102072 -68.873878) (xy 18.094971 -68.868313) (xy 18.078065 -68.862054) (xy 18.069052 -68.861686)
			(xy 18.001996 -68.861686) (xy 17.992979 -68.862044) (xy 17.976063 -68.868291) (xy 17.968976 -68.873878)
			(xy 17.968976 -68.874132) (xy 17.968722 -68.874132) (xy 17.947797 -68.891779) (xy 17.901821 -68.921489)
			(xy 17.852072 -68.944323) (xy 17.79957 -68.959812) (xy 17.745394 -68.967639) (xy 17.718024 -68.968112)
			(xy 17.691711 -68.967625) (xy 17.639583 -68.960393) (xy 17.588941 -68.946078) (xy 17.540742 -68.924949)
			(xy 17.495898 -68.897407) (xy 17.455257 -68.863972) (xy 17.4371 -68.844922) (xy 17.429577 -68.837522)
			(xy 17.410298 -68.828996) (xy 17.399762 -68.828412) (xy 17.325086 -68.828412) (xy 17.314533 -68.828916)
			(xy 17.295238 -68.837468) (xy 17.287748 -68.844922) (xy 17.269615 -68.864) (xy 17.22898 -68.897454)
			(xy 17.184135 -68.92501) (xy 17.13593 -68.946144) (xy 17.085278 -68.960457) (xy 17.033141 -68.967676)
			(xy 17.006824 -68.968112) (xy 16.979572 -68.967622) (xy 16.925622 -68.959869) (xy 16.873325 -68.944516)
			(xy 16.823745 -68.921877) (xy 16.777892 -68.892411) (xy 16.736699 -68.85672) (xy 16.701005 -68.81553)
			(xy 16.671537 -68.769679) (xy 16.648894 -68.720101) (xy 16.633537 -68.667805) (xy 16.62578 -68.613856)
			(xy 16.625316 -68.586604) (xy 14.252861 -68.586604) (xy 14.247876 -68.987162) (xy 14.243558 -69.334634)
			(xy 14.22554 -71.555864) (xy 19.194524 -71.555864) (xy 19.198595 -71.500242) (xy 19.210721 -71.445805)
			(xy 19.230644 -71.393714) (xy 19.25794 -71.345079) (xy 19.292026 -71.300936) (xy 19.332175 -71.262227)
			(xy 19.377533 -71.229776) (xy 19.427133 -71.204275) (xy 19.479917 -71.186268) (xy 19.53476 -71.176138)
			(xy 19.590494 -71.174101) (xy 19.645931 -71.180201) (xy 19.699888 -71.194307) (xy 19.751217 -71.216119)
			(xy 19.798823 -71.245173) (xy 19.841691 -71.280848) (xy 19.878908 -71.322385) (xy 19.909681 -71.368898)
			(xy 19.933353 -71.419395) (xy 19.949421 -71.472802) (xy 19.957541 -71.527978) (xy 19.95805 -71.555864)
			(xy 19.957541 -71.58375) (xy 19.951702 -71.623428) (xy 20.703538 -71.623428) (xy 20.707609 -71.567806)
			(xy 20.719735 -71.513369) (xy 20.739658 -71.461278) (xy 20.766954 -71.412643) (xy 20.80104 -71.3685)
			(xy 20.841189 -71.329791) (xy 20.886547 -71.29734) (xy 20.936147 -71.271839) (xy 20.988931 -71.253832)
			(xy 21.043774 -71.243702) (xy 21.099508 -71.241665) (xy 21.154945 -71.247765) (xy 21.208902 -71.261871)
			(xy 21.260231 -71.283683) (xy 21.307837 -71.312737) (xy 21.350705 -71.348412) (xy 21.387922 -71.389949)
			(xy 21.418695 -71.436462) (xy 21.442367 -71.486959) (xy 21.458435 -71.540366) (xy 21.466555 -71.595542)
			(xy 21.467064 -71.623428) (xy 21.466555 -71.651314) (xy 21.458435 -71.70649) (xy 21.442367 -71.759897)
			(xy 21.418695 -71.810394) (xy 21.387922 -71.856907) (xy 21.350705 -71.898444) (xy 21.307837 -71.934119)
			(xy 21.260231 -71.963173) (xy 21.208902 -71.984985) (xy 21.154945 -71.999091) (xy 21.099508 -72.005191)
			(xy 21.043774 -72.003154) (xy 20.988931 -71.993024) (xy 20.936147 -71.975017) (xy 20.886547 -71.949516)
			(xy 20.841189 -71.917065) (xy 20.80104 -71.878356) (xy 20.766954 -71.834213) (xy 20.739658 -71.785578)
			(xy 20.719735 -71.733487) (xy 20.707609 -71.67905) (xy 20.703538 -71.623428) (xy 19.951702 -71.623428)
			(xy 19.949421 -71.638926) (xy 19.933353 -71.692333) (xy 19.909681 -71.74283) (xy 19.878908 -71.789343)
			(xy 19.841691 -71.83088) (xy 19.798823 -71.866555) (xy 19.751217 -71.895609) (xy 19.699888 -71.917421)
			(xy 19.645931 -71.931527) (xy 19.590494 -71.937627) (xy 19.53476 -71.93559) (xy 19.479917 -71.92546)
			(xy 19.427133 -71.907453) (xy 19.377533 -71.881952) (xy 19.332175 -71.849501) (xy 19.292026 -71.810792)
			(xy 19.25794 -71.766649) (xy 19.230644 -71.718014) (xy 19.210721 -71.665923) (xy 19.198595 -71.611486)
			(xy 19.194524 -71.555864) (xy 14.22554 -71.555864) (xy 14.116304 -85.022182) (xy 14.116367 -85.025989)
			(xy 14.117508 -85.033517) (xy 14.11859 -85.037168) (xy 16.021702 -91.315794) (xy 31.655256 -91.315794)
			(xy 31.659327 -91.260172) (xy 31.671453 -91.205735) (xy 31.691376 -91.153644) (xy 31.718672 -91.105009)
			(xy 31.752758 -91.060866) (xy 31.792907 -91.022157) (xy 31.838265 -90.989706) (xy 31.887865 -90.964205)
			(xy 31.940649 -90.946198) (xy 31.995492 -90.936068) (xy 32.051226 -90.934031) (xy 32.106663 -90.940131)
			(xy 32.16062 -90.954237) (xy 32.211949 -90.976049) (xy 32.259555 -91.005103) (xy 32.302423 -91.040778)
			(xy 32.33964 -91.082315) (xy 32.370413 -91.128828) (xy 32.394085 -91.179325) (xy 32.410153 -91.232732)
			(xy 32.418273 -91.287908) (xy 32.418782 -91.315794) (xy 32.418273 -91.34368) (xy 32.410153 -91.398856)
			(xy 32.394085 -91.452263) (xy 32.370413 -91.50276) (xy 32.33964 -91.549273) (xy 32.302423 -91.59081)
			(xy 32.259555 -91.626485) (xy 32.211949 -91.655539) (xy 32.16062 -91.677351) (xy 32.106663 -91.691457)
			(xy 32.051226 -91.697557) (xy 31.995492 -91.69552) (xy 31.940649 -91.68539) (xy 31.887865 -91.667383)
			(xy 31.838265 -91.641882) (xy 31.792907 -91.609431) (xy 31.752758 -91.570722) (xy 31.718672 -91.526579)
			(xy 31.691376 -91.477944) (xy 31.671453 -91.425853) (xy 31.659327 -91.371416) (xy 31.655256 -91.315794)
			(xy 16.021702 -91.315794) (xy 16.510203 -92.927424) (xy 31.559244 -92.927424) (xy 31.563315 -92.871802)
			(xy 31.575441 -92.817365) (xy 31.595364 -92.765274) (xy 31.62266 -92.716639) (xy 31.656746 -92.672496)
			(xy 31.696895 -92.633787) (xy 31.742253 -92.601336) (xy 31.791853 -92.575835) (xy 31.844637 -92.557828)
			(xy 31.89948 -92.547698) (xy 31.955214 -92.545661) (xy 32.010651 -92.551761) (xy 32.064608 -92.565867)
			(xy 32.115937 -92.587679) (xy 32.163543 -92.616733) (xy 32.206411 -92.652408) (xy 32.243628 -92.693945)
			(xy 32.274401 -92.740458) (xy 32.298073 -92.790955) (xy 32.314141 -92.844362) (xy 32.322261 -92.899538)
			(xy 32.32277 -92.927424) (xy 32.322261 -92.95531) (xy 32.314141 -93.010486) (xy 32.298073 -93.063893)
			(xy 32.274401 -93.11439) (xy 32.243628 -93.160903) (xy 32.206411 -93.20244) (xy 32.163543 -93.238115)
			(xy 32.115937 -93.267169) (xy 32.064608 -93.288981) (xy 32.010651 -93.303087) (xy 31.955214 -93.309187)
			(xy 31.89948 -93.30715) (xy 31.844637 -93.29702) (xy 31.791853 -93.279013) (xy 31.742253 -93.253512)
			(xy 31.696895 -93.221061) (xy 31.656746 -93.182352) (xy 31.62266 -93.138209) (xy 31.595364 -93.089574)
			(xy 31.575441 -93.037483) (xy 31.563315 -92.983046) (xy 31.559244 -92.927424) (xy 16.510203 -92.927424)
			(xy 17.176473 -95.12554) (xy 24.574752 -95.12554) (xy 24.578823 -95.069918) (xy 24.590949 -95.015481)
			(xy 24.610872 -94.96339) (xy 24.638168 -94.914755) (xy 24.672254 -94.870612) (xy 24.712403 -94.831903)
			(xy 24.757761 -94.799452) (xy 24.807361 -94.773951) (xy 24.860145 -94.755944) (xy 24.914988 -94.745814)
			(xy 24.970722 -94.743777) (xy 25.026159 -94.749877) (xy 25.080116 -94.763983) (xy 25.131445 -94.785795)
			(xy 25.179051 -94.814849) (xy 25.221919 -94.850524) (xy 25.259136 -94.892061) (xy 25.289909 -94.938574)
			(xy 25.313581 -94.989071) (xy 25.329649 -95.042478) (xy 25.337769 -95.097654) (xy 25.338278 -95.12554)
			(xy 25.337769 -95.153426) (xy 25.329649 -95.208602) (xy 25.313581 -95.262009) (xy 25.289909 -95.312506)
			(xy 25.259136 -95.359019) (xy 25.221919 -95.400556) (xy 25.179051 -95.436231) (xy 25.131445 -95.465285)
			(xy 25.080116 -95.487097) (xy 25.026159 -95.501203) (xy 24.970722 -95.507303) (xy 24.914988 -95.505266)
			(xy 24.860145 -95.495136) (xy 24.807361 -95.477129) (xy 24.757761 -95.451628) (xy 24.712403 -95.419177)
			(xy 24.672254 -95.380468) (xy 24.638168 -95.336325) (xy 24.610872 -95.28769) (xy 24.590949 -95.235599)
			(xy 24.578823 -95.181162) (xy 24.574752 -95.12554) (xy 17.176473 -95.12554) (xy 17.437315 -95.986092)
			(xy 25.048462 -95.986092) (xy 25.052533 -95.93047) (xy 25.064659 -95.876033) (xy 25.084582 -95.823942)
			(xy 25.111878 -95.775307) (xy 25.145964 -95.731164) (xy 25.186113 -95.692455) (xy 25.231471 -95.660004)
			(xy 25.281071 -95.634503) (xy 25.333855 -95.616496) (xy 25.388698 -95.606366) (xy 25.444432 -95.604329)
			(xy 25.499869 -95.610429) (xy 25.553826 -95.624535) (xy 25.605155 -95.646347) (xy 25.652761 -95.675401)
			(xy 25.695629 -95.711076) (xy 25.732846 -95.752613) (xy 25.763619 -95.799126) (xy 25.787291 -95.849623)
			(xy 25.803359 -95.90303) (xy 25.811479 -95.958206) (xy 25.811988 -95.986092) (xy 25.811479 -96.013978)
			(xy 25.803359 -96.069154) (xy 25.787291 -96.122561) (xy 25.763619 -96.173058) (xy 25.732846 -96.219571)
			(xy 25.695629 -96.261108) (xy 25.652761 -96.296783) (xy 25.605155 -96.325837) (xy 25.553826 -96.347649)
			(xy 25.499869 -96.361755) (xy 25.444432 -96.367855) (xy 25.388698 -96.365818) (xy 25.333855 -96.355688)
			(xy 25.281071 -96.337681) (xy 25.231471 -96.31218) (xy 25.186113 -96.279729) (xy 25.145964 -96.24102)
			(xy 25.111878 -96.196877) (xy 25.084582 -96.148242) (xy 25.064659 -96.096151) (xy 25.052533 -96.041714)
			(xy 25.048462 -95.986092) (xy 17.437315 -95.986092) (xy 17.751279 -97.021904) (xy 25.034746 -97.021904)
			(xy 25.038817 -96.966282) (xy 25.050943 -96.911845) (xy 25.070866 -96.859754) (xy 25.098162 -96.811119)
			(xy 25.132248 -96.766976) (xy 25.172397 -96.728267) (xy 25.217755 -96.695816) (xy 25.267355 -96.670315)
			(xy 25.320139 -96.652308) (xy 25.374982 -96.642178) (xy 25.430716 -96.640141) (xy 25.486153 -96.646241)
			(xy 25.54011 -96.660347) (xy 25.591439 -96.682159) (xy 25.639045 -96.711213) (xy 25.681913 -96.746888)
			(xy 25.71913 -96.788425) (xy 25.749903 -96.834938) (xy 25.773575 -96.885435) (xy 25.789643 -96.938842)
			(xy 25.797763 -96.994018) (xy 25.798272 -97.021904) (xy 25.797763 -97.04979) (xy 25.789643 -97.104966)
			(xy 25.773575 -97.158373) (xy 25.749903 -97.20887) (xy 25.71913 -97.255383) (xy 25.681913 -97.29692)
			(xy 25.639045 -97.332595) (xy 25.591439 -97.361649) (xy 25.54011 -97.383461) (xy 25.486153 -97.397567)
			(xy 25.430716 -97.403667) (xy 25.374982 -97.40163) (xy 25.320139 -97.3915) (xy 25.267355 -97.373493)
			(xy 25.217755 -97.347992) (xy 25.172397 -97.315541) (xy 25.132248 -97.276832) (xy 25.098162 -97.232689)
			(xy 25.070866 -97.184054) (xy 25.050943 -97.131963) (xy 25.038817 -97.077526) (xy 25.034746 -97.021904)
			(xy 17.751279 -97.021904) (xy 19.25543 -101.984302) (xy 35.277552 -101.984302) (xy 35.277552 -101.120702)
			(xy 35.278042 -101.090734) (xy 35.285865 -101.031312) (xy 35.301378 -100.973419) (xy 35.324314 -100.918046)
			(xy 35.354281 -100.86614) (xy 35.390768 -100.81859) (xy 35.433148 -100.77621) (xy 35.480698 -100.739723)
			(xy 35.532604 -100.709756) (xy 35.587977 -100.68682) (xy 35.64587 -100.671307) (xy 35.705292 -100.663484)
			(xy 35.765228 -100.663484) (xy 35.82465 -100.671307) (xy 35.882543 -100.68682) (xy 35.937916 -100.709756)
			(xy 35.989822 -100.739723) (xy 36.037372 -100.77621) (xy 36.079752 -100.81859) (xy 36.116239 -100.86614)
			(xy 36.146206 -100.918046) (xy 36.169142 -100.973419) (xy 36.184655 -101.031312) (xy 36.192478 -101.090734)
			(xy 36.192968 -101.120702) (xy 36.192968 -101.984302) (xy 36.192478 -102.01427) (xy 36.184655 -102.073692)
			(xy 36.169142 -102.131585) (xy 36.146206 -102.186958) (xy 36.116239 -102.238864) (xy 36.079752 -102.286414)
			(xy 36.037372 -102.328794) (xy 35.989822 -102.365281) (xy 35.937916 -102.395248) (xy 35.882543 -102.418184)
			(xy 35.82465 -102.433697) (xy 35.765228 -102.44152) (xy 35.705292 -102.44152) (xy 35.64587 -102.433697)
			(xy 35.587977 -102.418184) (xy 35.532604 -102.395248) (xy 35.480698 -102.365281) (xy 35.433148 -102.328794)
			(xy 35.390768 -102.286414) (xy 35.354281 -102.238864) (xy 35.324314 -102.186958) (xy 35.301378 -102.131585)
			(xy 35.285865 -102.073692) (xy 35.278042 -102.01427) (xy 35.277552 -101.984302) (xy 19.25543 -101.984302)
			(xy 20.346684 -105.584498) (xy 34.667952 -105.584498) (xy 34.667952 -104.720898) (xy 34.668442 -104.69093)
			(xy 34.676265 -104.631508) (xy 34.691778 -104.573615) (xy 34.714714 -104.518242) (xy 34.744681 -104.466336)
			(xy 34.781168 -104.418786) (xy 34.823548 -104.376406) (xy 34.871098 -104.339919) (xy 34.923004 -104.309952)
			(xy 34.978377 -104.287016) (xy 35.03627 -104.271503) (xy 35.095692 -104.26368) (xy 35.155628 -104.26368)
			(xy 35.21505 -104.271503) (xy 35.272943 -104.287016) (xy 35.328316 -104.309952) (xy 35.380222 -104.339919)
			(xy 35.427772 -104.376406) (xy 35.470152 -104.418786) (xy 35.506639 -104.466336) (xy 35.536606 -104.518242)
			(xy 35.559542 -104.573615) (xy 35.575055 -104.631508) (xy 35.582878 -104.69093) (xy 35.583368 -104.720898)
			(xy 35.583368 -105.584498) (xy 35.582878 -105.614466) (xy 35.575055 -105.673888) (xy 35.559542 -105.731781)
			(xy 35.536606 -105.787154) (xy 35.506639 -105.83906) (xy 35.470152 -105.88661) (xy 35.427772 -105.92899)
			(xy 35.380222 -105.965477) (xy 35.328316 -105.995444) (xy 35.272943 -106.01838) (xy 35.21505 -106.033893)
			(xy 35.155628 -106.041716) (xy 35.095692 -106.041716) (xy 35.03627 -106.033893) (xy 34.978377 -106.01838)
			(xy 34.923004 -105.995444) (xy 34.871098 -105.965477) (xy 34.823548 -105.92899) (xy 34.781168 -105.88661)
			(xy 34.744681 -105.83906) (xy 34.714714 -105.787154) (xy 34.691778 -105.731781) (xy 34.676265 -105.673888)
			(xy 34.668442 -105.614466) (xy 34.667952 -105.584498) (xy 20.346684 -105.584498) (xy 20.890232 -107.377738)
			(xy 37.31006 -107.377738) (xy 37.31006 -106.514138) (xy 37.31055 -106.48417) (xy 37.318373 -106.424748)
			(xy 37.333886 -106.366855) (xy 37.356822 -106.311482) (xy 37.386789 -106.259576) (xy 37.423276 -106.212026)
			(xy 37.465656 -106.169646) (xy 37.513206 -106.133159) (xy 37.565112 -106.103192) (xy 37.620485 -106.080256)
			(xy 37.678378 -106.064743) (xy 37.7378 -106.05692) (xy 37.797736 -106.05692) (xy 37.857158 -106.064743)
			(xy 37.915051 -106.080256) (xy 37.970424 -106.103192) (xy 38.02233 -106.133159) (xy 38.06988 -106.169646)
			(xy 38.11226 -106.212026) (xy 38.148747 -106.259576) (xy 38.178714 -106.311482) (xy 38.20165 -106.366855)
			(xy 38.217163 -106.424748) (xy 38.224986 -106.48417) (xy 38.225476 -106.514138) (xy 38.225476 -107.377738)
			(xy 38.224986 -107.407706) (xy 38.217163 -107.467128) (xy 38.20165 -107.525021) (xy 38.178714 -107.580394)
			(xy 38.148747 -107.6323) (xy 38.11226 -107.67985) (xy 38.06988 -107.72223) (xy 38.02233 -107.758717)
			(xy 37.970424 -107.788684) (xy 37.915051 -107.81162) (xy 37.857158 -107.827133) (xy 37.797736 -107.834956)
			(xy 37.7378 -107.834956) (xy 37.678378 -107.827133) (xy 37.620485 -107.81162) (xy 37.565112 -107.788684)
			(xy 37.513206 -107.758717) (xy 37.465656 -107.72223) (xy 37.423276 -107.67985) (xy 37.386789 -107.6323)
			(xy 37.356822 -107.580394) (xy 37.333886 -107.525021) (xy 37.318373 -107.467128) (xy 37.31055 -107.407706)
			(xy 37.31006 -107.377738) (xy 20.890232 -107.377738) (xy 21.206968 -108.422694) (xy 21.439534 -109.18444)
			(xy 34.667952 -109.18444) (xy 34.667952 -108.32084) (xy 34.668442 -108.290872) (xy 34.676265 -108.23145)
			(xy 34.691778 -108.173557) (xy 34.714714 -108.118184) (xy 34.744681 -108.066278) (xy 34.781168 -108.018728)
			(xy 34.823548 -107.976348) (xy 34.871098 -107.939861) (xy 34.923004 -107.909894) (xy 34.978377 -107.886958)
			(xy 35.03627 -107.871445) (xy 35.095692 -107.863622) (xy 35.155628 -107.863622) (xy 35.21505 -107.871445)
			(xy 35.272943 -107.886958) (xy 35.328316 -107.909894) (xy 35.380222 -107.939861) (xy 35.427772 -107.976348)
			(xy 35.470152 -108.018728) (xy 35.506639 -108.066278) (xy 35.536606 -108.118184) (xy 35.559542 -108.173557)
			(xy 35.575055 -108.23145) (xy 35.582878 -108.290872) (xy 35.583368 -108.32084) (xy 35.583368 -109.18444)
			(xy 35.582878 -109.214408) (xy 35.575055 -109.27383) (xy 35.559542 -109.331723) (xy 35.536606 -109.387096)
			(xy 35.506639 -109.439002) (xy 35.470152 -109.486552) (xy 35.427772 -109.528932) (xy 35.380222 -109.565419)
			(xy 35.328316 -109.595386) (xy 35.272943 -109.618322) (xy 35.21505 -109.633835) (xy 35.155628 -109.641658)
			(xy 35.095692 -109.641658) (xy 35.03627 -109.633835) (xy 34.978377 -109.618322) (xy 34.923004 -109.595386)
			(xy 34.871098 -109.565419) (xy 34.823548 -109.528932) (xy 34.781168 -109.486552) (xy 34.744681 -109.439002)
			(xy 34.714714 -109.387096) (xy 34.691778 -109.331723) (xy 34.676265 -109.27383) (xy 34.668442 -109.214408)
			(xy 34.667952 -109.18444) (xy 21.439534 -109.18444) (xy 21.987101 -110.977934) (xy 37.31006 -110.977934)
			(xy 37.31006 -110.114334) (xy 37.31055 -110.084366) (xy 37.318373 -110.024944) (xy 37.333886 -109.967051)
			(xy 37.356822 -109.911678) (xy 37.386789 -109.859772) (xy 37.423276 -109.812222) (xy 37.465656 -109.769842)
			(xy 37.513206 -109.733355) (xy 37.565112 -109.703388) (xy 37.620485 -109.680452) (xy 37.678378 -109.664939)
			(xy 37.7378 -109.657116) (xy 37.797736 -109.657116) (xy 37.857158 -109.664939) (xy 37.915051 -109.680452)
			(xy 37.970424 -109.703388) (xy 38.02233 -109.733355) (xy 38.06988 -109.769842) (xy 38.11226 -109.812222)
			(xy 38.148747 -109.859772) (xy 38.178714 -109.911678) (xy 38.20165 -109.967051) (xy 38.217163 -110.024944)
			(xy 38.224986 -110.084366) (xy 38.225476 -110.114334) (xy 38.225476 -110.977934) (xy 38.224986 -111.007902)
			(xy 38.217163 -111.067324) (xy 38.20165 -111.125217) (xy 38.178714 -111.18059) (xy 38.148747 -111.232496)
			(xy 38.11226 -111.280046) (xy 38.06988 -111.322426) (xy 38.02233 -111.358913) (xy 37.970424 -111.38888)
			(xy 37.915051 -111.411816) (xy 37.857158 -111.427329) (xy 37.797736 -111.435152) (xy 37.7378 -111.435152)
			(xy 37.678378 -111.427329) (xy 37.620485 -111.411816) (xy 37.565112 -111.38888) (xy 37.513206 -111.358913)
			(xy 37.465656 -111.322426) (xy 37.423276 -111.280046) (xy 37.386789 -111.232496) (xy 37.356822 -111.18059)
			(xy 37.333886 -111.125217) (xy 37.318373 -111.067324) (xy 37.31055 -111.007902) (xy 37.31006 -110.977934)
			(xy 21.987101 -110.977934) (xy 22.538622 -112.784382) (xy 34.667952 -112.784382) (xy 34.667952 -111.920782)
			(xy 34.668442 -111.890814) (xy 34.676265 -111.831392) (xy 34.691778 -111.773499) (xy 34.714714 -111.718126)
			(xy 34.744681 -111.66622) (xy 34.781168 -111.61867) (xy 34.823548 -111.57629) (xy 34.871098 -111.539803)
			(xy 34.923004 -111.509836) (xy 34.978377 -111.4869) (xy 35.03627 -111.471387) (xy 35.095692 -111.463564)
			(xy 35.155628 -111.463564) (xy 35.21505 -111.471387) (xy 35.272943 -111.4869) (xy 35.328316 -111.509836)
			(xy 35.380222 -111.539803) (xy 35.427772 -111.57629) (xy 35.470152 -111.61867) (xy 35.506639 -111.66622)
			(xy 35.536606 -111.718126) (xy 35.559542 -111.773499) (xy 35.575055 -111.831392) (xy 35.582878 -111.890814)
			(xy 35.583368 -111.920782) (xy 35.583368 -112.784382) (xy 35.582878 -112.81435) (xy 35.575055 -112.873772)
			(xy 35.559542 -112.931665) (xy 35.536606 -112.987038) (xy 35.506639 -113.038944) (xy 35.470152 -113.086494)
			(xy 35.427772 -113.128874) (xy 35.380222 -113.165361) (xy 35.328316 -113.195328) (xy 35.272943 -113.218264)
			(xy 35.21505 -113.233777) (xy 35.155628 -113.2416) (xy 35.095692 -113.2416) (xy 35.03627 -113.233777)
			(xy 34.978377 -113.218264) (xy 34.923004 -113.195328) (xy 34.871098 -113.165361) (xy 34.823548 -113.128874)
			(xy 34.781168 -113.086494) (xy 34.744681 -113.038944) (xy 34.714714 -112.987038) (xy 34.691778 -112.931665)
			(xy 34.676265 -112.873772) (xy 34.668442 -112.81435) (xy 34.667952 -112.784382) (xy 22.538622 -112.784382)
			(xy 23.685194 -116.539853) (xy 36.544449 -116.539853) (xy 36.544449 -116.485347) (xy 36.552207 -116.431394)
			(xy 36.567563 -116.379095) (xy 36.590206 -116.329514) (xy 36.619675 -116.28366) (xy 36.65537 -116.242467)
			(xy 36.696563 -116.206773) (xy 36.742418 -116.177304) (xy 36.791999 -116.154662) (xy 36.844298 -116.139306)
			(xy 36.898251 -116.131549) (xy 36.925504 -116.131086) (xy 36.951818 -116.131555) (xy 37.003946 -116.13879)
			(xy 37.054589 -116.153109) (xy 37.102788 -116.174242) (xy 37.147631 -116.201787) (xy 37.188271 -116.235225)
			(xy 37.206428 -116.254276) (xy 37.21394 -116.261688) (xy 37.233227 -116.270208) (xy 37.243766 -116.270786)
			(xy 37.318442 -116.270786) (xy 37.32899 -116.270243) (xy 37.348286 -116.261718) (xy 37.35578 -116.254276)
			(xy 37.372776 -116.236393) (xy 37.410614 -116.204732) (xy 37.452222 -116.17822) (xy 37.474398 -116.167408)
			(xy 37.484558 -116.162582) (xy 37.498782 -116.145818) (xy 37.525198 -116.049044) (xy 37.521642 -116.027708)
			(xy 37.515292 -116.018564) (xy 37.515292 -116.01831) (xy 37.499726 -115.994464) (xy 37.475069 -115.943134)
			(xy 37.458304 -115.888713) (xy 37.449802 -115.832406) (xy 37.449252 -115.803934) (xy 37.449827 -115.775043)
			(xy 37.458508 -115.717917) (xy 37.475707 -115.662754) (xy 37.501031 -115.610817) (xy 37.5339 -115.563294)
			(xy 37.573561 -115.521273) (xy 37.619107 -115.485716) (xy 37.669495 -115.457436) (xy 37.723573 -115.437081)
			(xy 37.780103 -115.425117) (xy 37.808916 -115.422934) (xy 37.819838 -115.422426) (xy 37.839142 -115.412266)
			(xy 37.899848 -115.335304) (xy 37.905182 -115.314222) (xy 37.90315 -115.303554) (xy 37.900308 -115.286807)
			(xy 37.897252 -115.252975) (xy 37.897054 -115.23599) (xy 37.897054 -115.235228) (xy 37.89754 -115.207977)
			(xy 37.905296 -115.154029) (xy 37.920651 -115.101734) (xy 37.943293 -115.052157) (xy 37.972759 -115.006307)
			(xy 38.00845 -114.965116) (xy 38.049641 -114.929425) (xy 38.095491 -114.899959) (xy 38.145068 -114.877317)
			(xy 38.197363 -114.861962) (xy 38.251311 -114.854206) (xy 38.305813 -114.854206) (xy 38.359761 -114.861962)
			(xy 38.412056 -114.877317) (xy 38.461633 -114.899959) (xy 38.507483 -114.929425) (xy 38.548674 -114.965116)
			(xy 38.584365 -115.006307) (xy 38.613831 -115.052157) (xy 38.636473 -115.101734) (xy 38.651828 -115.154029)
			(xy 38.659584 -115.207977) (xy 38.66007 -115.235228) (xy 38.659626 -115.264125) (xy 38.650934 -115.32126)
			(xy 38.633722 -115.37643) (xy 38.608384 -115.428372) (xy 38.575501 -115.475897) (xy 38.535825 -115.517919)
			(xy 38.490263 -115.553474) (xy 38.43986 -115.581749) (xy 38.385768 -115.602096) (xy 38.329225 -115.614052)
			(xy 38.300406 -115.616228) (xy 38.289484 -115.616736) (xy 38.27018 -115.626896) (xy 38.209474 -115.703858)
			(xy 38.20414 -115.72494) (xy 38.206172 -115.735608) (xy 38.209022 -115.752353) (xy 38.212073 -115.786187)
			(xy 38.212268 -115.803172) (xy 38.212268 -115.803934) (xy 38.211754 -115.830915) (xy 38.204134 -115.884336)
			(xy 38.189064 -115.936152) (xy 38.166846 -115.985327) (xy 38.137922 -116.030883) (xy 38.102869 -116.07191)
			(xy 38.062387 -116.10759) (xy 38.017282 -116.137212) (xy 37.993066 -116.14912) (xy 37.982906 -116.153946)
			(xy 37.968682 -116.17071) (xy 37.942266 -116.267484) (xy 37.945822 -116.28882) (xy 37.952172 -116.297964)
			(xy 37.952172 -116.298218) (xy 37.967757 -116.322053) (xy 37.992408 -116.373387) (xy 38.009167 -116.427812)
			(xy 38.017664 -116.484121) (xy 38.018212 -116.512594) (xy 38.017739 -116.539847) (xy 38.009983 -116.593797)
			(xy 37.994628 -116.646094) (xy 37.971986 -116.695674) (xy 37.942519 -116.741527) (xy 37.906827 -116.78272)
			(xy 37.865635 -116.818413) (xy 37.819783 -116.847882) (xy 37.770204 -116.870524) (xy 37.717907 -116.885881)
			(xy 37.663957 -116.893638) (xy 37.636704 -116.894102) (xy 37.61039 -116.893631) (xy 37.558262 -116.886397)
			(xy 37.507619 -116.872079) (xy 37.45942 -116.850947) (xy 37.414577 -116.823401) (xy 37.373937 -116.789963)
			(xy 37.35578 -116.770912) (xy 37.348266 -116.763501) (xy 37.32898 -116.754982) (xy 37.318442 -116.754402)
			(xy 37.243766 -116.754402) (xy 37.233219 -116.754953) (xy 37.213923 -116.763473) (xy 37.206428 -116.770912)
			(xy 37.188254 -116.789949) (xy 37.147628 -116.823408) (xy 37.102792 -116.850969) (xy 37.054594 -116.87211)
			(xy 37.00395 -116.886431) (xy 36.951819 -116.893661) (xy 36.925504 -116.894102) (xy 36.898251 -116.893651)
			(xy 36.844298 -116.885894) (xy 36.791999 -116.870538) (xy 36.742418 -116.847896) (xy 36.696563 -116.818427)
			(xy 36.65537 -116.782733) (xy 36.619675 -116.74154) (xy 36.590206 -116.695686) (xy 36.567563 -116.646105)
			(xy 36.552207 -116.593806) (xy 36.544449 -116.539853) (xy 23.685194 -116.539853) (xy 24.056004 -117.7544)
			(xy 37.088062 -117.7544) (xy 37.092133 -117.698778) (xy 37.104259 -117.644341) (xy 37.124182 -117.59225)
			(xy 37.151478 -117.543615) (xy 37.185564 -117.499472) (xy 37.225713 -117.460763) (xy 37.271071 -117.428312)
			(xy 37.320671 -117.402811) (xy 37.373455 -117.384804) (xy 37.428298 -117.374674) (xy 37.484032 -117.372637)
			(xy 37.539469 -117.378737) (xy 37.593426 -117.392843) (xy 37.644755 -117.414655) (xy 37.692361 -117.443709)
			(xy 37.735229 -117.479384) (xy 37.772446 -117.520921) (xy 37.803219 -117.567434) (xy 37.826891 -117.617931)
			(xy 37.842959 -117.671338) (xy 37.851079 -117.726514) (xy 37.851588 -117.7544) (xy 37.851079 -117.782286)
			(xy 37.842959 -117.837462) (xy 37.826891 -117.890869) (xy 37.803219 -117.941366) (xy 37.772446 -117.987879)
			(xy 37.735229 -118.029416) (xy 37.692361 -118.065091) (xy 37.644755 -118.094145) (xy 37.593426 -118.115957)
			(xy 37.539469 -118.130063) (xy 37.484032 -118.136163) (xy 37.428298 -118.134126) (xy 37.373455 -118.123996)
			(xy 37.320671 -118.105989) (xy 37.271071 -118.080488) (xy 37.225713 -118.048037) (xy 37.185564 -118.009328)
			(xy 37.151478 -117.965185) (xy 37.124182 -117.91655) (xy 37.104259 -117.864459) (xy 37.092133 -117.810022)
			(xy 37.088062 -117.7544) (xy 24.056004 -117.7544) (xy 24.310594 -118.588282) (xy 24.322265 -118.6281)
			(xy 24.339685 -118.709235) (xy 24.345392 -118.750334) (xy 24.35098 -118.79326) (xy 24.352758 -118.801388)
			(xy 24.431244 -119.060214) (xy 24.442664 -119.099363) (xy 24.459833 -119.179092) (xy 24.465534 -119.219472)
			(xy 24.57977 -120.087898) (xy 34.667952 -120.087898) (xy 34.667952 -119.224298) (xy 34.668442 -119.19433)
			(xy 34.676265 -119.134908) (xy 34.691778 -119.077015) (xy 34.714714 -119.021642) (xy 34.744681 -118.969736)
			(xy 34.781168 -118.922186) (xy 34.823548 -118.879806) (xy 34.871098 -118.843319) (xy 34.923004 -118.813352)
			(xy 34.978377 -118.790416) (xy 35.03627 -118.774903) (xy 35.095692 -118.76708) (xy 35.155628 -118.76708)
			(xy 35.21505 -118.774903) (xy 35.272943 -118.790416) (xy 35.328316 -118.813352) (xy 35.380222 -118.843319)
			(xy 35.427772 -118.879806) (xy 35.470152 -118.922186) (xy 35.506639 -118.969736) (xy 35.536606 -119.021642)
			(xy 35.559542 -119.077015) (xy 35.575055 -119.134908) (xy 35.582878 -119.19433) (xy 35.583368 -119.224298)
			(xy 35.583368 -120.087898) (xy 35.582878 -120.117866) (xy 35.575055 -120.177288) (xy 35.559542 -120.235181)
			(xy 35.536606 -120.290554) (xy 35.506639 -120.34246) (xy 35.470152 -120.39001) (xy 35.427772 -120.43239)
			(xy 35.380222 -120.468877) (xy 35.328316 -120.498844) (xy 35.272943 -120.52178) (xy 35.21505 -120.537293)
			(xy 35.155628 -120.545116) (xy 35.095692 -120.545116) (xy 35.03627 -120.537293) (xy 34.978377 -120.52178)
			(xy 34.923004 -120.498844) (xy 34.871098 -120.468877) (xy 34.823548 -120.43239) (xy 34.781168 -120.39001)
			(xy 34.744681 -120.34246) (xy 34.714714 -120.290554) (xy 34.691778 -120.235181) (xy 34.676265 -120.177288)
			(xy 34.668442 -120.117866) (xy 34.667952 -120.087898) (xy 24.57977 -120.087898) (xy 24.817398 -121.894346)
			(xy 37.31006 -121.894346) (xy 37.31006 -121.030746) (xy 37.31055 -121.000778) (xy 37.318373 -120.941356)
			(xy 37.333886 -120.883463) (xy 37.356822 -120.82809) (xy 37.386789 -120.776184) (xy 37.423276 -120.728634)
			(xy 37.465656 -120.686254) (xy 37.513206 -120.649767) (xy 37.565112 -120.6198) (xy 37.620485 -120.596864)
			(xy 37.678378 -120.581351) (xy 37.7378 -120.573528) (xy 37.797736 -120.573528) (xy 37.857158 -120.581351)
			(xy 37.915051 -120.596864) (xy 37.970424 -120.6198) (xy 38.02233 -120.649767) (xy 38.06988 -120.686254)
			(xy 38.11226 -120.728634) (xy 38.148747 -120.776184) (xy 38.178714 -120.82809) (xy 38.20165 -120.883463)
			(xy 38.217163 -120.941356) (xy 38.224986 -121.000778) (xy 38.225476 -121.030746) (xy 38.225476 -121.894346)
			(xy 38.224986 -121.924314) (xy 38.217163 -121.983736) (xy 38.20165 -122.041629) (xy 38.178714 -122.097002)
			(xy 38.148747 -122.148908) (xy 38.11226 -122.196458) (xy 38.06988 -122.238838) (xy 38.02233 -122.275325)
			(xy 37.970424 -122.305292) (xy 37.915051 -122.328228) (xy 37.857158 -122.343741) (xy 37.797736 -122.351564)
			(xy 37.7378 -122.351564) (xy 37.678378 -122.343741) (xy 37.620485 -122.328228) (xy 37.565112 -122.305292)
			(xy 37.513206 -122.275325) (xy 37.465656 -122.238838) (xy 37.423276 -122.196458) (xy 37.386789 -122.148908)
			(xy 37.356822 -122.097002) (xy 37.333886 -122.041629) (xy 37.318373 -121.983736) (xy 37.31055 -121.924314)
			(xy 37.31006 -121.894346) (xy 24.817398 -121.894346) (xy 25.053322 -123.68784) (xy 34.667952 -123.68784)
			(xy 34.667952 -122.82424) (xy 34.668442 -122.794272) (xy 34.676265 -122.73485) (xy 34.691778 -122.676957)
			(xy 34.714714 -122.621584) (xy 34.744681 -122.569678) (xy 34.781168 -122.522128) (xy 34.823548 -122.479748)
			(xy 34.871098 -122.443261) (xy 34.923004 -122.413294) (xy 34.978377 -122.390358) (xy 35.03627 -122.374845)
			(xy 35.095692 -122.367022) (xy 35.155628 -122.367022) (xy 35.21505 -122.374845) (xy 35.272943 -122.390358)
			(xy 35.328316 -122.413294) (xy 35.380222 -122.443261) (xy 35.427772 -122.479748) (xy 35.470152 -122.522128)
			(xy 35.506639 -122.569678) (xy 35.536606 -122.621584) (xy 35.559542 -122.676957) (xy 35.575055 -122.73485)
			(xy 35.582878 -122.794272) (xy 35.583368 -122.82424) (xy 35.583368 -123.68784) (xy 35.582878 -123.717808)
			(xy 35.575055 -123.77723) (xy 35.559542 -123.835123) (xy 35.536606 -123.890496) (xy 35.506639 -123.942402)
			(xy 35.470152 -123.989952) (xy 35.427772 -124.032332) (xy 35.380222 -124.068819) (xy 35.328316 -124.098786)
			(xy 35.272943 -124.121722) (xy 35.21505 -124.137235) (xy 35.155628 -124.145058) (xy 35.095692 -124.145058)
			(xy 35.03627 -124.137235) (xy 34.978377 -124.121722) (xy 34.923004 -124.098786) (xy 34.871098 -124.068819)
			(xy 34.823548 -124.032332) (xy 34.781168 -123.989952) (xy 34.744681 -123.942402) (xy 34.714714 -123.890496)
			(xy 34.691778 -123.835123) (xy 34.676265 -123.77723) (xy 34.668442 -123.717808) (xy 34.667952 -123.68784)
			(xy 25.053322 -123.68784) (xy 25.290983 -125.494542) (xy 37.31006 -125.494542) (xy 37.31006 -124.630942)
			(xy 37.31055 -124.600974) (xy 37.318373 -124.541552) (xy 37.333886 -124.483659) (xy 37.356822 -124.428286)
			(xy 37.386789 -124.37638) (xy 37.423276 -124.32883) (xy 37.465656 -124.28645) (xy 37.513206 -124.249963)
			(xy 37.565112 -124.219996) (xy 37.620485 -124.19706) (xy 37.678378 -124.181547) (xy 37.7378 -124.173724)
			(xy 37.797736 -124.173724) (xy 37.857158 -124.181547) (xy 37.915051 -124.19706) (xy 37.970424 -124.219996)
			(xy 38.02233 -124.249963) (xy 38.06988 -124.28645) (xy 38.11226 -124.32883) (xy 38.148747 -124.37638)
			(xy 38.178714 -124.428286) (xy 38.20165 -124.483659) (xy 38.217163 -124.541552) (xy 38.224986 -124.600974)
			(xy 38.225476 -124.630942) (xy 38.225476 -125.494542) (xy 38.224986 -125.52451) (xy 38.217163 -125.583932)
			(xy 38.20165 -125.641825) (xy 38.178714 -125.697198) (xy 38.148747 -125.749104) (xy 38.11226 -125.796654)
			(xy 38.06988 -125.839034) (xy 38.02233 -125.875521) (xy 37.970424 -125.905488) (xy 37.915051 -125.928424)
			(xy 37.857158 -125.943937) (xy 37.797736 -125.95176) (xy 37.7378 -125.95176) (xy 37.678378 -125.943937)
			(xy 37.620485 -125.928424) (xy 37.565112 -125.905488) (xy 37.513206 -125.875521) (xy 37.465656 -125.839034)
			(xy 37.423276 -125.796654) (xy 37.386789 -125.749104) (xy 37.356822 -125.697198) (xy 37.333886 -125.641825)
			(xy 37.318373 -125.583932) (xy 37.31055 -125.52451) (xy 37.31006 -125.494542) (xy 25.290983 -125.494542)
			(xy 26.054385 -131.297934) (xy 34.667952 -131.297934) (xy 34.667952 -130.434334) (xy 34.668442 -130.404366)
			(xy 34.676265 -130.344944) (xy 34.691778 -130.287051) (xy 34.714714 -130.231678) (xy 34.744681 -130.179772)
			(xy 34.781168 -130.132222) (xy 34.823548 -130.089842) (xy 34.871098 -130.053355) (xy 34.923004 -130.023388)
			(xy 34.978377 -130.000452) (xy 35.03627 -129.984939) (xy 35.095692 -129.977116) (xy 35.155628 -129.977116)
			(xy 35.21505 -129.984939) (xy 35.272943 -130.000452) (xy 35.328316 -130.023388) (xy 35.380222 -130.053355)
			(xy 35.427772 -130.089842) (xy 35.470152 -130.132222) (xy 35.506639 -130.179772) (xy 35.536606 -130.231678)
			(xy 35.559542 -130.287051) (xy 35.575055 -130.344944) (xy 35.582878 -130.404366) (xy 35.583368 -130.434334)
			(xy 35.583368 -131.297934) (xy 35.582878 -131.327902) (xy 35.575055 -131.387324) (xy 35.559542 -131.445217)
			(xy 35.536606 -131.50059) (xy 35.506639 -131.552496) (xy 35.470152 -131.600046) (xy 35.427772 -131.642426)
			(xy 35.380222 -131.678913) (xy 35.328316 -131.70888) (xy 35.272943 -131.731816) (xy 35.21505 -131.747329)
			(xy 35.155628 -131.755152) (xy 35.095692 -131.755152) (xy 35.03627 -131.747329) (xy 34.978377 -131.731816)
			(xy 34.923004 -131.70888) (xy 34.871098 -131.678913) (xy 34.823548 -131.642426) (xy 34.781168 -131.600046)
			(xy 34.744681 -131.552496) (xy 34.714714 -131.50059) (xy 34.691778 -131.445217) (xy 34.676265 -131.387324)
			(xy 34.668442 -131.327902) (xy 34.667952 -131.297934) (xy 26.054385 -131.297934) (xy 26.292013 -133.104382)
			(xy 37.31006 -133.104382) (xy 37.31006 -132.240782) (xy 37.31055 -132.210814) (xy 37.318373 -132.151392)
			(xy 37.333886 -132.093499) (xy 37.356822 -132.038126) (xy 37.386789 -131.98622) (xy 37.423276 -131.93867)
			(xy 37.465656 -131.89629) (xy 37.513206 -131.859803) (xy 37.565112 -131.829836) (xy 37.620485 -131.8069)
			(xy 37.678378 -131.791387) (xy 37.7378 -131.783564) (xy 37.797736 -131.783564) (xy 37.857158 -131.791387)
			(xy 37.915051 -131.8069) (xy 37.970424 -131.829836) (xy 38.02233 -131.859803) (xy 38.06988 -131.89629)
			(xy 38.11226 -131.93867) (xy 38.148747 -131.98622) (xy 38.178714 -132.038126) (xy 38.20165 -132.093499)
			(xy 38.217163 -132.151392) (xy 38.224986 -132.210814) (xy 38.225476 -132.240782) (xy 38.225476 -133.104382)
			(xy 38.224986 -133.13435) (xy 38.217163 -133.193772) (xy 38.20165 -133.251665) (xy 38.178714 -133.307038)
			(xy 38.148747 -133.358944) (xy 38.11226 -133.406494) (xy 38.06988 -133.448874) (xy 38.02233 -133.485361)
			(xy 37.970424 -133.515328) (xy 37.915051 -133.538264) (xy 37.857158 -133.553777) (xy 37.797736 -133.5616)
			(xy 37.7378 -133.5616) (xy 37.678378 -133.553777) (xy 37.620485 -133.538264) (xy 37.565112 -133.515328)
			(xy 37.513206 -133.485361) (xy 37.465656 -133.448874) (xy 37.423276 -133.406494) (xy 37.386789 -133.358944)
			(xy 37.356822 -133.307038) (xy 37.333886 -133.251665) (xy 37.318373 -133.193772) (xy 37.31055 -133.13435)
			(xy 37.31006 -133.104382) (xy 26.292013 -133.104382) (xy 26.527936 -134.897876) (xy 34.667952 -134.897876)
			(xy 34.667952 -134.034276) (xy 34.668442 -134.004308) (xy 34.676265 -133.944886) (xy 34.691778 -133.886993)
			(xy 34.714714 -133.83162) (xy 34.744681 -133.779714) (xy 34.781168 -133.732164) (xy 34.823548 -133.689784)
			(xy 34.871098 -133.653297) (xy 34.923004 -133.62333) (xy 34.978377 -133.600394) (xy 35.03627 -133.584881)
			(xy 35.095692 -133.577058) (xy 35.155628 -133.577058) (xy 35.21505 -133.584881) (xy 35.272943 -133.600394)
			(xy 35.328316 -133.62333) (xy 35.380222 -133.653297) (xy 35.427772 -133.689784) (xy 35.470152 -133.732164)
			(xy 35.506639 -133.779714) (xy 35.536606 -133.83162) (xy 35.559542 -133.886993) (xy 35.575055 -133.944886)
			(xy 35.582878 -134.004308) (xy 35.583368 -134.034276) (xy 35.583368 -134.897876) (xy 35.582878 -134.927844)
			(xy 35.575055 -134.987266) (xy 35.559542 -135.045159) (xy 35.536606 -135.100532) (xy 35.506639 -135.152438)
			(xy 35.470152 -135.199988) (xy 35.427772 -135.242368) (xy 35.380222 -135.278855) (xy 35.328316 -135.308822)
			(xy 35.272943 -135.331758) (xy 35.21505 -135.347271) (xy 35.155628 -135.355094) (xy 35.095692 -135.355094)
			(xy 35.03627 -135.347271) (xy 34.978377 -135.331758) (xy 34.923004 -135.308822) (xy 34.871098 -135.278855)
			(xy 34.823548 -135.242368) (xy 34.781168 -135.199988) (xy 34.744681 -135.152438) (xy 34.714714 -135.100532)
			(xy 34.691778 -135.045159) (xy 34.676265 -134.987266) (xy 34.668442 -134.927844) (xy 34.667952 -134.897876)
			(xy 26.527936 -134.897876) (xy 27.242022 -140.326364) (xy 35.692078 -140.326364) (xy 35.696149 -140.270742)
			(xy 35.708275 -140.216305) (xy 35.728198 -140.164214) (xy 35.755494 -140.115579) (xy 35.78958 -140.071436)
			(xy 35.829729 -140.032727) (xy 35.875087 -140.000276) (xy 35.924687 -139.974775) (xy 35.977471 -139.956768)
			(xy 36.032314 -139.946638) (xy 36.088048 -139.944601) (xy 36.143485 -139.950701) (xy 36.197442 -139.964807)
			(xy 36.248771 -139.986619) (xy 36.296377 -140.015673) (xy 36.339245 -140.051348) (xy 36.376462 -140.092885)
			(xy 36.407235 -140.139398) (xy 36.430907 -140.189895) (xy 36.446975 -140.243302) (xy 36.455095 -140.298478)
			(xy 36.455604 -140.326364) (xy 36.455095 -140.35425) (xy 36.446975 -140.409426) (xy 36.430907 -140.462833)
			(xy 36.407235 -140.51333) (xy 36.376462 -140.559843) (xy 36.339245 -140.60138) (xy 36.296377 -140.637055)
			(xy 36.248771 -140.666109) (xy 36.197442 -140.687921) (xy 36.143485 -140.702027) (xy 36.088048 -140.708127)
			(xy 36.032314 -140.70609) (xy 35.977471 -140.69596) (xy 35.924687 -140.677953) (xy 35.875087 -140.652452)
			(xy 35.829729 -140.620001) (xy 35.78958 -140.581292) (xy 35.755494 -140.537149) (xy 35.728198 -140.488514)
			(xy 35.708275 -140.436423) (xy 35.696149 -140.381986) (xy 35.692078 -140.326364) (xy 27.242022 -140.326364)
			(xy 27.751024 -144.1958) (xy 27.751278 -144.197324) (xy 29.475328 -153.3144) (xy 37.190932 -153.3144)
			(xy 37.195003 -153.258778) (xy 37.207129 -153.204341) (xy 37.227052 -153.15225) (xy 37.254348 -153.103615)
			(xy 37.288434 -153.059472) (xy 37.328583 -153.020763) (xy 37.373941 -152.988312) (xy 37.423541 -152.962811)
			(xy 37.476325 -152.944804) (xy 37.531168 -152.934674) (xy 37.586902 -152.932637) (xy 37.642339 -152.938737)
			(xy 37.696296 -152.952843) (xy 37.747625 -152.974655) (xy 37.795231 -153.003709) (xy 37.838099 -153.039384)
			(xy 37.875316 -153.080921) (xy 37.906089 -153.127434) (xy 37.929761 -153.177931) (xy 37.945829 -153.231338)
			(xy 37.953949 -153.286514) (xy 37.954458 -153.3144) (xy 37.953949 -153.342286) (xy 37.945829 -153.397462)
			(xy 37.929761 -153.450869) (xy 37.906089 -153.501366) (xy 37.875316 -153.547879) (xy 37.838099 -153.589416)
			(xy 37.795231 -153.625091) (xy 37.747625 -153.654145) (xy 37.696296 -153.675957) (xy 37.642339 -153.690063)
			(xy 37.586902 -153.696163) (xy 37.531168 -153.694126) (xy 37.476325 -153.683996) (xy 37.423541 -153.665989)
			(xy 37.373941 -153.640488) (xy 37.328583 -153.608037) (xy 37.288434 -153.569328) (xy 37.254348 -153.525185)
			(xy 37.227052 -153.47655) (xy 37.207129 -153.424459) (xy 37.195003 -153.370022) (xy 37.190932 -153.3144)
			(xy 29.475328 -153.3144) (xy 30.243835 -157.3784) (xy 37.190932 -157.3784) (xy 37.195003 -157.322778)
			(xy 37.207129 -157.268341) (xy 37.227052 -157.21625) (xy 37.254348 -157.167615) (xy 37.288434 -157.123472)
			(xy 37.328583 -157.084763) (xy 37.373941 -157.052312) (xy 37.423541 -157.026811) (xy 37.476325 -157.008804)
			(xy 37.531168 -156.998674) (xy 37.586902 -156.996637) (xy 37.642339 -157.002737) (xy 37.696296 -157.016843)
			(xy 37.747625 -157.038655) (xy 37.795231 -157.067709) (xy 37.838099 -157.103384) (xy 37.875316 -157.144921)
			(xy 37.906089 -157.191434) (xy 37.929761 -157.241931) (xy 37.945829 -157.295338) (xy 37.953949 -157.350514)
			(xy 37.954458 -157.3784) (xy 37.953949 -157.406286) (xy 37.945829 -157.461462) (xy 37.929761 -157.514869)
			(xy 37.906089 -157.565366) (xy 37.875316 -157.611879) (xy 37.838099 -157.653416) (xy 37.795231 -157.689091)
			(xy 37.747625 -157.718145) (xy 37.696296 -157.739957) (xy 37.642339 -157.754063) (xy 37.586902 -157.760163)
			(xy 37.531168 -157.758126) (xy 37.476325 -157.747996) (xy 37.423541 -157.729989) (xy 37.373941 -157.704488)
			(xy 37.328583 -157.672037) (xy 37.288434 -157.633328) (xy 37.254348 -157.589185) (xy 37.227052 -157.54055)
			(xy 37.207129 -157.488459) (xy 37.195003 -157.434022) (xy 37.190932 -157.3784) (xy 30.243835 -157.3784)
			(xy 30.435962 -158.3944) (xy 37.190932 -158.3944) (xy 37.195003 -158.338778) (xy 37.207129 -158.284341)
			(xy 37.227052 -158.23225) (xy 37.254348 -158.183615) (xy 37.288434 -158.139472) (xy 37.328583 -158.100763)
			(xy 37.373941 -158.068312) (xy 37.423541 -158.042811) (xy 37.476325 -158.024804) (xy 37.531168 -158.014674)
			(xy 37.586902 -158.012637) (xy 37.642339 -158.018737) (xy 37.696296 -158.032843) (xy 37.747625 -158.054655)
			(xy 37.795231 -158.083709) (xy 37.838099 -158.119384) (xy 37.875316 -158.160921) (xy 37.906089 -158.207434)
			(xy 37.929761 -158.257931) (xy 37.945829 -158.311338) (xy 37.953949 -158.366514) (xy 37.954458 -158.3944)
			(xy 37.953949 -158.422286) (xy 37.945829 -158.477462) (xy 37.929761 -158.530869) (xy 37.906089 -158.581366)
			(xy 37.875316 -158.627879) (xy 37.838099 -158.669416) (xy 37.795231 -158.705091) (xy 37.747625 -158.734145)
			(xy 37.696296 -158.755957) (xy 37.642339 -158.770063) (xy 37.586902 -158.776163) (xy 37.531168 -158.774126)
			(xy 37.476325 -158.763996) (xy 37.423541 -158.745989) (xy 37.373941 -158.720488) (xy 37.328583 -158.688037)
			(xy 37.288434 -158.649328) (xy 37.254348 -158.605185) (xy 37.227052 -158.55655) (xy 37.207129 -158.504459)
			(xy 37.195003 -158.450022) (xy 37.190932 -158.3944) (xy 30.435962 -158.3944) (xy 30.944618 -161.08426)
			(xy 37.583108 -161.08426) (xy 37.587179 -161.028638) (xy 37.599305 -160.974201) (xy 37.619228 -160.92211)
			(xy 37.646524 -160.873475) (xy 37.68061 -160.829332) (xy 37.720759 -160.790623) (xy 37.766117 -160.758172)
			(xy 37.815717 -160.732671) (xy 37.868501 -160.714664) (xy 37.923344 -160.704534) (xy 37.979078 -160.702497)
			(xy 38.034515 -160.708597) (xy 38.088472 -160.722703) (xy 38.139801 -160.744515) (xy 38.187407 -160.773569)
			(xy 38.230275 -160.809244) (xy 38.267492 -160.850781) (xy 38.298265 -160.897294) (xy 38.321937 -160.947791)
			(xy 38.338005 -161.001198) (xy 38.346125 -161.056374) (xy 38.346634 -161.08426) (xy 38.346125 -161.112146)
			(xy 38.338005 -161.167322) (xy 38.321937 -161.220729) (xy 38.298265 -161.271226) (xy 38.267492 -161.317739)
			(xy 38.230275 -161.359276) (xy 38.187407 -161.394951) (xy 38.139801 -161.424005) (xy 38.088472 -161.445817)
			(xy 38.034515 -161.459923) (xy 37.979078 -161.466023) (xy 37.923344 -161.463986) (xy 37.868501 -161.453856)
			(xy 37.815717 -161.435849) (xy 37.766117 -161.410348) (xy 37.720759 -161.377897) (xy 37.68061 -161.339188)
			(xy 37.646524 -161.295045) (xy 37.619228 -161.24641) (xy 37.599305 -161.194319) (xy 37.587179 -161.139882)
			(xy 37.583108 -161.08426) (xy 30.944618 -161.08426) (xy 31.482525 -163.928806) (xy 38.393114 -163.928806)
			(xy 38.397185 -163.873184) (xy 38.409311 -163.818747) (xy 38.429234 -163.766656) (xy 38.45653 -163.718021)
			(xy 38.490616 -163.673878) (xy 38.530765 -163.635169) (xy 38.576123 -163.602718) (xy 38.625723 -163.577217)
			(xy 38.678507 -163.55921) (xy 38.73335 -163.54908) (xy 38.789084 -163.547043) (xy 38.844521 -163.553143)
			(xy 38.898478 -163.567249) (xy 38.949807 -163.589061) (xy 38.997413 -163.618115) (xy 39.040281 -163.65379)
			(xy 39.077498 -163.695327) (xy 39.108271 -163.74184) (xy 39.131943 -163.792337) (xy 39.148011 -163.845744)
			(xy 39.156131 -163.90092) (xy 39.15664 -163.928806) (xy 39.156131 -163.956692) (xy 39.148011 -164.011868)
			(xy 39.131943 -164.065275) (xy 39.108271 -164.115772) (xy 39.077498 -164.162285) (xy 39.040281 -164.203822)
			(xy 38.997413 -164.239497) (xy 38.949807 -164.268551) (xy 38.898478 -164.290363) (xy 38.844521 -164.304469)
			(xy 38.789084 -164.310569) (xy 38.73335 -164.308532) (xy 38.678507 -164.298402) (xy 38.625723 -164.280395)
			(xy 38.576123 -164.254894) (xy 38.530765 -164.222443) (xy 38.490616 -164.183734) (xy 38.45653 -164.139591)
			(xy 38.429234 -164.090956) (xy 38.409311 -164.038865) (xy 38.397185 -163.984428) (xy 38.393114 -163.928806)
			(xy 31.482525 -163.928806) (xy 38.285928 -199.906382) (xy 41.159938 -215.080088) (xy 41.43629 -216.539572)
			(xy 41.439569 -216.549866) (xy 41.453221 -216.566587) (xy 41.472516 -216.576264) (xy 41.48328 -216.577164)
			(xy 43.780202 -216.577164) (xy 43.794183 -216.576684) (xy 43.821079 -216.569022) (xy 43.844891 -216.554357)
			(xy 43.863835 -216.533785) (xy 43.876492 -216.508848) (xy 43.881916 -216.481413) (xy 43.881294 -216.467436)
			(xy 42.758868 -202.56881) (xy 42.241724 -196.167502) (xy 42.069258 -194.031616) (xy 41.886124 -191.765428)
			(xy 40.497252 -174.570136) (xy 40.497252 -174.568866) (xy 40.496744 -174.564802) (xy 40.49649 -174.562516)
			(xy 40.496236 -174.559468) (xy 40.496236 -174.558706) (xy 40.495982 -174.55642) (xy 40.495474 -174.55007)
			(xy 40.429942 -173.739302) (xy 40.261794 -171.656502) (xy 40.120316 -169.905426) (xy 40.069262 -169.272204)
			(xy 39.845742 -166.503604) (xy 39.619936 -163.70554) (xy 39.618666 -163.686744) (xy 39.251382 -157.708854)
			(xy 39.028624 -154.084528) (xy 39.028624 -154.083766) (xy 38.999922 -153.71826) (xy 38.23081 -143.940784)
			(xy 38.23081 -143.93926) (xy 37.940488 -141.181328) (xy 37.938019 -141.156127) (xy 37.935351 -141.105556)
			(xy 37.935154 -141.080236) (xy 37.929312 -138.52398) (xy 37.929312 -138.521694) (xy 37.929403 -138.4981)
			(xy 37.931565 -138.450963) (xy 37.93363 -138.42746) (xy 37.938202 -138.38809) (xy 37.95268 -138.28141)
			(xy 38.095936 -137.230104) (xy 38.09619 -137.225278) (xy 38.09619 -137.221722) (xy 38.095575 -137.209874)
			(xy 38.084984 -137.188677) (xy 38.07587 -137.181082) (xy 38.05555 -137.165842) (xy 38.0111 -137.132568)
			(xy 38.007798 -137.130028) (xy 38.004242 -137.127488) (xy 37.996876 -137.124948) (xy 37.993041 -137.123789)
			(xy 37.985133 -137.122518) (xy 37.981128 -137.122408) (xy 37.97046 -137.122408) (xy 37.962078 -137.12317)
			(xy 37.946838 -137.126218) (xy 37.94252 -137.127996) (xy 37.910632 -137.140362) (xy 37.844187 -137.15656)
			(xy 37.810186 -137.160254) (xy 37.767768 -137.162032) (xy 37.737801 -137.16154) (xy 37.678381 -137.153713)
			(xy 37.62049 -137.138199) (xy 37.565119 -137.115261) (xy 37.513216 -137.085292) (xy 37.465668 -137.048806)
			(xy 37.423289 -137.006426) (xy 37.386803 -136.958878) (xy 37.356836 -136.906974) (xy 37.333899 -136.851603)
			(xy 37.318385 -136.793712) (xy 37.31056 -136.734291) (xy 37.31006 -136.704324) (xy 37.31006 -135.840724)
			(xy 37.310549 -135.810755) (xy 37.318369 -135.751328) (xy 37.333879 -135.693431) (xy 37.356813 -135.638053)
			(xy 37.38678 -135.586143) (xy 37.423265 -135.538588) (xy 37.465646 -135.496202) (xy 37.513196 -135.459711)
			(xy 37.565103 -135.429738) (xy 37.620478 -135.406797) (xy 37.678373 -135.39128) (xy 37.737799 -135.383452)
			(xy 37.767768 -135.383016) (xy 37.798363 -135.383432) (xy 37.859023 -135.391455) (xy 37.888672 -135.399018)
			(xy 37.899094 -135.401956) (xy 37.919678 -135.408687) (xy 37.92982 -135.41248) (xy 37.945099 -135.418389)
			(xy 37.974846 -135.43212) (xy 37.989256 -135.439912) (xy 37.994844 -135.44296) (xy 38.004496 -135.4455)
			(xy 38.007544 -135.446262) (xy 38.013894 -135.448294) (xy 38.02761 -135.449056) (xy 38.051994 -135.443468)
			(xy 38.061646 -135.441436) (xy 38.090856 -135.421624) (xy 38.09619 -135.414512) (xy 38.114164 -135.391401)
			(xy 38.156012 -135.350455) (xy 38.179502 -135.332978) (xy 38.200962 -135.318046) (xy 38.247163 -135.293577)
			(xy 38.296281 -135.275669) (xy 38.321742 -135.269732) (xy 38.321996 -135.269732) (xy 38.328854 -135.268208)
			(xy 38.343078 -135.260588) (xy 38.347142 -135.257286) (xy 38.347396 -135.257032) (xy 38.349682 -135.255254)
			(xy 38.357648 -135.248832) (xy 38.368126 -135.231277) (xy 38.370002 -135.221218) (xy 38.38702 -135.097012)
			(xy 38.406578 -134.953502) (xy 38.459664 -134.563358) (xy 38.469062 -134.495032) (xy 38.585902 -133.637528)
			(xy 38.585902 -133.63702) (xy 38.587426 -133.626098) (xy 38.698678 -132.808726) (xy 38.69944 -132.80263)
			(xy 38.69944 -132.802376) (xy 38.781482 -132.04317) (xy 38.795706 -131.911344) (xy 38.79596 -131.90728)
			(xy 38.890702 -123.120658) (xy 38.928548 -119.60606) (xy 38.928548 -119.604028) (xy 38.789102 -115.000786)
			(xy 38.541198 -106.81335) (xy 38.499796 -105.5497) (xy 38.485572 -105.121456) (xy 38.485572 -105.118916)
			(xy 38.428168 -104.40289) (xy 38.427063 -104.393798) (xy 38.419263 -104.377244) (xy 38.412928 -104.370632)
			(xy 38.406324 -104.364028) (xy 38.389814 -104.356916) (xy 38.380416 -104.356408) (xy 38.35222 -104.354293)
			(xy 38.296861 -104.342796) (xy 38.243802 -104.323262) (xy 38.194202 -104.29612) (xy 38.149146 -104.261961)
			(xy 38.109618 -104.221534) (xy 38.092634 -104.198928) (xy 38.090856 -104.196642) (xy 38.06825 -104.18191)
			(xy 38.064416 -104.179514) (xy 38.056114 -104.17594) (xy 38.05174 -104.174798) (xy 38.030912 -104.169972)
			(xy 38.027401 -104.169279) (xy 38.020262 -104.168769) (xy 38.016688 -104.168956) (xy 38.011755 -104.169349)
			(xy 38.002166 -104.171786) (xy 37.997638 -104.173782) (xy 37.99459 -104.17556) (xy 37.968664 -104.189795)
			(xy 37.913925 -104.212201) (xy 37.856753 -104.227355) (xy 37.798103 -104.235004) (xy 37.76853 -104.235504)
			(xy 37.767768 -104.235504) (xy 37.737802 -104.235012) (xy 37.678383 -104.227185) (xy 37.620493 -104.21167)
			(xy 37.565124 -104.188732) (xy 37.513223 -104.158763) (xy 37.465677 -104.122277) (xy 37.4233 -104.079896)
			(xy 37.386817 -104.032347) (xy 37.356852 -103.980444) (xy 37.333918 -103.925073) (xy 37.318408 -103.867182)
			(xy 37.310586 -103.807762) (xy 37.31006 -103.777796) (xy 37.31006 -102.914196) (xy 37.31055 -102.884228)
			(xy 37.318374 -102.824804) (xy 37.333886 -102.76691) (xy 37.356822 -102.711535) (xy 37.38679 -102.659628)
			(xy 37.423275 -102.612077) (xy 37.465656 -102.569694) (xy 37.513205 -102.533205) (xy 37.56511 -102.503235)
			(xy 37.620483 -102.480295) (xy 37.678377 -102.464779) (xy 37.7378 -102.456952) (xy 37.767768 -102.456488)
			(xy 37.77107 -102.456488) (xy 37.799485 -102.457086) (xy 37.855839 -102.464465) (xy 37.910843 -102.478776)
			(xy 37.963648 -102.499798) (xy 37.988748 -102.51313) (xy 37.98951 -102.513638) (xy 37.994336 -102.516178)
			(xy 38.017196 -102.522528) (xy 38.030658 -102.52202) (xy 38.051486 -102.517194) (xy 38.06063 -102.515162)
			(xy 38.090856 -102.49535) (xy 38.09619 -102.488238) (xy 38.115468 -102.463457) (xy 38.160744 -102.419964)
			(xy 38.212539 -102.384486) (xy 38.240716 -102.370636) (xy 38.241732 -102.370128) (xy 38.24351 -102.369366)
			(xy 38.24732 -102.367334) (xy 38.25494 -102.353872) (xy 38.258406 -102.347173) (xy 38.261646 -102.33245)
			(xy 38.26129 -102.324916) (xy 38.249352 -102.177342) (xy 38.198806 -101.54793) (xy 38.145466 -100.883974)
			(xy 38.127178 -100.65639) (xy 38.12626 -100.648609) (xy 38.120305 -100.634127) (xy 38.115494 -100.627942)
			(xy 38.110414 -100.621846) (xy 38.107874 -100.618798) (xy 38.106858 -100.617528) (xy 38.104572 -100.614734)
			(xy 38.10381 -100.613972) (xy 38.096698 -100.604574) (xy 38.09111 -100.596954) (xy 38.06952 -100.58273)
			(xy 38.063192 -100.578858) (xy 38.048994 -100.574584) (xy 38.04158 -100.574348) (xy 38.01364 -100.574348)
			(xy 38.010084 -100.574602) (xy 38.001194 -100.575618) (xy 37.988748 -100.579428) (xy 37.984176 -100.581968)
			(xy 37.975286 -100.58654) (xy 37.951529 -100.59809) (xy 37.901934 -100.616282) (xy 37.850581 -100.628668)
			(xy 37.82441 -100.63226) (xy 37.801266 -100.634907) (xy 37.754692 -100.636054) (xy 37.731446 -100.634546)
			(xy 37.728144 -100.634292) (xy 37.698749 -100.631271) (xy 37.641028 -100.618618) (xy 37.585414 -100.598641)
			(xy 37.532835 -100.571673) (xy 37.484163 -100.538163) (xy 37.440209 -100.498667) (xy 37.401703 -100.453843)
			(xy 37.369286 -100.404436) (xy 37.343497 -100.351268) (xy 37.333682 -100.323396) (xy 37.322705 -100.288209)
			(xy 37.31083 -100.215467) (xy 37.31006 -100.178616) (xy 37.31006 -99.746308) (xy 37.309806 -99.314254)
			(xy 37.310298 -99.284281) (xy 37.318125 -99.224849) (xy 37.333639 -99.166947) (xy 37.356574 -99.111563)
			(xy 37.38654 -99.059644) (xy 37.423022 -99.012079) (xy 37.465399 -98.969681) (xy 37.512945 -98.933173)
			(xy 37.564847 -98.903181) (xy 37.620219 -98.880216) (xy 37.678114 -98.864672) (xy 37.737542 -98.856814)
			(xy 37.767514 -98.856292) (xy 37.767768 -98.856292) (xy 37.81044 -98.858324) (xy 37.812218 -98.858578)
			(xy 37.813234 -98.858578) (xy 37.821108 -98.859594) (xy 37.822378 -98.859594) (xy 37.831014 -98.860864)
			(xy 37.832538 -98.860864) (xy 37.834062 -98.861118) (xy 37.835078 -98.861372) (xy 37.83965 -98.86188)
			(xy 37.840158 -98.86188) (xy 37.844222 -98.862642) (xy 37.84473 -98.862642) (xy 37.857117 -98.864902)
			(xy 37.881643 -98.870617) (xy 37.893752 -98.874072) (xy 37.897308 -98.875088) (xy 37.904674 -98.876104)
			(xy 37.915067 -98.877008) (xy 37.935127 -98.871358) (xy 37.943536 -98.865182) (xy 37.977826 -98.837242)
			(xy 37.981128 -98.834448) (xy 37.879274 -97.566226) (xy 37.877994 -97.558938) (xy 37.871802 -97.545508)
			(xy 37.867082 -97.53981) (xy 37.864127 -97.536661) (xy 37.857361 -97.531297) (xy 37.85362 -97.529142)
			(xy 37.834062 -97.51822) (xy 37.820854 -97.517966) (xy 37.791136 -97.517966) (xy 37.779452 -97.521014)
			(xy 37.77488 -97.5233) (xy 37.748713 -97.535458) (xy 37.693633 -97.552638) (xy 37.636596 -97.561345)
			(xy 37.607748 -97.561908) (xy 37.60089 -97.561908) (xy 37.573949 -97.560976) (xy 37.520721 -97.552464)
			(xy 37.46922 -97.536542) (xy 37.420474 -97.51353) (xy 37.375453 -97.483884) (xy 37.335054 -97.448195)
			(xy 37.300081 -97.407175) (xy 37.271232 -97.361639) (xy 37.24908 -97.312496) (xy 37.234068 -97.260723)
			(xy 37.226493 -97.207353) (xy 37.225986 -97.1804) (xy 37.226472 -97.153149) (xy 37.234228 -97.099201)
			(xy 37.249583 -97.046905) (xy 37.272224 -96.997328) (xy 37.301691 -96.951477) (xy 37.337382 -96.910286)
			(xy 37.378572 -96.874594) (xy 37.424423 -96.845127) (xy 37.474 -96.822485) (xy 37.526295 -96.80713)
			(xy 37.580243 -96.799372) (xy 37.607494 -96.798892) (xy 37.609018 -96.798892) (xy 37.63974 -96.799635)
			(xy 37.700358 -96.809721) (xy 37.729668 -96.818958) (xy 37.737796 -96.819974) (xy 37.747448 -96.819974)
			(xy 37.753314 -96.81981) (xy 37.764734 -96.817117) (xy 37.770054 -96.81464) (xy 37.774118 -96.812608)
			(xy 37.778944 -96.810322) (xy 37.7952 -96.797114) (xy 37.799291 -96.793783) (xy 37.806089 -96.785717)
			(xy 37.808662 -96.781112) (xy 37.811347 -96.775451) (xy 37.814173 -96.763247) (xy 37.81425 -96.756982)
			(xy 37.799772 -96.57715) (xy 37.797934 -96.56618) (xy 37.786336 -96.547227) (xy 37.77742 -96.540574)
			(xy 37.775896 -96.539558) (xy 37.768276 -96.534732) (xy 37.757354 -96.529906) (xy 37.75202 -96.528636)
			(xy 37.742622 -96.52762) (xy 37.724334 -96.52762) (xy 37.717222 -96.529652) (xy 37.690427 -96.537241)
			(xy 37.635339 -96.545409) (xy 37.607494 -96.545908) (xy 37.580243 -96.545422) (xy 37.526296 -96.537665)
			(xy 37.474002 -96.522309) (xy 37.424425 -96.499667) (xy 37.378576 -96.470201) (xy 37.337386 -96.434509)
			(xy 37.301695 -96.393319) (xy 37.27223 -96.347469) (xy 37.249589 -96.297892) (xy 37.234234 -96.245598)
			(xy 37.226478 -96.191651) (xy 37.226478 -96.137149) (xy 37.234234 -96.083202) (xy 37.249589 -96.030908)
			(xy 37.27223 -95.981331) (xy 37.301695 -95.935481) (xy 37.337386 -95.894291) (xy 37.378576 -95.858599)
			(xy 37.424425 -95.829133) (xy 37.474002 -95.806491) (xy 37.526296 -95.791135) (xy 37.580243 -95.783378)
			(xy 37.607494 -95.782892) (xy 37.616384 -95.782892) (xy 37.627666 -95.783259) (xy 37.65016 -95.785165)
			(xy 37.661342 -95.786702) (xy 37.662358 -95.786956) (xy 37.664898 -95.78721) (xy 37.669724 -95.787464)
			(xy 37.680392 -95.788226) (xy 37.690298 -95.78467) (xy 37.69488 -95.782924) (xy 37.703318 -95.777931)
			(xy 37.707062 -95.774764) (xy 37.711888 -95.770192) (xy 37.715698 -95.766636) (xy 37.723572 -95.758311)
			(xy 37.731757 -95.736942) (xy 37.731446 -95.725488) (xy 36.329366 -78.260448) (xy 36.149534 -76.021692)
			(xy 35.292538 -65.347088) (xy 35.29203 -65.34023) (xy 35.290252 -65.30721) (xy 35.150044 -61.804042)
			(xy 35.149406 -61.796205) (xy 35.143982 -61.781457) (xy 35.139376 -61.775086) (xy 35.134804 -61.76899)
			(xy 35.121596 -61.7601) (xy 35.117278 -61.75883) (xy 35.090941 -61.750921) (xy 35.040695 -61.728582)
			(xy 34.994176 -61.69926) (xy 34.952349 -61.663563) (xy 34.916081 -61.622231) (xy 34.886122 -61.576119)
			(xy 34.863095 -61.526184) (xy 34.847476 -61.473461) (xy 34.839589 -61.41904) (xy 34.839148 -61.391546)
			(xy 34.839655 -61.363308) (xy 34.847975 -61.307448) (xy 34.86444 -61.253426) (xy 34.888691 -61.202422)
			(xy 34.920197 -61.155551) (xy 34.958269 -61.113837) (xy 34.979864 -61.095636) (xy 34.980372 -61.095128)
			(xy 34.98342 -61.092588) (xy 34.987992 -61.08192) (xy 34.990173 -61.076602) (xy 34.992341 -61.065317)
			(xy 34.99231 -61.059568) (xy 34.991548 -61.036962) (xy 34.989262 -60.977526) (xy 34.988485 -60.970401)
			(xy 34.983463 -60.956983) (xy 34.979356 -60.95111) (xy 34.968942 -60.940696) (xy 34.966148 -60.938664)
			(xy 34.944826 -60.922095) (xy 34.90662 -60.883937) (xy 34.874176 -60.840773) (xy 34.848142 -60.793466)
			(xy 34.829038 -60.742961) (xy 34.817246 -60.690266) (xy 34.813002 -60.636436) (xy 34.81639 -60.582545)
			(xy 34.827343 -60.52967) (xy 34.845642 -60.478867) (xy 34.870921 -60.431152) (xy 34.902675 -60.387478)
			(xy 34.940269 -60.348718) (xy 34.982954 -60.315645) (xy 35.029875 -60.288922) (xy 35.054794 -60.278518)
			(xy 35.06216 -60.275724) (xy 35.074352 -60.265818) (xy 35.07867 -60.259214) (xy 35.082721 -60.252418)
			(xy 35.086855 -60.237154) (xy 35.086798 -60.229242) (xy 35.072066 -59.860942) (xy 35.030664 -58.824368)
			(xy 35.03027 -58.818009) (xy 35.026678 -58.805789) (xy 35.023552 -58.800238) (xy 35.017202 -58.78957)
			(xy 35.011106 -58.786268) (xy 34.986597 -58.77261) (xy 34.941516 -58.739209) (xy 34.901809 -58.699569)
			(xy 34.868333 -58.654544) (xy 34.841808 -58.605103) (xy 34.822807 -58.552312) (xy 34.811738 -58.497308)
			(xy 34.80884 -58.441277) (xy 34.814175 -58.385424) (xy 34.827628 -58.330955) (xy 34.84891 -58.279041)
			(xy 34.877562 -58.230802) (xy 34.912967 -58.187277) (xy 34.933382 -58.168032) (xy 34.944081 -58.158399)
			(xy 34.96671 -58.140598) (xy 34.978594 -58.132472) (xy 34.979102 -58.132218) (xy 34.984381 -58.128479)
			(xy 34.99299 -58.118829) (xy 34.99612 -58.113168) (xy 34.99866 -58.107834) (xy 35.001454 -58.095388)
			(xy 34.99612 -57.960006) (xy 34.898584 -55.523384) (xy 34.898584 -55.522876) (xy 34.897822 -55.505858)
			(xy 34.897822 -55.50535) (xy 34.897568 -55.484014) (xy 34.897568 -55.483506) (xy 34.897568 -55.482744)
			(xy 34.897822 -55.468012) (xy 34.897822 -55.467758) (xy 34.904172 -55.056024) (xy 34.940748 -52.72151)
			(xy 34.940748 -52.71897) (xy 34.916872 -52.033932) (xy 34.842704 -49.91227) (xy 34.841903 -49.901866)
			(xy 34.833056 -49.882992) (xy 34.817418 -49.869209) (xy 34.807652 -49.865534) (xy 34.755582 -49.844706)
			(xy 34.755074 -49.844706) (xy 34.74212 -49.839626) (xy 34.741612 -49.839626) (xy 34.731706 -49.835816)
			(xy 34.722816 -49.835816) (xy 34.718652 -49.836041) (xy 34.710482 -49.837703) (xy 34.70656 -49.839118)
			(xy 34.704528 -49.83988) (xy 34.681922 -49.849532) (xy 34.675064 -49.856136) (xy 34.67481 -49.85639)
			(xy 34.652583 -49.877343) (xy 34.602866 -49.912826) (xy 34.548271 -49.940217) (xy 34.490105 -49.958862)
			(xy 34.42976 -49.968315) (xy 34.39922 -49.968912) (xy 34.398966 -49.968912) (xy 34.371085 -49.968433)
			(xy 34.315878 -49.96058) (xy 34.26233 -49.945022) (xy 34.21151 -49.92207) (xy 34.164434 -49.892182)
			(xy 34.142934 -49.874424) (xy 34.136076 -49.868582) (xy 34.118804 -49.862232) (xy 34.108136 -49.862232)
			(xy 34.102698 -49.862085) (xy 34.09207 -49.859768) (xy 34.087054 -49.85766) (xy 34.073592 -49.851564)
			(xy 34.064931 -49.847947) (xy 34.046214 -49.846722) (xy 34.028322 -49.852353) (xy 34.02076 -49.857914)
			(xy 34.013648 -49.863502) (xy 34.009076 -49.867058) (xy 34.008314 -49.867566) (xy 33.987673 -49.884207)
			(xy 33.94266 -49.912224) (xy 33.894201 -49.933739) (xy 33.843231 -49.948336) (xy 33.790729 -49.955736)
			(xy 33.76422 -49.956212) (xy 33.754314 -49.956212) (xy 33.725593 -49.954972) (xy 33.668992 -49.944919)
			(xy 33.614545 -49.926473) (xy 33.56349 -49.900053) (xy 33.539938 -49.883568) (xy 33.531302 -49.877472)
			(xy 33.526222 -49.873154) (xy 33.518856 -49.868582) (xy 33.516824 -49.867566) (xy 33.511498 -49.865106)
			(xy 33.500082 -49.862418) (xy 33.494218 -49.862232) (xy 33.473136 -49.862232) (xy 33.467698 -49.862085)
			(xy 33.45707 -49.859768) (xy 33.452054 -49.85766) (xy 33.438592 -49.851564) (xy 33.429931 -49.847947)
			(xy 33.411214 -49.846722) (xy 33.393322 -49.852353) (xy 33.38576 -49.857914) (xy 33.378648 -49.863502)
			(xy 33.374076 -49.867058) (xy 33.373314 -49.867566) (xy 33.352673 -49.884207) (xy 33.30766 -49.912224)
			(xy 33.259201 -49.933739) (xy 33.208231 -49.948336) (xy 33.155729 -49.955736) (xy 33.12922 -49.956212)
			(xy 33.119314 -49.956212) (xy 33.090593 -49.954972) (xy 33.033992 -49.944919) (xy 32.979545 -49.926473)
			(xy 32.92849 -49.900053) (xy 32.904938 -49.883568) (xy 32.896302 -49.877472) (xy 32.891222 -49.873154)
			(xy 32.883856 -49.868582) (xy 32.881824 -49.867566) (xy 32.876498 -49.865106) (xy 32.865082 -49.862418)
			(xy 32.859218 -49.862232) (xy 32.838136 -49.862232) (xy 32.832698 -49.862085) (xy 32.82207 -49.859768)
			(xy 32.817054 -49.85766) (xy 32.803592 -49.851564) (xy 32.794931 -49.847947) (xy 32.776214 -49.846722)
			(xy 32.758322 -49.852353) (xy 32.75076 -49.857914) (xy 32.743648 -49.863502) (xy 32.739076 -49.867058)
			(xy 32.738314 -49.867566) (xy 32.717673 -49.884207) (xy 32.67266 -49.912224) (xy 32.624201 -49.933739)
			(xy 32.573231 -49.948336) (xy 32.520729 -49.955736) (xy 32.49422 -49.956212) (xy 32.493966 -49.956212)
			(xy 32.466716 -49.955724) (xy 32.412771 -49.947963) (xy 32.36048 -49.932605) (xy 32.310907 -49.909962)
			(xy 32.26506 -49.880494) (xy 32.223874 -49.844802) (xy 32.188185 -49.803613) (xy 32.158722 -49.757763)
			(xy 32.136083 -49.708188) (xy 32.120729 -49.655895) (xy 32.112974 -49.60195) (xy 32.112974 -49.54745)
			(xy 32.120729 -49.493505) (xy 32.136083 -49.441212) (xy 32.158722 -49.391637) (xy 32.188185 -49.345787)
			(xy 32.223874 -49.304598) (xy 32.26506 -49.268906) (xy 32.310907 -49.239438) (xy 32.36048 -49.216795)
			(xy 32.412771 -49.201437) (xy 32.466716 -49.193676) (xy 32.493966 -49.193196) (xy 32.49422 -49.193196)
			(xy 32.519837 -49.193607) (xy 32.57061 -49.200462) (xy 32.620006 -49.214059) (xy 32.667135 -49.234154)
			(xy 32.711146 -49.260383) (xy 32.731456 -49.276) (xy 32.736282 -49.27981) (xy 32.743648 -49.283112)
			(xy 32.748387 -49.284986) (xy 32.758366 -49.287042) (xy 32.76346 -49.287176) (xy 32.784796 -49.287176)
			(xy 32.790236 -49.287315) (xy 32.800872 -49.289615) (xy 32.805878 -49.291748) (xy 32.81934 -49.297844)
			(xy 32.828001 -49.301454) (xy 32.846712 -49.302669) (xy 32.864595 -49.297031) (xy 32.872172 -49.291494)
			(xy 32.879284 -49.285906) (xy 32.883856 -49.28235) (xy 32.884618 -49.281842) (xy 32.90526 -49.265203)
			(xy 32.950273 -49.237189) (xy 32.998732 -49.215677) (xy 33.049703 -49.201084) (xy 33.102203 -49.193689)
			(xy 33.128712 -49.193196) (xy 33.138618 -49.193196) (xy 33.169405 -49.194569) (xy 33.229956 -49.206009)
			(xy 33.287885 -49.227026) (xy 33.341687 -49.257072) (xy 33.366202 -49.275746) (xy 33.371282 -49.27981)
			(xy 33.379156 -49.283366) (xy 33.383783 -49.285143) (xy 33.393505 -49.287071) (xy 33.39846 -49.287176)
			(xy 33.419796 -49.287176) (xy 33.425236 -49.287315) (xy 33.435872 -49.289615) (xy 33.440878 -49.291748)
			(xy 33.45434 -49.297844) (xy 33.463001 -49.301454) (xy 33.481712 -49.302669) (xy 33.499595 -49.297031)
			(xy 33.507172 -49.291494) (xy 33.514284 -49.285906) (xy 33.518856 -49.28235) (xy 33.519618 -49.281842)
			(xy 33.54026 -49.265203) (xy 33.585273 -49.237189) (xy 33.633732 -49.215677) (xy 33.684703 -49.201084)
			(xy 33.737203 -49.193689) (xy 33.763712 -49.193196) (xy 33.773618 -49.193196) (xy 33.804405 -49.194569)
			(xy 33.864956 -49.206009) (xy 33.922885 -49.227026) (xy 33.976687 -49.257072) (xy 34.001202 -49.275746)
			(xy 34.006282 -49.27981) (xy 34.014156 -49.283366) (xy 34.018783 -49.285143) (xy 34.028505 -49.287071)
			(xy 34.03346 -49.287176) (xy 34.108898 -49.287176) (xy 34.113978 -49.286922) (xy 34.124646 -49.284636)
			(xy 34.136584 -49.280572) (xy 34.144204 -49.274222) (xy 34.144458 -49.273968) (xy 34.165892 -49.256433)
			(xy 34.212743 -49.226908) (xy 34.263261 -49.204223) (xy 34.316454 -49.188821) (xy 34.371278 -49.181006)
			(xy 34.398966 -49.180496) (xy 34.427724 -49.181042) (xy 34.484625 -49.189438) (xy 34.539705 -49.206001)
			(xy 34.591801 -49.230378) (xy 34.639808 -49.262055) (xy 34.661602 -49.280826) (xy 34.662872 -49.281842)
			(xy 34.668464 -49.286313) (xy 34.681482 -49.292255) (xy 34.688526 -49.293526) (xy 34.695638 -49.294542)
			(xy 34.703004 -49.293272) (xy 34.714688 -49.28997) (xy 34.753042 -49.271936) (xy 34.75355 -49.271936)
			(xy 34.792666 -49.252886) (xy 34.79812 -49.249514) (xy 34.80724 -49.240506) (xy 34.8107 -49.235106)
			(xy 34.812224 -49.232566) (xy 34.815028 -49.226997) (xy 34.818119 -49.214921) (xy 34.81832 -49.20869)
			(xy 34.818066 -49.201324) (xy 34.817812 -49.19345) (xy 34.814764 -49.10836) (xy 34.775394 -47.980346)
			(xy 34.775394 -47.978822) (xy 33.686496 -39.919656) (xy 33.682734 -39.890264) (xy 33.678286 -39.83117)
			(xy 33.677606 -39.801546) (xy 33.666938 -39.111936) (xy 33.664398 -39.101014) (xy 33.661858 -39.095934)
			(xy 33.661604 -39.09568) (xy 33.661604 -39.095426) (xy 33.646361 -39.063949) (xy 33.619795 -38.999246)
			(xy 33.608518 -38.96614) (xy 33.593253 -38.917886) (xy 33.571392 -38.819063) (xy 33.559638 -38.718535)
			(xy 33.558226 -38.667944) (xy 33.557972 -38.653212) (xy 33.55213 -38.278308) (xy 33.550606 -38.172644)
			(xy 33.550606 -38.17239) (xy 33.550352 -38.157658) (xy 33.550352 -38.15715) (xy 33.550352 -38.156134)
			(xy 33.550579 -38.125129) (xy 33.554395 -38.063235) (xy 33.557972 -38.032436) (xy 33.55848 -38.029388)
			(xy 33.55848 -38.015672) (xy 33.55848 -38.013132) (xy 33.55848 -37.991542) (xy 33.55848 -37.99078)
			(xy 33.56483 -37.682424) (xy 33.56356 -37.676328) (xy 33.55308 -37.62648) (xy 33.541121 -37.525316)
			(xy 33.539684 -37.474398) (xy 33.532064 -36.978082) (xy 33.52927 -36.9697) (xy 33.525206 -36.958778)
			(xy 33.522666 -36.95192) (xy 33.519872 -36.944554) (xy 33.519872 -36.944046) (xy 33.51657 -36.935664)
			(xy 33.51276 -36.92525) (xy 33.51022 -36.919408) (xy 33.506683 -36.913014) (xy 33.496616 -36.902433)
			(xy 33.490408 -36.89858) (xy 33.46734 -36.903892) (xy 33.42035 -36.909617) (xy 33.396682 -36.91001)
			(xy 33.396174 -36.91001) (xy 33.367995 -36.909506) (xy 33.312212 -36.901482) (xy 33.258138 -36.885601)
			(xy 33.206874 -36.862187) (xy 33.159465 -36.831716) (xy 33.116874 -36.794808) (xy 33.079969 -36.752215)
			(xy 33.049501 -36.704803) (xy 33.02609 -36.653538) (xy 33.010213 -36.599463) (xy 33.002192 -36.543679)
			(xy 33.002192 -36.487321) (xy 33.010213 -36.431537) (xy 33.02609 -36.377462) (xy 33.049501 -36.326197)
			(xy 33.079969 -36.278785) (xy 33.116874 -36.236192) (xy 33.159465 -36.199284) (xy 33.206874 -36.168813)
			(xy 33.258138 -36.145399) (xy 33.312212 -36.129518) (xy 33.367995 -36.121494) (xy 33.396174 -36.121086)
			(xy 33.431988 -36.122864) (xy 33.434782 -36.120578) (xy 33.449514 -36.107878) (xy 33.457134 -36.101274)
			(xy 33.467802 -36.080192) (xy 33.469834 -36.076128) (xy 33.475168 -36.058856) (xy 33.475676 -36.05403)
			(xy 33.478216 -36.032948) (xy 33.478216 -36.03244) (xy 33.480756 -36.015676) (xy 33.481518 -36.010342)
			(xy 33.488206 -35.970918) (xy 33.50715 -35.893224) (xy 33.519364 -35.855148) (xy 33.533051 -35.815025)
			(xy 33.566373 -35.737068) (xy 33.585912 -35.699446) (xy 33.59023 -35.691318) (xy 33.5915 -35.68192)
			(xy 33.591955 -35.677661) (xy 33.591573 -35.669103) (xy 33.590738 -35.664902) (xy 33.588198 -35.654742)
			(xy 33.585658 -35.644836) (xy 33.578038 -35.61715) (xy 33.578038 -35.616642) (xy 33.560004 -35.551364)
			(xy 33.557193 -35.544491) (xy 33.548293 -35.532612) (xy 33.542478 -35.527996) (xy 33.49244 -35.498024)
			(xy 33.491932 -35.498024) (xy 33.480248 -35.491166) (xy 33.472628 -35.487356) (xy 33.47212 -35.487356)
			(xy 33.468818 -35.486086) (xy 33.450784 -35.490404) (xy 33.444688 -35.491928) (xy 33.423706 -35.496853)
			(xy 33.3814 -35.50511) (xy 33.360106 -35.508438) (xy 33.359598 -35.508438) (xy 33.325562 -35.513264)
			(xy 33.325054 -35.513264) (xy 33.297844 -35.51623) (xy 33.243203 -35.519534) (xy 33.215834 -35.519868)
			(xy 33.203134 -35.519868) (xy 33.156738 -35.518989) (xy 33.064404 -35.50967) (xy 32.973337 -35.491809)
			(xy 32.884324 -35.465559) (xy 32.798137 -35.431148) (xy 32.715521 -35.388875) (xy 32.676084 -35.36442)
			(xy 32.674052 -35.364928) (xy 32.669988 -35.36569) (xy 32.65299 -35.368566) (xy 32.618647 -35.371622)
			(xy 32.601408 -35.371786) (xy 32.6009 -35.371786) (xy 32.57382 -35.371313) (xy 32.520203 -35.363654)
			(xy 32.468208 -35.348492) (xy 32.41888 -35.32613) (xy 32.373209 -35.297017) (xy 32.332113 -35.26174)
			(xy 32.296419 -35.221006) (xy 32.266842 -35.175634) (xy 32.243979 -35.126536) (xy 32.228287 -35.074698)
			(xy 32.220083 -35.021163) (xy 32.219392 -34.994088) (xy 32.219392 -34.990024) (xy 32.219901 -34.96277)
			(xy 32.22769 -34.90882) (xy 32.243057 -34.856522) (xy 32.253936 -34.831528) (xy 32.256222 -34.826448)
			(xy 32.258 -34.81832) (xy 32.243788 -34.770385) (xy 32.223893 -34.672397) (xy 32.213895 -34.572912)
			(xy 32.213296 -34.522918) (xy 32.213296 -34.52241) (xy 32.21373 -34.479823) (xy 32.220969 -34.394958)
			(xy 32.235421 -34.31102) (xy 32.256981 -34.228621) (xy 32.285491 -34.148361) (xy 32.302704 -34.109406)
			(xy 32.30589 -34.100273) (xy 32.305893 -34.080946) (xy 32.302704 -34.071814) (xy 32.285494 -34.032858)
			(xy 32.256997 -33.952595) (xy 32.235444 -33.870195) (xy 32.220989 -33.786259) (xy 32.21374 -33.701396)
			(xy 32.213296 -33.65881) (xy 32.213296 -33.657794) (xy 32.213924 -33.607927) (xy 32.223931 -33.508696)
			(xy 32.243803 -33.410961) (xy 32.258 -33.363154) (xy 32.256984 -33.358582) (xy 32.253428 -33.348168)
			(xy 32.252412 -33.345882) (xy 32.242206 -33.321858) (xy 32.227668 -33.271726) (xy 32.220083 -33.220083)
			(xy 32.219392 -33.19399) (xy 32.219392 -33.188656) (xy 32.219983 -33.161477) (xy 32.227917 -33.107696)
			(xy 32.243406 -33.055587) (xy 32.266134 -33.006203) (xy 32.295643 -32.960546) (xy 32.331333 -32.91954)
			(xy 32.372483 -32.884016) (xy 32.418259 -32.854692) (xy 32.467734 -32.832164) (xy 32.519906 -32.816886)
			(xy 32.573719 -32.80917) (xy 32.6009 -32.808672) (xy 32.605472 -32.808672) (xy 32.621565 -32.80901)
			(xy 32.653612 -32.812061) (xy 32.66948 -32.814768) (xy 32.676846 -32.816038) (xy 32.716187 -32.791746)
			(xy 32.798553 -32.749724) (xy 32.884455 -32.715508) (xy 32.973157 -32.689391) (xy 33.063895 -32.671598)
			(xy 33.155891 -32.662283) (xy 33.202118 -32.661352) (xy 33.21431 -32.661352) (xy 33.260928 -32.662081)
			(xy 33.353725 -32.671158) (xy 33.44527 -32.688859) (xy 33.534763 -32.715029) (xy 33.621422 -32.749438)
			(xy 33.70449 -32.791787) (xy 33.744154 -32.816292) (xy 33.74517 -32.816038) (xy 33.750504 -32.815022)
			(xy 33.753298 -32.814514) (xy 33.765998 -32.812482) (xy 33.766506 -32.812482) (xy 33.780648 -32.81053)
			(xy 33.809126 -32.808498) (xy 33.823402 -32.808418) (xy 33.82518 -32.808418) (xy 33.842198 -32.808926)
			(xy 33.8657 -32.810596) (xy 33.91206 -32.819008) (xy 33.934654 -32.82569) (xy 33.936686 -32.826198)
			(xy 33.939226 -32.827214) (xy 33.943036 -32.828484) (xy 33.951164 -32.829754) (xy 33.960996 -32.830841)
			(xy 33.980222 -32.826275) (xy 33.988502 -32.820864) (xy 34.034476 -32.788098) (xy 34.059114 -32.770572)
			(xy 34.062162 -32.76727) (xy 34.068004 -32.759904) (xy 34.067496 -32.741108) (xy 34.067496 -32.722312)
			(xy 34.06793 -32.679725) (xy 34.075169 -32.59486) (xy 34.089621 -32.510922) (xy 34.11118 -32.428523)
			(xy 34.13969 -32.348263) (xy 34.156904 -32.309308) (xy 34.16009 -32.300175) (xy 34.160094 -32.280847)
			(xy 34.156904 -32.271716) (xy 34.139694 -32.23276) (xy 34.111197 -32.152497) (xy 34.089643 -32.070097)
			(xy 34.075189 -31.986161) (xy 34.067939 -31.901298) (xy 34.067496 -31.858712) (xy 34.067496 -31.858458)
			(xy 34.067593 -31.839898) (xy 34.068992 -31.802805) (xy 34.07029 -31.78429) (xy 34.07029 -31.783782)
			(xy 34.07156 -31.764986) (xy 34.071306 -31.764478) (xy 34.070798 -31.76397) (xy 34.069782 -31.762446)
			(xy 34.059368 -31.74873) (xy 34.055304 -31.74365) (xy 34.050636 -31.73855) (xy 34.039178 -31.730821)
			(xy 34.032698 -31.72841) (xy 34.026094 -31.726124) (xy 34.011616 -31.72587) (xy 33.99282 -31.730696)
			(xy 33.98774 -31.733236) (xy 33.97377 -31.73984) (xy 33.966658 -31.742634) (xy 33.96615 -31.742888)
			(xy 33.956752 -31.746698) (xy 33.320228 -31.99638) (xy 33.309859 -31.999874) (xy 33.288031 -31.99868)
			(xy 33.268655 -31.98856) (xy 33.255204 -31.971328) (xy 33.252156 -31.96082) (xy 33.248346 -31.945072)
			(xy 33.242758 -31.932118) (xy 33.23844 -31.92526) (xy 33.23463 -31.922212) (xy 33.231836 -31.919926)
			(xy 33.202626 -31.919672) (xy 33.156281 -31.918774) (xy 33.06405 -31.909439) (xy 32.973083 -31.891591)
			(xy 32.884163 -31.865382) (xy 32.798057 -31.83104) (xy 32.715508 -31.788859) (xy 32.676084 -31.764478)
			(xy 32.666178 -31.766256) (xy 32.645604 -31.769304) (xy 32.640778 -31.769812) (xy 32.640524 -31.769812)
			(xy 32.637984 -31.770066) (xy 32.616394 -31.77159) (xy 32.60598 -31.771844) (xy 32.602932 -31.771844)
			(xy 32.6009 -31.771844) (xy 32.573752 -31.771366) (xy 32.520003 -31.763668) (xy 32.467889 -31.748429)
			(xy 32.418461 -31.725955) (xy 32.372719 -31.696701) (xy 32.331586 -31.661258) (xy 32.295893 -31.620341)
			(xy 32.266362 -31.574778) (xy 32.243588 -31.525488) (xy 32.228031 -31.473468) (xy 32.220007 -31.419767)
			(xy 32.219392 -31.392622) (xy 32.219392 -31.389828) (xy 32.219884 -31.361597) (xy 32.22817 -31.305747)
			(xy 32.244595 -31.251728) (xy 32.256222 -31.225998) (xy 32.258 -31.218632) (xy 32.243963 -31.171265)
			(xy 32.224201 -31.074463) (xy 32.214088 -30.976183) (xy 32.213296 -30.926786) (xy 32.213296 -30.922468)
			(xy 32.213732 -30.879882) (xy 32.220975 -30.795018) (xy 32.23543 -30.711081) (xy 32.256992 -30.628684)
			(xy 32.285505 -30.548426) (xy 32.302704 -30.509464) (xy 32.305882 -30.500331) (xy 32.305871 -30.48101)
			(xy 32.302704 -30.471872) (xy 32.285492 -30.432916) (xy 32.25699 -30.352654) (xy 32.235432 -30.270254)
			(xy 32.220973 -30.186318) (xy 32.213718 -30.101454) (xy 32.213296 -30.058868) (xy 32.213296 -30.05836)
			(xy 32.21394 -30.008319) (xy 32.224015 -29.908744) (xy 32.243998 -29.810676) (xy 32.258254 -29.762704)
			(xy 32.256476 -29.755084) (xy 32.25419 -29.750258) (xy 32.243183 -29.725168) (xy 32.227673 -29.672621)
			(xy 32.219852 -29.618394) (xy 32.219392 -29.591) (xy 32.219392 -29.590238) (xy 32.219853 -29.562983)
			(xy 32.227605 -29.509028) (xy 32.242958 -29.456726) (xy 32.265598 -29.407141) (xy 32.295065 -29.361283)
			(xy 32.330759 -29.320086) (xy 32.371953 -29.284388) (xy 32.417808 -29.254917) (xy 32.46739 -29.232271)
			(xy 32.519691 -29.216913) (xy 32.573645 -29.209155) (xy 32.6009 -29.20873) (xy 32.601916 -29.20873)
			(xy 32.618382 -29.208879) (xy 32.651195 -29.211674) (xy 32.667448 -29.214318) (xy 32.6771 -29.216096)
			(xy 32.717027 -29.191466) (xy 32.800665 -29.14896) (xy 32.887922 -29.114488) (xy 32.978028 -29.088355)
			(xy 33.070189 -29.070791) (xy 33.163591 -29.061951) (xy 33.2105 -29.06141) (xy 33.257411 -29.061944)
			(xy 33.350819 -29.070753) (xy 33.442986 -29.088302) (xy 33.533096 -29.114435) (xy 33.62035 -29.148922)
			(xy 33.703977 -29.191457) (xy 33.7439 -29.216096) (xy 33.75025 -29.214826) (xy 33.76756 -29.211882)
			(xy 33.802542 -29.208828) (xy 33.8201 -29.20873) (xy 33.824164 -29.20873) (xy 33.85337 -29.209558)
			(xy 33.911028 -29.218993) (xy 33.938972 -29.227526) (xy 33.93948 -29.22778) (xy 33.942782 -29.228796)
			(xy 33.948624 -29.230066) (xy 33.959463 -29.231676) (xy 33.980775 -29.226671) (xy 33.989772 -29.220414)
			(xy 33.990026 -29.22016) (xy 33.991042 -29.219652) (xy 34.057082 -29.1719) (xy 34.060226 -29.169321)
			(xy 34.065712 -29.163321) (xy 34.068004 -29.159962) (xy 34.067496 -29.14142) (xy 34.067496 -29.12237)
			(xy 34.067932 -29.079784) (xy 34.075174 -28.99492) (xy 34.089629 -28.910983) (xy 34.111192 -28.828585)
			(xy 34.139704 -28.748327) (xy 34.156904 -28.709366) (xy 34.160082 -28.700233) (xy 34.160072 -28.680912)
			(xy 34.156904 -28.671774) (xy 34.139692 -28.632818) (xy 34.11119 -28.552556) (xy 34.089631 -28.470156)
			(xy 34.075172 -28.38622) (xy 34.067917 -28.301356) (xy 34.067496 -28.25877) (xy 34.067984 -28.211623)
			(xy 34.076758 -28.117738) (xy 34.085022 -28.071318) (xy 34.088669 -28.052831) (xy 34.09718 -28.016118)
			(xy 34.10204 -27.997912) (xy 34.1122 -27.96286) (xy 34.1122 -27.962606) (xy 34.110422 -27.954224)
			(xy 34.108136 -27.949144) (xy 34.107882 -27.948636) (xy 34.097338 -27.924428) (xy 34.082279 -27.873819)
			(xy 34.07436 -27.821614) (xy 34.073592 -27.79522) (xy 34.073592 -27.789886) (xy 34.074092 -27.762645)
			(xy 34.081874 -27.70872) (xy 34.097247 -27.656451) (xy 34.119901 -27.606901) (xy 34.149373 -27.561077)
			(xy 34.185064 -27.519913) (xy 34.226249 -27.484244) (xy 34.272089 -27.454798) (xy 34.321652 -27.432172)
			(xy 34.37393 -27.416828) (xy 34.427858 -27.409077) (xy 34.4551 -27.408632) (xy 34.472657 -27.408751)
			(xy 34.507638 -27.411803) (xy 34.52495 -27.414728) (xy 34.526982 -27.415236) (xy 34.529522 -27.415744)
			(xy 34.530284 -27.415744) (xy 34.531554 -27.415998) (xy 34.57448 -27.39009) (xy 34.575496 -27.389582)
			(xy 34.578798 -27.387804) (xy 34.596324 -27.378152) (xy 34.599372 -27.370786) (xy 34.619692 -27.295348)
			(xy 34.619438 -27.281632) (xy 34.61766 -27.275028) (xy 34.613342 -27.259534) (xy 34.610294 -27.2542)
			(xy 34.598598 -27.232664) (xy 34.580179 -27.18725) (xy 34.567718 -27.139853) (xy 34.56142 -27.091252)
			(xy 34.561018 -27.066748) (xy 34.561018 -27.057604) (xy 34.561272 -27.05354) (xy 34.561272 -27.052778)
			(xy 34.563558 -27.022552) (xy 34.566662 -26.998918) (xy 34.57801 -26.95262) (xy 34.595055 -26.908104)
			(xy 34.605976 -26.886916) (xy 34.618805 -26.863799) (xy 34.649875 -26.821021) (xy 34.686554 -26.782945)
			(xy 34.707068 -26.766266) (xy 34.7091 -26.764742) (xy 34.716212 -26.757884) (xy 34.729166 -26.742136)
			(xy 34.731706 -26.736802) (xy 34.734246 -26.725118) (xy 34.730182 -26.647394) (xy 34.729674 -26.634948)
			(xy 34.714688 -26.609294) (xy 34.706814 -26.59888) (xy 34.699448 -26.591514) (xy 34.69132 -26.584656)
			(xy 34.689034 -26.583132) (xy 34.667137 -26.567858) (xy 34.62743 -26.532169) (xy 34.593083 -26.491296)
			(xy 34.564765 -26.446036) (xy 34.543029 -26.397272) (xy 34.528299 -26.345956) (xy 34.520861 -26.293088)
			(xy 34.520378 -26.266394) (xy 34.520864 -26.239125) (xy 34.528626 -26.185141) (xy 34.543991 -26.132811)
			(xy 34.566648 -26.083201) (xy 34.596134 -26.03732) (xy 34.631849 -25.996103) (xy 34.673066 -25.960388)
			(xy 34.718947 -25.930902) (xy 34.768557 -25.908245) (xy 34.820887 -25.89288) (xy 34.874871 -25.885118)
			(xy 34.929409 -25.885118) (xy 34.983393 -25.89288) (xy 35.035723 -25.908245) (xy 35.085333 -25.930902)
			(xy 35.131214 -25.960388) (xy 35.172431 -25.996103) (xy 35.208146 -26.03732) (xy 35.237632 -26.083201)
			(xy 35.260289 -26.132811) (xy 35.275654 -26.185141) (xy 35.283416 -26.239125) (xy 35.283902 -26.266394)
			(xy 35.283364 -26.295751) (xy 35.274377 -26.353772) (xy 35.256613 -26.409734) (xy 35.230491 -26.462317)
			(xy 35.196627 -26.51028) (xy 35.15582 -26.552495) (xy 35.132772 -26.570686) (xy 35.12947 -26.573226)
			(xy 35.12566 -26.577036) (xy 35.119564 -26.58491) (xy 35.115838 -26.591022) (xy 35.111598 -26.604687)
			(xy 35.111182 -26.611834) (xy 35.114992 -26.69667) (xy 35.119818 -26.706068) (xy 35.120834 -26.708354)
			(xy 35.129724 -26.72334) (xy 35.13328 -26.729182) (xy 35.149028 -26.745438) (xy 35.155378 -26.749756)
			(xy 35.177238 -26.764968) (xy 35.216889 -26.800521) (xy 35.251204 -26.841247) (xy 35.279517 -26.886354)
			(xy 35.301274 -26.934963) (xy 35.316054 -26.986127) (xy 35.323567 -27.038851) (xy 35.324034 -27.065478)
			(xy 35.324034 -27.07005) (xy 35.32319 -27.100326) (xy 35.313107 -27.160046) (xy 35.303968 -27.188922)
			(xy 35.300666 -27.198828) (xy 35.301174 -27.20848) (xy 35.301625 -27.21357) (xy 35.304305 -27.223428)
			(xy 35.306508 -27.228038) (xy 35.319716 -27.254454) (xy 35.334448 -27.283664) (xy 35.334956 -27.284426)
			(xy 35.335718 -27.28595) (xy 35.339782 -27.292046) (xy 35.34664 -27.299158) (xy 35.35172 -27.303476)
			(xy 35.363658 -27.307286) (xy 35.403456 -27.32023) (xy 35.458771 -27.342846) (xy 42.523664 -27.342846)
			(xy 42.523664 -26.479246) (xy 42.524154 -26.449278) (xy 42.531977 -26.389856) (xy 42.54749 -26.331963)
			(xy 42.570426 -26.27659) (xy 42.600393 -26.224684) (xy 42.63688 -26.177134) (xy 42.67926 -26.134754)
			(xy 42.72681 -26.098267) (xy 42.778716 -26.0683) (xy 42.834089 -26.045364) (xy 42.891982 -26.029851)
			(xy 42.951404 -26.022028) (xy 43.01134 -26.022028) (xy 43.070762 -26.029851) (xy 43.128655 -26.045364)
			(xy 43.184028 -26.0683) (xy 43.235934 -26.098267) (xy 43.283484 -26.134754) (xy 43.325864 -26.177134)
			(xy 43.362351 -26.224684) (xy 43.392318 -26.27659) (xy 43.415254 -26.331963) (xy 43.423003 -26.360882)
			(xy 45.08957 -26.360882) (xy 45.093641 -26.30526) (xy 45.105767 -26.250823) (xy 45.12569 -26.198732)
			(xy 45.152986 -26.150097) (xy 45.187072 -26.105954) (xy 45.227221 -26.067245) (xy 45.272579 -26.034794)
			(xy 45.322179 -26.009293) (xy 45.374963 -25.991286) (xy 45.429806 -25.981156) (xy 45.48554 -25.979119)
			(xy 45.540977 -25.985219) (xy 45.594934 -25.999325) (xy 45.646263 -26.021137) (xy 45.693869 -26.050191)
			(xy 45.736737 -26.085866) (xy 45.773954 -26.127403) (xy 45.804727 -26.173916) (xy 45.828399 -26.224413)
			(xy 45.844467 -26.27782) (xy 45.850635 -26.319734) (xy 50.841908 -26.319734) (xy 50.845979 -26.264112)
			(xy 50.858105 -26.209675) (xy 50.878028 -26.157584) (xy 50.905324 -26.108949) (xy 50.93941 -26.064806)
			(xy 50.979559 -26.026097) (xy 51.024917 -25.993646) (xy 51.074517 -25.968145) (xy 51.127301 -25.950138)
			(xy 51.182144 -25.940008) (xy 51.237878 -25.937971) (xy 51.293315 -25.944071) (xy 51.347272 -25.958177)
			(xy 51.398601 -25.979989) (xy 51.446207 -26.009043) (xy 51.475872 -26.03373) (xy 57.267854 -26.03373)
			(xy 57.271925 -25.978108) (xy 57.284051 -25.923671) (xy 57.303974 -25.87158) (xy 57.33127 -25.822945)
			(xy 57.365356 -25.778802) (xy 57.405505 -25.740093) (xy 57.450863 -25.707642) (xy 57.500463 -25.682141)
			(xy 57.553247 -25.664134) (xy 57.60809 -25.654004) (xy 57.663824 -25.651967) (xy 57.719261 -25.658067)
			(xy 57.773218 -25.672173) (xy 57.824547 -25.693985) (xy 57.872153 -25.723039) (xy 57.915021 -25.758714)
			(xy 57.952238 -25.800251) (xy 57.983011 -25.846764) (xy 58.006683 -25.897261) (xy 58.022751 -25.950668)
			(xy 58.030871 -26.005844) (xy 58.03138 -26.03373) (xy 58.030871 -26.061616) (xy 58.022751 -26.116792)
			(xy 58.006683 -26.170199) (xy 57.983011 -26.220696) (xy 57.952238 -26.267209) (xy 57.915021 -26.308746)
			(xy 57.872153 -26.344421) (xy 57.824547 -26.373475) (xy 57.773218 -26.395287) (xy 57.719261 -26.409393)
			(xy 57.663824 -26.415493) (xy 57.60809 -26.413456) (xy 57.553247 -26.403326) (xy 57.500463 -26.385319)
			(xy 57.450863 -26.359818) (xy 57.405505 -26.327367) (xy 57.365356 -26.288658) (xy 57.33127 -26.244515)
			(xy 57.303974 -26.19588) (xy 57.284051 -26.143789) (xy 57.271925 -26.089352) (xy 57.267854 -26.03373)
			(xy 51.475872 -26.03373) (xy 51.489075 -26.044718) (xy 51.526292 -26.086255) (xy 51.557065 -26.132768)
			(xy 51.580737 -26.183265) (xy 51.596805 -26.236672) (xy 51.604925 -26.291848) (xy 51.605434 -26.319734)
			(xy 51.604925 -26.34762) (xy 51.596805 -26.402796) (xy 51.580737 -26.456203) (xy 51.557065 -26.5067)
			(xy 51.526292 -26.553213) (xy 51.489075 -26.59475) (xy 51.446207 -26.630425) (xy 51.398601 -26.659479)
			(xy 51.347272 -26.681291) (xy 51.293315 -26.695397) (xy 51.237878 -26.701497) (xy 51.182144 -26.69946)
			(xy 51.127301 -26.68933) (xy 51.074517 -26.671323) (xy 51.024917 -26.645822) (xy 50.979559 -26.613371)
			(xy 50.93941 -26.574662) (xy 50.905324 -26.530519) (xy 50.878028 -26.481884) (xy 50.858105 -26.429793)
			(xy 50.845979 -26.375356) (xy 50.841908 -26.319734) (xy 45.850635 -26.319734) (xy 45.852587 -26.332996)
			(xy 45.853096 -26.360882) (xy 45.852587 -26.388768) (xy 45.844467 -26.443944) (xy 45.828399 -26.497351)
			(xy 45.804727 -26.547848) (xy 45.773954 -26.594361) (xy 45.736737 -26.635898) (xy 45.693869 -26.671573)
			(xy 45.646263 -26.700627) (xy 45.594934 -26.722439) (xy 45.540977 -26.736545) (xy 45.48554 -26.742645)
			(xy 45.429806 -26.740608) (xy 45.374963 -26.730478) (xy 45.322179 -26.712471) (xy 45.272579 -26.68697)
			(xy 45.227221 -26.654519) (xy 45.187072 -26.61581) (xy 45.152986 -26.571667) (xy 45.12569 -26.523032)
			(xy 45.105767 -26.470941) (xy 45.093641 -26.416504) (xy 45.08957 -26.360882) (xy 43.423003 -26.360882)
			(xy 43.430767 -26.389856) (xy 43.43859 -26.449278) (xy 43.43908 -26.479246) (xy 43.43908 -26.971244)
			(xy 46.85106 -26.971244) (xy 46.855131 -26.915622) (xy 46.867257 -26.861185) (xy 46.88718 -26.809094)
			(xy 46.914476 -26.760459) (xy 46.948562 -26.716316) (xy 46.988711 -26.677607) (xy 47.034069 -26.645156)
			(xy 47.083669 -26.619655) (xy 47.136453 -26.601648) (xy 47.191296 -26.591518) (xy 47.24703 -26.589481)
			(xy 47.302467 -26.595581) (xy 47.356424 -26.609687) (xy 47.407753 -26.631499) (xy 47.455359 -26.660553)
			(xy 47.498227 -26.696228) (xy 47.535444 -26.737765) (xy 47.566217 -26.784278) (xy 47.589889 -26.834775)
			(xy 47.605957 -26.888182) (xy 47.614077 -26.943358) (xy 47.614586 -26.971244) (xy 47.614077 -26.99913)
			(xy 47.605957 -27.054306) (xy 47.589889 -27.107713) (xy 47.566217 -27.15821) (xy 47.535444 -27.204723)
			(xy 47.498227 -27.24626) (xy 47.455359 -27.281935) (xy 47.407753 -27.310989) (xy 47.356424 -27.332801)
			(xy 47.302467 -27.346907) (xy 47.24703 -27.353007) (xy 47.191296 -27.35097) (xy 47.136453 -27.34084)
			(xy 47.083669 -27.322833) (xy 47.034069 -27.297332) (xy 46.988711 -27.264881) (xy 46.948562 -27.226172)
			(xy 46.914476 -27.182029) (xy 46.88718 -27.133394) (xy 46.867257 -27.081303) (xy 46.855131 -27.026866)
			(xy 46.85106 -26.971244) (xy 43.43908 -26.971244) (xy 43.43908 -27.342846) (xy 43.43859 -27.372814)
			(xy 43.430767 -27.432236) (xy 43.415254 -27.490129) (xy 43.392318 -27.545502) (xy 43.362351 -27.597408)
			(xy 43.325864 -27.644958) (xy 43.283484 -27.687338) (xy 43.235934 -27.723825) (xy 43.184028 -27.753792)
			(xy 43.128655 -27.776728) (xy 43.070762 -27.792241) (xy 43.01134 -27.800064) (xy 42.951404 -27.800064)
			(xy 42.891982 -27.792241) (xy 42.834089 -27.776728) (xy 42.778716 -27.753792) (xy 42.72681 -27.723825)
			(xy 42.67926 -27.687338) (xy 42.63688 -27.644958) (xy 42.600393 -27.597408) (xy 42.570426 -27.545502)
			(xy 42.54749 -27.490129) (xy 42.531977 -27.432236) (xy 42.524154 -27.372814) (xy 42.523664 -27.342846)
			(xy 35.458771 -27.342846) (xy 35.480926 -27.351904) (xy 35.555468 -27.389962) (xy 35.591242 -27.41168)
			(xy 35.599878 -27.41168) (xy 35.612078 -27.410169) (xy 35.636608 -27.40852) (xy 35.6489 -27.408378)
			(xy 35.668204 -27.408886) (xy 35.677856 -27.409648) (xy 35.704864 -27.412181) (xy 35.757825 -27.423913)
			(xy 35.808592 -27.443027) (xy 35.85614 -27.469136) (xy 35.899513 -27.501715) (xy 35.937835 -27.540106)
			(xy 35.954462 -27.56154) (xy 35.956494 -27.56408) (xy 36.00089 -27.571474) (xy 36.088231 -27.593234)
			(xy 36.173255 -27.622774) (xy 36.255273 -27.659854) (xy 36.333617 -27.704171) (xy 36.40765 -27.755367)
			(xy 36.47677 -27.813023) (xy 36.508944 -27.844496) (xy 37.77892 -29.114242) (xy 44.847256 -29.114242)
			(xy 44.847256 -28.250642) (xy 44.847746 -28.220658) (xy 44.855574 -28.161202) (xy 44.871095 -28.103277)
			(xy 44.894044 -28.047873) (xy 44.924028 -27.995939) (xy 44.960534 -27.948363) (xy 45.002939 -27.905958)
			(xy 45.050515 -27.869452) (xy 45.102449 -27.839468) (xy 45.157853 -27.816519) (xy 45.215778 -27.800998)
			(xy 45.275234 -27.79317) (xy 45.335202 -27.79317) (xy 45.394658 -27.800998) (xy 45.452583 -27.816519)
			(xy 45.507987 -27.839468) (xy 45.559921 -27.869452) (xy 45.607497 -27.905958) (xy 45.649902 -27.948363)
			(xy 45.686408 -27.995939) (xy 45.716392 -28.047873) (xy 45.739341 -28.103277) (xy 45.754862 -28.161202)
			(xy 45.76269 -28.220658) (xy 45.76318 -28.250642) (xy 45.76318 -28.469082) (xy 49.752502 -28.469082)
			(xy 49.756573 -28.41346) (xy 49.768699 -28.359023) (xy 49.788622 -28.306932) (xy 49.815918 -28.258297)
			(xy 49.850004 -28.214154) (xy 49.890153 -28.175445) (xy 49.935511 -28.142994) (xy 49.985111 -28.117493)
			(xy 50.037895 -28.099486) (xy 50.092738 -28.089356) (xy 50.148472 -28.087319) (xy 50.203909 -28.093419)
			(xy 50.257866 -28.107525) (xy 50.309195 -28.129337) (xy 50.325251 -28.139136) (xy 54.397908 -28.139136)
			(xy 54.401979 -28.083514) (xy 54.414105 -28.029077) (xy 54.434028 -27.976986) (xy 54.461324 -27.928351)
			(xy 54.49541 -27.884208) (xy 54.535559 -27.845499) (xy 54.580917 -27.813048) (xy 54.630517 -27.787547)
			(xy 54.683301 -27.76954) (xy 54.738144 -27.75941) (xy 54.793878 -27.757373) (xy 54.849315 -27.763473)
			(xy 54.903272 -27.777579) (xy 54.954601 -27.799391) (xy 55.002207 -27.828445) (xy 55.045075 -27.86412)
			(xy 55.082292 -27.905657) (xy 55.113065 -27.95217) (xy 55.136737 -28.002667) (xy 55.152805 -28.056074)
			(xy 55.160925 -28.11125) (xy 55.161434 -28.139136) (xy 55.667908 -28.139136) (xy 55.671979 -28.083514)
			(xy 55.684105 -28.029077) (xy 55.704028 -27.976986) (xy 55.731324 -27.928351) (xy 55.76541 -27.884208)
			(xy 55.805559 -27.845499) (xy 55.850917 -27.813048) (xy 55.900517 -27.787547) (xy 55.953301 -27.76954)
			(xy 56.008144 -27.75941) (xy 56.063878 -27.757373) (xy 56.119315 -27.763473) (xy 56.173272 -27.777579)
			(xy 56.224601 -27.799391) (xy 56.272207 -27.828445) (xy 56.315075 -27.86412) (xy 56.352292 -27.905657)
			(xy 56.383065 -27.95217) (xy 56.406737 -28.002667) (xy 56.422805 -28.056074) (xy 56.430925 -28.11125)
			(xy 56.431434 -28.139136) (xy 56.430925 -28.167022) (xy 56.422805 -28.222198) (xy 56.406737 -28.275605)
			(xy 56.383065 -28.326102) (xy 56.352292 -28.372615) (xy 56.315075 -28.414152) (xy 56.272207 -28.449827)
			(xy 56.224601 -28.478881) (xy 56.173272 -28.500693) (xy 56.119315 -28.514799) (xy 56.063878 -28.520899)
			(xy 56.008144 -28.518862) (xy 55.953301 -28.508732) (xy 55.900517 -28.490725) (xy 55.850917 -28.465224)
			(xy 55.805559 -28.432773) (xy 55.76541 -28.394064) (xy 55.731324 -28.349921) (xy 55.704028 -28.301286)
			(xy 55.684105 -28.249195) (xy 55.671979 -28.194758) (xy 55.667908 -28.139136) (xy 55.161434 -28.139136)
			(xy 55.160925 -28.167022) (xy 55.152805 -28.222198) (xy 55.136737 -28.275605) (xy 55.113065 -28.326102)
			(xy 55.082292 -28.372615) (xy 55.045075 -28.414152) (xy 55.002207 -28.449827) (xy 54.954601 -28.478881)
			(xy 54.903272 -28.500693) (xy 54.849315 -28.514799) (xy 54.793878 -28.520899) (xy 54.738144 -28.518862)
			(xy 54.683301 -28.508732) (xy 54.630517 -28.490725) (xy 54.580917 -28.465224) (xy 54.535559 -28.432773)
			(xy 54.49541 -28.394064) (xy 54.461324 -28.349921) (xy 54.434028 -28.301286) (xy 54.414105 -28.249195)
			(xy 54.401979 -28.194758) (xy 54.397908 -28.139136) (xy 50.325251 -28.139136) (xy 50.356801 -28.158391)
			(xy 50.399669 -28.194066) (xy 50.436886 -28.235603) (xy 50.467659 -28.282116) (xy 50.491331 -28.332613)
			(xy 50.507399 -28.38602) (xy 50.515519 -28.441196) (xy 50.516028 -28.469082) (xy 50.515519 -28.496968)
			(xy 50.507399 -28.552144) (xy 50.491331 -28.605551) (xy 50.467659 -28.656048) (xy 50.436886 -28.702561)
			(xy 50.399669 -28.744098) (xy 50.356801 -28.779773) (xy 50.309195 -28.808827) (xy 50.257866 -28.830639)
			(xy 50.203909 -28.844745) (xy 50.148472 -28.850845) (xy 50.092738 -28.848808) (xy 50.037895 -28.838678)
			(xy 49.985111 -28.820671) (xy 49.935511 -28.79517) (xy 49.890153 -28.762719) (xy 49.850004 -28.72401)
			(xy 49.815918 -28.679867) (xy 49.788622 -28.631232) (xy 49.768699 -28.579141) (xy 49.756573 -28.524704)
			(xy 49.752502 -28.469082) (xy 45.76318 -28.469082) (xy 45.76318 -29.114242) (xy 45.76269 -29.144226)
			(xy 45.754862 -29.203682) (xy 45.739341 -29.261607) (xy 45.716392 -29.317011) (xy 45.686408 -29.368945)
			(xy 45.649902 -29.416521) (xy 45.607497 -29.458926) (xy 45.559921 -29.495432) (xy 45.507987 -29.525416)
			(xy 45.452583 -29.548365) (xy 45.394658 -29.563886) (xy 45.335202 -29.571714) (xy 45.275234 -29.571714)
			(xy 45.215778 -29.563886) (xy 45.157853 -29.548365) (xy 45.102449 -29.525416) (xy 45.050515 -29.495432)
			(xy 45.002939 -29.458926) (xy 44.960534 -29.416521) (xy 44.924028 -29.368945) (xy 44.894044 -29.317011)
			(xy 44.871095 -29.261607) (xy 44.855574 -29.203682) (xy 44.847746 -29.144226) (xy 44.847256 -29.114242)
			(xy 37.77892 -29.114242) (xy 37.911024 -29.246322) (xy 37.914072 -29.247846) (xy 37.91712 -29.24937)
			(xy 37.918136 -29.249878) (xy 37.944623 -29.263996) (xy 37.993183 -29.29927) (xy 38.035623 -29.341709)
			(xy 38.070899 -29.390268) (xy 38.085014 -29.416756) (xy 38.085522 -29.417772) (xy 38.087046 -29.42082)
			(xy 38.08857 -29.423868) (xy 38.20795 -29.543248) (xy 39.407846 -30.743398) (xy 39.432506 -30.768433)
			(xy 39.47865 -30.821441) (xy 39.500048 -30.849316) (xy 39.515198 -30.869693) (xy 39.543661 -30.91175)
			(xy 39.549149 -30.92069) (xy 47.489364 -30.92069) (xy 47.489364 -30.05709) (xy 47.489854 -30.027106)
			(xy 47.497682 -29.96765) (xy 47.513203 -29.909725) (xy 47.536152 -29.854321) (xy 47.566136 -29.802387)
			(xy 47.602642 -29.754811) (xy 47.645047 -29.712406) (xy 47.692623 -29.6759) (xy 47.744557 -29.645916)
			(xy 47.799961 -29.622967) (xy 47.857886 -29.607446) (xy 47.917342 -29.599618) (xy 47.97731 -29.599618)
			(xy 48.036766 -29.607446) (xy 48.094691 -29.622967) (xy 48.150095 -29.645916) (xy 48.202029 -29.6759)
			(xy 48.249605 -29.712406) (xy 48.29201 -29.754811) (xy 48.328516 -29.802387) (xy 48.3585 -29.854321)
			(xy 48.381449 -29.909725) (xy 48.39697 -29.96765) (xy 48.404798 -30.027106) (xy 48.405288 -30.05709)
			(xy 48.405288 -30.376876) (xy 52.888896 -30.376876) (xy 52.889433 -30.347959) (xy 52.898153 -30.290787)
			(xy 52.915405 -30.235587) (xy 52.940793 -30.183625) (xy 52.973735 -30.136091) (xy 53.013476 -30.094075)
			(xy 53.035962 -30.075886) (xy 53.044776 -30.068286) (xy 53.054953 -30.047379) (xy 53.05552 -30.035754)
			(xy 53.05552 -29.955998) (xy 53.054961 -29.944369) (xy 53.044785 -29.92346) (xy 53.035962 -29.915866)
			(xy 53.013454 -29.897704) (xy 52.973722 -29.855677) (xy 52.940787 -29.808136) (xy 52.915403 -29.756169)
			(xy 52.898152 -29.700967) (xy 52.889428 -29.643794) (xy 52.888896 -29.614876) (xy 52.889382 -29.587625)
			(xy 52.897138 -29.533677) (xy 52.912493 -29.481382) (xy 52.935135 -29.431805) (xy 52.964601 -29.385955)
			(xy 53.000292 -29.344764) (xy 53.041483 -29.309073) (xy 53.087333 -29.279607) (xy 53.13691 -29.256965)
			(xy 53.189205 -29.24161) (xy 53.243153 -29.233854) (xy 53.297655 -29.233854) (xy 53.351603 -29.24161)
			(xy 53.403898 -29.256965) (xy 53.453475 -29.279607) (xy 53.499325 -29.309073) (xy 53.540516 -29.344764)
			(xy 53.576207 -29.385955) (xy 53.605673 -29.431805) (xy 53.628315 -29.481382) (xy 53.64367 -29.533677)
			(xy 53.651426 -29.587625) (xy 53.651912 -29.614876) (xy 53.65141 -29.643794) (xy 53.642682 -29.700967)
			(xy 53.625423 -29.756168) (xy 53.600029 -29.80813) (xy 53.567081 -29.855664) (xy 53.527334 -29.897678)
			(xy 53.504846 -29.915866) (xy 53.496055 -29.923488) (xy 53.485865 -29.944378) (xy 53.485288 -29.955998)
			(xy 53.485288 -30.035754) (xy 53.485815 -30.047387) (xy 53.496013 -30.068296) (xy 53.504846 -30.075886)
			(xy 53.527332 -30.094073) (xy 53.567065 -30.136095) (xy 53.600003 -30.183631) (xy 53.62539 -30.235593)
			(xy 53.642646 -30.290791) (xy 53.651376 -30.34796) (xy 53.651912 -30.376876) (xy 55.929022 -30.376876)
			(xy 55.929586 -30.347961) (xy 55.938305 -30.290791) (xy 55.955553 -30.235593) (xy 55.980936 -30.183631)
			(xy 56.013872 -30.136096) (xy 56.053606 -30.094077) (xy 56.076088 -30.075886) (xy 56.08489 -30.068273)
			(xy 56.095077 -30.047377) (xy 56.095646 -30.035754) (xy 56.095646 -29.955998) (xy 56.095113 -29.944365)
			(xy 56.084922 -29.923454) (xy 56.076088 -29.915866) (xy 56.053586 -29.897697) (xy 56.013852 -29.855672)
			(xy 55.980916 -29.808133) (xy 55.955531 -29.756167) (xy 55.938279 -29.700966) (xy 55.929554 -29.643793)
			(xy 55.929022 -29.614876) (xy 55.929508 -29.587625) (xy 55.937264 -29.533677) (xy 55.952619 -29.481382)
			(xy 55.975261 -29.431805) (xy 56.004727 -29.385955) (xy 56.040418 -29.344764) (xy 56.081609 -29.309073)
			(xy 56.127459 -29.279607) (xy 56.177036 -29.256965) (xy 56.229331 -29.24161) (xy 56.283279 -29.233854)
			(xy 56.337781 -29.233854) (xy 56.391729 -29.24161) (xy 56.444024 -29.256965) (xy 56.493601 -29.279607)
			(xy 56.539451 -29.309073) (xy 56.580642 -29.344764) (xy 56.616333 -29.385955) (xy 56.645799 -29.431805)
			(xy 56.668441 -29.481382) (xy 56.683796 -29.533677) (xy 56.691552 -29.587625) (xy 56.692038 -29.614876)
			(xy 56.691526 -29.643793) (xy 56.682799 -29.700966) (xy 56.665541 -29.756166) (xy 56.640149 -29.808128)
			(xy 56.607203 -29.855662) (xy 56.567459 -29.897677) (xy 56.544972 -29.915866) (xy 56.536185 -29.923493)
			(xy 56.525992 -29.944379) (xy 56.525414 -29.955998) (xy 56.525414 -30.035754) (xy 56.525931 -30.047389)
			(xy 56.536135 -30.068298) (xy 56.544972 -30.075886) (xy 56.567443 -30.094092) (xy 56.60718 -30.136108)
			(xy 56.640122 -30.183639) (xy 56.665512 -30.235598) (xy 56.682771 -30.290793) (xy 56.691502 -30.347961)
			(xy 56.692038 -30.376876) (xy 56.691552 -30.404127) (xy 56.683796 -30.458075) (xy 56.668441 -30.51037)
			(xy 56.645799 -30.559947) (xy 56.616333 -30.605797) (xy 56.580642 -30.646988) (xy 56.539451 -30.682679)
			(xy 56.493601 -30.712145) (xy 56.444024 -30.734787) (xy 56.391729 -30.750142) (xy 56.337781 -30.757898)
			(xy 56.283279 -30.757898) (xy 56.229331 -30.750142) (xy 56.177036 -30.734787) (xy 56.127459 -30.712145)
			(xy 56.081609 -30.682679) (xy 56.040418 -30.646988) (xy 56.004727 -30.605797) (xy 55.975261 -30.559947)
			(xy 55.952619 -30.51037) (xy 55.937264 -30.458075) (xy 55.929508 -30.404127) (xy 55.929022 -30.376876)
			(xy 53.651912 -30.376876) (xy 53.651426 -30.404127) (xy 53.64367 -30.458075) (xy 53.628315 -30.51037)
			(xy 53.605673 -30.559947) (xy 53.576207 -30.605797) (xy 53.540516 -30.646988) (xy 53.499325 -30.682679)
			(xy 53.453475 -30.712145) (xy 53.403898 -30.734787) (xy 53.351603 -30.750142) (xy 53.297655 -30.757898)
			(xy 53.243153 -30.757898) (xy 53.189205 -30.750142) (xy 53.13691 -30.734787) (xy 53.087333 -30.712145)
			(xy 53.041483 -30.682679) (xy 53.000292 -30.646988) (xy 52.964601 -30.605797) (xy 52.935135 -30.559947)
			(xy 52.912493 -30.51037) (xy 52.897138 -30.458075) (xy 52.889382 -30.404127) (xy 52.888896 -30.376876)
			(xy 48.405288 -30.376876) (xy 48.405288 -30.92069) (xy 48.404798 -30.950674) (xy 48.39697 -31.01013)
			(xy 48.381449 -31.068055) (xy 48.3585 -31.123459) (xy 48.328516 -31.175393) (xy 48.29201 -31.222969)
			(xy 48.249605 -31.265374) (xy 48.202029 -31.30188) (xy 48.150095 -31.331864) (xy 48.094691 -31.354813)
			(xy 48.036766 -31.370334) (xy 47.97731 -31.378162) (xy 47.917342 -31.378162) (xy 47.857886 -31.370334)
			(xy 47.799961 -31.354813) (xy 47.744557 -31.331864) (xy 47.692623 -31.30188) (xy 47.645047 -31.265374)
			(xy 47.602642 -31.222969) (xy 47.566136 -31.175393) (xy 47.536152 -31.123459) (xy 47.513203 -31.068055)
			(xy 47.497682 -31.01013) (xy 47.489854 -30.950674) (xy 47.489364 -30.92069) (xy 39.549149 -30.92069)
			(xy 39.556944 -30.93339) (xy 39.55796 -30.935168) (xy 39.564056 -30.94355) (xy 39.577893 -30.958748)
			(xy 39.604444 -30.990127) (xy 39.617142 -31.006288) (xy 39.630246 -31.023207) (xy 39.655148 -31.058017)
			(xy 39.666926 -31.075884) (xy 39.683436 -31.1023) (xy 39.684452 -31.104332) (xy 39.685976 -31.106618)
			(xy 39.692072 -31.116778) (xy 39.7002 -31.130748) (xy 39.7002 -31.131002) (xy 39.706296 -31.142178)
			(xy 39.707312 -31.14421) (xy 39.719268 -31.166691) (xy 39.741121 -31.212689) (xy 39.751 -31.236158)
			(xy 40.341296 -32.660844) (xy 40.363436 -32.714184) (xy 44.847256 -32.714184) (xy 44.847256 -31.850584)
			(xy 44.847746 -31.8206) (xy 44.855574 -31.761144) (xy 44.871095 -31.703219) (xy 44.894044 -31.647815)
			(xy 44.924028 -31.595881) (xy 44.960534 -31.548305) (xy 45.002939 -31.5059) (xy 45.050515 -31.469394)
			(xy 45.102449 -31.43941) (xy 45.157853 -31.416461) (xy 45.215778 -31.40094) (xy 45.275234 -31.393112)
			(xy 45.335202 -31.393112) (xy 45.394658 -31.40094) (xy 45.452583 -31.416461) (xy 45.507987 -31.43941)
			(xy 45.559921 -31.469394) (xy 45.607497 -31.5059) (xy 45.649902 -31.548305) (xy 45.664924 -31.567882)
			(xy 52.998622 -31.567882) (xy 53.002693 -31.51226) (xy 53.014819 -31.457823) (xy 53.034742 -31.405732)
			(xy 53.062038 -31.357097) (xy 53.096124 -31.312954) (xy 53.136273 -31.274245) (xy 53.181631 -31.241794)
			(xy 53.231231 -31.216293) (xy 53.284015 -31.198286) (xy 53.338858 -31.188156) (xy 53.394592 -31.186119)
			(xy 53.450029 -31.192219) (xy 53.503986 -31.206325) (xy 53.555315 -31.228137) (xy 53.602921 -31.257191)
			(xy 53.645789 -31.292866) (xy 53.683006 -31.334403) (xy 53.713779 -31.380916) (xy 53.737451 -31.431413)
			(xy 53.753519 -31.48482) (xy 53.761639 -31.539996) (xy 53.762148 -31.567882) (xy 53.761639 -31.595768)
			(xy 53.753519 -31.650944) (xy 53.737451 -31.704351) (xy 53.730459 -31.719266) (xy 54.285386 -31.719266)
			(xy 54.289457 -31.663644) (xy 54.301583 -31.609207) (xy 54.321506 -31.557116) (xy 54.348802 -31.508481)
			(xy 54.382888 -31.464338) (xy 54.423037 -31.425629) (xy 54.468395 -31.393178) (xy 54.517995 -31.367677)
			(xy 54.570779 -31.34967) (xy 54.625622 -31.33954) (xy 54.681356 -31.337503) (xy 54.736793 -31.343603)
			(xy 54.79075 -31.357709) (xy 54.842079 -31.379521) (xy 54.889685 -31.408575) (xy 54.932553 -31.44425)
			(xy 54.96977 -31.485787) (xy 55.000543 -31.5323) (xy 55.024215 -31.582797) (xy 55.040283 -31.636204)
			(xy 55.044433 -31.664402) (xy 55.560974 -31.664402) (xy 55.565045 -31.60878) (xy 55.577171 -31.554343)
			(xy 55.597094 -31.502252) (xy 55.62439 -31.453617) (xy 55.658476 -31.409474) (xy 55.698625 -31.370765)
			(xy 55.743983 -31.338314) (xy 55.793583 -31.312813) (xy 55.846367 -31.294806) (xy 55.90121 -31.284676)
			(xy 55.956944 -31.282639) (xy 56.012381 -31.288739) (xy 56.066338 -31.302845) (xy 56.117667 -31.324657)
			(xy 56.165273 -31.353711) (xy 56.208141 -31.389386) (xy 56.245358 -31.430923) (xy 56.276131 -31.477436)
			(xy 56.299803 -31.527933) (xy 56.315871 -31.58134) (xy 56.323991 -31.636516) (xy 56.3245 -31.664402)
			(xy 56.323991 -31.692288) (xy 56.315871 -31.747464) (xy 56.306931 -31.777178) (xy 56.826148 -31.777178)
			(xy 56.830219 -31.721556) (xy 56.842345 -31.667119) (xy 56.862268 -31.615028) (xy 56.889564 -31.566393)
			(xy 56.92365 -31.52225) (xy 56.963799 -31.483541) (xy 57.009157 -31.45109) (xy 57.058757 -31.425589)
			(xy 57.111541 -31.407582) (xy 57.166384 -31.397452) (xy 57.222118 -31.395415) (xy 57.277555 -31.401515)
			(xy 57.331512 -31.415621) (xy 57.382841 -31.437433) (xy 57.430447 -31.466487) (xy 57.473315 -31.502162)
			(xy 57.510532 -31.543699) (xy 57.541305 -31.590212) (xy 57.564977 -31.640709) (xy 57.581045 -31.694116)
			(xy 57.589165 -31.749292) (xy 57.589674 -31.777178) (xy 57.589165 -31.805064) (xy 57.581045 -31.86024)
			(xy 57.564977 -31.913647) (xy 57.541305 -31.964144) (xy 57.510532 -32.010657) (xy 57.473315 -32.052194)
			(xy 57.430447 -32.087869) (xy 57.382841 -32.116923) (xy 57.331512 -32.138735) (xy 57.277555 -32.152841)
			(xy 57.222118 -32.158941) (xy 57.166384 -32.156904) (xy 57.111541 -32.146774) (xy 57.058757 -32.128767)
			(xy 57.009157 -32.103266) (xy 56.963799 -32.070815) (xy 56.92365 -32.032106) (xy 56.889564 -31.987963)
			(xy 56.862268 -31.939328) (xy 56.842345 -31.887237) (xy 56.830219 -31.8328) (xy 56.826148 -31.777178)
			(xy 56.306931 -31.777178) (xy 56.299803 -31.800871) (xy 56.276131 -31.851368) (xy 56.245358 -31.897881)
			(xy 56.208141 -31.939418) (xy 56.165273 -31.975093) (xy 56.117667 -32.004147) (xy 56.066338 -32.025959)
			(xy 56.012381 -32.040065) (xy 55.956944 -32.046165) (xy 55.90121 -32.044128) (xy 55.846367 -32.033998)
			(xy 55.793583 -32.015991) (xy 55.743983 -31.99049) (xy 55.698625 -31.958039) (xy 55.658476 -31.91933)
			(xy 55.62439 -31.875187) (xy 55.597094 -31.826552) (xy 55.577171 -31.774461) (xy 55.565045 -31.720024)
			(xy 55.560974 -31.664402) (xy 55.044433 -31.664402) (xy 55.048403 -31.69138) (xy 55.048912 -31.719266)
			(xy 55.048403 -31.747152) (xy 55.040283 -31.802328) (xy 55.024215 -31.855735) (xy 55.000543 -31.906232)
			(xy 54.96977 -31.952745) (xy 54.932553 -31.994282) (xy 54.889685 -32.029957) (xy 54.842079 -32.059011)
			(xy 54.79075 -32.080823) (xy 54.736793 -32.094929) (xy 54.681356 -32.101029) (xy 54.625622 -32.098992)
			(xy 54.570779 -32.088862) (xy 54.517995 -32.070855) (xy 54.468395 -32.045354) (xy 54.423037 -32.012903)
			(xy 54.382888 -31.974194) (xy 54.348802 -31.930051) (xy 54.321506 -31.881416) (xy 54.301583 -31.829325)
			(xy 54.289457 -31.774888) (xy 54.285386 -31.719266) (xy 53.730459 -31.719266) (xy 53.713779 -31.754848)
			(xy 53.683006 -31.801361) (xy 53.645789 -31.842898) (xy 53.602921 -31.878573) (xy 53.555315 -31.907627)
			(xy 53.503986 -31.929439) (xy 53.450029 -31.943545) (xy 53.394592 -31.949645) (xy 53.338858 -31.947608)
			(xy 53.284015 -31.937478) (xy 53.231231 -31.919471) (xy 53.181631 -31.89397) (xy 53.136273 -31.861519)
			(xy 53.096124 -31.82281) (xy 53.062038 -31.778667) (xy 53.034742 -31.730032) (xy 53.014819 -31.677941)
			(xy 53.002693 -31.623504) (xy 52.998622 -31.567882) (xy 45.664924 -31.567882) (xy 45.686408 -31.595881)
			(xy 45.716392 -31.647815) (xy 45.739341 -31.703219) (xy 45.754862 -31.761144) (xy 45.76269 -31.8206)
			(xy 45.76318 -31.850584) (xy 45.76318 -32.714184) (xy 45.76269 -32.744168) (xy 45.754862 -32.803624)
			(xy 45.739341 -32.861549) (xy 45.716392 -32.916953) (xy 45.686408 -32.968887) (xy 45.649902 -33.016463)
			(xy 45.607497 -33.058868) (xy 45.559921 -33.095374) (xy 45.507987 -33.125358) (xy 45.452583 -33.148307)
			(xy 45.394658 -33.163828) (xy 45.335202 -33.171656) (xy 45.275234 -33.171656) (xy 45.215778 -33.163828)
			(xy 45.157853 -33.148307) (xy 45.102449 -33.125358) (xy 45.050515 -33.095374) (xy 45.002939 -33.058868)
			(xy 44.960534 -33.016463) (xy 44.924028 -32.968887) (xy 44.894044 -32.916953) (xy 44.871095 -32.861549)
			(xy 44.855574 -32.803624) (xy 44.847746 -32.744168) (xy 44.847256 -32.714184) (xy 40.363436 -32.714184)
			(xy 40.41267 -32.832802) (xy 40.414299 -32.836437) (xy 40.418512 -32.843196) (xy 40.421052 -32.846264)
			(xy 40.425878 -32.852106) (xy 40.434514 -32.856932) (xy 40.459483 -32.87145) (xy 40.505126 -32.906839)
			(xy 40.544914 -32.948703) (xy 40.57794 -32.996084) (xy 40.603448 -33.047901) (xy 40.620857 -33.10297)
			(xy 40.629768 -33.160034) (xy 40.630348 -33.18891) (xy 40.630348 -33.192974) (xy 40.629586 -33.215834)
			(xy 40.629586 -33.216342) (xy 40.628211 -33.233161) (xy 40.622872 -33.266485) (xy 40.618918 -33.28289)
			(xy 40.617394 -33.288986) (xy 40.614854 -33.299908) (xy 40.614092 -33.307782) (xy 40.614854 -33.320482)
			(xy 41.111926 -34.520886) (xy 47.489364 -34.520886) (xy 47.489364 -33.657286) (xy 47.489854 -33.627302)
			(xy 47.497682 -33.567846) (xy 47.513203 -33.509921) (xy 47.536152 -33.454517) (xy 47.566136 -33.402583)
			(xy 47.602642 -33.355007) (xy 47.645047 -33.312602) (xy 47.692623 -33.276096) (xy 47.744557 -33.246112)
			(xy 47.799961 -33.223163) (xy 47.857886 -33.207642) (xy 47.917342 -33.199814) (xy 47.97731 -33.199814)
			(xy 48.036766 -33.207642) (xy 48.094691 -33.223163) (xy 48.150095 -33.246112) (xy 48.202029 -33.276096)
			(xy 48.249605 -33.312602) (xy 48.29201 -33.355007) (xy 48.328516 -33.402583) (xy 48.3585 -33.454517)
			(xy 48.381449 -33.509921) (xy 48.39697 -33.567846) (xy 48.404798 -33.627302) (xy 48.405288 -33.657286)
			(xy 48.405288 -34.520886) (xy 48.404798 -34.55087) (xy 48.39697 -34.610326) (xy 48.381449 -34.668251)
			(xy 48.3585 -34.723655) (xy 48.328516 -34.775589) (xy 48.29201 -34.823165) (xy 48.249605 -34.86557)
			(xy 48.202029 -34.902076) (xy 48.150095 -34.93206) (xy 48.094691 -34.955009) (xy 48.036766 -34.97053)
			(xy 47.97731 -34.978358) (xy 47.917342 -34.978358) (xy 47.857886 -34.97053) (xy 47.799961 -34.955009)
			(xy 47.744557 -34.93206) (xy 47.692623 -34.902076) (xy 47.645047 -34.86557) (xy 47.602642 -34.823165)
			(xy 47.566136 -34.775589) (xy 47.536152 -34.723655) (xy 47.513203 -34.668251) (xy 47.497682 -34.610326)
			(xy 47.489854 -34.55087) (xy 47.489364 -34.520886) (xy 41.111926 -34.520886) (xy 41.40327 -35.224466)
			(xy 41.419997 -35.264852) (xy 55.90235 -35.264852) (xy 55.906421 -35.20923) (xy 55.918547 -35.154793)
			(xy 55.93847 -35.102702) (xy 55.965766 -35.054067) (xy 55.999852 -35.009924) (xy 56.040001 -34.971215)
			(xy 56.085359 -34.938764) (xy 56.134959 -34.913263) (xy 56.187743 -34.895256) (xy 56.242586 -34.885126)
			(xy 56.29832 -34.883089) (xy 56.353757 -34.889189) (xy 56.407714 -34.903295) (xy 56.459043 -34.925107)
			(xy 56.506649 -34.954161) (xy 56.549517 -34.989836) (xy 56.586734 -35.031373) (xy 56.617507 -35.077886)
			(xy 56.641179 -35.128383) (xy 56.657247 -35.18179) (xy 56.665367 -35.236966) (xy 56.665876 -35.264852)
			(xy 56.665367 -35.292738) (xy 56.657247 -35.347914) (xy 56.641179 -35.401321) (xy 56.617507 -35.451818)
			(xy 56.586734 -35.498331) (xy 56.549517 -35.539868) (xy 56.506649 -35.575543) (xy 56.459043 -35.604597)
			(xy 56.407714 -35.626409) (xy 56.353757 -35.640515) (xy 56.29832 -35.646615) (xy 56.242586 -35.644578)
			(xy 56.187743 -35.634448) (xy 56.134959 -35.616441) (xy 56.085359 -35.59094) (xy 56.040001 -35.558489)
			(xy 55.999852 -35.51978) (xy 55.965766 -35.475637) (xy 55.93847 -35.427002) (xy 55.918547 -35.374911)
			(xy 55.906421 -35.320474) (xy 55.90235 -35.264852) (xy 41.419997 -35.264852) (xy 41.67343 -35.876738)
			(xy 44.717206 -35.876738) (xy 44.721277 -35.821116) (xy 44.733403 -35.766679) (xy 44.753326 -35.714588)
			(xy 44.780622 -35.665953) (xy 44.814708 -35.62181) (xy 44.854857 -35.583101) (xy 44.900215 -35.55065)
			(xy 44.949815 -35.525149) (xy 45.002599 -35.507142) (xy 45.057442 -35.497012) (xy 45.113176 -35.494975)
			(xy 45.168613 -35.501075) (xy 45.22257 -35.515181) (xy 45.273899 -35.536993) (xy 45.321505 -35.566047)
			(xy 45.364373 -35.601722) (xy 45.40159 -35.643259) (xy 45.432363 -35.689772) (xy 45.456035 -35.740269)
			(xy 45.472103 -35.793676) (xy 45.480223 -35.848852) (xy 45.480732 -35.876738) (xy 48.788826 -35.876738)
			(xy 48.792897 -35.821116) (xy 48.805023 -35.766679) (xy 48.824946 -35.714588) (xy 48.852242 -35.665953)
			(xy 48.886328 -35.62181) (xy 48.926477 -35.583101) (xy 48.971835 -35.55065) (xy 49.021435 -35.525149)
			(xy 49.074219 -35.507142) (xy 49.129062 -35.497012) (xy 49.184796 -35.494975) (xy 49.240233 -35.501075)
			(xy 49.29419 -35.515181) (xy 49.345519 -35.536993) (xy 49.393125 -35.566047) (xy 49.435993 -35.601722)
			(xy 49.47321 -35.643259) (xy 49.503983 -35.689772) (xy 49.527655 -35.740269) (xy 49.543723 -35.793676)
			(xy 49.551843 -35.848852) (xy 49.552352 -35.876738) (xy 49.551843 -35.904624) (xy 49.543723 -35.9598)
			(xy 49.527655 -36.013207) (xy 49.503983 -36.063704) (xy 49.47321 -36.110217) (xy 49.435993 -36.151754)
			(xy 49.393125 -36.187429) (xy 49.345519 -36.216483) (xy 49.29419 -36.238295) (xy 49.240233 -36.252401)
			(xy 49.184796 -36.258501) (xy 49.129062 -36.256464) (xy 49.074219 -36.246334) (xy 49.021435 -36.228327)
			(xy 48.971835 -36.202826) (xy 48.926477 -36.170375) (xy 48.886328 -36.131666) (xy 48.852242 -36.087523)
			(xy 48.824946 -36.038888) (xy 48.805023 -35.986797) (xy 48.792897 -35.93236) (xy 48.788826 -35.876738)
			(xy 45.480732 -35.876738) (xy 45.480223 -35.904624) (xy 45.472103 -35.9598) (xy 45.456035 -36.013207)
			(xy 45.432363 -36.063704) (xy 45.40159 -36.110217) (xy 45.364373 -36.151754) (xy 45.321505 -36.187429)
			(xy 45.273899 -36.216483) (xy 45.22257 -36.238295) (xy 45.168613 -36.252401) (xy 45.113176 -36.258501)
			(xy 45.057442 -36.256464) (xy 45.002599 -36.246334) (xy 44.949815 -36.228327) (xy 44.900215 -36.202826)
			(xy 44.854857 -36.170375) (xy 44.814708 -36.131666) (xy 44.780622 -36.087523) (xy 44.753326 -36.038888)
			(xy 44.733403 -35.986797) (xy 44.721277 -35.93236) (xy 44.717206 -35.876738) (xy 41.67343 -35.876738)
			(xy 41.935699 -36.50996) (xy 46.613824 -36.50996) (xy 46.617895 -36.454338) (xy 46.630021 -36.399901)
			(xy 46.649944 -36.34781) (xy 46.67724 -36.299175) (xy 46.711326 -36.255032) (xy 46.751475 -36.216323)
			(xy 46.796833 -36.183872) (xy 46.846433 -36.158371) (xy 46.899217 -36.140364) (xy 46.95406 -36.130234)
			(xy 47.009794 -36.128197) (xy 47.065231 -36.134297) (xy 47.119188 -36.148403) (xy 47.170517 -36.170215)
			(xy 47.218123 -36.199269) (xy 47.260991 -36.234944) (xy 47.298208 -36.276481) (xy 47.328981 -36.322994)
			(xy 47.352653 -36.373491) (xy 47.368721 -36.426898) (xy 47.372646 -36.453572) (xy 49.928524 -36.453572)
			(xy 49.932595 -36.39795) (xy 49.944721 -36.343513) (xy 49.964644 -36.291422) (xy 49.99194 -36.242787)
			(xy 50.026026 -36.198644) (xy 50.066175 -36.159935) (xy 50.111533 -36.127484) (xy 50.161133 -36.101983)
			(xy 50.213917 -36.083976) (xy 50.26876 -36.073846) (xy 50.324494 -36.071809) (xy 50.379931 -36.077909)
			(xy 50.433888 -36.092015) (xy 50.485217 -36.113827) (xy 50.532823 -36.142881) (xy 50.575691 -36.178556)
			(xy 50.612908 -36.220093) (xy 50.643681 -36.266606) (xy 50.653217 -36.286948) (xy 57.20029 -36.286948)
			(xy 57.204361 -36.231326) (xy 57.216487 -36.176889) (xy 57.23641 -36.124798) (xy 57.263706 -36.076163)
			(xy 57.297792 -36.03202) (xy 57.337941 -35.993311) (xy 57.383299 -35.96086) (xy 57.432899 -35.935359)
			(xy 57.485683 -35.917352) (xy 57.540526 -35.907222) (xy 57.59626 -35.905185) (xy 57.651697 -35.911285)
			(xy 57.705654 -35.925391) (xy 57.756983 -35.947203) (xy 57.804589 -35.976257) (xy 57.847457 -36.011932)
			(xy 57.884674 -36.053469) (xy 57.915447 -36.099982) (xy 57.939119 -36.150479) (xy 57.955187 -36.203886)
			(xy 57.963307 -36.259062) (xy 57.963816 -36.286948) (xy 57.963307 -36.314834) (xy 57.955187 -36.37001)
			(xy 57.939119 -36.423417) (xy 57.915447 -36.473914) (xy 57.884674 -36.520427) (xy 57.847457 -36.561964)
			(xy 57.804589 -36.597639) (xy 57.756983 -36.626693) (xy 57.705654 -36.648505) (xy 57.651697 -36.662611)
			(xy 57.59626 -36.668711) (xy 57.540526 -36.666674) (xy 57.485683 -36.656544) (xy 57.432899 -36.638537)
			(xy 57.383299 -36.613036) (xy 57.337941 -36.580585) (xy 57.297792 -36.541876) (xy 57.263706 -36.497733)
			(xy 57.23641 -36.449098) (xy 57.216487 -36.397007) (xy 57.204361 -36.34257) (xy 57.20029 -36.286948)
			(xy 50.653217 -36.286948) (xy 50.667353 -36.317103) (xy 50.683421 -36.37051) (xy 50.691541 -36.425686)
			(xy 50.69205 -36.453572) (xy 50.691541 -36.481458) (xy 50.683421 -36.536634) (xy 50.667353 -36.590041)
			(xy 50.643681 -36.640538) (xy 50.612908 -36.687051) (xy 50.575691 -36.728588) (xy 50.532823 -36.764263)
			(xy 50.485217 -36.793317) (xy 50.433888 -36.815129) (xy 50.379931 -36.829235) (xy 50.324494 -36.835335)
			(xy 50.26876 -36.833298) (xy 50.213917 -36.823168) (xy 50.161133 -36.805161) (xy 50.111533 -36.77966)
			(xy 50.066175 -36.747209) (xy 50.026026 -36.7085) (xy 49.99194 -36.664357) (xy 49.964644 -36.615722)
			(xy 49.944721 -36.563631) (xy 49.932595 -36.509194) (xy 49.928524 -36.453572) (xy 47.372646 -36.453572)
			(xy 47.376841 -36.482074) (xy 47.37735 -36.50996) (xy 47.376841 -36.537846) (xy 47.368721 -36.593022)
			(xy 47.352653 -36.646429) (xy 47.328981 -36.696926) (xy 47.298208 -36.743439) (xy 47.260991 -36.784976)
			(xy 47.218123 -36.820651) (xy 47.170517 -36.849705) (xy 47.119188 -36.871517) (xy 47.065231 -36.885623)
			(xy 47.009794 -36.891723) (xy 46.95406 -36.889686) (xy 46.899217 -36.879556) (xy 46.846433 -36.861549)
			(xy 46.796833 -36.836048) (xy 46.751475 -36.803597) (xy 46.711326 -36.764888) (xy 46.67724 -36.720745)
			(xy 46.649944 -36.67211) (xy 46.630021 -36.620019) (xy 46.617895 -36.565582) (xy 46.613824 -36.50996)
			(xy 41.935699 -36.50996) (xy 42.176192 -37.090604) (xy 42.190255 -37.125598) (xy 42.213647 -37.197305)
			(xy 42.222928 -37.23386) (xy 42.22369 -37.236654) (xy 42.224452 -37.239194) (xy 42.233342 -37.260022)
			(xy 42.233342 -37.26053) (xy 42.245026 -37.28847) (xy 42.24528 -37.28847) (xy 42.25036 -37.300662)
			(xy 42.25036 -37.30117) (xy 42.269071 -37.347187) (xy 42.29834 -37.442121) (xy 42.305021 -37.47516)
			(xy 43.759118 -37.47516) (xy 43.763189 -37.419538) (xy 43.775315 -37.365101) (xy 43.795238 -37.31301)
			(xy 43.822534 -37.264375) (xy 43.85662 -37.220232) (xy 43.896769 -37.181523) (xy 43.942127 -37.149072)
			(xy 43.991727 -37.123571) (xy 44.044511 -37.105564) (xy 44.099354 -37.095434) (xy 44.155088 -37.093397)
			(xy 44.210525 -37.099497) (xy 44.264482 -37.113603) (xy 44.315811 -37.135415) (xy 44.363417 -37.164469)
			(xy 44.406285 -37.200144) (xy 44.443502 -37.241681) (xy 44.474275 -37.288194) (xy 44.497947 -37.338691)
			(xy 44.514015 -37.392098) (xy 44.522135 -37.447274) (xy 44.522644 -37.47516) (xy 44.522135 -37.503046)
			(xy 44.514015 -37.558222) (xy 44.497947 -37.611629) (xy 44.474275 -37.662126) (xy 44.474122 -37.662358)
			(xy 45.948344 -37.662358) (xy 45.952415 -37.606736) (xy 45.964541 -37.552299) (xy 45.984464 -37.500208)
			(xy 46.01176 -37.451573) (xy 46.045846 -37.40743) (xy 46.085995 -37.368721) (xy 46.131353 -37.33627)
			(xy 46.180953 -37.310769) (xy 46.233737 -37.292762) (xy 46.28858 -37.282632) (xy 46.344314 -37.280595)
			(xy 46.399751 -37.286695) (xy 46.453708 -37.300801) (xy 46.505037 -37.322613) (xy 46.552643 -37.351667)
			(xy 46.595511 -37.387342) (xy 46.632728 -37.428879) (xy 46.663501 -37.475392) (xy 46.687173 -37.525889)
			(xy 46.703241 -37.579296) (xy 46.711361 -37.634472) (xy 46.71187 -37.662358) (xy 46.711361 -37.690244)
			(xy 46.703241 -37.74542) (xy 46.694607 -37.774118) (xy 57.464704 -37.774118) (xy 57.468775 -37.718496)
			(xy 57.480901 -37.664059) (xy 57.500824 -37.611968) (xy 57.52812 -37.563333) (xy 57.562206 -37.51919)
			(xy 57.602355 -37.480481) (xy 57.647713 -37.44803) (xy 57.697313 -37.422529) (xy 57.750097 -37.404522)
			(xy 57.80494 -37.394392) (xy 57.860674 -37.392355) (xy 57.916111 -37.398455) (xy 57.970068 -37.412561)
			(xy 58.021397 -37.434373) (xy 58.069003 -37.463427) (xy 58.111871 -37.499102) (xy 58.149088 -37.540639)
			(xy 58.179861 -37.587152) (xy 58.203533 -37.637649) (xy 58.219601 -37.691056) (xy 58.227721 -37.746232)
			(xy 58.22823 -37.774118) (xy 58.227721 -37.802004) (xy 58.219601 -37.85718) (xy 58.203533 -37.910587)
			(xy 58.179861 -37.961084) (xy 58.149088 -38.007597) (xy 58.111871 -38.049134) (xy 58.069003 -38.084809)
			(xy 58.021397 -38.113863) (xy 57.970068 -38.135675) (xy 57.916111 -38.149781) (xy 57.860674 -38.155881)
			(xy 57.80494 -38.153844) (xy 57.750097 -38.143714) (xy 57.697313 -38.125707) (xy 57.647713 -38.100206)
			(xy 57.602355 -38.067755) (xy 57.562206 -38.029046) (xy 57.52812 -37.984903) (xy 57.500824 -37.936268)
			(xy 57.480901 -37.884177) (xy 57.468775 -37.82974) (xy 57.464704 -37.774118) (xy 46.694607 -37.774118)
			(xy 46.687173 -37.798827) (xy 46.663501 -37.849324) (xy 46.632728 -37.895837) (xy 46.595511 -37.937374)
			(xy 46.552643 -37.973049) (xy 46.505037 -38.002103) (xy 46.453708 -38.023915) (xy 46.399751 -38.038021)
			(xy 46.344314 -38.044121) (xy 46.28858 -38.042084) (xy 46.233737 -38.031954) (xy 46.180953 -38.013947)
			(xy 46.131353 -37.988446) (xy 46.085995 -37.955995) (xy 46.045846 -37.917286) (xy 46.01176 -37.873143)
			(xy 45.984464 -37.824508) (xy 45.964541 -37.772417) (xy 45.952415 -37.71798) (xy 45.948344 -37.662358)
			(xy 44.474122 -37.662358) (xy 44.443502 -37.708639) (xy 44.406285 -37.750176) (xy 44.363417 -37.785851)
			(xy 44.315811 -37.814905) (xy 44.264482 -37.836717) (xy 44.210525 -37.850823) (xy 44.155088 -37.856923)
			(xy 44.099354 -37.854886) (xy 44.044511 -37.844756) (xy 43.991727 -37.826749) (xy 43.942127 -37.801248)
			(xy 43.896769 -37.768797) (xy 43.85662 -37.730088) (xy 43.822534 -37.685945) (xy 43.795238 -37.63731)
			(xy 43.775315 -37.585219) (xy 43.763189 -37.530782) (xy 43.759118 -37.47516) (xy 42.305021 -37.47516)
			(xy 42.318031 -37.539493) (xy 42.32795 -37.638341) (xy 42.328592 -37.688012) (xy 42.328592 -37.704522)
			(xy 42.328592 -37.705538) (xy 42.316908 -38.411912) (xy 42.31386 -38.593268) (xy 42.312504 -38.640617)
			(xy 42.302486 -38.729952) (xy 49.700897 -38.729952) (xy 49.700897 -38.675448) (xy 49.708655 -38.6215)
			(xy 49.724011 -38.569204) (xy 49.746654 -38.519627) (xy 49.776123 -38.473777) (xy 49.811817 -38.432587)
			(xy 49.85301 -38.396898) (xy 49.898864 -38.367434) (xy 49.948444 -38.344796) (xy 50.000741 -38.329446)
			(xy 50.05469 -38.321694) (xy 50.081942 -38.321234) (xy 50.110245 -38.321753) (xy 50.166233 -38.330098)
			(xy 50.220372 -38.346627) (xy 50.271474 -38.370977) (xy 50.318414 -38.402613) (xy 50.360162 -38.440841)
			(xy 50.395801 -38.48482) (xy 50.410618 -38.50894) (xy 50.418226 -38.520968) (xy 50.438843 -38.540569)
			(xy 50.464072 -38.553712) (xy 50.491951 -38.559372) (xy 50.520309 -38.557109) (xy 50.546937 -38.5471)
			(xy 50.569764 -38.530123) (xy 50.578766 -38.5191) (xy 50.596977 -38.496244) (xy 50.639135 -38.455779)
			(xy 50.686965 -38.422209) (xy 50.739352 -38.396319) (xy 50.795072 -38.378712) (xy 50.852824 -38.3698)
			(xy 50.882042 -38.36924) (xy 50.909295 -38.369633) (xy 50.963245 -38.377395) (xy 51.015541 -38.392756)
			(xy 51.065119 -38.415402) (xy 51.11097 -38.444873) (xy 51.15216 -38.480569) (xy 51.187852 -38.521764)
			(xy 51.217318 -38.567618) (xy 51.239959 -38.617198) (xy 51.255314 -38.669496) (xy 51.26307 -38.723447)
			(xy 51.26307 -38.777953) (xy 51.255314 -38.831904) (xy 51.239959 -38.884202) (xy 51.217318 -38.933782)
			(xy 51.187852 -38.979636) (xy 51.15216 -39.020831) (xy 51.11097 -39.056527) (xy 51.065119 -39.085998)
			(xy 51.015541 -39.108644) (xy 50.963245 -39.124005) (xy 50.909295 -39.131767) (xy 50.882042 -39.132256)
			(xy 50.853738 -39.131754) (xy 50.797749 -39.123407) (xy 50.743609 -39.106876) (xy 50.692508 -39.082523)
			(xy 50.645568 -39.050883) (xy 50.60382 -39.012653) (xy 50.568183 -38.968671) (xy 50.553366 -38.94455)
			(xy 50.545779 -38.932508) (xy 50.525157 -38.912908) (xy 50.499923 -38.899767) (xy 50.472041 -38.894109)
			(xy 50.44368 -38.896374) (xy 50.417049 -38.906386) (xy 50.394221 -38.923366) (xy 50.385218 -38.93439)
			(xy 50.367014 -38.957251) (xy 50.324855 -38.997717) (xy 50.277023 -39.031286) (xy 50.224635 -39.057176)
			(xy 50.168913 -39.074781) (xy 50.11116 -39.083691) (xy 50.081942 -39.08425) (xy 50.05469 -39.083706)
			(xy 50.000741 -39.075954) (xy 49.948444 -39.060604) (xy 49.898864 -39.037966) (xy 49.85301 -39.008502)
			(xy 49.811817 -38.972813) (xy 49.776123 -38.931623) (xy 49.746654 -38.885773) (xy 49.724011 -38.836196)
			(xy 49.708655 -38.7839) (xy 49.700897 -38.729952) (xy 42.302486 -38.729952) (xy 42.301947 -38.734756)
			(xy 42.292778 -38.781228) (xy 42.24274 -39.020242) (xy 42.043545 -39.97198) (xy 51.895754 -39.97198)
			(xy 51.899825 -39.916358) (xy 51.911951 -39.861921) (xy 51.931874 -39.80983) (xy 51.95917 -39.761195)
			(xy 51.993256 -39.717052) (xy 52.033405 -39.678343) (xy 52.078763 -39.645892) (xy 52.128363 -39.620391)
			(xy 52.181147 -39.602384) (xy 52.23599 -39.592254) (xy 52.291724 -39.590217) (xy 52.347161 -39.596317)
			(xy 52.401118 -39.610423) (xy 52.452447 -39.632235) (xy 52.500053 -39.661289) (xy 52.542921 -39.696964)
			(xy 52.580138 -39.738501) (xy 52.610911 -39.785014) (xy 52.634583 -39.835511) (xy 52.650651 -39.888918)
			(xy 52.658771 -39.944094) (xy 52.65928 -39.97198) (xy 52.658771 -39.999866) (xy 52.650651 -40.055042)
			(xy 52.634583 -40.108449) (xy 52.610911 -40.158946) (xy 52.580138 -40.205459) (xy 52.542921 -40.246996)
			(xy 52.500053 -40.282671) (xy 52.452447 -40.311725) (xy 52.401118 -40.333537) (xy 52.347161 -40.347643)
			(xy 52.291724 -40.353743) (xy 52.23599 -40.351706) (xy 52.181147 -40.341576) (xy 52.128363 -40.323569)
			(xy 52.078763 -40.298068) (xy 52.033405 -40.265617) (xy 51.993256 -40.226908) (xy 51.95917 -40.182765)
			(xy 51.931874 -40.13413) (xy 51.911951 -40.082039) (xy 51.899825 -40.027602) (xy 51.895754 -39.97198)
			(xy 42.043545 -39.97198) (xy 41.867582 -40.81272) (xy 41.867328 -40.813482) (xy 41.86601 -40.823164)
			(xy 41.869914 -40.842294) (xy 41.880646 -40.858603) (xy 41.88841 -40.864536) (xy 41.965118 -40.917622)
			(xy 41.971458 -40.921699) (xy 41.985786 -40.926358) (xy 41.993312 -40.926766) (xy 42.000678 -40.92702)
			(xy 42.014648 -40.922956) (xy 42.021252 -40.918892) (xy 42.04422 -40.904933) (xy 42.093242 -40.882901)
			(xy 42.144872 -40.867968) (xy 42.198087 -40.860432) (xy 42.22496 -40.859964) (xy 42.2537 -40.860482)
			(xy 42.310529 -40.869101) (xy 42.365423 -40.886149) (xy 42.417136 -40.91124) (xy 42.4645 -40.943807)
			(xy 42.485818 -40.963088) (xy 42.486072 -40.963342) (xy 42.490054 -40.966814) (xy 42.499146 -40.972189)
			(xy 42.504106 -40.97401) (xy 42.508114 -40.975292) (xy 42.51641 -40.976692) (xy 42.520616 -40.976804)
			(xy 42.589704 -40.976804) (xy 42.593913 -40.976723) (xy 42.602213 -40.975318) (xy 42.606214 -40.97401)
			(xy 42.611174 -40.97219) (xy 42.620268 -40.966817) (xy 42.624248 -40.963342) (xy 42.624502 -40.963088)
			(xy 42.645829 -40.943817) (xy 42.693191 -40.911249) (xy 42.744903 -40.886155) (xy 42.799793 -40.869101)
			(xy 42.856621 -40.860473) (xy 42.88536 -40.859964) (xy 42.912617 -40.860424) (xy 42.966576 -40.868177)
			(xy 43.018883 -40.883531) (xy 43.068471 -40.906173) (xy 43.114333 -40.935642) (xy 43.155534 -40.971338)
			(xy 43.191234 -41.012535) (xy 43.220708 -41.058393) (xy 43.243355 -41.10798) (xy 43.258714 -41.160285)
			(xy 43.266473 -41.214243) (xy 43.266473 -41.268757) (xy 43.258714 -41.322715) (xy 43.243355 -41.37502)
			(xy 43.220708 -41.424607) (xy 43.191234 -41.470465) (xy 43.155534 -41.511662) (xy 43.114333 -41.547358)
			(xy 43.068471 -41.576827) (xy 43.018883 -41.599469) (xy 42.966576 -41.614823) (xy 42.912617 -41.622576)
			(xy 42.88536 -41.62298) (xy 42.856622 -41.622456) (xy 42.799798 -41.613828) (xy 42.744911 -41.596772)
			(xy 42.693204 -41.571676) (xy 42.645846 -41.539107) (xy 42.624502 -41.519856) (xy 42.624248 -41.519602)
			(xy 42.620268 -41.516126) (xy 42.611179 -41.510743) (xy 42.606214 -41.508934) (xy 42.602206 -41.507652)
			(xy 42.59391 -41.50625) (xy 42.589704 -41.50614) (xy 42.520616 -41.50614) (xy 42.516407 -41.506219)
			(xy 42.508106 -41.507622) (xy 42.504106 -41.508934) (xy 42.499149 -41.510758) (xy 42.49006 -41.516138)
			(xy 42.486072 -41.519602) (xy 42.485818 -41.519856) (xy 42.464491 -41.539127) (xy 42.417128 -41.571693)
			(xy 42.365416 -41.596787) (xy 42.310526 -41.613842) (xy 42.253699 -41.622471) (xy 42.22496 -41.62298)
			(xy 42.198358 -41.622516) (xy 42.14567 -41.615121) (xy 42.094521 -41.600481) (xy 42.0459 -41.578878)
			(xy 42.000751 -41.550731) (xy 41.959948 -41.516587) (xy 41.924283 -41.477107) (xy 41.908984 -41.45534)
			(xy 41.908984 -41.455086) (xy 41.904607 -41.449127) (xy 41.893124 -41.439823) (xy 41.886378 -41.436798)
			(xy 41.87938 -41.434203) (xy 41.864531 -41.432785) (xy 41.857168 -41.434004) (xy 41.765474 -41.451784)
			(xy 41.756838 -41.454324) (xy 41.749029 -41.457658) (xy 41.736044 -41.468584) (xy 41.727351 -41.483159)
			(xy 41.725342 -41.491408) (xy 41.345555 -43.305222) (xy 44.307252 -43.305222) (xy 44.307718 -43.277852)
			(xy 44.315534 -43.223672) (xy 44.331022 -43.171168) (xy 44.353864 -43.121422) (xy 44.38359 -43.075455)
			(xy 44.401232 -43.054524) (xy 44.401486 -43.05427) (xy 44.407048 -43.047166) (xy 44.41331 -43.030263)
			(xy 44.413678 -43.02125) (xy 44.413678 -42.954194) (xy 44.413329 -42.945176) (xy 44.407076 -42.928259)
			(xy 44.401486 -42.921174) (xy 44.401232 -42.921174) (xy 44.401232 -42.92092) (xy 44.383594 -42.899987)
			(xy 44.353881 -42.854015) (xy 44.331044 -42.804268) (xy 44.315553 -42.751767) (xy 44.307725 -42.697591)
			(xy 44.307252 -42.670222) (xy 44.307802 -42.641484) (xy 44.31642 -42.584659) (xy 44.333465 -42.529769)
			(xy 44.35855 -42.478057) (xy 44.391109 -42.430692) (xy 44.410376 -42.409364) (xy 44.41698 -42.402506)
			(xy 44.424092 -42.384472) (xy 44.424092 -42.295572) (xy 44.41698 -42.277538) (xy 44.410376 -42.27068)
			(xy 44.391129 -42.249333) (xy 44.358567 -42.201973) (xy 44.333478 -42.150264) (xy 44.316428 -42.095377)
			(xy 44.307805 -42.038553) (xy 44.307802 -41.981079) (xy 44.316421 -41.924255) (xy 44.333466 -41.869366)
			(xy 44.358551 -41.817655) (xy 44.391109 -41.770292) (xy 44.410376 -41.748964) (xy 44.41698 -41.742106)
			(xy 44.424092 -41.724072) (xy 44.424092 -41.635172) (xy 44.41698 -41.617138) (xy 44.410376 -41.61028)
			(xy 44.391122 -41.588938) (xy 44.358552 -41.541581) (xy 44.333456 -41.489873) (xy 44.316401 -41.434985)
			(xy 44.307775 -41.37816) (xy 44.307252 -41.349422) (xy 44.307738 -41.322171) (xy 44.315494 -41.268223)
			(xy 44.330849 -41.215928) (xy 44.353491 -41.166351) (xy 44.382957 -41.120501) (xy 44.418648 -41.07931)
			(xy 44.459839 -41.043619) (xy 44.505689 -41.014153) (xy 44.555266 -40.991511) (xy 44.607561 -40.976156)
			(xy 44.661509 -40.9684) (xy 44.716011 -40.9684) (xy 44.739132 -40.971724) (xy 52.594 -40.971724)
			(xy 52.598071 -40.916102) (xy 52.610197 -40.861665) (xy 52.63012 -40.809574) (xy 52.657416 -40.760939)
			(xy 52.691502 -40.716796) (xy 52.731651 -40.678087) (xy 52.777009 -40.645636) (xy 52.826609 -40.620135)
			(xy 52.879393 -40.602128) (xy 52.934236 -40.591998) (xy 52.98997 -40.589961) (xy 53.045407 -40.596061)
			(xy 53.099364 -40.610167) (xy 53.150693 -40.631979) (xy 53.198299 -40.661033) (xy 53.241167 -40.696708)
			(xy 53.278384 -40.738245) (xy 53.309157 -40.784758) (xy 53.332829 -40.835255) (xy 53.348897 -40.888662)
			(xy 53.357017 -40.943838) (xy 53.357526 -40.971724) (xy 53.357017 -40.99961) (xy 53.348897 -41.054786)
			(xy 53.332829 -41.108193) (xy 53.309157 -41.15869) (xy 53.278384 -41.205203) (xy 53.241167 -41.24674)
			(xy 53.198299 -41.282415) (xy 53.150693 -41.311469) (xy 53.099364 -41.333281) (xy 53.045407 -41.347387)
			(xy 52.98997 -41.353487) (xy 52.934236 -41.35145) (xy 52.879393 -41.34132) (xy 52.826609 -41.323313)
			(xy 52.777009 -41.297812) (xy 52.731651 -41.265361) (xy 52.691502 -41.226652) (xy 52.657416 -41.182509)
			(xy 52.63012 -41.133874) (xy 52.610197 -41.081783) (xy 52.598071 -41.027346) (xy 52.594 -40.971724)
			(xy 44.739132 -40.971724) (xy 44.769959 -40.976156) (xy 44.822254 -40.991511) (xy 44.871831 -41.014153)
			(xy 44.917681 -41.043619) (xy 44.958872 -41.07931) (xy 44.994563 -41.120501) (xy 45.024029 -41.166351)
			(xy 45.046671 -41.215928) (xy 45.062026 -41.268223) (xy 45.069782 -41.322171) (xy 45.070268 -41.349422)
			(xy 45.069739 -41.37816) (xy 45.061115 -41.434987) (xy 45.044065 -41.489877) (xy 45.018975 -41.541589)
			(xy 44.986413 -41.588952) (xy 44.967144 -41.61028) (xy 44.96054 -41.617138) (xy 44.953428 -41.635172)
			(xy 44.953428 -41.724072) (xy 44.96054 -41.742106) (xy 44.967144 -41.748964) (xy 44.986438 -41.770271)
			(xy 45.019005 -41.817636) (xy 45.044098 -41.869351) (xy 45.061148 -41.924245) (xy 45.069769 -41.981076)
			(xy 45.069767 -42.038556) (xy 45.06114 -42.095386) (xy 45.044086 -42.150279) (xy 45.018989 -42.201992)
			(xy 44.986418 -42.249354) (xy 44.967144 -42.27068) (xy 44.96054 -42.277538) (xy 44.953428 -42.295572)
			(xy 44.953428 -42.384472) (xy 44.96054 -42.402506) (xy 44.967144 -42.409364) (xy 44.986422 -42.430685)
			(xy 45.018988 -42.478048) (xy 45.044079 -42.529761) (xy 45.061128 -42.584654) (xy 45.069749 -42.641482)
			(xy 45.070268 -42.670222) (xy 45.069823 -42.697593) (xy 45.062001 -42.751773) (xy 45.046508 -42.804277)
			(xy 45.025951 -42.849038) (xy 46.891954 -42.849038) (xy 46.896025 -42.793416) (xy 46.908151 -42.738979)
			(xy 46.928074 -42.686888) (xy 46.95537 -42.638253) (xy 46.989456 -42.59411) (xy 47.029605 -42.555401)
			(xy 47.074963 -42.52295) (xy 47.124563 -42.497449) (xy 47.177347 -42.479442) (xy 47.23219 -42.469312)
			(xy 47.287924 -42.467275) (xy 47.343361 -42.473375) (xy 47.397318 -42.487481) (xy 47.448647 -42.509293)
			(xy 47.496253 -42.538347) (xy 47.539121 -42.574022) (xy 47.576338 -42.615559) (xy 47.607111 -42.662072)
			(xy 47.630783 -42.712569) (xy 47.646851 -42.765976) (xy 47.654971 -42.821152) (xy 47.655332 -42.84091)
			(xy 52.93309 -42.84091) (xy 52.937161 -42.785288) (xy 52.949287 -42.730851) (xy 52.96921 -42.67876)
			(xy 52.996506 -42.630125) (xy 53.030592 -42.585982) (xy 53.070741 -42.547273) (xy 53.116099 -42.514822)
			(xy 53.165699 -42.489321) (xy 53.218483 -42.471314) (xy 53.273326 -42.461184) (xy 53.32906 -42.459147)
			(xy 53.384497 -42.465247) (xy 53.438454 -42.479353) (xy 53.489783 -42.501165) (xy 53.537389 -42.530219)
			(xy 53.580257 -42.565894) (xy 53.617474 -42.607431) (xy 53.648247 -42.653944) (xy 53.671919 -42.704441)
			(xy 53.687987 -42.757848) (xy 53.696107 -42.813024) (xy 53.696616 -42.84091) (xy 53.696107 -42.868796)
			(xy 53.687987 -42.923972) (xy 53.671919 -42.977379) (xy 53.648247 -43.027876) (xy 53.617474 -43.074389)
			(xy 53.580257 -43.115926) (xy 53.537389 -43.151601) (xy 53.489783 -43.180655) (xy 53.438454 -43.202467)
			(xy 53.384497 -43.216573) (xy 53.32906 -43.222673) (xy 53.273326 -43.220636) (xy 53.218483 -43.210506)
			(xy 53.165699 -43.192499) (xy 53.116099 -43.166998) (xy 53.070741 -43.134547) (xy 53.030592 -43.095838)
			(xy 52.996506 -43.051695) (xy 52.96921 -43.00306) (xy 52.949287 -42.950969) (xy 52.937161 -42.896532)
			(xy 52.93309 -42.84091) (xy 47.655332 -42.84091) (xy 47.65548 -42.849038) (xy 47.654971 -42.876924)
			(xy 47.646851 -42.9321) (xy 47.630783 -42.985507) (xy 47.607111 -43.036004) (xy 47.576338 -43.082517)
			(xy 47.539121 -43.124054) (xy 47.496253 -43.159729) (xy 47.448647 -43.188783) (xy 47.397318 -43.210595)
			(xy 47.343361 -43.224701) (xy 47.287924 -43.230801) (xy 47.23219 -43.228764) (xy 47.177347 -43.218634)
			(xy 47.124563 -43.200627) (xy 47.074963 -43.175126) (xy 47.029605 -43.142675) (xy 46.989456 -43.103966)
			(xy 46.95537 -43.059823) (xy 46.928074 -43.011188) (xy 46.908151 -42.959097) (xy 46.896025 -42.90466)
			(xy 46.891954 -42.849038) (xy 45.025951 -42.849038) (xy 45.023661 -42.854024) (xy 44.993932 -42.899989)
			(xy 44.976288 -42.92092) (xy 44.976034 -42.921174) (xy 44.970444 -42.928258) (xy 44.964201 -42.945177)
			(xy 44.963842 -42.954194) (xy 44.963842 -43.02125) (xy 44.964214 -43.030266) (xy 44.97045 -43.047183)
			(xy 44.976034 -43.05427) (xy 44.976288 -43.05427) (xy 44.976288 -43.054524) (xy 44.993903 -43.075475)
			(xy 45.023619 -43.121443) (xy 45.04646 -43.171185) (xy 45.061956 -43.223682) (xy 45.069791 -43.277854)
			(xy 45.070268 -43.305222) (xy 45.069782 -43.332473) (xy 45.062026 -43.386421) (xy 45.046671 -43.438716)
			(xy 45.024029 -43.488293) (xy 44.994563 -43.534143) (xy 44.958872 -43.575334) (xy 44.917681 -43.611025)
			(xy 44.871831 -43.640491) (xy 44.822254 -43.663133) (xy 44.769959 -43.678488) (xy 44.716011 -43.686244)
			(xy 44.661509 -43.686244) (xy 44.607561 -43.678488) (xy 44.555266 -43.663133) (xy 44.505689 -43.640491)
			(xy 44.459839 -43.611025) (xy 44.418648 -43.575334) (xy 44.382957 -43.534143) (xy 44.353491 -43.488293)
			(xy 44.330849 -43.438716) (xy 44.315494 -43.386421) (xy 44.307738 -43.332473) (xy 44.307252 -43.305222)
			(xy 41.345555 -43.305222) (xy 41.255302 -43.73626) (xy 46.213012 -43.73626) (xy 46.217083 -43.680638)
			(xy 46.229209 -43.626201) (xy 46.249132 -43.57411) (xy 46.276428 -43.525475) (xy 46.310514 -43.481332)
			(xy 46.350663 -43.442623) (xy 46.396021 -43.410172) (xy 46.445621 -43.384671) (xy 46.498405 -43.366664)
			(xy 46.553248 -43.356534) (xy 46.608982 -43.354497) (xy 46.664419 -43.360597) (xy 46.718376 -43.374703)
			(xy 46.769705 -43.396515) (xy 46.817311 -43.425569) (xy 46.860179 -43.461244) (xy 46.897396 -43.502781)
			(xy 46.928169 -43.549294) (xy 46.951841 -43.599791) (xy 46.967909 -43.653198) (xy 46.976029 -43.708374)
			(xy 46.976538 -43.73626) (xy 46.976029 -43.764146) (xy 46.967909 -43.819322) (xy 46.9566 -43.85691)
			(xy 50.719734 -43.85691) (xy 50.723805 -43.801288) (xy 50.735931 -43.746851) (xy 50.755854 -43.69476)
			(xy 50.78315 -43.646125) (xy 50.817236 -43.601982) (xy 50.857385 -43.563273) (xy 50.902743 -43.530822)
			(xy 50.952343 -43.505321) (xy 51.005127 -43.487314) (xy 51.05997 -43.477184) (xy 51.115704 -43.475147)
			(xy 51.171141 -43.481247) (xy 51.225098 -43.495353) (xy 51.276427 -43.517165) (xy 51.324033 -43.546219)
			(xy 51.366901 -43.581894) (xy 51.404118 -43.623431) (xy 51.434891 -43.669944) (xy 51.458563 -43.720441)
			(xy 51.474631 -43.773848) (xy 51.482751 -43.829024) (xy 51.48326 -43.85691) (xy 51.482751 -43.884796)
			(xy 51.474631 -43.939972) (xy 51.458563 -43.993379) (xy 51.434891 -44.043876) (xy 51.404118 -44.090389)
			(xy 51.366901 -44.131926) (xy 51.324033 -44.167601) (xy 51.276427 -44.196655) (xy 51.225098 -44.218467)
			(xy 51.171141 -44.232573) (xy 51.115704 -44.238673) (xy 51.05997 -44.236636) (xy 51.005127 -44.226506)
			(xy 50.952343 -44.208499) (xy 50.902743 -44.182998) (xy 50.857385 -44.150547) (xy 50.817236 -44.111838)
			(xy 50.78315 -44.067695) (xy 50.755854 -44.01906) (xy 50.735931 -43.966969) (xy 50.723805 -43.912532)
			(xy 50.719734 -43.85691) (xy 46.9566 -43.85691) (xy 46.951841 -43.872729) (xy 46.928169 -43.923226)
			(xy 46.897396 -43.969739) (xy 46.860179 -44.011276) (xy 46.817311 -44.046951) (xy 46.769705 -44.076005)
			(xy 46.718376 -44.097817) (xy 46.664419 -44.111923) (xy 46.608982 -44.118023) (xy 46.553248 -44.115986)
			(xy 46.498405 -44.105856) (xy 46.445621 -44.087849) (xy 46.396021 -44.062348) (xy 46.350663 -44.029897)
			(xy 46.310514 -43.991188) (xy 46.276428 -43.947045) (xy 46.249132 -43.89841) (xy 46.229209 -43.846319)
			(xy 46.217083 -43.791882) (xy 46.213012 -43.73626) (xy 41.255302 -43.73626) (xy 41.177972 -44.105576)
			(xy 41.177972 -44.106592) (xy 40.987423 -45.114464) (xy 46.065438 -45.114464) (xy 46.069509 -45.058842)
			(xy 46.081635 -45.004405) (xy 46.101558 -44.952314) (xy 46.128854 -44.903679) (xy 46.16294 -44.859536)
			(xy 46.203089 -44.820827) (xy 46.248447 -44.788376) (xy 46.298047 -44.762875) (xy 46.350831 -44.744868)
			(xy 46.405674 -44.734738) (xy 46.461408 -44.732701) (xy 46.516845 -44.738801) (xy 46.570802 -44.752907)
			(xy 46.622131 -44.774719) (xy 46.669737 -44.803773) (xy 46.712605 -44.839448) (xy 46.742587 -44.87291)
			(xy 52.93309 -44.87291) (xy 52.937161 -44.817288) (xy 52.949287 -44.762851) (xy 52.96921 -44.71076)
			(xy 52.996506 -44.662125) (xy 53.030592 -44.617982) (xy 53.070741 -44.579273) (xy 53.116099 -44.546822)
			(xy 53.165699 -44.521321) (xy 53.218483 -44.503314) (xy 53.273326 -44.493184) (xy 53.32906 -44.491147)
			(xy 53.384497 -44.497247) (xy 53.438454 -44.511353) (xy 53.489783 -44.533165) (xy 53.537389 -44.562219)
			(xy 53.580257 -44.597894) (xy 53.617474 -44.639431) (xy 53.648247 -44.685944) (xy 53.671919 -44.736441)
			(xy 53.687987 -44.789848) (xy 53.696107 -44.845024) (xy 53.696616 -44.87291) (xy 53.696107 -44.900796)
			(xy 53.687987 -44.955972) (xy 53.671919 -45.009379) (xy 53.648247 -45.059876) (xy 53.617474 -45.106389)
			(xy 53.580257 -45.147926) (xy 53.537389 -45.183601) (xy 53.489783 -45.212655) (xy 53.438454 -45.234467)
			(xy 53.384497 -45.248573) (xy 53.32906 -45.254673) (xy 53.273326 -45.252636) (xy 53.218483 -45.242506)
			(xy 53.165699 -45.224499) (xy 53.116099 -45.198998) (xy 53.070741 -45.166547) (xy 53.030592 -45.127838)
			(xy 52.996506 -45.083695) (xy 52.96921 -45.03506) (xy 52.949287 -44.982969) (xy 52.937161 -44.928532)
			(xy 52.93309 -44.87291) (xy 46.742587 -44.87291) (xy 46.749822 -44.880985) (xy 46.780595 -44.927498)
			(xy 46.804267 -44.977995) (xy 46.820335 -45.031402) (xy 46.828455 -45.086578) (xy 46.828964 -45.114464)
			(xy 46.828455 -45.14235) (xy 46.820335 -45.197526) (xy 46.804267 -45.250933) (xy 46.780595 -45.30143)
			(xy 46.749822 -45.347943) (xy 46.74418 -45.35424) (xy 50.703732 -45.35424) (xy 50.707803 -45.298618)
			(xy 50.719929 -45.244181) (xy 50.739852 -45.19209) (xy 50.767148 -45.143455) (xy 50.801234 -45.099312)
			(xy 50.841383 -45.060603) (xy 50.886741 -45.028152) (xy 50.936341 -45.002651) (xy 50.989125 -44.984644)
			(xy 51.043968 -44.974514) (xy 51.099702 -44.972477) (xy 51.155139 -44.978577) (xy 51.209096 -44.992683)
			(xy 51.260425 -45.014495) (xy 51.308031 -45.043549) (xy 51.350899 -45.079224) (xy 51.388116 -45.120761)
			(xy 51.418889 -45.167274) (xy 51.442561 -45.217771) (xy 51.458629 -45.271178) (xy 51.466749 -45.326354)
			(xy 51.467258 -45.35424) (xy 51.466749 -45.382126) (xy 51.458629 -45.437302) (xy 51.442561 -45.490709)
			(xy 51.418889 -45.541206) (xy 51.388116 -45.587719) (xy 51.350899 -45.629256) (xy 51.308031 -45.664931)
			(xy 51.260425 -45.693985) (xy 51.209096 -45.715797) (xy 51.155139 -45.729903) (xy 51.099702 -45.736003)
			(xy 51.043968 -45.733966) (xy 50.989125 -45.723836) (xy 50.936341 -45.705829) (xy 50.886741 -45.680328)
			(xy 50.841383 -45.647877) (xy 50.801234 -45.609168) (xy 50.767148 -45.565025) (xy 50.739852 -45.51639)
			(xy 50.719929 -45.464299) (xy 50.707803 -45.409862) (xy 50.703732 -45.35424) (xy 46.74418 -45.35424)
			(xy 46.712605 -45.38948) (xy 46.669737 -45.425155) (xy 46.622131 -45.454209) (xy 46.570802 -45.476021)
			(xy 46.516845 -45.490127) (xy 46.461408 -45.496227) (xy 46.405674 -45.49419) (xy 46.350831 -45.48406)
			(xy 46.298047 -45.466053) (xy 46.248447 -45.440552) (xy 46.203089 -45.408101) (xy 46.16294 -45.369392)
			(xy 46.128854 -45.325249) (xy 46.101558 -45.276614) (xy 46.081635 -45.224523) (xy 46.069509 -45.170086)
			(xy 46.065438 -45.114464) (xy 40.987423 -45.114464) (xy 40.804462 -46.082204) (xy 44.05249 -46.082204)
			(xy 44.052959 -46.054951) (xy 44.060715 -46.001001) (xy 44.076071 -45.948703) (xy 44.098713 -45.899123)
			(xy 44.12818 -45.85327) (xy 44.163873 -45.812077) (xy 44.205065 -45.776384) (xy 44.250918 -45.746916)
			(xy 44.300497 -45.724273) (xy 44.352795 -45.708917) (xy 44.406745 -45.701159) (xy 44.433998 -45.700696)
			(xy 44.460901 -45.70116) (xy 44.51417 -45.708731) (xy 44.565849 -45.72371) (xy 44.61491 -45.7458)
			(xy 44.660383 -45.774562) (xy 44.701364 -45.809427) (xy 44.737042 -45.849702) (xy 44.75226 -45.871892)
			(xy 44.759372 -45.882814) (xy 44.782232 -45.894752) (xy 44.8945 -45.89272) (xy 44.916852 -45.879766)
			(xy 44.92371 -45.86859) (xy 44.938638 -45.844993) (xy 44.974316 -45.802041) (xy 45.015873 -45.764748)
			(xy 45.062422 -45.73391) (xy 45.112969 -45.710186) (xy 45.166433 -45.694082) (xy 45.221674 -45.685943)
			(xy 45.249592 -45.685456) (xy 45.276585 -45.685922) (xy 45.330033 -45.693527) (xy 45.381876 -45.708586)
			(xy 45.431081 -45.730799) (xy 45.476665 -45.759722) (xy 45.497496 -45.776896) (xy 45.505624 -45.784008)
			(xy 45.526198 -45.790104) (xy 45.611542 -45.779182) (xy 45.622082 -45.777389) (xy 45.640367 -45.766348)
			(xy 45.646848 -45.757846) (xy 45.662178 -45.736598) (xy 45.697769 -45.698145) (xy 45.73829 -45.664928)
			(xy 45.782977 -45.637572) (xy 45.830989 -45.616591) (xy 45.881421 -45.602382) (xy 45.933324 -45.595211)
			(xy 45.959522 -45.594778) (xy 45.986771 -45.595294) (xy 46.040714 -45.603053) (xy 46.093005 -45.618409)
			(xy 46.142577 -45.64105) (xy 46.188423 -45.670516) (xy 46.229609 -45.706206) (xy 46.265297 -45.747395)
			(xy 46.29476 -45.793242) (xy 46.317399 -45.842816) (xy 46.332752 -45.895107) (xy 46.340508 -45.949051)
			(xy 46.340508 -46.003549) (xy 46.332752 -46.057493) (xy 46.317399 -46.109784) (xy 46.29476 -46.159358)
			(xy 46.265297 -46.205205) (xy 46.229609 -46.246394) (xy 46.188423 -46.282084) (xy 46.142577 -46.31155)
			(xy 46.093005 -46.334191) (xy 46.040714 -46.349547) (xy 45.986771 -46.357306) (xy 45.959522 -46.357794)
			(xy 45.93253 -46.357308) (xy 45.879083 -46.349706) (xy 45.82724 -46.334651) (xy 45.778035 -46.312443)
			(xy 45.73245 -46.283525) (xy 45.711618 -46.266354) (xy 45.70349 -46.259242) (xy 45.682916 -46.253146)
			(xy 45.597572 -46.264068) (xy 45.587026 -46.265836) (xy 45.568745 -46.276896) (xy 45.562266 -46.285404)
			(xy 45.544654 -46.309705) (xy 45.503058 -46.352964) (xy 45.479462 -46.37151) (xy 45.471588 -46.377352)
			(xy 45.461174 -46.394878) (xy 45.447966 -46.485302) (xy 45.452792 -46.504606) (xy 45.458634 -46.51248)
			(xy 45.458634 -46.512734) (xy 45.476132 -46.537482) (xy 45.503937 -46.591333) (xy 45.522875 -46.648904)
			(xy 45.530078 -46.693836) (xy 50.676302 -46.693836) (xy 50.676788 -46.666585) (xy 50.684544 -46.612637)
			(xy 50.699899 -46.560342) (xy 50.722541 -46.510765) (xy 50.752007 -46.464915) (xy 50.787698 -46.423724)
			(xy 50.828889 -46.388033) (xy 50.874739 -46.358567) (xy 50.924316 -46.335925) (xy 50.976611 -46.32057)
			(xy 51.030559 -46.312814) (xy 51.085061 -46.312814) (xy 51.139009 -46.32057) (xy 51.191304 -46.335925)
			(xy 51.240881 -46.358567) (xy 51.286731 -46.388033) (xy 51.327922 -46.423724) (xy 51.363613 -46.464915)
			(xy 51.393079 -46.510765) (xy 51.415721 -46.560342) (xy 51.431076 -46.612637) (xy 51.438832 -46.666585)
			(xy 51.439318 -46.693836) (xy 51.438843 -46.720263) (xy 51.431534 -46.772611) (xy 51.417061 -46.823446)
			(xy 51.395702 -46.871793) (xy 51.382168 -46.894496) (xy 51.381914 -46.89475) (xy 51.376577 -46.904768)
			(xy 51.374321 -46.927318) (xy 51.377596 -46.938184) (xy 51.403758 -47.01286) (xy 51.408139 -47.023377)
			(xy 51.42423 -47.039465) (xy 51.434746 -47.043848) (xy 51.435 -47.043848) (xy 51.459499 -47.052944)
			(xy 51.505952 -47.076881) (xy 51.548706 -47.106932) (xy 51.586959 -47.142535) (xy 51.619998 -47.183025)
			(xy 51.647203 -47.227643) (xy 51.668066 -47.275556) (xy 51.682197 -47.325868) (xy 51.689331 -47.377637)
			(xy 51.689762 -47.403766) (xy 51.689276 -47.431017) (xy 51.687753 -47.441612) (xy 52.961792 -47.441612)
			(xy 52.965863 -47.38599) (xy 52.977989 -47.331553) (xy 52.997912 -47.279462) (xy 53.025208 -47.230827)
			(xy 53.059294 -47.186684) (xy 53.099443 -47.147975) (xy 53.144801 -47.115524) (xy 53.194401 -47.090023)
			(xy 53.247185 -47.072016) (xy 53.302028 -47.061886) (xy 53.357762 -47.059849) (xy 53.413199 -47.065949)
			(xy 53.467156 -47.080055) (xy 53.518485 -47.101867) (xy 53.566091 -47.130921) (xy 53.608959 -47.166596)
			(xy 53.646176 -47.208133) (xy 53.676949 -47.254646) (xy 53.700621 -47.305143) (xy 53.716689 -47.35855)
			(xy 53.724809 -47.413726) (xy 53.725318 -47.441612) (xy 53.724809 -47.469498) (xy 53.716689 -47.524674)
			(xy 53.700621 -47.578081) (xy 53.676949 -47.628578) (xy 53.646176 -47.675091) (xy 53.608959 -47.716628)
			(xy 53.566091 -47.752303) (xy 53.518485 -47.781357) (xy 53.467156 -47.803169) (xy 53.413199 -47.817275)
			(xy 53.357762 -47.823375) (xy 53.302028 -47.821338) (xy 53.247185 -47.811208) (xy 53.194401 -47.793201)
			(xy 53.144801 -47.7677) (xy 53.099443 -47.735249) (xy 53.059294 -47.69654) (xy 53.025208 -47.652397)
			(xy 52.997912 -47.603762) (xy 52.977989 -47.551671) (xy 52.965863 -47.497234) (xy 52.961792 -47.441612)
			(xy 51.687753 -47.441612) (xy 51.68152 -47.484965) (xy 51.666165 -47.53726) (xy 51.643523 -47.586837)
			(xy 51.614057 -47.632687) (xy 51.578366 -47.673878) (xy 51.537175 -47.709569) (xy 51.491325 -47.739035)
			(xy 51.441748 -47.761677) (xy 51.389453 -47.777032) (xy 51.335505 -47.784788) (xy 51.281003 -47.784788)
			(xy 51.227055 -47.777032) (xy 51.17476 -47.761677) (xy 51.125183 -47.739035) (xy 51.079333 -47.709569)
			(xy 51.038142 -47.673878) (xy 51.002451 -47.632687) (xy 50.972985 -47.586837) (xy 50.950343 -47.53726)
			(xy 50.934988 -47.484965) (xy 50.927232 -47.431017) (xy 50.926746 -47.403766) (xy 50.927213 -47.377338)
			(xy 50.934523 -47.32499) (xy 50.948998 -47.274155) (xy 50.97036 -47.225809) (xy 50.983896 -47.203106)
			(xy 50.98415 -47.202852) (xy 50.989485 -47.192834) (xy 50.991744 -47.170284) (xy 50.988468 -47.159418)
			(xy 50.962306 -47.084742) (xy 50.95794 -47.074217) (xy 50.941839 -47.058132) (xy 50.931318 -47.053754)
			(xy 50.931064 -47.053754) (xy 50.906558 -47.044677) (xy 50.860105 -47.020736) (xy 50.817353 -46.990681)
			(xy 50.779101 -46.955075) (xy 50.746064 -46.914583) (xy 50.71886 -46.869963) (xy 50.697998 -46.822048)
			(xy 50.683867 -46.771736) (xy 50.676733 -46.719966) (xy 50.676302 -46.693836) (xy 45.530078 -46.693836)
			(xy 45.532468 -46.708745) (xy 45.533056 -46.739048) (xy 45.532567 -46.766298) (xy 45.524805 -46.820243)
			(xy 45.509446 -46.872535) (xy 45.486803 -46.922109) (xy 45.457336 -46.967957) (xy 45.421646 -47.009146)
			(xy 45.380457 -47.044836) (xy 45.334609 -47.074303) (xy 45.285035 -47.096946) (xy 45.232743 -47.112305)
			(xy 45.178798 -47.120067) (xy 45.151548 -47.120556) (xy 45.125514 -47.120131) (xy 45.07393 -47.113038)
			(xy 45.023788 -47.099003) (xy 44.976018 -47.078287) (xy 44.931504 -47.051274) (xy 44.91101 -47.035212)
			(xy 44.903257 -47.029464) (xy 44.884843 -47.023727) (xy 44.875196 -47.024036) (xy 44.79544 -47.030386)
			(xy 44.77766 -47.039022) (xy 44.77131 -47.046388) (xy 44.753147 -47.066051) (xy 44.712235 -47.100572)
			(xy 44.666903 -47.129039) (xy 44.618038 -47.150893) (xy 44.566599 -47.165707) (xy 44.513595 -47.173189)
			(xy 44.48683 -47.173642) (xy 44.459581 -47.173094) (xy 44.405637 -47.165342) (xy 44.353346 -47.149993)
			(xy 44.303771 -47.127358) (xy 44.257922 -47.097898) (xy 44.216733 -47.062213) (xy 44.181041 -47.021029)
			(xy 44.151573 -46.975185) (xy 44.12893 -46.925614) (xy 44.113571 -46.873325) (xy 44.105811 -46.819383)
			(xy 44.105322 -46.792134) (xy 44.105841 -46.76336) (xy 44.114492 -46.706465) (xy 44.13159 -46.651514)
			(xy 44.156745 -46.599754) (xy 44.189387 -46.552358) (xy 44.2087 -46.531022) (xy 44.216066 -46.523148)
			(xy 44.223178 -46.503336) (xy 44.215812 -46.40707) (xy 44.205906 -46.388274) (xy 44.197524 -46.38167)
			(xy 44.17534 -46.363444) (xy 44.13613 -46.321509) (xy 44.103644 -46.274174) (xy 44.078615 -46.222506)
			(xy 44.061609 -46.167672) (xy 44.053008 -46.110909) (xy 44.05249 -46.082204) (xy 40.804462 -46.082204)
			(xy 40.643302 -46.934628) (xy 40.383906 -48.30699) (xy 50.553872 -48.30699) (xy 50.557943 -48.251368)
			(xy 50.570069 -48.196931) (xy 50.589992 -48.14484) (xy 50.617288 -48.096205) (xy 50.651374 -48.052062)
			(xy 50.691523 -48.013353) (xy 50.736881 -47.980902) (xy 50.786481 -47.955401) (xy 50.839265 -47.937394)
			(xy 50.894108 -47.927264) (xy 50.949842 -47.925227) (xy 51.005279 -47.931327) (xy 51.059236 -47.945433)
			(xy 51.110565 -47.967245) (xy 51.158171 -47.996299) (xy 51.201039 -48.031974) (xy 51.238256 -48.073511)
			(xy 51.269029 -48.120024) (xy 51.292701 -48.170521) (xy 51.308769 -48.223928) (xy 51.316889 -48.279104)
			(xy 51.317398 -48.30699) (xy 51.316889 -48.334876) (xy 51.308769 -48.390052) (xy 51.292701 -48.443459)
			(xy 51.269029 -48.493956) (xy 51.238256 -48.540469) (xy 51.201039 -48.582006) (xy 51.158171 -48.617681)
			(xy 51.110565 -48.646735) (xy 51.059236 -48.668547) (xy 51.005279 -48.682653) (xy 50.949842 -48.688753)
			(xy 50.894108 -48.686716) (xy 50.839265 -48.676586) (xy 50.786481 -48.658579) (xy 50.736881 -48.633078)
			(xy 50.691523 -48.600627) (xy 50.651374 -48.561918) (xy 50.617288 -48.517775) (xy 50.589992 -48.46914)
			(xy 50.570069 -48.417049) (xy 50.557943 -48.362612) (xy 50.553872 -48.30699) (xy 40.383906 -48.30699)
			(xy 40.37584 -48.349662) (xy 40.299595 -48.753014) (xy 47.168306 -48.753014) (xy 47.172377 -48.697392)
			(xy 47.184503 -48.642955) (xy 47.204426 -48.590864) (xy 47.231722 -48.542229) (xy 47.265808 -48.498086)
			(xy 47.305957 -48.459377) (xy 47.351315 -48.426926) (xy 47.400915 -48.401425) (xy 47.453699 -48.383418)
			(xy 47.508542 -48.373288) (xy 47.564276 -48.371251) (xy 47.619713 -48.377351) (xy 47.67367 -48.391457)
			(xy 47.724999 -48.413269) (xy 47.772605 -48.442323) (xy 47.815473 -48.477998) (xy 47.85269 -48.519535)
			(xy 47.883463 -48.566048) (xy 47.907135 -48.616545) (xy 47.923203 -48.669952) (xy 47.931323 -48.725128)
			(xy 47.931832 -48.753014) (xy 47.931323 -48.7809) (xy 47.923203 -48.836076) (xy 47.907135 -48.889483)
			(xy 47.905739 -48.89246) (xy 49.214022 -48.89246) (xy 49.218093 -48.836838) (xy 49.230219 -48.782401)
			(xy 49.250142 -48.73031) (xy 49.277438 -48.681675) (xy 49.311524 -48.637532) (xy 49.351673 -48.598823)
			(xy 49.397031 -48.566372) (xy 49.446631 -48.540871) (xy 49.499415 -48.522864) (xy 49.554258 -48.512734)
			(xy 49.609992 -48.510697) (xy 49.665429 -48.516797) (xy 49.719386 -48.530903) (xy 49.770715 -48.552715)
			(xy 49.818321 -48.581769) (xy 49.861189 -48.617444) (xy 49.898406 -48.658981) (xy 49.929179 -48.705494)
			(xy 49.952851 -48.755991) (xy 49.968919 -48.809398) (xy 49.977039 -48.864574) (xy 49.977548 -48.89246)
			(xy 49.977039 -48.920346) (xy 49.974601 -48.93691) (xy 52.93309 -48.93691) (xy 52.937161 -48.881288)
			(xy 52.949287 -48.826851) (xy 52.96921 -48.77476) (xy 52.996506 -48.726125) (xy 53.030592 -48.681982)
			(xy 53.070741 -48.643273) (xy 53.116099 -48.610822) (xy 53.165699 -48.585321) (xy 53.218483 -48.567314)
			(xy 53.273326 -48.557184) (xy 53.32906 -48.555147) (xy 53.384497 -48.561247) (xy 53.438454 -48.575353)
			(xy 53.489783 -48.597165) (xy 53.537389 -48.626219) (xy 53.580257 -48.661894) (xy 53.617474 -48.703431)
			(xy 53.648247 -48.749944) (xy 53.671919 -48.800441) (xy 53.687987 -48.853848) (xy 53.696107 -48.909024)
			(xy 53.696616 -48.93691) (xy 53.696107 -48.964796) (xy 53.687987 -49.019972) (xy 53.671919 -49.073379)
			(xy 53.648247 -49.123876) (xy 53.617474 -49.170389) (xy 53.580257 -49.211926) (xy 53.537389 -49.247601)
			(xy 53.489783 -49.276655) (xy 53.438454 -49.298467) (xy 53.384497 -49.312573) (xy 53.32906 -49.318673)
			(xy 53.273326 -49.316636) (xy 53.218483 -49.306506) (xy 53.165699 -49.288499) (xy 53.116099 -49.262998)
			(xy 53.070741 -49.230547) (xy 53.030592 -49.191838) (xy 52.996506 -49.147695) (xy 52.96921 -49.09906)
			(xy 52.949287 -49.046969) (xy 52.937161 -48.992532) (xy 52.93309 -48.93691) (xy 49.974601 -48.93691)
			(xy 49.968919 -48.975522) (xy 49.952851 -49.028929) (xy 49.929179 -49.079426) (xy 49.898406 -49.125939)
			(xy 49.861189 -49.167476) (xy 49.818321 -49.203151) (xy 49.770715 -49.232205) (xy 49.719386 -49.254017)
			(xy 49.665429 -49.268123) (xy 49.609992 -49.274223) (xy 49.554258 -49.272186) (xy 49.499415 -49.262056)
			(xy 49.446631 -49.244049) (xy 49.397031 -49.218548) (xy 49.351673 -49.186097) (xy 49.311524 -49.147388)
			(xy 49.277438 -49.103245) (xy 49.250142 -49.05461) (xy 49.230219 -49.002519) (xy 49.218093 -48.948082)
			(xy 49.214022 -48.89246) (xy 47.905739 -48.89246) (xy 47.883463 -48.93998) (xy 47.85269 -48.986493)
			(xy 47.815473 -49.02803) (xy 47.772605 -49.063705) (xy 47.724999 -49.092759) (xy 47.67367 -49.114571)
			(xy 47.619713 -49.128677) (xy 47.564276 -49.134777) (xy 47.508542 -49.13274) (xy 47.453699 -49.12261)
			(xy 47.400915 -49.104603) (xy 47.351315 -49.079102) (xy 47.305957 -49.046651) (xy 47.265808 -49.007942)
			(xy 47.231722 -48.963799) (xy 47.204426 -48.915164) (xy 47.184503 -48.863073) (xy 47.172377 -48.808636)
			(xy 47.168306 -48.753014) (xy 40.299595 -48.753014) (xy 40.183308 -49.368202) (xy 40.1574 -49.504854)
			(xy 40.156638 -49.51349) (xy 40.149788 -49.95291) (xy 52.93309 -49.95291) (xy 52.937161 -49.897288)
			(xy 52.949287 -49.842851) (xy 52.96921 -49.79076) (xy 52.996506 -49.742125) (xy 53.030592 -49.697982)
			(xy 53.070741 -49.659273) (xy 53.116099 -49.626822) (xy 53.165699 -49.601321) (xy 53.218483 -49.583314)
			(xy 53.273326 -49.573184) (xy 53.32906 -49.571147) (xy 53.384497 -49.577247) (xy 53.438454 -49.591353)
			(xy 53.489783 -49.613165) (xy 53.537389 -49.642219) (xy 53.580257 -49.677894) (xy 53.617474 -49.719431)
			(xy 53.648247 -49.765944) (xy 53.671919 -49.816441) (xy 53.687987 -49.869848) (xy 53.696107 -49.925024)
			(xy 53.696616 -49.95291) (xy 53.696107 -49.980796) (xy 53.687987 -50.035972) (xy 53.671919 -50.089379)
			(xy 53.648247 -50.139876) (xy 53.617474 -50.186389) (xy 53.580257 -50.227926) (xy 53.537389 -50.263601)
			(xy 53.489783 -50.292655) (xy 53.438454 -50.314467) (xy 53.384497 -50.328573) (xy 53.32906 -50.334673)
			(xy 53.273326 -50.332636) (xy 53.218483 -50.322506) (xy 53.165699 -50.304499) (xy 53.116099 -50.278998)
			(xy 53.070741 -50.246547) (xy 53.030592 -50.207838) (xy 52.996506 -50.163695) (xy 52.96921 -50.11506)
			(xy 52.949287 -50.062969) (xy 52.937161 -50.008532) (xy 52.93309 -49.95291) (xy 40.149788 -49.95291)
			(xy 40.133162 -51.019456) (xy 50.749452 -51.019456) (xy 50.753523 -50.963834) (xy 50.765649 -50.909397)
			(xy 50.785572 -50.857306) (xy 50.812868 -50.808671) (xy 50.846954 -50.764528) (xy 50.887103 -50.725819)
			(xy 50.932461 -50.693368) (xy 50.982061 -50.667867) (xy 51.034845 -50.64986) (xy 51.089688 -50.63973)
			(xy 51.145422 -50.637693) (xy 51.200859 -50.643793) (xy 51.254816 -50.657899) (xy 51.306145 -50.679711)
			(xy 51.353751 -50.708765) (xy 51.396619 -50.74444) (xy 51.433836 -50.785977) (xy 51.464609 -50.83249)
			(xy 51.488281 -50.882987) (xy 51.504349 -50.936394) (xy 51.512469 -50.99157) (xy 51.512978 -51.019456)
			(xy 51.512469 -51.047342) (xy 51.504349 -51.102518) (xy 51.488281 -51.155925) (xy 51.464609 -51.206422)
			(xy 51.439753 -51.243992) (xy 59.132978 -51.243992) (xy 59.13342 -51.216621) (xy 59.141241 -51.16244)
			(xy 59.156735 -51.109936) (xy 59.179582 -51.060189) (xy 59.209313 -51.014224) (xy 59.226958 -50.993294)
			(xy 59.227212 -50.99304) (xy 59.232789 -50.985947) (xy 59.239041 -50.969035) (xy 59.239404 -50.96002)
			(xy 59.239404 -50.892964) (xy 59.239063 -50.883946) (xy 59.232804 -50.867029) (xy 59.227212 -50.859944)
			(xy 59.226958 -50.859944) (xy 59.226958 -50.85969) (xy 59.209294 -50.838778) (xy 59.179587 -50.792799)
			(xy 59.156757 -50.743046) (xy 59.141271 -50.690542) (xy 59.133449 -50.636362) (xy 59.132978 -50.608992)
			(xy 59.13347 -50.581741) (xy 59.141228 -50.527794) (xy 59.156583 -50.475501) (xy 59.179224 -50.425924)
			(xy 59.20869 -50.380075) (xy 59.244381 -50.338885) (xy 59.28557 -50.303193) (xy 59.331419 -50.273727)
			(xy 59.380995 -50.251085) (xy 59.433289 -50.235729) (xy 59.487235 -50.227971) (xy 59.514486 -50.227484)
			(xy 59.543404 -50.22798) (xy 59.600578 -50.236709) (xy 59.655778 -50.25397) (xy 59.707741 -50.279365)
			(xy 59.755274 -50.312314) (xy 59.797288 -50.352061) (xy 59.815476 -50.37455) (xy 59.823095 -50.383345)
			(xy 59.843987 -50.393533) (xy 59.855608 -50.394108) (xy 59.935364 -50.394108) (xy 59.946998 -50.393588)
			(xy 59.967907 -50.383385) (xy 59.975496 -50.37455) (xy 59.993677 -50.352058) (xy 60.0357 -50.312326)
			(xy 60.083238 -50.279389) (xy 60.135201 -50.254003) (xy 60.190399 -50.236748) (xy 60.24757 -50.228019)
			(xy 60.276486 -50.227484) (xy 60.303738 -50.227968) (xy 60.357688 -50.235723) (xy 60.409985 -50.251077)
			(xy 60.459564 -50.273717) (xy 60.505417 -50.303183) (xy 60.54661 -50.338875) (xy 60.582304 -50.380065)
			(xy 60.611772 -50.425916) (xy 60.634415 -50.475495) (xy 60.649772 -50.527791) (xy 60.65753 -50.58174)
			(xy 60.657994 -50.608992) (xy 60.657523 -50.635306) (xy 60.650289 -50.687434) (xy 60.635971 -50.738077)
			(xy 60.614839 -50.786276) (xy 60.587294 -50.83112) (xy 60.553855 -50.871759) (xy 60.534804 -50.889916)
			(xy 60.527394 -50.89743) (xy 60.518874 -50.916716) (xy 60.518294 -50.927254) (xy 60.518294 -51.00193)
			(xy 60.518849 -51.012477) (xy 60.527366 -51.031772) (xy 60.534804 -51.039268) (xy 60.553886 -51.057397)
			(xy 60.587341 -51.098032) (xy 60.614896 -51.142878) (xy 60.63603 -51.191084) (xy 60.650342 -51.241736)
			(xy 60.657559 -51.293874) (xy 60.657994 -51.320192) (xy 60.657537 -51.347445) (xy 60.649781 -51.401397)
			(xy 60.634425 -51.453696) (xy 60.611783 -51.503277) (xy 60.582314 -51.549131) (xy 60.54662 -51.590324)
			(xy 60.505426 -51.626018) (xy 60.459572 -51.655486) (xy 60.40999 -51.678127) (xy 60.357691 -51.693482)
			(xy 60.303739 -51.701238) (xy 60.276486 -51.7017) (xy 60.248821 -51.701199) (xy 60.194071 -51.693198)
			(xy 60.141049 -51.677379) (xy 60.090865 -51.654074) (xy 60.044569 -51.623771) (xy 60.003131 -51.587105)
			(xy 59.967419 -51.544842) (xy 59.952382 -51.521614) (xy 59.945763 -51.511923) (xy 59.925889 -51.499487)
			(xy 59.914282 -51.497738) (xy 59.834272 -51.489864) (xy 59.822633 -51.489219) (xy 59.800795 -51.497308)
			(xy 59.792362 -51.505358) (xy 59.792108 -51.505612) (xy 59.774008 -51.524174) (xy 59.73368 -51.556754)
			(xy 59.68931 -51.583569) (xy 59.641715 -51.604125) (xy 59.591774 -51.618043) (xy 59.540408 -51.625065)
			(xy 59.514486 -51.6255) (xy 59.487234 -51.625035) (xy 59.433285 -51.617277) (xy 59.38099 -51.601919)
			(xy 59.331412 -51.579276) (xy 59.285561 -51.549807) (xy 59.244371 -51.514114) (xy 59.208679 -51.472921)
			(xy 59.179214 -51.427069) (xy 59.156573 -51.37749) (xy 59.141219 -51.325193) (xy 59.133463 -51.271244)
			(xy 59.132978 -51.243992) (xy 51.439753 -51.243992) (xy 51.433836 -51.252935) (xy 51.396619 -51.294472)
			(xy 51.353751 -51.330147) (xy 51.306145 -51.359201) (xy 51.254816 -51.381013) (xy 51.200859 -51.395119)
			(xy 51.145422 -51.401219) (xy 51.089688 -51.399182) (xy 51.034845 -51.389052) (xy 50.982061 -51.371045)
			(xy 50.932461 -51.345544) (xy 50.887103 -51.313093) (xy 50.846954 -51.274384) (xy 50.812868 -51.230241)
			(xy 50.785572 -51.181606) (xy 50.765649 -51.129515) (xy 50.753523 -51.075078) (xy 50.749452 -51.019456)
			(xy 40.133162 -51.019456) (xy 40.117324 -52.035456) (xy 52.941218 -52.035456) (xy 52.945289 -51.979834)
			(xy 52.957415 -51.925397) (xy 52.977338 -51.873306) (xy 53.004634 -51.824671) (xy 53.03872 -51.780528)
			(xy 53.078869 -51.741819) (xy 53.124227 -51.709368) (xy 53.173827 -51.683867) (xy 53.226611 -51.66586)
			(xy 53.281454 -51.65573) (xy 53.337188 -51.653693) (xy 53.392625 -51.659793) (xy 53.446582 -51.673899)
			(xy 53.497911 -51.695711) (xy 53.545517 -51.724765) (xy 53.588385 -51.76044) (xy 53.625602 -51.801977)
			(xy 53.656375 -51.84849) (xy 53.680047 -51.898987) (xy 53.696115 -51.952394) (xy 53.704235 -52.00757)
			(xy 53.704744 -52.035456) (xy 53.704235 -52.063342) (xy 53.696115 -52.118518) (xy 53.680047 -52.171925)
			(xy 53.656375 -52.222422) (xy 53.625602 -52.268935) (xy 53.588385 -52.310472) (xy 53.545517 -52.346147)
			(xy 53.497911 -52.375201) (xy 53.446582 -52.397013) (xy 53.392625 -52.411119) (xy 53.337188 -52.417219)
			(xy 53.281454 -52.415182) (xy 53.226611 -52.405052) (xy 53.173827 -52.387045) (xy 53.124227 -52.361544)
			(xy 53.078869 -52.329093) (xy 53.03872 -52.290384) (xy 53.004634 -52.246241) (xy 52.977338 -52.197606)
			(xy 52.957415 -52.145515) (xy 52.945289 -52.091078) (xy 52.941218 -52.035456) (xy 40.117324 -52.035456)
			(xy 40.11041 -52.47894) (xy 40.110455 -52.484922) (xy 40.113023 -52.496604) (xy 40.11549 -52.502054)
			(xy 40.11803 -52.507388) (xy 40.12565 -52.516532) (xy 40.13073 -52.520342) (xy 40.152078 -52.536919)
			(xy 40.190337 -52.575095) (xy 40.222836 -52.618281) (xy 40.248926 -52.665615) (xy 40.268087 -52.716153)
			(xy 40.279936 -52.768887) (xy 40.284237 -52.822764) (xy 40.280904 -52.876709) (xy 40.270004 -52.929647)
			(xy 40.251754 -52.980521) (xy 40.226518 -53.028316) (xy 40.210994 -53.05044) (xy 40.204644 -53.059076)
			(xy 40.200834 -53.063902) (xy 40.1955 -53.072538) (xy 40.194992 -53.073554) (xy 40.192533 -53.07888)
			(xy 40.189843 -53.090296) (xy 40.189658 -53.09616) (xy 40.189658 -53.117242) (xy 40.189513 -53.122681)
			(xy 40.187202 -53.133311) (xy 40.185086 -53.138324) (xy 40.17899 -53.151786) (xy 40.175368 -53.160448)
			(xy 40.174134 -53.179169) (xy 40.179763 -53.197066) (xy 40.18534 -53.204618) (xy 40.190928 -53.21173)
			(xy 40.194484 -53.216302) (xy 40.194992 -53.217064) (xy 40.1955 -53.217572) (xy 40.196262 -53.218588)
			(xy 40.212451 -53.238851) (xy 40.239777 -53.282933) (xy 40.260874 -53.330313) (xy 40.275352 -53.380116)
			(xy 40.282944 -53.431422) (xy 40.283638 -53.457348) (xy 40.283638 -53.460396) (xy 40.283302 -53.48578)
			(xy 40.276736 -53.536119) (xy 40.263559 -53.585144) (xy 40.254174 -53.608732) (xy 40.254174 -53.608986)
			(xy 40.252904 -53.611526) (xy 40.244257 -53.630985) (xy 40.223252 -53.668028) (xy 40.210994 -53.68544)
			(xy 40.204898 -53.693822) (xy 40.200326 -53.699664) (xy 40.196008 -53.706522) (xy 40.194992 -53.708554)
			(xy 40.192533 -53.71388) (xy 40.189843 -53.725296) (xy 40.189658 -53.73116) (xy 40.189658 -53.752242)
			(xy 40.189513 -53.757681) (xy 40.187202 -53.768311) (xy 40.185086 -53.773324) (xy 40.17899 -53.786786)
			(xy 40.175368 -53.795448) (xy 40.174134 -53.814169) (xy 40.179763 -53.832066) (xy 40.18534 -53.839618)
			(xy 40.190928 -53.84673) (xy 40.194484 -53.851302) (xy 40.194992 -53.852064) (xy 40.1955 -53.852572)
			(xy 40.196262 -53.853588) (xy 40.212451 -53.873851) (xy 40.239777 -53.917933) (xy 40.260874 -53.965313)
			(xy 40.275352 -54.015116) (xy 40.282944 -54.066422) (xy 40.283638 -54.092348) (xy 40.283638 -54.095396)
			(xy 40.283302 -54.12078) (xy 40.276736 -54.171119) (xy 40.263559 -54.220144) (xy 40.254174 -54.243732)
			(xy 40.254174 -54.243986) (xy 40.252904 -54.246526) (xy 40.244257 -54.265985) (xy 40.223252 -54.303028)
			(xy 40.210994 -54.32044) (xy 40.204898 -54.328822) (xy 40.200326 -54.334664) (xy 40.196008 -54.341522)
			(xy 40.194992 -54.343554) (xy 40.192533 -54.34888) (xy 40.189843 -54.360296) (xy 40.189658 -54.36616)
			(xy 40.189658 -54.387496) (xy 40.190928 -54.400704) (xy 40.203882 -54.4322) (xy 40.210486 -54.439058)
			(xy 40.22869 -54.458839) (xy 40.260479 -54.502192) (xy 40.286537 -54.549214) (xy 40.306449 -54.599149)
			(xy 40.319893 -54.6512) (xy 40.326656 -54.704532) (xy 40.327072 -54.731412) (xy 40.326586 -54.760657)
			(xy 40.322375 -54.791102) (xy 42.176446 -54.791102) (xy 42.176902 -54.763731) (xy 42.184721 -54.709551)
			(xy 42.200211 -54.657048) (xy 42.223056 -54.607301) (xy 42.252783 -54.561335) (xy 42.270426 -54.540404)
			(xy 42.27068 -54.54015) (xy 42.276261 -54.53306) (xy 42.282509 -54.516146) (xy 42.282872 -54.50713)
			(xy 42.282872 -54.440074) (xy 42.282534 -54.431055) (xy 42.276274 -54.414138) (xy 42.27068 -54.407054)
			(xy 42.270426 -54.407054) (xy 42.270426 -54.4068) (xy 42.252787 -54.385866) (xy 42.223063 -54.339898)
			(xy 42.200217 -54.290152) (xy 42.184721 -54.23765) (xy 42.176892 -54.183472) (xy 42.176892 -54.128731)
			(xy 42.18472 -54.074553) (xy 42.200216 -54.022051) (xy 42.223061 -53.972305) (xy 42.252785 -53.926337)
			(xy 42.270426 -53.905404) (xy 42.27068 -53.90515) (xy 42.276261 -53.89806) (xy 42.282509 -53.881146)
			(xy 42.282872 -53.87213) (xy 42.282872 -53.805074) (xy 42.282534 -53.796055) (xy 42.276274 -53.779138)
			(xy 42.27068 -53.772054) (xy 42.270426 -53.772054) (xy 42.270426 -53.7718) (xy 42.252787 -53.750866)
			(xy 42.223063 -53.704898) (xy 42.200217 -53.655152) (xy 42.184721 -53.60265) (xy 42.176892 -53.548472)
			(xy 42.176892 -53.493731) (xy 42.18472 -53.439553) (xy 42.200216 -53.387051) (xy 42.223061 -53.337305)
			(xy 42.252785 -53.291337) (xy 42.270426 -53.270404) (xy 42.27068 -53.27015) (xy 42.276261 -53.26306)
			(xy 42.282509 -53.246146) (xy 42.282872 -53.23713) (xy 42.282872 -53.170074) (xy 42.282534 -53.161055)
			(xy 42.276274 -53.144138) (xy 42.27068 -53.137054) (xy 42.270426 -53.137054) (xy 42.270426 -53.1368)
			(xy 42.252777 -53.115875) (xy 42.223066 -53.069901) (xy 42.200232 -53.020152) (xy 42.184743 -52.967649)
			(xy 42.176918 -52.913472) (xy 42.176446 -52.886102) (xy 42.176932 -52.858851) (xy 42.184688 -52.804903)
			(xy 42.200043 -52.752608) (xy 42.222685 -52.703031) (xy 42.252151 -52.657181) (xy 42.287842 -52.61599)
			(xy 42.329033 -52.580299) (xy 42.374883 -52.550833) (xy 42.42446 -52.528191) (xy 42.476755 -52.512836)
			(xy 42.530703 -52.50508) (xy 42.585205 -52.50508) (xy 42.639153 -52.512836) (xy 42.691448 -52.528191)
			(xy 42.730557 -52.546052) (xy 47.679573 -52.546052) (xy 47.679573 -52.491548) (xy 47.68733 -52.437599)
			(xy 47.702686 -52.385303) (xy 47.725328 -52.335724) (xy 47.754796 -52.289873) (xy 47.790489 -52.248682)
			(xy 47.831681 -52.21299) (xy 47.877533 -52.183523) (xy 47.927112 -52.160883) (xy 47.979409 -52.145528)
			(xy 48.033358 -52.137773) (xy 48.06061 -52.13731) (xy 48.087981 -52.137768) (xy 48.14216 -52.145587)
			(xy 48.194663 -52.161078) (xy 48.24441 -52.183922) (xy 48.290377 -52.213648) (xy 48.311308 -52.23129)
			(xy 48.311562 -52.231544) (xy 48.318651 -52.237126) (xy 48.335566 -52.243374) (xy 48.344582 -52.243736)
			(xy 48.411638 -52.243736) (xy 48.420656 -52.243389) (xy 48.437572 -52.237134) (xy 48.444658 -52.231544)
			(xy 48.444658 -52.23129) (xy 48.444912 -52.23129) (xy 48.465845 -52.213649) (xy 48.511813 -52.183925)
			(xy 48.561559 -52.161079) (xy 48.614061 -52.145583) (xy 48.668239 -52.137754) (xy 48.722981 -52.137754)
			(xy 48.777159 -52.145583) (xy 48.829661 -52.161079) (xy 48.879407 -52.183925) (xy 48.925375 -52.213649)
			(xy 48.946308 -52.23129) (xy 48.946562 -52.231544) (xy 48.953651 -52.237126) (xy 48.970566 -52.243374)
			(xy 48.979582 -52.243736) (xy 49.046638 -52.243736) (xy 49.055656 -52.243389) (xy 49.072572 -52.237134)
			(xy 49.079658 -52.231544) (xy 49.079658 -52.23129) (xy 49.079912 -52.23129) (xy 49.100865 -52.213677)
			(xy 49.146832 -52.183962) (xy 49.196574 -52.161121) (xy 49.24907 -52.145624) (xy 49.303242 -52.137788)
			(xy 49.33061 -52.13731) (xy 49.357862 -52.137761) (xy 49.411811 -52.145519) (xy 49.464107 -52.160875)
			(xy 49.513686 -52.183518) (xy 49.559537 -52.212986) (xy 49.600728 -52.248679) (xy 49.63642 -52.289871)
			(xy 49.665887 -52.335723) (xy 49.688528 -52.385302) (xy 49.703884 -52.437599) (xy 49.71164 -52.491548)
			(xy 49.71164 -52.546052) (xy 49.705696 -52.587398) (xy 50.755294 -52.587398) (xy 50.759365 -52.531776)
			(xy 50.771491 -52.477339) (xy 50.791414 -52.425248) (xy 50.81871 -52.376613) (xy 50.852796 -52.33247)
			(xy 50.892945 -52.293761) (xy 50.938303 -52.26131) (xy 50.987903 -52.235809) (xy 51.040687 -52.217802)
			(xy 51.09553 -52.207672) (xy 51.151264 -52.205635) (xy 51.206701 -52.211735) (xy 51.260658 -52.225841)
			(xy 51.311987 -52.247653) (xy 51.359593 -52.276707) (xy 51.402461 -52.312382) (xy 51.439678 -52.353919)
			(xy 51.470451 -52.400432) (xy 51.494123 -52.450929) (xy 51.510191 -52.504336) (xy 51.517787 -52.555953)
			(xy 58.583779 -52.555953) (xy 58.583779 -52.501447) (xy 58.591537 -52.447497) (xy 58.606893 -52.3952)
			(xy 58.629536 -52.345621) (xy 58.659005 -52.29977) (xy 58.6947 -52.258579) (xy 58.735894 -52.222887)
			(xy 58.781748 -52.193422) (xy 58.831329 -52.170783) (xy 58.883627 -52.15543) (xy 58.937577 -52.147677)
			(xy 58.96483 -52.147216) (xy 58.992201 -52.147661) (xy 59.046381 -52.155483) (xy 59.098885 -52.170977)
			(xy 59.148631 -52.193823) (xy 59.194597 -52.223553) (xy 59.215528 -52.241196) (xy 59.215782 -52.24145)
			(xy 59.222865 -52.247041) (xy 59.239785 -52.253284) (xy 59.248802 -52.253642) (xy 59.315858 -52.253642)
			(xy 59.324874 -52.253278) (xy 59.341792 -52.247037) (xy 59.348878 -52.24145) (xy 59.348878 -52.241196)
			(xy 59.349132 -52.241196) (xy 59.370078 -52.223575) (xy 59.416047 -52.19386) (xy 59.465791 -52.171021)
			(xy 59.518289 -52.155526) (xy 59.572462 -52.147693) (xy 59.59983 -52.147216) (xy 59.627082 -52.147656)
			(xy 59.681029 -52.155416) (xy 59.733324 -52.170775) (xy 59.7829 -52.193419) (xy 59.82875 -52.222888)
			(xy 59.869939 -52.258582) (xy 59.90563 -52.299774) (xy 59.935095 -52.345626) (xy 59.957735 -52.395204)
			(xy 59.97309 -52.4475) (xy 59.980846 -52.501448) (xy 59.980846 -52.555952) (xy 59.97309 -52.6099)
			(xy 59.957735 -52.662196) (xy 59.935095 -52.711774) (xy 59.90563 -52.757626) (xy 59.869939 -52.798818)
			(xy 59.82875 -52.834512) (xy 59.7829 -52.863981) (xy 59.733324 -52.886625) (xy 59.681029 -52.901984)
			(xy 59.627082 -52.909744) (xy 59.59983 -52.910232) (xy 59.57246 -52.909765) (xy 59.51828 -52.90195)
			(xy 59.465776 -52.886462) (xy 59.416029 -52.86362) (xy 59.370063 -52.833894) (xy 59.349132 -52.816252)
			(xy 59.348878 -52.815998) (xy 59.341802 -52.810396) (xy 59.324877 -52.804159) (xy 59.315858 -52.803806)
			(xy 59.248802 -52.803806) (xy 59.239785 -52.804163) (xy 59.222868 -52.81041) (xy 59.215782 -52.815998)
			(xy 59.215782 -52.816252) (xy 59.215528 -52.816252) (xy 59.19459 -52.833884) (xy 59.14862 -52.863599)
			(xy 59.098874 -52.886437) (xy 59.046374 -52.901929) (xy 58.992199 -52.909758) (xy 58.96483 -52.910232)
			(xy 58.937577 -52.909723) (xy 58.883627 -52.90197) (xy 58.831329 -52.886617) (xy 58.781748 -52.863978)
			(xy 58.735894 -52.834513) (xy 58.6947 -52.798821) (xy 58.659005 -52.75763) (xy 58.629536 -52.711779)
			(xy 58.606893 -52.6622) (xy 58.591537 -52.609903) (xy 58.583779 -52.555953) (xy 51.517787 -52.555953)
			(xy 51.518311 -52.559512) (xy 51.51882 -52.587398) (xy 51.518311 -52.615284) (xy 51.510191 -52.67046)
			(xy 51.494123 -52.723867) (xy 51.470451 -52.774364) (xy 51.439678 -52.820877) (xy 51.402461 -52.862414)
			(xy 51.359593 -52.898089) (xy 51.311987 -52.927143) (xy 51.260658 -52.948955) (xy 51.206701 -52.963061)
			(xy 51.151264 -52.969161) (xy 51.09553 -52.967124) (xy 51.040687 -52.956994) (xy 50.987903 -52.938987)
			(xy 50.938303 -52.913486) (xy 50.892945 -52.881035) (xy 50.852796 -52.842326) (xy 50.81871 -52.798183)
			(xy 50.791414 -52.749548) (xy 50.771491 -52.697457) (xy 50.759365 -52.64302) (xy 50.755294 -52.587398)
			(xy 49.705696 -52.587398) (xy 49.703884 -52.600001) (xy 49.688528 -52.652298) (xy 49.665887 -52.701877)
			(xy 49.63642 -52.747729) (xy 49.600728 -52.788921) (xy 49.559537 -52.824614) (xy 49.513686 -52.854082)
			(xy 49.464107 -52.876725) (xy 49.411811 -52.892081) (xy 49.357862 -52.899839) (xy 49.33061 -52.900326)
			(xy 49.303239 -52.899872) (xy 49.249059 -52.892054) (xy 49.196555 -52.876563) (xy 49.146808 -52.853718)
			(xy 49.100843 -52.82399) (xy 49.079912 -52.806346) (xy 49.079658 -52.806092) (xy 49.07256 -52.800523)
			(xy 49.055652 -52.794266) (xy 49.046638 -52.7939) (xy 48.979582 -52.7939) (xy 48.970564 -52.794249)
			(xy 48.953647 -52.800502) (xy 48.946562 -52.806092) (xy 48.946308 -52.806346) (xy 48.925375 -52.823987)
			(xy 48.879407 -52.853711) (xy 48.829661 -52.876557) (xy 48.777159 -52.892053) (xy 48.722981 -52.899882)
			(xy 48.668239 -52.899882) (xy 48.614061 -52.892053) (xy 48.561559 -52.876557) (xy 48.511813 -52.853711)
			(xy 48.465845 -52.823987) (xy 48.444912 -52.806346) (xy 48.444658 -52.806092) (xy 48.43756 -52.800523)
			(xy 48.420652 -52.794266) (xy 48.411638 -52.7939) (xy 48.344582 -52.7939) (xy 48.335564 -52.794249)
			(xy 48.318647 -52.800502) (xy 48.311562 -52.806092) (xy 48.311562 -52.806346) (xy 48.311308 -52.806346)
			(xy 48.290377 -52.823986) (xy 48.244405 -52.8537) (xy 48.194657 -52.876536) (xy 48.142156 -52.892027)
			(xy 48.087979 -52.899853) (xy 48.06061 -52.900326) (xy 48.033358 -52.899827) (xy 47.979409 -52.892072)
			(xy 47.927112 -52.876717) (xy 47.877533 -52.854077) (xy 47.831681 -52.82461) (xy 47.790489 -52.788918)
			(xy 47.754796 -52.747727) (xy 47.725328 -52.701876) (xy 47.702686 -52.652297) (xy 47.68733 -52.600001)
			(xy 47.679573 -52.546052) (xy 42.730557 -52.546052) (xy 42.741025 -52.550833) (xy 42.786875 -52.580299)
			(xy 42.828066 -52.61599) (xy 42.863757 -52.657181) (xy 42.893223 -52.703031) (xy 42.915865 -52.752608)
			(xy 42.93122 -52.804903) (xy 42.938976 -52.858851) (xy 42.939462 -52.886102) (xy 42.939006 -52.913473)
			(xy 42.931187 -52.967653) (xy 42.915696 -53.020156) (xy 42.892852 -53.069903) (xy 42.863125 -53.115869)
			(xy 42.845482 -53.1368) (xy 42.845228 -53.137054) (xy 42.839646 -53.144143) (xy 42.833399 -53.161058)
			(xy 42.833036 -53.170074) (xy 42.833036 -53.23713) (xy 42.833371 -53.246149) (xy 42.839633 -53.263067)
			(xy 42.845228 -53.27015) (xy 42.845482 -53.27015) (xy 42.845482 -53.270404) (xy 42.863124 -53.291335)
			(xy 42.892848 -53.337304) (xy 42.915693 -53.38705) (xy 42.931189 -53.439552) (xy 42.939017 -53.493731)
			(xy 42.939017 -53.548472) (xy 42.931188 -53.602651) (xy 42.915692 -53.655153) (xy 42.892847 -53.704899)
			(xy 42.863122 -53.750867) (xy 42.846552 -53.77053) (xy 43.210734 -53.77053) (xy 43.211261 -53.741613)
			(xy 43.219986 -53.684442) (xy 43.237242 -53.629243) (xy 43.262632 -53.577281) (xy 43.295574 -53.529747)
			(xy 43.335315 -53.48773) (xy 43.3578 -53.46954) (xy 43.366579 -53.461906) (xy 43.376778 -53.441026)
			(xy 43.377358 -53.429408) (xy 43.377358 -53.349652) (xy 43.376847 -53.338016) (xy 43.36664 -53.317106)
			(xy 43.3578 -53.30952) (xy 43.335326 -53.291318) (xy 43.29559 -53.2493) (xy 43.26265 -53.201768)
			(xy 43.23726 -53.149809) (xy 43.220002 -53.094613) (xy 43.21127 -53.037445) (xy 43.210734 -53.00853)
			(xy 43.211183 -52.981276) (xy 43.218937 -52.927322) (xy 43.234292 -52.875022) (xy 43.256934 -52.825439)
			(xy 43.286403 -52.779584) (xy 43.322098 -52.738389) (xy 43.363293 -52.702695) (xy 43.409149 -52.673228)
			(xy 43.458733 -52.650587) (xy 43.511034 -52.635235) (xy 43.564988 -52.627482) (xy 43.592242 -52.627022)
			(xy 43.618557 -52.627454) (xy 43.670688 -52.634695) (xy 43.721331 -52.649021) (xy 43.76953 -52.67016)
			(xy 43.814373 -52.697712) (xy 43.855011 -52.731157) (xy 43.873166 -52.750212) (xy 43.880697 -52.757603)
			(xy 43.89997 -52.766133) (xy 43.910504 -52.766722) (xy 43.98518 -52.766722) (xy 43.995729 -52.766189)
			(xy 44.015024 -52.757656) (xy 44.022518 -52.750212) (xy 44.040674 -52.731157) (xy 44.081303 -52.697699)
			(xy 44.126144 -52.67014) (xy 44.174344 -52.649001) (xy 44.224992 -52.634684) (xy 44.277126 -52.62746)
			(xy 44.303442 -52.627022) (xy 44.330696 -52.627439) (xy 44.384647 -52.635202) (xy 44.436945 -52.650564)
			(xy 44.486525 -52.673212) (xy 44.532376 -52.702685) (xy 44.573567 -52.738384) (xy 44.609258 -52.779581)
			(xy 44.638723 -52.825439) (xy 44.661361 -52.875022) (xy 44.676713 -52.927323) (xy 44.684466 -52.981276)
			(xy 44.68495 -53.00853) (xy 44.684484 -53.036197) (xy 44.682253 -53.051456) (xy 52.941218 -53.051456)
			(xy 52.945289 -52.995834) (xy 52.957415 -52.941397) (xy 52.977338 -52.889306) (xy 53.004634 -52.840671)
			(xy 53.03872 -52.796528) (xy 53.078869 -52.757819) (xy 53.124227 -52.725368) (xy 53.173827 -52.699867)
			(xy 53.226611 -52.68186) (xy 53.281454 -52.67173) (xy 53.337188 -52.669693) (xy 53.392625 -52.675793)
			(xy 53.446582 -52.689899) (xy 53.497911 -52.711711) (xy 53.545517 -52.740765) (xy 53.588385 -52.77644)
			(xy 53.625602 -52.817977) (xy 53.656375 -52.86449) (xy 53.680047 -52.914987) (xy 53.696115 -52.968394)
			(xy 53.704235 -53.02357) (xy 53.704744 -53.051456) (xy 53.704235 -53.079342) (xy 53.696115 -53.134518)
			(xy 53.680047 -53.187925) (xy 53.656375 -53.238422) (xy 53.625602 -53.284935) (xy 53.588385 -53.326472)
			(xy 53.545517 -53.362147) (xy 53.497911 -53.391201) (xy 53.446582 -53.413013) (xy 53.392625 -53.427119)
			(xy 53.337188 -53.433219) (xy 53.281454 -53.431182) (xy 53.226611 -53.421052) (xy 53.173827 -53.403045)
			(xy 53.124227 -53.377544) (xy 53.078869 -53.345093) (xy 53.03872 -53.306384) (xy 53.004634 -53.262241)
			(xy 52.977338 -53.213606) (xy 52.957415 -53.161515) (xy 52.945289 -53.107078) (xy 52.941218 -53.051456)
			(xy 44.682253 -53.051456) (xy 44.676479 -53.090949) (xy 44.660656 -53.143973) (xy 44.637346 -53.194158)
			(xy 44.607037 -53.240453) (xy 44.570364 -53.281889) (xy 44.528095 -53.317599) (xy 44.504864 -53.332634)
			(xy 44.495176 -53.339257) (xy 44.482737 -53.359128) (xy 44.480988 -53.370734) (xy 44.473114 -53.450744)
			(xy 44.472473 -53.462382) (xy 44.480561 -53.484219) (xy 44.488608 -53.492654) (xy 44.488862 -53.492908)
			(xy 44.507422 -53.51101) (xy 44.540004 -53.551336) (xy 44.566821 -53.595706) (xy 44.587377 -53.643301)
			(xy 44.601295 -53.693242) (xy 44.608316 -53.744608) (xy 44.60875 -53.77053) (xy 44.60825 -53.79778)
			(xy 44.600491 -53.851725) (xy 44.585134 -53.904017) (xy 44.562492 -53.953592) (xy 44.533027 -53.99944)
			(xy 44.497337 -54.040629) (xy 44.456149 -54.07632) (xy 44.410302 -54.105787) (xy 44.360728 -54.12843)
			(xy 44.308437 -54.143788) (xy 44.254492 -54.151549) (xy 44.227242 -54.152038) (xy 44.199872 -54.151562)
			(xy 44.145693 -54.143749) (xy 44.093189 -54.128263) (xy 44.043442 -54.105423) (xy 43.997475 -54.075699)
			(xy 43.976544 -54.058058) (xy 43.97629 -54.057804) (xy 43.96921 -54.052208) (xy 43.952288 -54.045967)
			(xy 43.94327 -54.045612) (xy 43.876214 -54.045612) (xy 43.867197 -54.045973) (xy 43.85028 -54.052217)
			(xy 43.843194 -54.057804) (xy 43.843194 -54.058058) (xy 43.84294 -54.058058) (xy 43.821998 -54.075685)
			(xy 43.776029 -54.1054) (xy 43.726284 -54.128239) (xy 43.673785 -54.143733) (xy 43.619611 -54.151563)
			(xy 43.592242 -54.152038) (xy 43.564992 -54.151506) (xy 43.511045 -54.143755) (xy 43.45875 -54.128406)
			(xy 43.409172 -54.105771) (xy 43.36332 -54.07631) (xy 43.322128 -54.040623) (xy 43.286433 -53.999438)
			(xy 43.256964 -53.953591) (xy 43.234319 -53.904018) (xy 43.21896 -53.851726) (xy 43.211199 -53.79778)
			(xy 43.210734 -53.77053) (xy 42.846552 -53.77053) (xy 42.845482 -53.7718) (xy 42.845228 -53.772054)
			(xy 42.839646 -53.779143) (xy 42.833399 -53.796058) (xy 42.833036 -53.805074) (xy 42.833036 -53.87213)
			(xy 42.833371 -53.881149) (xy 42.839633 -53.898067) (xy 42.845228 -53.90515) (xy 42.845482 -53.90515)
			(xy 42.845482 -53.905404) (xy 42.863124 -53.926335) (xy 42.892848 -53.972304) (xy 42.915693 -54.02205)
			(xy 42.931189 -54.074552) (xy 42.939017 -54.128731) (xy 42.939017 -54.183472) (xy 42.931188 -54.237651)
			(xy 42.915692 -54.290153) (xy 42.9019 -54.320186) (xy 45.130466 -54.320186) (xy 45.130908 -54.292815)
			(xy 45.138729 -54.238634) (xy 45.154223 -54.18613) (xy 45.17707 -54.136383) (xy 45.206801 -54.090418)
			(xy 45.224446 -54.069488) (xy 45.2247 -54.069234) (xy 45.230278 -54.062142) (xy 45.23653 -54.045229)
			(xy 45.236892 -54.036214) (xy 45.236892 -53.969158) (xy 45.236509 -53.960144) (xy 45.23028 -53.943227)
			(xy 45.2247 -53.936138) (xy 45.224446 -53.936138) (xy 45.224446 -53.935884) (xy 45.20684 -53.914925)
			(xy 45.177122 -53.86896) (xy 45.154279 -53.81922) (xy 45.13878 -53.766725) (xy 45.130944 -53.712553)
			(xy 45.130466 -53.685186) (xy 45.130952 -53.657935) (xy 45.138708 -53.603987) (xy 45.154063 -53.551692)
			(xy 45.176705 -53.502115) (xy 45.206171 -53.456265) (xy 45.241862 -53.415074) (xy 45.283053 -53.379383)
			(xy 45.328903 -53.349917) (xy 45.37848 -53.327275) (xy 45.430775 -53.31192) (xy 45.484723 -53.304164)
			(xy 45.539225 -53.304164) (xy 45.593173 -53.31192) (xy 45.645468 -53.327275) (xy 45.695045 -53.349917)
			(xy 45.740895 -53.379383) (xy 45.782086 -53.415074) (xy 45.817777 -53.456265) (xy 45.843668 -53.496552)
			(xy 58.133464 -53.496552) (xy 58.133464 -53.442048) (xy 58.14122 -53.3881) (xy 58.156575 -53.335804)
			(xy 58.179216 -53.286226) (xy 58.208683 -53.240374) (xy 58.244374 -53.199183) (xy 58.285565 -53.16349)
			(xy 58.331415 -53.134022) (xy 58.380993 -53.11138) (xy 58.433288 -53.096023) (xy 58.487236 -53.088265)
			(xy 58.514488 -53.087778) (xy 58.541859 -53.088232) (xy 58.596039 -53.09605) (xy 58.648543 -53.111541)
			(xy 58.69829 -53.134386) (xy 58.744256 -53.164114) (xy 58.765186 -53.181758) (xy 58.76544 -53.182012)
			(xy 58.772539 -53.187581) (xy 58.789446 -53.193838) (xy 58.79846 -53.194204) (xy 58.865516 -53.194204)
			(xy 58.874534 -53.193854) (xy 58.89145 -53.187601) (xy 58.898536 -53.182012) (xy 58.898536 -53.181758)
			(xy 58.89879 -53.181758) (xy 58.919709 -53.164103) (xy 58.965686 -53.134395) (xy 59.015437 -53.111563)
			(xy 59.06794 -53.096075) (xy 59.122118 -53.08825) (xy 59.149488 -53.087778) (xy 59.17674 -53.088268)
			(xy 59.230691 -53.096024) (xy 59.282988 -53.111378) (xy 59.332568 -53.134019) (xy 59.378421 -53.163486)
			(xy 59.419613 -53.199178) (xy 59.455307 -53.24037) (xy 59.484775 -53.286222) (xy 59.507418 -53.335801)
			(xy 59.522774 -53.388098) (xy 59.530531 -53.442048) (xy 59.530531 -53.496552) (xy 59.522774 -53.550502)
			(xy 59.507418 -53.602799) (xy 59.484775 -53.652378) (xy 59.455307 -53.69823) (xy 59.419613 -53.739422)
			(xy 59.378421 -53.775114) (xy 59.332568 -53.804581) (xy 59.282988 -53.827222) (xy 59.230691 -53.842576)
			(xy 59.17674 -53.850332) (xy 59.149488 -53.850794) (xy 59.122117 -53.850336) (xy 59.067938 -53.842517)
			(xy 59.015435 -53.827026) (xy 58.965688 -53.804182) (xy 58.919721 -53.774456) (xy 58.89879 -53.756814)
			(xy 58.898536 -53.75656) (xy 58.891447 -53.750977) (xy 58.874532 -53.744729) (xy 58.865516 -53.744368)
			(xy 58.79846 -53.744368) (xy 58.789442 -53.744713) (xy 58.772525 -53.75097) (xy 58.76544 -53.75656)
			(xy 58.76544 -53.756814) (xy 58.765186 -53.756814) (xy 58.744234 -53.774428) (xy 58.698267 -53.804143)
			(xy 58.648524 -53.826984) (xy 58.596028 -53.842481) (xy 58.541856 -53.850316) (xy 58.514488 -53.850794)
			(xy 58.487236 -53.850335) (xy 58.433288 -53.842577) (xy 58.380993 -53.82722) (xy 58.331415 -53.804578)
			(xy 58.285565 -53.77511) (xy 58.244374 -53.739417) (xy 58.208683 -53.698226) (xy 58.179216 -53.652374)
			(xy 58.156575 -53.602796) (xy 58.14122 -53.5505) (xy 58.133464 -53.496552) (xy 45.843668 -53.496552)
			(xy 45.847243 -53.502115) (xy 45.869885 -53.551692) (xy 45.88524 -53.603987) (xy 45.892996 -53.657935)
			(xy 45.893482 -53.685186) (xy 45.893012 -53.712556) (xy 45.885196 -53.766735) (xy 45.869708 -53.819238)
			(xy 45.846867 -53.868985) (xy 45.817143 -53.914952) (xy 45.799502 -53.935884) (xy 45.799248 -53.936138)
			(xy 45.793675 -53.943234) (xy 45.787421 -53.960144) (xy 45.787056 -53.969158) (xy 45.787056 -54.036214)
			(xy 45.787394 -54.045233) (xy 45.793654 -54.06215) (xy 45.799248 -54.069234) (xy 45.799502 -54.069234)
			(xy 45.799502 -54.069488) (xy 45.817149 -54.090414) (xy 45.84686 -54.136388) (xy 45.869694 -54.186137)
			(xy 45.885183 -54.238639) (xy 45.893009 -54.292816) (xy 45.893482 -54.320186) (xy 45.892996 -54.347437)
			(xy 45.88524 -54.401385) (xy 45.869885 -54.45368) (xy 45.847243 -54.503257) (xy 45.817777 -54.549107)
			(xy 45.782086 -54.590298) (xy 45.740895 -54.625989) (xy 45.695045 -54.655455) (xy 45.645468 -54.678097)
			(xy 45.593173 -54.693452) (xy 45.539225 -54.701208) (xy 45.484723 -54.701208) (xy 45.430775 -54.693452)
			(xy 45.37848 -54.678097) (xy 45.328903 -54.655455) (xy 45.283053 -54.625989) (xy 45.241862 -54.590298)
			(xy 45.206171 -54.549107) (xy 45.176705 -54.503257) (xy 45.154063 -54.45368) (xy 45.138708 -54.401385)
			(xy 45.130952 -54.347437) (xy 45.130466 -54.320186) (xy 42.9019 -54.320186) (xy 42.892847 -54.339899)
			(xy 42.863122 -54.385867) (xy 42.845482 -54.4068) (xy 42.845228 -54.407054) (xy 42.839646 -54.414143)
			(xy 42.833399 -54.431058) (xy 42.833036 -54.440074) (xy 42.833036 -54.50713) (xy 42.833371 -54.516149)
			(xy 42.839633 -54.533067) (xy 42.845228 -54.54015) (xy 42.845482 -54.54015) (xy 42.845482 -54.540404)
			(xy 42.863134 -54.561326) (xy 42.892844 -54.607301) (xy 42.915678 -54.657051) (xy 42.931166 -54.709554)
			(xy 42.93899 -54.763732) (xy 42.939107 -54.770528) (xy 46.071028 -54.770528) (xy 46.071504 -54.743158)
			(xy 46.079318 -54.688979) (xy 46.094805 -54.636476) (xy 46.117644 -54.586729) (xy 46.147367 -54.540762)
			(xy 46.165008 -54.51983) (xy 46.165262 -54.519576) (xy 46.170872 -54.512506) (xy 46.177103 -54.495576)
			(xy 46.177454 -54.486556) (xy 46.177454 -54.4195) (xy 46.177107 -54.410482) (xy 46.170853 -54.393565)
			(xy 46.165262 -54.38648) (xy 46.165008 -54.38648) (xy 46.165008 -54.386226) (xy 46.147369 -54.365294)
			(xy 46.117657 -54.319321) (xy 46.094821 -54.269574) (xy 46.07933 -54.217073) (xy 46.071502 -54.162897)
			(xy 46.071028 -54.135528) (xy 46.071514 -54.108277) (xy 46.07927 -54.054329) (xy 46.094625 -54.002034)
			(xy 46.117267 -53.952457) (xy 46.146733 -53.906607) (xy 46.182424 -53.865416) (xy 46.223615 -53.829725)
			(xy 46.269465 -53.800259) (xy 46.319042 -53.777617) (xy 46.371337 -53.762262) (xy 46.425285 -53.754506)
			(xy 46.479787 -53.754506) (xy 46.533735 -53.762262) (xy 46.58603 -53.777617) (xy 46.635607 -53.800259)
			(xy 46.681457 -53.829725) (xy 46.722648 -53.865416) (xy 46.758339 -53.906607) (xy 46.787805 -53.952457)
			(xy 46.79288 -53.96357) (xy 50.772058 -53.96357) (xy 50.776129 -53.907948) (xy 50.788255 -53.853511)
			(xy 50.808178 -53.80142) (xy 50.835474 -53.752785) (xy 50.86956 -53.708642) (xy 50.909709 -53.669933)
			(xy 50.955067 -53.637482) (xy 51.004667 -53.611981) (xy 51.057451 -53.593974) (xy 51.112294 -53.583844)
			(xy 51.168028 -53.581807) (xy 51.223465 -53.587907) (xy 51.277422 -53.602013) (xy 51.328751 -53.623825)
			(xy 51.376357 -53.652879) (xy 51.419225 -53.688554) (xy 51.456442 -53.730091) (xy 51.487215 -53.776604)
			(xy 51.510887 -53.827101) (xy 51.526955 -53.880508) (xy 51.535075 -53.935684) (xy 51.535584 -53.96357)
			(xy 51.535075 -53.991456) (xy 51.526955 -54.046632) (xy 51.510887 -54.100039) (xy 51.487215 -54.150536)
			(xy 51.456442 -54.197049) (xy 51.419225 -54.238586) (xy 51.376357 -54.274261) (xy 51.328751 -54.303315)
			(xy 51.277422 -54.325127) (xy 51.223465 -54.339233) (xy 51.168028 -54.345333) (xy 51.112294 -54.343296)
			(xy 51.057451 -54.333166) (xy 51.004667 -54.315159) (xy 50.955067 -54.289658) (xy 50.909709 -54.257207)
			(xy 50.86956 -54.218498) (xy 50.835474 -54.174355) (xy 50.808178 -54.12572) (xy 50.788255 -54.073629)
			(xy 50.776129 -54.019192) (xy 50.772058 -53.96357) (xy 46.79288 -53.96357) (xy 46.810447 -54.002034)
			(xy 46.825802 -54.054329) (xy 46.833558 -54.108277) (xy 46.834044 -54.135528) (xy 46.833608 -54.162899)
			(xy 46.825785 -54.21708) (xy 46.81029 -54.269584) (xy 46.787441 -54.319331) (xy 46.757709 -54.365296)
			(xy 46.740064 -54.386226) (xy 46.73981 -54.38648) (xy 46.734227 -54.393569) (xy 46.727978 -54.410484)
			(xy 46.727618 -54.4195) (xy 46.727618 -54.486556) (xy 46.727992 -54.495571) (xy 46.734228 -54.512488)
			(xy 46.73981 -54.519576) (xy 46.740064 -54.519576) (xy 46.740064 -54.51983) (xy 46.757678 -54.540782)
			(xy 46.787395 -54.586749) (xy 46.810236 -54.636491) (xy 46.825733 -54.688988) (xy 46.833567 -54.74316)
			(xy 46.834044 -54.770528) (xy 46.833558 -54.797779) (xy 46.825802 -54.851727) (xy 46.810447 -54.904022)
			(xy 46.787805 -54.953599) (xy 46.765021 -54.989051) (xy 55.901068 -54.989051) (xy 55.901068 -54.934549)
			(xy 55.908824 -54.880601) (xy 55.924179 -54.828307) (xy 55.946819 -54.778729) (xy 55.976284 -54.732879)
			(xy 56.011975 -54.691688) (xy 56.053164 -54.655995) (xy 56.099013 -54.626528) (xy 56.14859 -54.603885)
			(xy 56.200884 -54.588528) (xy 56.254831 -54.580769) (xy 56.282082 -54.580282) (xy 56.310173 -54.580791)
			(xy 56.36575 -54.589016) (xy 56.419518 -54.605304) (xy 56.470316 -54.629305) (xy 56.517043 -54.660497)
			(xy 56.558688 -54.698207) (xy 56.594351 -54.741619) (xy 56.609234 -54.765448) (xy 56.614568 -54.774338)
			(xy 56.631586 -54.78653) (xy 56.724804 -54.80685) (xy 56.745378 -54.802532) (xy 56.754014 -54.79669)
			(xy 56.778072 -54.780681) (xy 56.830006 -54.75534) (xy 56.885165 -54.738117) (xy 56.942291 -54.729405)
			(xy 56.971184 -54.728872) (xy 56.998434 -54.729393) (xy 57.052379 -54.737147) (xy 57.104672 -54.752499)
			(xy 57.154248 -54.775137) (xy 57.200097 -54.804599) (xy 57.241287 -54.840287) (xy 57.276979 -54.881474)
			(xy 57.306446 -54.92732) (xy 57.329088 -54.976894) (xy 57.344445 -55.029185) (xy 57.352204 -55.08313)
			(xy 57.352692 -55.11038) (xy 57.352216 -55.13775) (xy 57.344401 -55.191929) (xy 57.328914 -55.244432)
			(xy 57.306075 -55.294179) (xy 57.276352 -55.340146) (xy 57.258712 -55.361078) (xy 57.258458 -55.361332)
			(xy 57.252889 -55.36843) (xy 57.246633 -55.385338) (xy 57.246266 -55.394352) (xy 57.246266 -55.461408)
			(xy 57.246626 -55.470424) (xy 57.252872 -55.487341) (xy 57.258458 -55.494428) (xy 57.258712 -55.494428)
			(xy 57.258712 -55.494682) (xy 57.276331 -55.515631) (xy 57.306054 -55.561597) (xy 57.328898 -55.611341)
			(xy 57.344394 -55.66384) (xy 57.352224 -55.718016) (xy 57.352226 -55.772754) (xy 57.344401 -55.82693)
			(xy 57.328909 -55.879431) (xy 57.306069 -55.929176) (xy 57.27635 -55.975145) (xy 57.258712 -55.996078)
			(xy 57.258458 -55.996332) (xy 57.252889 -56.00343) (xy 57.246633 -56.020338) (xy 57.246266 -56.029352)
			(xy 57.246266 -56.096408) (xy 57.246626 -56.105424) (xy 57.252872 -56.122341) (xy 57.258458 -56.129428)
			(xy 57.258712 -56.129428) (xy 57.258712 -56.129682) (xy 57.276358 -56.150608) (xy 57.306068 -56.196583)
			(xy 57.328903 -56.246332) (xy 57.344392 -56.298834) (xy 57.352219 -56.35301) (xy 57.352692 -56.38038)
			(xy 57.352206 -56.407631) (xy 57.34445 -56.461579) (xy 57.329095 -56.513874) (xy 57.306453 -56.563451)
			(xy 57.276987 -56.609301) (xy 57.241296 -56.650492) (xy 57.200105 -56.686183) (xy 57.154255 -56.715649)
			(xy 57.104678 -56.738291) (xy 57.052383 -56.753646) (xy 56.998435 -56.761402) (xy 56.943933 -56.761402)
			(xy 56.889985 -56.753646) (xy 56.83769 -56.738291) (xy 56.788113 -56.715649) (xy 56.742263 -56.686183)
			(xy 56.701072 -56.650492) (xy 56.665381 -56.609301) (xy 56.635915 -56.563451) (xy 56.613273 -56.513874)
			(xy 56.597918 -56.461579) (xy 56.590162 -56.407631) (xy 56.589676 -56.38038) (xy 56.590112 -56.353008)
			(xy 56.597934 -56.298827) (xy 56.613429 -56.246323) (xy 56.636278 -56.196577) (xy 56.666011 -56.150612)
			(xy 56.683656 -56.129682) (xy 56.68391 -56.129428) (xy 56.689492 -56.122338) (xy 56.695741 -56.105424)
			(xy 56.696102 -56.096408) (xy 56.696102 -56.029352) (xy 56.695719 -56.020338) (xy 56.689489 -56.003421)
			(xy 56.68391 -55.996332) (xy 56.683656 -55.996332) (xy 56.683656 -55.996078) (xy 56.665995 -55.975162)
			(xy 56.636268 -55.929192) (xy 56.613422 -55.879443) (xy 56.597926 -55.826938) (xy 56.590099 -55.772757)
			(xy 56.590101 -55.718013) (xy 56.597933 -55.663832) (xy 56.613433 -55.611329) (xy 56.636283 -55.561582)
			(xy 56.666013 -55.515614) (xy 56.683656 -55.494682) (xy 56.68391 -55.494428) (xy 56.689492 -55.487338)
			(xy 56.695741 -55.470424) (xy 56.696102 -55.461408) (xy 56.696102 -55.394352) (xy 56.695719 -55.385338)
			(xy 56.689489 -55.368421) (xy 56.68391 -55.361332) (xy 56.683656 -55.360824) (xy 56.67271 -55.348091)
			(xy 56.65287 -55.320999) (xy 56.644032 -55.306722) (xy 56.638698 -55.297832) (xy 56.62168 -55.28564)
			(xy 56.528462 -55.26532) (xy 56.507888 -55.269638) (xy 56.499252 -55.27548) (xy 56.475174 -55.291458)
			(xy 56.423248 -55.316806) (xy 56.368094 -55.334038) (xy 56.310973 -55.34276) (xy 56.282082 -55.343298)
			(xy 56.254831 -55.342831) (xy 56.200884 -55.335072) (xy 56.14859 -55.319715) (xy 56.099013 -55.297072)
			(xy 56.053164 -55.267605) (xy 56.011975 -55.231912) (xy 55.976284 -55.190721) (xy 55.946819 -55.144871)
			(xy 55.924179 -55.095293) (xy 55.908824 -55.042999) (xy 55.901068 -54.989051) (xy 46.765021 -54.989051)
			(xy 46.758339 -54.999449) (xy 46.722648 -55.04064) (xy 46.681457 -55.076331) (xy 46.635607 -55.105797)
			(xy 46.58603 -55.128439) (xy 46.533735 -55.143794) (xy 46.479787 -55.15155) (xy 46.425285 -55.15155)
			(xy 46.371337 -55.143794) (xy 46.319042 -55.128439) (xy 46.269465 -55.105797) (xy 46.223615 -55.076331)
			(xy 46.182424 -55.04064) (xy 46.146733 -54.999449) (xy 46.117267 -54.953599) (xy 46.094625 -54.904022)
			(xy 46.07927 -54.851727) (xy 46.071514 -54.797779) (xy 46.071028 -54.770528) (xy 42.939107 -54.770528)
			(xy 42.939462 -54.791102) (xy 42.938976 -54.818353) (xy 42.93122 -54.872301) (xy 42.915865 -54.924596)
			(xy 42.893223 -54.974173) (xy 42.863757 -55.020023) (xy 42.828066 -55.061214) (xy 42.786875 -55.096905)
			(xy 42.741025 -55.126371) (xy 42.691448 -55.149013) (xy 42.639153 -55.164368) (xy 42.585205 -55.172124)
			(xy 42.530703 -55.172124) (xy 42.476755 -55.164368) (xy 42.42446 -55.149013) (xy 42.374883 -55.126371)
			(xy 42.329033 -55.096905) (xy 42.287842 -55.061214) (xy 42.252151 -55.020023) (xy 42.222685 -54.974173)
			(xy 42.200043 -54.924596) (xy 42.184688 -54.872301) (xy 42.176932 -54.818353) (xy 42.176446 -54.791102)
			(xy 40.322375 -54.791102) (xy 40.318572 -54.818595) (xy 40.302698 -54.874889) (xy 40.279262 -54.928479)
			(xy 40.248707 -54.978353) (xy 40.211608 -55.023571) (xy 40.168664 -55.063282) (xy 40.144954 -55.080408)
			(xy 40.141398 -55.082948) (xy 40.139874 -55.083964) (xy 40.134032 -55.090568) (xy 40.13073 -55.09514)
			(xy 40.116252 -55.121048) (xy 40.113966 -55.127398) (xy 40.113712 -55.128414) (xy 40.112696 -55.13324)
			(xy 40.111934 -55.141876) (xy 40.127174 -55.59044) (xy 40.131757 -55.722266) (xy 51.834032 -55.722266)
			(xy 51.838103 -55.666644) (xy 51.850229 -55.612207) (xy 51.870152 -55.560116) (xy 51.897448 -55.511481)
			(xy 51.931534 -55.467338) (xy 51.971683 -55.428629) (xy 52.017041 -55.396178) (xy 52.066641 -55.370677)
			(xy 52.119425 -55.35267) (xy 52.174268 -55.34254) (xy 52.230002 -55.340503) (xy 52.285439 -55.346603)
			(xy 52.339396 -55.360709) (xy 52.390725 -55.382521) (xy 52.438331 -55.411575) (xy 52.449477 -55.420851)
			(xy 54.224668 -55.420851) (xy 54.224668 -55.366349) (xy 54.232424 -55.312401) (xy 54.247779 -55.260107)
			(xy 54.270419 -55.210529) (xy 54.299884 -55.164679) (xy 54.335575 -55.123488) (xy 54.376764 -55.087795)
			(xy 54.422613 -55.058328) (xy 54.47219 -55.035685) (xy 54.524484 -55.020328) (xy 54.578431 -55.012569)
			(xy 54.605682 -55.012082) (xy 54.631995 -55.012567) (xy 54.684123 -55.019799) (xy 54.734765 -55.034115)
			(xy 54.782964 -55.055244) (xy 54.827808 -55.082787) (xy 54.868449 -55.116222) (xy 54.886606 -55.135272)
			(xy 54.894127 -55.142674) (xy 54.913407 -55.151199) (xy 54.923944 -55.151782) (xy 54.99862 -55.151782)
			(xy 55.009167 -55.151228) (xy 55.028463 -55.142711) (xy 55.035958 -55.135272) (xy 55.054087 -55.11619)
			(xy 55.094723 -55.082736) (xy 55.139569 -55.055181) (xy 55.187775 -55.034048) (xy 55.238427 -55.019736)
			(xy 55.290564 -55.012517) (xy 55.316882 -55.012082) (xy 55.344135 -55.012564) (xy 55.398086 -55.020319)
			(xy 55.450385 -55.035673) (xy 55.499966 -55.058314) (xy 55.54582 -55.08778) (xy 55.587014 -55.123473)
			(xy 55.622709 -55.164665) (xy 55.652178 -55.210518) (xy 55.674821 -55.260098) (xy 55.690177 -55.312396)
			(xy 55.697935 -55.366347) (xy 55.697935 -55.420853) (xy 55.690177 -55.474804) (xy 55.674821 -55.527102)
			(xy 55.652178 -55.576682) (xy 55.622709 -55.622535) (xy 55.587014 -55.663727) (xy 55.54582 -55.69942)
			(xy 55.499966 -55.728886) (xy 55.450385 -55.751527) (xy 55.398086 -55.766881) (xy 55.344135 -55.774636)
			(xy 55.316882 -55.775098) (xy 55.290568 -55.774643) (xy 55.238439 -55.767406) (xy 55.187796 -55.753084)
			(xy 55.139597 -55.73195) (xy 55.094753 -55.704401) (xy 55.054114 -55.670961) (xy 55.035958 -55.651908)
			(xy 55.028453 -55.644487) (xy 55.00916 -55.635974) (xy 54.99862 -55.635398) (xy 54.923944 -55.635398)
			(xy 54.913396 -55.635938) (xy 54.8941 -55.644466) (xy 54.886606 -55.651908) (xy 54.868442 -55.670955)
			(xy 54.827814 -55.704413) (xy 54.782975 -55.731973) (xy 54.734776 -55.753113) (xy 54.68413 -55.767432)
			(xy 54.631998 -55.774658) (xy 54.605682 -55.775098) (xy 54.578431 -55.774631) (xy 54.524484 -55.766872)
			(xy 54.47219 -55.751515) (xy 54.422613 -55.728872) (xy 54.376764 -55.699405) (xy 54.335575 -55.663712)
			(xy 54.299884 -55.622521) (xy 54.270419 -55.576671) (xy 54.247779 -55.527093) (xy 54.232424 -55.474799)
			(xy 54.224668 -55.420851) (xy 52.449477 -55.420851) (xy 52.481199 -55.44725) (xy 52.518416 -55.488787)
			(xy 52.549189 -55.5353) (xy 52.572861 -55.585797) (xy 52.588929 -55.639204) (xy 52.597049 -55.69438)
			(xy 52.597558 -55.722266) (xy 52.597049 -55.750152) (xy 52.588929 -55.805328) (xy 52.572861 -55.858735)
			(xy 52.549189 -55.909232) (xy 52.518416 -55.955745) (xy 52.481199 -55.997282) (xy 52.438331 -56.032957)
			(xy 52.390725 -56.062011) (xy 52.339396 -56.083823) (xy 52.285439 -56.097929) (xy 52.230002 -56.104029)
			(xy 52.174268 -56.101992) (xy 52.119425 -56.091862) (xy 52.066641 -56.073855) (xy 52.017041 -56.048354)
			(xy 51.971683 -56.015903) (xy 51.931534 -55.977194) (xy 51.897448 -55.933051) (xy 51.870152 -55.884416)
			(xy 51.850229 -55.832325) (xy 51.838103 -55.777888) (xy 51.834032 -55.722266) (xy 40.131757 -55.722266)
			(xy 40.13581 -55.838852) (xy 40.141652 -56.007254) (xy 40.14216 -56.019192) (xy 40.142668 -56.035448)
			(xy 40.155368 -56.397652) (xy 40.158162 -56.47436) (xy 40.15994 -56.527192) (xy 40.161972 -56.536082)
			(xy 40.164766 -56.544464) (xy 40.166562 -56.548414) (xy 40.171292 -56.555689) (xy 40.174164 -56.558942)
			(xy 40.175434 -56.560212) (xy 40.195611 -56.58171) (xy 40.229765 -56.629766) (xy 40.256118 -56.682505)
			(xy 40.274043 -56.738671) (xy 40.283113 -56.796926) (xy 40.283638 -56.826404) (xy 40.283638 -56.82742)
			(xy 40.283184 -56.853475) (xy 40.276028 -56.905093) (xy 40.261905 -56.955255) (xy 40.24112 -57.002934)
			(xy 47.563532 -57.002934) (xy 47.56403 -56.974842) (xy 47.572253 -56.919264) (xy 47.588542 -56.865494)
			(xy 47.612544 -56.814696) (xy 47.643739 -56.767969) (xy 47.681452 -56.726324) (xy 47.724867 -56.690663)
			(xy 47.748698 -56.675782) (xy 47.757588 -56.670448) (xy 47.76978 -56.65343) (xy 47.7901 -56.560212)
			(xy 47.785782 -56.539638) (xy 47.77994 -56.531002) (xy 47.763931 -56.506944) (xy 47.738592 -56.45501)
			(xy 47.721369 -56.39985) (xy 47.712656 -56.342725) (xy 47.712122 -56.313832) (xy 47.712585 -56.286579)
			(xy 47.720339 -56.232626) (xy 47.735692 -56.180326) (xy 47.758333 -56.130744) (xy 47.7878 -56.08489)
			(xy 47.823494 -56.043696) (xy 47.864688 -56.008002) (xy 47.910543 -55.978534) (xy 47.960125 -55.955893)
			(xy 48.012424 -55.940539) (xy 48.066377 -55.932785) (xy 48.09363 -55.932324) (xy 48.121001 -55.932767)
			(xy 48.175181 -55.940589) (xy 48.227685 -55.956083) (xy 48.277432 -55.978931) (xy 48.323397 -56.00866)
			(xy 48.344328 -56.026304) (xy 48.344582 -56.026558) (xy 48.351665 -56.03215) (xy 48.368585 -56.038392)
			(xy 48.377602 -56.03875) (xy 48.444658 -56.03875) (xy 48.453674 -56.038384) (xy 48.470592 -56.032144)
			(xy 48.477678 -56.026558) (xy 48.477678 -56.026304) (xy 48.477932 -56.026304) (xy 48.498865 -56.008663)
			(xy 48.544833 -55.978939) (xy 48.594579 -55.956093) (xy 48.647081 -55.940597) (xy 48.701259 -55.932768)
			(xy 48.756001 -55.932768) (xy 48.810179 -55.940597) (xy 48.862681 -55.956093) (xy 48.912427 -55.978939)
			(xy 48.958395 -56.008663) (xy 48.979328 -56.026304) (xy 48.979582 -56.026558) (xy 48.986665 -56.03215)
			(xy 49.003585 -56.038392) (xy 49.012602 -56.03875) (xy 49.079658 -56.03875) (xy 49.088674 -56.038384)
			(xy 49.105592 -56.032144) (xy 49.112678 -56.026558) (xy 49.112678 -56.026304) (xy 49.112932 -56.026304)
			(xy 49.133879 -56.008684) (xy 49.179848 -55.978969) (xy 49.229592 -55.956129) (xy 49.282089 -55.940634)
			(xy 49.336262 -55.932801) (xy 49.36363 -55.932324) (xy 49.390882 -55.932748) (xy 49.444831 -55.940509)
			(xy 49.497127 -55.955868) (xy 49.546704 -55.978512) (xy 49.592555 -56.007982) (xy 49.633745 -56.043676)
			(xy 49.669436 -56.084869) (xy 49.698902 -56.130722) (xy 49.721543 -56.180301) (xy 49.736898 -56.232598)
			(xy 49.744654 -56.286548) (xy 49.744654 -56.297068) (xy 50.086512 -56.297068) (xy 50.090583 -56.241446)
			(xy 50.102709 -56.187009) (xy 50.122632 -56.134918) (xy 50.149928 -56.086283) (xy 50.184014 -56.04214)
			(xy 50.224163 -56.003431) (xy 50.269521 -55.97098) (xy 50.319121 -55.945479) (xy 50.371905 -55.927472)
			(xy 50.426748 -55.917342) (xy 50.482482 -55.915305) (xy 50.537919 -55.921405) (xy 50.591876 -55.935511)
			(xy 50.643205 -55.957323) (xy 50.690811 -55.986377) (xy 50.733679 -56.022052) (xy 50.770896 -56.063589)
			(xy 50.801669 -56.110102) (xy 50.825341 -56.160599) (xy 50.841409 -56.214006) (xy 50.849529 -56.269182)
			(xy 50.850038 -56.297068) (xy 50.849529 -56.324954) (xy 50.841409 -56.38013) (xy 50.825341 -56.433537)
			(xy 50.801669 -56.484034) (xy 50.770896 -56.530547) (xy 50.733679 -56.572084) (xy 50.690811 -56.607759)
			(xy 50.643205 -56.636813) (xy 50.591876 -56.658625) (xy 50.537919 -56.672731) (xy 50.482482 -56.678831)
			(xy 50.426748 -56.676794) (xy 50.371905 -56.666664) (xy 50.319121 -56.648657) (xy 50.269521 -56.623156)
			(xy 50.224163 -56.590705) (xy 50.184014 -56.551996) (xy 50.149928 -56.507853) (xy 50.122632 -56.459218)
			(xy 50.102709 -56.407127) (xy 50.090583 -56.35269) (xy 50.086512 -56.297068) (xy 49.744654 -56.297068)
			(xy 49.744654 -56.341052) (xy 49.736898 -56.395002) (xy 49.721543 -56.447299) (xy 49.698902 -56.496878)
			(xy 49.669436 -56.542731) (xy 49.633745 -56.583924) (xy 49.592555 -56.619618) (xy 49.546704 -56.649088)
			(xy 49.497127 -56.671732) (xy 49.444831 -56.687091) (xy 49.390882 -56.694852) (xy 49.36363 -56.69534)
			(xy 49.33626 -56.694871) (xy 49.28208 -56.687056) (xy 49.229577 -56.671569) (xy 49.17983 -56.648727)
			(xy 49.133863 -56.619002) (xy 49.112932 -56.60136) (xy 49.112678 -56.601106) (xy 49.105601 -56.595505)
			(xy 49.088677 -56.589267) (xy 49.079658 -56.588914) (xy 49.012602 -56.588914) (xy 49.003585 -56.589269)
			(xy 48.986668 -56.595518) (xy 48.979582 -56.601106) (xy 48.979582 -56.60136) (xy 48.979328 -56.60136)
			(xy 48.958395 -56.619001) (xy 48.912427 -56.648725) (xy 48.862681 -56.671571) (xy 48.810179 -56.687067)
			(xy 48.756001 -56.694896) (xy 48.701259 -56.694896) (xy 48.647081 -56.687067) (xy 48.594579 -56.671571)
			(xy 48.544833 -56.648725) (xy 48.498865 -56.619001) (xy 48.477932 -56.60136) (xy 48.477678 -56.601106)
			(xy 48.470601 -56.595505) (xy 48.453677 -56.589267) (xy 48.444658 -56.588914) (xy 48.377602 -56.588914)
			(xy 48.368585 -56.589269) (xy 48.351668 -56.595518) (xy 48.344582 -56.601106) (xy 48.344074 -56.60136)
			(xy 48.331339 -56.612303) (xy 48.304248 -56.632145) (xy 48.289972 -56.640984) (xy 48.281082 -56.646318)
			(xy 48.26889 -56.663336) (xy 48.24857 -56.756554) (xy 48.252888 -56.777128) (xy 48.25873 -56.785764)
			(xy 48.27472 -56.809834) (xy 48.300064 -56.861763) (xy 48.317293 -56.91692) (xy 48.326011 -56.974042)
			(xy 48.326548 -57.002934) (xy 48.326062 -57.030185) (xy 48.318306 -57.084133) (xy 48.302951 -57.136428)
			(xy 48.280309 -57.186005) (xy 48.250843 -57.231855) (xy 48.215152 -57.273046) (xy 48.173961 -57.308737)
			(xy 48.128111 -57.338203) (xy 48.078534 -57.360845) (xy 48.026239 -57.3762) (xy 47.972291 -57.383956)
			(xy 47.917789 -57.383956) (xy 47.863841 -57.3762) (xy 47.811546 -57.360845) (xy 47.761969 -57.338203)
			(xy 47.716119 -57.308737) (xy 47.674928 -57.273046) (xy 47.639237 -57.231855) (xy 47.609771 -57.186005)
			(xy 47.587129 -57.136428) (xy 47.571774 -57.084133) (xy 47.564018 -57.030185) (xy 47.563532 -57.002934)
			(xy 40.24112 -57.002934) (xy 40.241081 -57.003024) (xy 40.213942 -57.047512) (xy 40.197786 -57.067958)
			(xy 40.192452 -57.074562) (xy 40.18026 -57.107328) (xy 40.180514 -57.117234) (xy 40.180514 -57.117488)
			(xy 40.183054 -57.184544) (xy 40.183308 -57.192164) (xy 40.18915 -57.20969) (xy 40.195246 -57.217056)
			(xy 40.1955 -57.21731) (xy 40.199056 -57.221628) (xy 40.29075 -57.332372) (xy 40.296679 -57.340179)
			(xy 40.302651 -57.358832) (xy 40.301168 -57.378362) (xy 40.292448 -57.395899) (xy 40.285416 -57.40273)
			(xy 40.28059 -57.407556) (xy 40.281606 -57.421526) (xy 40.281606 -57.42305) (xy 40.282557 -57.432801)
			(xy 40.283575 -57.452369) (xy 40.283638 -57.462166) (xy 40.283638 -57.471056) (xy 40.283018 -57.48528)
			(xy 56.60593 -57.48528) (xy 56.610001 -57.429658) (xy 56.622127 -57.375221) (xy 56.64205 -57.32313)
			(xy 56.669346 -57.274495) (xy 56.703432 -57.230352) (xy 56.743581 -57.191643) (xy 56.788939 -57.159192)
			(xy 56.838539 -57.133691) (xy 56.891323 -57.115684) (xy 56.946166 -57.105554) (xy 57.0019 -57.103517)
			(xy 57.057337 -57.109617) (xy 57.111294 -57.123723) (xy 57.162623 -57.145535) (xy 57.210229 -57.174589)
			(xy 57.253097 -57.210264) (xy 57.290314 -57.251801) (xy 57.321087 -57.298314) (xy 57.344759 -57.348811)
			(xy 57.360827 -57.402218) (xy 57.368947 -57.457394) (xy 57.369456 -57.48528) (xy 57.368947 -57.513166)
			(xy 57.360827 -57.568342) (xy 57.344759 -57.621749) (xy 57.321087 -57.672246) (xy 57.290314 -57.718759)
			(xy 57.253097 -57.760296) (xy 57.210229 -57.795971) (xy 57.162623 -57.825025) (xy 57.111294 -57.846837)
			(xy 57.057337 -57.860943) (xy 57.0019 -57.867043) (xy 56.946166 -57.865006) (xy 56.891323 -57.854876)
			(xy 56.838539 -57.836869) (xy 56.788939 -57.811368) (xy 56.743581 -57.778917) (xy 56.703432 -57.740208)
			(xy 56.669346 -57.696065) (xy 56.64205 -57.64743) (xy 56.622127 -57.595339) (xy 56.610001 -57.540902)
			(xy 56.60593 -57.48528) (xy 40.283018 -57.48528) (xy 40.282426 -57.498869) (xy 40.272951 -57.553725)
			(xy 40.255621 -57.606628) (xy 40.230802 -57.656459) (xy 40.215312 -57.67959) (xy 40.212264 -57.683654)
			(xy 40.20693 -57.69102) (xy 40.20566 -57.69483) (xy 40.20312 -57.703212) (xy 40.201088 -57.709816)
			(xy 40.202358 -57.742582) (xy 40.202358 -57.74309) (xy 40.205152 -57.82056) (xy 40.205152 -57.821068)
			(xy 40.206168 -57.853834) (xy 40.20688 -57.859614) (xy 40.210599 -57.870648) (xy 40.213534 -57.875678)
			(xy 40.215312 -57.878472) (xy 40.216582 -57.88025) (xy 40.217344 -57.881266) (xy 40.217598 -57.88152)
			(xy 40.220138 -57.88533) (xy 40.221408 -57.887108) (xy 40.222424 -57.888886) (xy 40.224202 -57.891426)
			(xy 40.226488 -57.894982) (xy 40.239835 -57.917389) (xy 40.260993 -57.96506) (xy 40.275468 -58.015166)
			(xy 40.282991 -58.066775) (xy 40.283638 -58.092848) (xy 40.283638 -58.096658) (xy 40.283231 -58.121562)
			(xy 40.276746 -58.170946) (xy 40.263893 -58.219066) (xy 40.24489 -58.265107) (xy 40.232838 -58.286904)
			(xy 40.229536 -58.292492) (xy 40.222424 -58.317892) (xy 40.222678 -58.32602) (xy 40.22598 -58.420508)
			(xy 40.229536 -58.52287) (xy 40.231822 -58.535824) (xy 40.233346 -58.541158) (xy 40.235886 -58.546238)
			(xy 40.236394 -58.547) (xy 40.236648 -58.547508) (xy 40.237156 -58.54827) (xy 40.251784 -58.576463)
			(xy 40.272502 -58.636502) (xy 40.279685 -58.679334) (xy 47.995332 -58.679334) (xy 47.995745 -58.653018)
			(xy 48.00299 -58.600887) (xy 48.017319 -58.550243) (xy 48.038461 -58.502044) (xy 48.066017 -58.457202)
			(xy 48.099466 -58.416565) (xy 48.118522 -58.39841) (xy 48.125925 -58.39089) (xy 48.134448 -58.371608)
			(xy 48.135032 -58.361072) (xy 48.135032 -58.286396) (xy 48.134509 -58.275846) (xy 48.125968 -58.256551)
			(xy 48.118522 -58.249058) (xy 48.099457 -58.230912) (xy 48.066 -58.19028) (xy 48.038442 -58.145438)
			(xy 48.017305 -58.097236) (xy 48.00299 -58.046586) (xy 47.995768 -57.994451) (xy 47.995332 -57.968134)
			(xy 47.995818 -57.940883) (xy 48.003574 -57.886935) (xy 48.018929 -57.83464) (xy 48.041571 -57.785063)
			(xy 48.071037 -57.739213) (xy 48.106728 -57.698022) (xy 48.147919 -57.662331) (xy 48.193769 -57.632865)
			(xy 48.243346 -57.610223) (xy 48.295641 -57.594868) (xy 48.349589 -57.587112) (xy 48.404091 -57.587112)
			(xy 48.458039 -57.594868) (xy 48.510334 -57.610223) (xy 48.559911 -57.632865) (xy 48.605761 -57.662331)
			(xy 48.646952 -57.698022) (xy 48.682643 -57.739213) (xy 48.712109 -57.785063) (xy 48.734751 -57.83464)
			(xy 48.750106 -57.886935) (xy 48.757862 -57.940883) (xy 48.758348 -57.968134) (xy 48.75792 -57.994449)
			(xy 48.750679 -58.04658) (xy 48.743411 -58.072274) (xy 51.993544 -58.072274) (xy 51.997615 -58.016652)
			(xy 52.009741 -57.962215) (xy 52.029664 -57.910124) (xy 52.05696 -57.861489) (xy 52.091046 -57.817346)
			(xy 52.131195 -57.778637) (xy 52.176553 -57.746186) (xy 52.226153 -57.720685) (xy 52.278937 -57.702678)
			(xy 52.33378 -57.692548) (xy 52.389514 -57.690511) (xy 52.444951 -57.696611) (xy 52.498908 -57.710717)
			(xy 52.550237 -57.732529) (xy 52.597843 -57.761583) (xy 52.640711 -57.797258) (xy 52.677928 -57.838795)
			(xy 52.708701 -57.885308) (xy 52.732373 -57.935805) (xy 52.748441 -57.989212) (xy 52.756561 -58.044388)
			(xy 52.75707 -58.072274) (xy 52.757 -58.076084) (xy 57.358024 -58.076084) (xy 57.362095 -58.020462)
			(xy 57.374221 -57.966025) (xy 57.394144 -57.913934) (xy 57.42144 -57.865299) (xy 57.455526 -57.821156)
			(xy 57.495675 -57.782447) (xy 57.541033 -57.749996) (xy 57.590633 -57.724495) (xy 57.643417 -57.706488)
			(xy 57.69826 -57.696358) (xy 57.753994 -57.694321) (xy 57.809431 -57.700421) (xy 57.863388 -57.714527)
			(xy 57.914717 -57.736339) (xy 57.962323 -57.765393) (xy 58.005191 -57.801068) (xy 58.042408 -57.842605)
			(xy 58.058744 -57.867296) (xy 59.643008 -57.867296) (xy 59.647079 -57.811674) (xy 59.659205 -57.757237)
			(xy 59.679128 -57.705146) (xy 59.706424 -57.656511) (xy 59.74051 -57.612368) (xy 59.780659 -57.573659)
			(xy 59.826017 -57.541208) (xy 59.875617 -57.515707) (xy 59.928401 -57.4977) (xy 59.983244 -57.48757)
			(xy 60.038978 -57.485533) (xy 60.094415 -57.491633) (xy 60.148372 -57.505739) (xy 60.199701 -57.527551)
			(xy 60.247307 -57.556605) (xy 60.290175 -57.59228) (xy 60.327392 -57.633817) (xy 60.358165 -57.68033)
			(xy 60.381837 -57.730827) (xy 60.397905 -57.784234) (xy 60.406025 -57.83941) (xy 60.406534 -57.867296)
			(xy 60.406025 -57.895182) (xy 60.397905 -57.950358) (xy 60.381837 -58.003765) (xy 60.358165 -58.054262)
			(xy 60.327392 -58.100775) (xy 60.290175 -58.142312) (xy 60.247307 -58.177987) (xy 60.199701 -58.207041)
			(xy 60.148372 -58.228853) (xy 60.094415 -58.242959) (xy 60.038978 -58.249059) (xy 59.983244 -58.247022)
			(xy 59.928401 -58.236892) (xy 59.875617 -58.218885) (xy 59.826017 -58.193384) (xy 59.780659 -58.160933)
			(xy 59.74051 -58.122224) (xy 59.706424 -58.078081) (xy 59.679128 -58.029446) (xy 59.659205 -57.977355)
			(xy 59.647079 -57.922918) (xy 59.643008 -57.867296) (xy 58.058744 -57.867296) (xy 58.073181 -57.889118)
			(xy 58.096853 -57.939615) (xy 58.112921 -57.993022) (xy 58.121041 -58.048198) (xy 58.12155 -58.076084)
			(xy 58.121041 -58.10397) (xy 58.112921 -58.159146) (xy 58.096853 -58.212553) (xy 58.073181 -58.26305)
			(xy 58.042408 -58.309563) (xy 58.005191 -58.3511) (xy 57.962323 -58.386775) (xy 57.914717 -58.415829)
			(xy 57.863388 -58.437641) (xy 57.809431 -58.451747) (xy 57.753994 -58.457847) (xy 57.69826 -58.45581)
			(xy 57.643417 -58.44568) (xy 57.590633 -58.427673) (xy 57.541033 -58.402172) (xy 57.495675 -58.369721)
			(xy 57.455526 -58.331012) (xy 57.42144 -58.286869) (xy 57.394144 -58.238234) (xy 57.374221 -58.186143)
			(xy 57.362095 -58.131706) (xy 57.358024 -58.076084) (xy 52.757 -58.076084) (xy 52.756561 -58.10016)
			(xy 52.748441 -58.155336) (xy 52.732373 -58.208743) (xy 52.708701 -58.25924) (xy 52.677928 -58.305753)
			(xy 52.640711 -58.34729) (xy 52.597843 -58.382965) (xy 52.550237 -58.412019) (xy 52.498908 -58.433831)
			(xy 52.444951 -58.447937) (xy 52.389514 -58.454037) (xy 52.33378 -58.452) (xy 52.278937 -58.44187)
			(xy 52.226153 -58.423863) (xy 52.176553 -58.398362) (xy 52.131195 -58.365911) (xy 52.091046 -58.327202)
			(xy 52.05696 -58.283059) (xy 52.029664 -58.234424) (xy 52.009741 -58.182333) (xy 51.997615 -58.127896)
			(xy 51.993544 -58.072274) (xy 48.743411 -58.072274) (xy 48.736354 -58.097225) (xy 48.715214 -58.145424)
			(xy 48.68766 -58.190266) (xy 48.654213 -58.230903) (xy 48.635158 -58.249058) (xy 48.627781 -58.256601)
			(xy 48.619241 -58.275864) (xy 48.618648 -58.286396) (xy 48.618648 -58.361072) (xy 48.619165 -58.371623)
			(xy 48.627707 -58.39092) (xy 48.635158 -58.39841) (xy 48.654222 -58.416556) (xy 48.687677 -58.457189)
			(xy 48.715233 -58.502032) (xy 48.736369 -58.550234) (xy 48.739475 -58.561224) (xy 58.562238 -58.561224)
			(xy 58.566309 -58.505602) (xy 58.578435 -58.451165) (xy 58.598358 -58.399074) (xy 58.625654 -58.350439)
			(xy 58.65974 -58.306296) (xy 58.699889 -58.267587) (xy 58.745247 -58.235136) (xy 58.794847 -58.209635)
			(xy 58.847631 -58.191628) (xy 58.902474 -58.181498) (xy 58.958208 -58.179461) (xy 59.013645 -58.185561)
			(xy 59.067602 -58.199667) (xy 59.118931 -58.221479) (xy 59.166537 -58.250533) (xy 59.209405 -58.286208)
			(xy 59.246622 -58.327745) (xy 59.277395 -58.374258) (xy 59.301067 -58.424755) (xy 59.317135 -58.478162)
			(xy 59.325255 -58.533338) (xy 59.325764 -58.561224) (xy 59.325255 -58.58911) (xy 59.317135 -58.644286)
			(xy 59.301067 -58.697693) (xy 59.277395 -58.74819) (xy 59.246622 -58.794703) (xy 59.209405 -58.83624)
			(xy 59.166537 -58.871915) (xy 59.118931 -58.900969) (xy 59.067602 -58.922781) (xy 59.013645 -58.936887)
			(xy 58.958208 -58.942987) (xy 58.902474 -58.94095) (xy 58.847631 -58.93082) (xy 58.794847 -58.912813)
			(xy 58.745247 -58.887312) (xy 58.699889 -58.854861) (xy 58.65974 -58.816152) (xy 58.625654 -58.772009)
			(xy 58.598358 -58.723374) (xy 58.578435 -58.671283) (xy 58.566309 -58.616846) (xy 58.562238 -58.561224)
			(xy 48.739475 -58.561224) (xy 48.750685 -58.600883) (xy 48.75791 -58.653018) (xy 48.758348 -58.679334)
			(xy 48.757862 -58.706585) (xy 48.750106 -58.760533) (xy 48.734751 -58.812828) (xy 48.712109 -58.862405)
			(xy 48.682643 -58.908255) (xy 48.646952 -58.949446) (xy 48.605761 -58.985137) (xy 48.559911 -59.014603)
			(xy 48.510334 -59.037245) (xy 48.458039 -59.0526) (xy 48.404091 -59.060356) (xy 48.349589 -59.060356)
			(xy 48.295641 -59.0526) (xy 48.243346 -59.037245) (xy 48.193769 -59.014603) (xy 48.147919 -58.985137)
			(xy 48.106728 -58.949446) (xy 48.071037 -58.908255) (xy 48.041571 -58.862405) (xy 48.018929 -58.812828)
			(xy 48.003574 -58.760533) (xy 47.995818 -58.706585) (xy 47.995332 -58.679334) (xy 40.279685 -58.679334)
			(xy 40.283006 -58.69914) (xy 40.283638 -58.730896) (xy 40.283638 -58.73623) (xy 40.282876 -58.756804)
			(xy 40.282876 -58.757312) (xy 40.28186 -58.768488) (xy 40.28186 -58.769504) (xy 40.280437 -58.782709)
			(xy 40.275987 -58.808894) (xy 40.27297 -58.821828) (xy 40.268951 -58.837363) (xy 40.258647 -58.867755)
			(xy 40.252396 -58.882534) (xy 40.252396 -58.883042) (xy 40.251634 -58.884566) (xy 40.25138 -58.885074)
			(xy 40.251126 -58.885582) (xy 40.24884 -58.890662) (xy 40.247824 -58.892948) (xy 40.242998 -58.906918)
			(xy 40.243252 -58.915808) (xy 40.243252 -58.916824) (xy 40.252259 -59.174634) (xy 57.093102 -59.174634)
			(xy 57.097173 -59.119012) (xy 57.109299 -59.064575) (xy 57.129222 -59.012484) (xy 57.156518 -58.963849)
			(xy 57.190604 -58.919706) (xy 57.230753 -58.880997) (xy 57.276111 -58.848546) (xy 57.325711 -58.823045)
			(xy 57.378495 -58.805038) (xy 57.433338 -58.794908) (xy 57.489072 -58.792871) (xy 57.544509 -58.798971)
			(xy 57.598466 -58.813077) (xy 57.649795 -58.834889) (xy 57.697401 -58.863943) (xy 57.740269 -58.899618)
			(xy 57.777486 -58.941155) (xy 57.808259 -58.987668) (xy 57.831931 -59.038165) (xy 57.847999 -59.091572)
			(xy 57.856119 -59.146748) (xy 57.856628 -59.174634) (xy 57.856119 -59.20252) (xy 57.847999 -59.257696)
			(xy 57.831931 -59.311103) (xy 57.808259 -59.3616) (xy 57.777486 -59.408113) (xy 57.740269 -59.44965)
			(xy 57.697401 -59.485325) (xy 57.649795 -59.514379) (xy 57.598466 -59.536191) (xy 57.544509 -59.550297)
			(xy 57.489072 -59.556397) (xy 57.433338 -59.55436) (xy 57.378495 -59.54423) (xy 57.325711 -59.526223)
			(xy 57.276111 -59.500722) (xy 57.230753 -59.468271) (xy 57.190604 -59.429562) (xy 57.156518 -59.385419)
			(xy 57.129222 -59.336784) (xy 57.109299 -59.284693) (xy 57.097173 -59.230256) (xy 57.093102 -59.174634)
			(xy 40.252259 -59.174634) (xy 40.268906 -59.651138) (xy 40.281769 -60.019251) (xy 48.135784 -60.019251)
			(xy 48.135784 -59.964749) (xy 48.14354 -59.910803) (xy 48.158895 -59.85851) (xy 48.181535 -59.808934)
			(xy 48.211 -59.763084) (xy 48.246691 -59.721895) (xy 48.287879 -59.686204) (xy 48.333728 -59.656738)
			(xy 48.383304 -59.634097) (xy 48.435597 -59.618741) (xy 48.489543 -59.610984) (xy 48.516794 -59.610498)
			(xy 48.544164 -59.610968) (xy 48.598343 -59.618785) (xy 48.650846 -59.634273) (xy 48.700593 -59.657114)
			(xy 48.74656 -59.686837) (xy 48.767492 -59.704478) (xy 48.767746 -59.704732) (xy 48.774841 -59.710306)
			(xy 48.791751 -59.716559) (xy 48.800766 -59.716924) (xy 48.867822 -59.716924) (xy 48.876839 -59.716573)
			(xy 48.893756 -59.710321) (xy 48.900842 -59.704732) (xy 48.900842 -59.704478) (xy 48.901096 -59.704478)
			(xy 48.922029 -59.686837) (xy 48.967997 -59.657113) (xy 49.017743 -59.634267) (xy 49.070245 -59.618771)
			(xy 49.124423 -59.610942) (xy 49.179165 -59.610942) (xy 49.233343 -59.618771) (xy 49.285845 -59.634267)
			(xy 49.335591 -59.657113) (xy 49.381559 -59.686837) (xy 49.402492 -59.704478) (xy 49.402746 -59.704732)
			(xy 49.409841 -59.710306) (xy 49.426751 -59.716559) (xy 49.435766 -59.716924) (xy 49.502822 -59.716924)
			(xy 49.511839 -59.716573) (xy 49.528756 -59.710321) (xy 49.535842 -59.704732) (xy 49.535842 -59.704478)
			(xy 49.536096 -59.704478) (xy 49.557016 -59.686824) (xy 49.602992 -59.657115) (xy 49.652743 -59.634282)
			(xy 49.705246 -59.618795) (xy 49.759424 -59.61097) (xy 49.786794 -59.610498) (xy 49.814048 -59.610949)
			(xy 49.868 -59.618705) (xy 49.920299 -59.634061) (xy 49.969881 -59.656704) (xy 50.015736 -59.686172)
			(xy 50.05693 -59.721866) (xy 50.092624 -59.76306) (xy 50.122094 -59.808914) (xy 50.144737 -59.858495)
			(xy 50.160093 -59.910794) (xy 50.167851 -59.964746) (xy 50.167851 -60.019254) (xy 50.160093 -60.073206)
			(xy 50.144737 -60.125505) (xy 50.122094 -60.175086) (xy 50.092624 -60.22094) (xy 50.05693 -60.262134)
			(xy 50.015736 -60.297828) (xy 49.969881 -60.327296) (xy 49.920299 -60.349939) (xy 49.868 -60.365295)
			(xy 49.814048 -60.373051) (xy 49.786794 -60.373514) (xy 49.759424 -60.373048) (xy 49.705245 -60.36523)
			(xy 49.652742 -60.34974) (xy 49.602995 -60.326899) (xy 49.557028 -60.297175) (xy 49.536096 -60.279534)
			(xy 49.535842 -60.27928) (xy 49.528749 -60.273703) (xy 49.511837 -60.267451) (xy 49.502822 -60.267088)
			(xy 49.435766 -60.267088) (xy 49.426748 -60.267431) (xy 49.409831 -60.273688) (xy 49.402746 -60.27928)
			(xy 49.402492 -60.279534) (xy 49.381559 -60.297175) (xy 49.335591 -60.326899) (xy 49.285845 -60.349745)
			(xy 49.233343 -60.365241) (xy 49.179165 -60.37307) (xy 49.124423 -60.37307) (xy 49.070245 -60.365241)
			(xy 49.017743 -60.349745) (xy 48.967997 -60.326899) (xy 48.922029 -60.297175) (xy 48.901096 -60.279534)
			(xy 48.900842 -60.27928) (xy 48.893749 -60.273703) (xy 48.876837 -60.267451) (xy 48.867822 -60.267088)
			(xy 48.800766 -60.267088) (xy 48.791748 -60.267431) (xy 48.774831 -60.273688) (xy 48.767746 -60.27928)
			(xy 48.767746 -60.279534) (xy 48.767492 -60.279534) (xy 48.746578 -60.297196) (xy 48.7006 -60.326903)
			(xy 48.650848 -60.349734) (xy 48.598343 -60.36522) (xy 48.544164 -60.373043) (xy 48.516794 -60.373514)
			(xy 48.489543 -60.373016) (xy 48.435597 -60.365259) (xy 48.383304 -60.349903) (xy 48.333728 -60.327262)
			(xy 48.287879 -60.297796) (xy 48.246691 -60.262105) (xy 48.211 -60.220916) (xy 48.181535 -60.175066)
			(xy 48.158895 -60.12549) (xy 48.14354 -60.073197) (xy 48.135784 -60.019251) (xy 40.281769 -60.019251)
			(xy 40.303228 -60.633356) (xy 59.796932 -60.633356) (xy 59.801003 -60.577734) (xy 59.813129 -60.523297)
			(xy 59.833052 -60.471206) (xy 59.860348 -60.422571) (xy 59.894434 -60.378428) (xy 59.934583 -60.339719)
			(xy 59.979941 -60.307268) (xy 60.029541 -60.281767) (xy 60.082325 -60.26376) (xy 60.137168 -60.25363)
			(xy 60.192902 -60.251593) (xy 60.248339 -60.257693) (xy 60.302296 -60.271799) (xy 60.353625 -60.293611)
			(xy 60.401231 -60.322665) (xy 60.444099 -60.35834) (xy 60.481316 -60.399877) (xy 60.512089 -60.44639)
			(xy 60.535761 -60.496887) (xy 60.551829 -60.550294) (xy 60.559949 -60.60547) (xy 60.560458 -60.633356)
			(xy 60.559949 -60.661242) (xy 60.551829 -60.716418) (xy 60.535761 -60.769825) (xy 60.512089 -60.820322)
			(xy 60.481316 -60.866835) (xy 60.444099 -60.908372) (xy 60.401231 -60.944047) (xy 60.353625 -60.973101)
			(xy 60.302296 -60.994913) (xy 60.248339 -61.009019) (xy 60.192902 -61.015119) (xy 60.137168 -61.013082)
			(xy 60.082325 -61.002952) (xy 60.029541 -60.984945) (xy 59.979941 -60.959444) (xy 59.934583 -60.926993)
			(xy 59.894434 -60.888284) (xy 59.860348 -60.844141) (xy 59.833052 -60.795506) (xy 59.813129 -60.743415)
			(xy 59.801003 -60.688978) (xy 59.796932 -60.633356) (xy 40.303228 -60.633356) (xy 40.333086 -61.487812)
			(xy 58.304428 -61.487812) (xy 58.308499 -61.43219) (xy 58.320625 -61.377753) (xy 58.340548 -61.325662)
			(xy 58.367844 -61.277027) (xy 58.40193 -61.232884) (xy 58.442079 -61.194175) (xy 58.487437 -61.161724)
			(xy 58.537037 -61.136223) (xy 58.589821 -61.118216) (xy 58.644664 -61.108086) (xy 58.700398 -61.106049)
			(xy 58.755835 -61.112149) (xy 58.809792 -61.126255) (xy 58.861121 -61.148067) (xy 58.908727 -61.177121)
			(xy 58.951595 -61.212796) (xy 58.988812 -61.254333) (xy 59.019585 -61.300846) (xy 59.043257 -61.351343)
			(xy 59.059325 -61.40475) (xy 59.067445 -61.459926) (xy 59.067954 -61.487812) (xy 59.067445 -61.515698)
			(xy 59.059325 -61.570874) (xy 59.043257 -61.624281) (xy 59.019585 -61.674778) (xy 58.988812 -61.721291)
			(xy 58.951595 -61.762828) (xy 58.908727 -61.798503) (xy 58.861121 -61.827557) (xy 58.809792 -61.849369)
			(xy 58.755835 -61.863475) (xy 58.700398 -61.869575) (xy 58.644664 -61.867538) (xy 58.589821 -61.857408)
			(xy 58.537037 -61.839401) (xy 58.487437 -61.8139) (xy 58.442079 -61.781449) (xy 58.40193 -61.74274)
			(xy 58.367844 -61.698597) (xy 58.340548 -61.649962) (xy 58.320625 -61.597871) (xy 58.308499 -61.543434)
			(xy 58.304428 -61.487812) (xy 40.333086 -61.487812) (xy 40.334692 -61.533786) (xy 40.355187 -62.121034)
			(xy 56.242202 -62.121034) (xy 56.246273 -62.065412) (xy 56.258399 -62.010975) (xy 56.278322 -61.958884)
			(xy 56.305618 -61.910249) (xy 56.339704 -61.866106) (xy 56.379853 -61.827397) (xy 56.425211 -61.794946)
			(xy 56.474811 -61.769445) (xy 56.527595 -61.751438) (xy 56.582438 -61.741308) (xy 56.638172 -61.739271)
			(xy 56.693609 -61.745371) (xy 56.747566 -61.759477) (xy 56.798895 -61.781289) (xy 56.846501 -61.810343)
			(xy 56.889369 -61.846018) (xy 56.926586 -61.887555) (xy 56.957359 -61.934068) (xy 56.981031 -61.984565)
			(xy 56.997099 -62.037972) (xy 57.005219 -62.093148) (xy 57.005728 -62.121034) (xy 57.005219 -62.14892)
			(xy 56.997099 -62.204096) (xy 56.981031 -62.257503) (xy 56.957359 -62.308) (xy 56.926586 -62.354513)
			(xy 56.889369 -62.39605) (xy 56.846501 -62.431725) (xy 56.798895 -62.460779) (xy 56.747566 -62.482591)
			(xy 56.693609 -62.496697) (xy 56.638172 -62.502797) (xy 56.582438 -62.50076) (xy 56.527595 -62.49063)
			(xy 56.474811 -62.472623) (xy 56.425211 -62.447122) (xy 56.379853 -62.414671) (xy 56.339704 -62.375962)
			(xy 56.305618 -62.331819) (xy 56.278322 -62.283184) (xy 56.258399 -62.231093) (xy 56.246273 -62.176656)
			(xy 56.242202 -62.121034) (xy 40.355187 -62.121034) (xy 40.393317 -63.213553) (xy 48.120765 -63.213553)
			(xy 48.120765 -63.159047) (xy 48.128522 -63.105097) (xy 48.143878 -63.0528) (xy 48.166521 -63.003221)
			(xy 48.195989 -62.957369) (xy 48.231682 -62.916177) (xy 48.272875 -62.880484) (xy 48.318728 -62.851017)
			(xy 48.368308 -62.828376) (xy 48.420605 -62.813021) (xy 48.474555 -62.805265) (xy 48.501808 -62.804802)
			(xy 48.529178 -62.805263) (xy 48.583358 -62.813082) (xy 48.635861 -62.828572) (xy 48.685608 -62.851415)
			(xy 48.731574 -62.88114) (xy 48.752506 -62.898782) (xy 48.75276 -62.899036) (xy 48.759851 -62.904616)
			(xy 48.776765 -62.910866) (xy 48.78578 -62.911228) (xy 48.852836 -62.911228) (xy 48.861854 -62.910882)
			(xy 48.87877 -62.904626) (xy 48.885856 -62.899036) (xy 48.885856 -62.898782) (xy 48.88611 -62.898782)
			(xy 48.907043 -62.881141) (xy 48.953011 -62.851417) (xy 49.002757 -62.828571) (xy 49.055259 -62.813075)
			(xy 49.109437 -62.805246) (xy 49.164179 -62.805246) (xy 49.218357 -62.813075) (xy 49.270859 -62.828571)
			(xy 49.320605 -62.851417) (xy 49.366573 -62.881141) (xy 49.387506 -62.898782) (xy 49.38776 -62.899036)
			(xy 49.394851 -62.904616) (xy 49.411765 -62.910866) (xy 49.42078 -62.911228) (xy 49.487836 -62.911228)
			(xy 49.496854 -62.910882) (xy 49.51377 -62.904626) (xy 49.520856 -62.899036) (xy 49.520856 -62.898782)
			(xy 49.52111 -62.898782) (xy 49.542025 -62.881122) (xy 49.588003 -62.851414) (xy 49.637755 -62.828582)
			(xy 49.690259 -62.813096) (xy 49.744438 -62.805273) (xy 49.771808 -62.804802) (xy 49.79906 -62.805268)
			(xy 49.853008 -62.813026) (xy 49.905303 -62.828382) (xy 49.954881 -62.851024) (xy 50.000731 -62.880492)
			(xy 50.041922 -62.916184) (xy 50.077613 -62.957375) (xy 50.107079 -63.003226) (xy 50.129721 -63.052804)
			(xy 50.139537 -63.086234) (xy 53.387496 -63.086234) (xy 53.391567 -63.030612) (xy 53.403693 -62.976175)
			(xy 53.423616 -62.924084) (xy 53.450912 -62.875449) (xy 53.484998 -62.831306) (xy 53.525147 -62.792597)
			(xy 53.570505 -62.760146) (xy 53.620105 -62.734645) (xy 53.672889 -62.716638) (xy 53.727732 -62.706508)
			(xy 53.783466 -62.704471) (xy 53.838903 -62.710571) (xy 53.89286 -62.724677) (xy 53.944189 -62.746489)
			(xy 53.991795 -62.775543) (xy 54.034663 -62.811218) (xy 54.07188 -62.852755) (xy 54.102653 -62.899268)
			(xy 54.126325 -62.949765) (xy 54.142393 -63.003172) (xy 54.150513 -63.058348) (xy 54.151022 -63.086234)
			(xy 54.150513 -63.11412) (xy 54.142393 -63.169296) (xy 54.126325 -63.222703) (xy 54.102653 -63.2732)
			(xy 54.1025 -63.273432) (xy 55.576722 -63.273432) (xy 55.580793 -63.21781) (xy 55.592919 -63.163373)
			(xy 55.612842 -63.111282) (xy 55.640138 -63.062647) (xy 55.674224 -63.018504) (xy 55.714373 -62.979795)
			(xy 55.759731 -62.947344) (xy 55.809331 -62.921843) (xy 55.862115 -62.903836) (xy 55.916958 -62.893706)
			(xy 55.972692 -62.891669) (xy 56.028129 -62.897769) (xy 56.082086 -62.911875) (xy 56.133415 -62.933687)
			(xy 56.181021 -62.962741) (xy 56.223889 -62.998416) (xy 56.261106 -63.039953) (xy 56.291879 -63.086466)
			(xy 56.315551 -63.136963) (xy 56.331619 -63.19037) (xy 56.339739 -63.245546) (xy 56.340248 -63.273432)
			(xy 56.339739 -63.301318) (xy 56.331619 -63.356494) (xy 56.315551 -63.409901) (xy 56.291879 -63.460398)
			(xy 56.261106 -63.506911) (xy 56.223889 -63.548448) (xy 56.181021 -63.584123) (xy 56.133415 -63.613177)
			(xy 56.082086 -63.634989) (xy 56.028129 -63.649095) (xy 55.972692 -63.655195) (xy 55.916958 -63.653158)
			(xy 55.862115 -63.643028) (xy 55.809331 -63.625021) (xy 55.759731 -63.59952) (xy 55.714373 -63.567069)
			(xy 55.674224 -63.52836) (xy 55.640138 -63.484217) (xy 55.612842 -63.435582) (xy 55.592919 -63.383491)
			(xy 55.580793 -63.329054) (xy 55.576722 -63.273432) (xy 54.1025 -63.273432) (xy 54.07188 -63.319713)
			(xy 54.034663 -63.36125) (xy 53.991795 -63.396925) (xy 53.944189 -63.425979) (xy 53.89286 -63.447791)
			(xy 53.838903 -63.461897) (xy 53.783466 -63.467997) (xy 53.727732 -63.46596) (xy 53.672889 -63.45583)
			(xy 53.620105 -63.437823) (xy 53.570505 -63.412322) (xy 53.525147 -63.379871) (xy 53.484998 -63.341162)
			(xy 53.450912 -63.297019) (xy 53.423616 -63.248384) (xy 53.403693 -63.196293) (xy 53.391567 -63.141856)
			(xy 53.387496 -63.086234) (xy 50.139537 -63.086234) (xy 50.145076 -63.1051) (xy 50.152832 -63.159048)
			(xy 50.152832 -63.213552) (xy 50.145076 -63.2675) (xy 50.129721 -63.319796) (xy 50.107079 -63.369374)
			(xy 50.077613 -63.415225) (xy 50.041922 -63.456416) (xy 50.000731 -63.492108) (xy 49.954881 -63.521576)
			(xy 49.905303 -63.544218) (xy 49.853008 -63.559574) (xy 49.79906 -63.567332) (xy 49.771808 -63.567818)
			(xy 49.744437 -63.567367) (xy 49.690256 -63.559549) (xy 49.637752 -63.544057) (xy 49.588006 -63.521212)
			(xy 49.54204 -63.491482) (xy 49.52111 -63.473838) (xy 49.520856 -63.473584) (xy 49.513759 -63.468013)
			(xy 49.49685 -63.461757) (xy 49.487836 -63.461392) (xy 49.42078 -63.461392) (xy 49.411762 -63.461741)
			(xy 49.394846 -63.467995) (xy 49.38776 -63.473584) (xy 49.387506 -63.473838) (xy 49.366573 -63.491479)
			(xy 49.320605 -63.521203) (xy 49.270859 -63.544049) (xy 49.218357 -63.559545) (xy 49.164179 -63.567374)
			(xy 49.109437 -63.567374) (xy 49.055259 -63.559545) (xy 49.002757 -63.544049) (xy 48.953011 -63.521203)
			(xy 48.907043 -63.491479) (xy 48.88611 -63.473838) (xy 48.885856 -63.473584) (xy 48.878759 -63.468013)
			(xy 48.86185 -63.461757) (xy 48.852836 -63.461392) (xy 48.78578 -63.461392) (xy 48.776762 -63.461741)
			(xy 48.759846 -63.467995) (xy 48.75276 -63.473584) (xy 48.75276 -63.473838) (xy 48.752506 -63.473838)
			(xy 48.731588 -63.491494) (xy 48.685611 -63.521202) (xy 48.635859 -63.544034) (xy 48.583356 -63.559522)
			(xy 48.529178 -63.567346) (xy 48.501808 -63.567818) (xy 48.474555 -63.567335) (xy 48.420605 -63.559579)
			(xy 48.368308 -63.544224) (xy 48.318728 -63.521583) (xy 48.272875 -63.492116) (xy 48.231682 -63.456423)
			(xy 48.195989 -63.415231) (xy 48.166521 -63.369379) (xy 48.143878 -63.3198) (xy 48.128522 -63.267503)
			(xy 48.120765 -63.213553) (xy 40.393317 -63.213553) (xy 40.407082 -63.60795) (xy 40.418004 -63.920624)
			(xy 40.418004 -63.921132) (xy 40.43365 -64.312292) (xy 58.9059 -64.312292) (xy 58.909971 -64.25667)
			(xy 58.922097 -64.202233) (xy 58.94202 -64.150142) (xy 58.969316 -64.101507) (xy 59.003402 -64.057364)
			(xy 59.043551 -64.018655) (xy 59.088909 -63.986204) (xy 59.138509 -63.960703) (xy 59.191293 -63.942696)
			(xy 59.246136 -63.932566) (xy 59.30187 -63.930529) (xy 59.357307 -63.936629) (xy 59.411264 -63.950735)
			(xy 59.462593 -63.972547) (xy 59.510199 -64.001601) (xy 59.553067 -64.037276) (xy 59.590284 -64.078813)
			(xy 59.621057 -64.125326) (xy 59.644729 -64.175823) (xy 59.660797 -64.22923) (xy 59.668917 -64.284406)
			(xy 59.669426 -64.312292) (xy 59.668917 -64.340178) (xy 59.660797 -64.395354) (xy 59.644729 -64.448761)
			(xy 59.621057 -64.499258) (xy 59.590284 -64.545771) (xy 59.553067 -64.587308) (xy 59.510199 -64.622983)
			(xy 59.462593 -64.652037) (xy 59.411264 -64.673849) (xy 59.357307 -64.687955) (xy 59.30187 -64.694055)
			(xy 59.246136 -64.692018) (xy 59.191293 -64.681888) (xy 59.138509 -64.663881) (xy 59.088909 -64.63838)
			(xy 59.043551 -64.605929) (xy 59.003402 -64.56722) (xy 58.969316 -64.523077) (xy 58.94202 -64.474442)
			(xy 58.922097 -64.422351) (xy 58.909971 -64.367914) (xy 58.9059 -64.312292) (xy 40.43365 -64.312292)
			(xy 40.463978 -65.070482) (xy 40.463978 -65.071498) (xy 40.466312 -65.100962) (xy 46.132494 -65.100962)
			(xy 46.136565 -65.04534) (xy 46.148691 -64.990903) (xy 46.168614 -64.938812) (xy 46.19591 -64.890177)
			(xy 46.229996 -64.846034) (xy 46.270145 -64.807325) (xy 46.315503 -64.774874) (xy 46.365103 -64.749373)
			(xy 46.417887 -64.731366) (xy 46.47273 -64.721236) (xy 46.528464 -64.719199) (xy 46.583901 -64.725299)
			(xy 46.637858 -64.739405) (xy 46.689187 -64.761217) (xy 46.736793 -64.790271) (xy 46.779661 -64.825946)
			(xy 46.816878 -64.867483) (xy 46.847651 -64.913996) (xy 46.871323 -64.964493) (xy 46.887391 -65.0179)
			(xy 46.895511 -65.073076) (xy 46.89602 -65.100962) (xy 46.895511 -65.128848) (xy 46.887391 -65.184024)
			(xy 46.871323 -65.237431) (xy 46.847651 -65.287928) (xy 46.816878 -65.334441) (xy 46.779661 -65.375978)
			(xy 46.736793 -65.411653) (xy 46.689187 -65.440707) (xy 46.637858 -65.462519) (xy 46.583901 -65.476625)
			(xy 46.528464 -65.482725) (xy 46.47273 -65.480688) (xy 46.417887 -65.470558) (xy 46.365103 -65.452551)
			(xy 46.315503 -65.42705) (xy 46.270145 -65.394599) (xy 46.229996 -65.35589) (xy 46.19591 -65.311747)
			(xy 46.168614 -65.263112) (xy 46.148691 -65.211021) (xy 46.136565 -65.156584) (xy 46.132494 -65.100962)
			(xy 40.466312 -65.100962) (xy 40.473376 -65.190116) (xy 40.484552 -65.32626) (xy 40.486078 -65.337904)
			(xy 40.498115 -65.358037) (xy 40.507666 -65.364868) (xy 40.515286 -65.369694) (xy 40.515794 -65.369694)
			(xy 40.539924 -65.385442) (xy 40.542718 -65.387474) (xy 40.548306 -65.390268) (xy 40.548814 -65.390268)
			(xy 40.552227 -65.391731) (xy 40.559367 -65.393773) (xy 40.563038 -65.394332) (xy 40.563546 -65.394332)
			(xy 40.569642 -65.39484) (xy 40.59047 -65.39484) (xy 40.596566 -65.394332) (xy 40.60952 -65.3923)
			(xy 40.61206 -65.391538) (xy 40.613584 -65.39103) (xy 40.641279 -65.383016) (xy 40.698294 -65.374467)
			(xy 40.727122 -65.374012) (xy 40.73144 -65.374012) (xy 40.758563 -65.374684) (xy 40.812213 -65.382756)
			(xy 40.864179 -65.398347) (xy 40.913411 -65.421144) (xy 40.958917 -65.450685) (xy 40.999779 -65.486375)
			(xy 41.035173 -65.527494) (xy 41.064384 -65.573213) (xy 41.086823 -65.622609) (xy 41.102038 -65.674686)
			(xy 41.109722 -65.728393) (xy 41.110154 -65.75552) (xy 41.109667 -65.782772) (xy 41.101908 -65.83672)
			(xy 41.086552 -65.889015) (xy 41.06391 -65.938592) (xy 41.034444 -65.984443) (xy 40.998753 -66.025635)
			(xy 40.957564 -66.061329) (xy 40.911715 -66.090798) (xy 40.862139 -66.113443) (xy 40.809845 -66.128803)
			(xy 40.755897 -66.136565) (xy 40.728646 -66.137028) (xy 40.709985 -66.136836) (xy 40.672836 -66.133271)
			(xy 40.654478 -66.129916) (xy 40.64254 -66.12763) (xy 40.631364 -66.130678) (xy 40.625635 -66.132367)
			(xy 40.615115 -66.138018) (xy 40.610536 -66.141854) (xy 40.581072 -66.168524) (xy 40.57269 -66.176144)
			(xy 40.56443 -66.184412) (xy 40.555837 -66.206117) (xy 40.55618 -66.2178) (xy 40.578532 -66.497708)
			(xy 40.58158 -66.536062) (xy 40.590978 -66.654934) (xy 40.592529 -66.665088) (xy 40.602499 -66.683026)
			(xy 40.610282 -66.689732) (xy 40.637206 -66.710814) (xy 40.638476 -66.711576) (xy 40.644826 -66.717926)
			(xy 40.65397 -66.721736) (xy 40.658597 -66.723513) (xy 40.668319 -66.725439) (xy 40.673274 -66.725546)
			(xy 40.682926 -66.725546) (xy 40.68699 -66.724784) (xy 40.699738 -66.722883) (xy 40.725414 -66.720593)
			(xy 40.738298 -66.720212) (xy 40.749728 -66.720212) (xy 40.766746 -66.720466) (xy 40.767254 -66.72072)
			(xy 40.782487 -66.721622) (xy 40.81275 -66.725563) (xy 40.827706 -66.728594) (xy 40.843931 -66.732268)
			(xy 40.875728 -66.742056) (xy 40.891206 -66.748152) (xy 40.916339 -66.75885) (xy 40.963511 -66.786393)
			(xy 40.985186 -66.803016) (xy 40.985694 -66.80327) (xy 40.992522 -66.808263) (xy 41.008484 -66.813834)
			(xy 41.016936 -66.814192) (xy 41.038526 -66.814192) (xy 41.043966 -66.814334) (xy 41.054598 -66.81664)
			(xy 41.059608 -66.818764) (xy 41.07307 -66.82486) (xy 41.081733 -66.828483) (xy 41.100456 -66.829721)
			(xy 41.11836 -66.824101) (xy 41.125902 -66.81851) (xy 41.133014 -66.812922) (xy 41.137586 -66.809366)
			(xy 41.138348 -66.808858) (xy 41.15899 -66.792218) (xy 41.204003 -66.764202) (xy 41.252462 -66.742687)
			(xy 41.303432 -66.728087) (xy 41.355933 -66.720684) (xy 41.382442 -66.720212) (xy 41.382696 -66.720212)
			(xy 41.409949 -66.720675) (xy 41.463899 -66.728432) (xy 41.516196 -66.743788) (xy 41.565775 -66.76643)
			(xy 41.611628 -66.795898) (xy 41.652819 -66.831592) (xy 41.688511 -66.872785) (xy 41.717978 -66.918639)
			(xy 41.740618 -66.968219) (xy 41.755972 -67.020517) (xy 41.763726 -67.074467) (xy 41.764204 -67.10172)
			(xy 41.763729 -67.128797) (xy 41.756068 -67.182407) (xy 41.740903 -67.234395) (xy 41.718539 -67.283716)
			(xy 41.689425 -67.329379) (xy 41.654146 -67.370465) (xy 41.613411 -67.40615) (xy 41.568039 -67.435716)
			(xy 41.518943 -67.458569) (xy 41.467108 -67.474249) (xy 41.413577 -67.482442) (xy 41.386506 -67.483228)
			(xy 41.382188 -67.483228) (xy 41.352278 -67.482623) (xy 41.293195 -67.473251) (xy 41.236295 -67.454783)
			(xy 41.182969 -67.427673) (xy 41.158414 -67.410584) (xy 41.150032 -67.404234) (xy 41.145206 -67.400424)
			(xy 41.13657 -67.39509) (xy 41.135554 -67.394582) (xy 41.130228 -67.392122) (xy 41.118812 -67.389432)
			(xy 41.112948 -67.389248) (xy 41.091866 -67.389248) (xy 41.086427 -67.389104) (xy 41.075796 -67.386794)
			(xy 41.070784 -67.384676) (xy 41.057322 -67.37858) (xy 41.04866 -67.374957) (xy 41.029938 -67.373721)
			(xy 41.012038 -67.379346) (xy 41.00449 -67.38493) (xy 40.997378 -67.390518) (xy 40.992806 -67.394074)
			(xy 40.992044 -67.394582) (xy 40.971403 -67.411224) (xy 40.92639 -67.439244) (xy 40.877932 -67.460761)
			(xy 40.826961 -67.475362) (xy 40.77446 -67.482765) (xy 40.74795 -67.483228) (xy 40.741092 -67.483228)
			(xy 40.733218 -67.48399) (xy 40.726142 -67.485551) (xy 40.721242 -67.488054) (xy 44.779182 -67.488054)
			(xy 44.783253 -67.432432) (xy 44.795379 -67.377995) (xy 44.815302 -67.325904) (xy 44.842598 -67.277269)
			(xy 44.876684 -67.233126) (xy 44.916833 -67.194417) (xy 44.962191 -67.161966) (xy 45.011791 -67.136465)
			(xy 45.064575 -67.118458) (xy 45.119418 -67.108328) (xy 45.175152 -67.106291) (xy 45.230589 -67.112391)
			(xy 45.284546 -67.126497) (xy 45.335875 -67.148309) (xy 45.383481 -67.177363) (xy 45.426349 -67.213038)
			(xy 45.463566 -67.254575) (xy 45.494339 -67.301088) (xy 45.518011 -67.351585) (xy 45.534079 -67.404992)
			(xy 45.542199 -67.460168) (xy 45.542708 -67.488054) (xy 45.542199 -67.51594) (xy 45.539014 -67.537584)
			(xy 46.07128 -67.537584) (xy 46.075351 -67.481962) (xy 46.087477 -67.427525) (xy 46.1074 -67.375434)
			(xy 46.134696 -67.326799) (xy 46.168782 -67.282656) (xy 46.208931 -67.243947) (xy 46.254289 -67.211496)
			(xy 46.303889 -67.185995) (xy 46.356673 -67.167988) (xy 46.411516 -67.157858) (xy 46.46725 -67.155821)
			(xy 46.522687 -67.161921) (xy 46.576644 -67.176027) (xy 46.627973 -67.197839) (xy 46.675579 -67.226893)
			(xy 46.718447 -67.262568) (xy 46.755664 -67.304105) (xy 46.786437 -67.350618) (xy 46.810109 -67.401115)
			(xy 46.826177 -67.454522) (xy 46.834297 -67.509698) (xy 46.834806 -67.537584) (xy 46.834297 -67.56547)
			(xy 46.830252 -67.592956) (xy 47.345344 -67.592956) (xy 47.349415 -67.537334) (xy 47.361541 -67.482897)
			(xy 47.381464 -67.430806) (xy 47.40876 -67.382171) (xy 47.442846 -67.338028) (xy 47.482995 -67.299319)
			(xy 47.528353 -67.266868) (xy 47.577953 -67.241367) (xy 47.630737 -67.22336) (xy 47.68558 -67.21323)
			(xy 47.741314 -67.211193) (xy 47.796751 -67.217293) (xy 47.850708 -67.231399) (xy 47.902037 -67.253211)
			(xy 47.949643 -67.282265) (xy 47.992511 -67.31794) (xy 48.029728 -67.359477) (xy 48.060501 -67.40599)
			(xy 48.084173 -67.456487) (xy 48.100241 -67.509894) (xy 48.108358 -67.565048) (xy 50.446716 -67.565048)
			(xy 50.446716 -67.510552) (xy 50.454472 -67.456611) (xy 50.469824 -67.404323) (xy 50.492462 -67.354751)
			(xy 50.521924 -67.308906) (xy 50.557611 -67.267721) (xy 50.598795 -67.232033) (xy 50.644639 -67.202569)
			(xy 50.69421 -67.179929) (xy 50.746497 -67.164574) (xy 50.800438 -67.156817) (xy 50.827686 -67.15633)
			(xy 50.855056 -67.156797) (xy 50.909236 -67.164613) (xy 50.961739 -67.180102) (xy 51.011486 -67.202944)
			(xy 51.057453 -67.232668) (xy 51.078384 -67.25031) (xy 51.078638 -67.250564) (xy 51.085733 -67.256138)
			(xy 51.102643 -67.262391) (xy 51.111658 -67.262756) (xy 51.178714 -67.262756) (xy 51.187733 -67.262415)
			(xy 51.20465 -67.256158) (xy 51.211734 -67.250564) (xy 51.211734 -67.25031) (xy 51.211988 -67.25031)
			(xy 51.232915 -67.232665) (xy 51.278889 -67.202953) (xy 51.328638 -67.180118) (xy 51.38114 -67.164629)
			(xy 51.435316 -67.156803) (xy 51.462686 -67.15633) (xy 51.489942 -67.156716) (xy 51.5439 -67.164472)
			(xy 51.596205 -67.179828) (xy 51.645792 -67.202472) (xy 51.691651 -67.231943) (xy 51.73285 -67.26764)
			(xy 51.768549 -67.308837) (xy 51.798021 -67.354696) (xy 51.820667 -67.404282) (xy 51.836025 -67.456586)
			(xy 51.843783 -67.510544) (xy 51.843783 -67.565056) (xy 51.836025 -67.619014) (xy 51.820667 -67.671318)
			(xy 51.798021 -67.720904) (xy 51.768549 -67.766763) (xy 51.73285 -67.80796) (xy 51.691651 -67.843657)
			(xy 51.645792 -67.873128) (xy 51.596205 -67.895772) (xy 51.5439 -67.911128) (xy 51.489942 -67.918884)
			(xy 51.462686 -67.919346) (xy 51.435315 -67.918901) (xy 51.381134 -67.91108) (xy 51.32863 -67.895587)
			(xy 51.278884 -67.87274) (xy 51.232918 -67.84301) (xy 51.211988 -67.825366) (xy 51.211734 -67.825112)
			(xy 51.204641 -67.819535) (xy 51.187729 -67.813282) (xy 51.178714 -67.81292) (xy 51.111658 -67.81292)
			(xy 51.102643 -67.813301) (xy 51.085726 -67.819531) (xy 51.078638 -67.825112) (xy 51.078638 -67.825366)
			(xy 51.078384 -67.825366) (xy 51.057427 -67.842974) (xy 51.011461 -67.872692) (xy 50.96172 -67.895534)
			(xy 50.909225 -67.911032) (xy 50.855054 -67.918868) (xy 50.827686 -67.919346) (xy 50.800438 -67.918783)
			(xy 50.746497 -67.911026) (xy 50.69421 -67.895671) (xy 50.644639 -67.873031) (xy 50.598795 -67.843567)
			(xy 50.557611 -67.807879) (xy 50.521924 -67.766694) (xy 50.492462 -67.720849) (xy 50.469824 -67.671277)
			(xy 50.454472 -67.618989) (xy 50.446716 -67.565048) (xy 48.108358 -67.565048) (xy 48.108361 -67.56507)
			(xy 48.10887 -67.592956) (xy 48.108361 -67.620842) (xy 48.100241 -67.676018) (xy 48.084173 -67.729425)
			(xy 48.060501 -67.779922) (xy 48.029728 -67.826435) (xy 47.992511 -67.867972) (xy 47.949643 -67.903647)
			(xy 47.902037 -67.932701) (xy 47.850708 -67.954513) (xy 47.796751 -67.968619) (xy 47.741314 -67.974719)
			(xy 47.68558 -67.972682) (xy 47.630737 -67.962552) (xy 47.577953 -67.944545) (xy 47.528353 -67.919044)
			(xy 47.482995 -67.886593) (xy 47.442846 -67.847884) (xy 47.40876 -67.803741) (xy 47.381464 -67.755106)
			(xy 47.361541 -67.703015) (xy 47.349415 -67.648578) (xy 47.345344 -67.592956) (xy 46.830252 -67.592956)
			(xy 46.826177 -67.620646) (xy 46.810109 -67.674053) (xy 46.786437 -67.72455) (xy 46.755664 -67.771063)
			(xy 46.718447 -67.8126) (xy 46.675579 -67.848275) (xy 46.627973 -67.877329) (xy 46.576644 -67.899141)
			(xy 46.522687 -67.913247) (xy 46.46725 -67.919347) (xy 46.411516 -67.91731) (xy 46.356673 -67.90718)
			(xy 46.303889 -67.889173) (xy 46.254289 -67.863672) (xy 46.208931 -67.831221) (xy 46.168782 -67.792512)
			(xy 46.134696 -67.748369) (xy 46.1074 -67.699734) (xy 46.087477 -67.647643) (xy 46.075351 -67.593206)
			(xy 46.07128 -67.537584) (xy 45.539014 -67.537584) (xy 45.534079 -67.571116) (xy 45.518011 -67.624523)
			(xy 45.494339 -67.67502) (xy 45.463566 -67.721533) (xy 45.426349 -67.76307) (xy 45.383481 -67.798745)
			(xy 45.335875 -67.827799) (xy 45.284546 -67.849611) (xy 45.230589 -67.863717) (xy 45.175152 -67.869817)
			(xy 45.119418 -67.86778) (xy 45.064575 -67.85765) (xy 45.011791 -67.839643) (xy 44.962191 -67.814142)
			(xy 44.916833 -67.781691) (xy 44.876684 -67.742982) (xy 44.842598 -67.698839) (xy 44.815302 -67.650204)
			(xy 44.795379 -67.598113) (xy 44.783253 -67.543676) (xy 44.779182 -67.488054) (xy 40.721242 -67.488054)
			(xy 40.713243 -67.49214) (xy 40.707818 -67.496944) (xy 40.690292 -67.515486) (xy 40.689784 -67.515994)
			(xy 40.677592 -67.529202) (xy 40.670893 -67.537267) (xy 40.664085 -67.557074) (xy 40.664384 -67.567556)
			(xy 40.746128 -68.586604) (xy 42.625264 -68.586604) (xy 42.625717 -68.559233) (xy 42.633535 -68.505053)
			(xy 42.649027 -68.452549) (xy 42.671872 -68.402802) (xy 42.701601 -68.356837) (xy 42.719244 -68.335906)
			(xy 42.719498 -68.335652) (xy 42.725069 -68.328555) (xy 42.731325 -68.311646) (xy 42.73169 -68.302632)
			(xy 42.73169 -68.235576) (xy 42.731347 -68.226558) (xy 42.72509 -68.209641) (xy 42.719498 -68.202556)
			(xy 42.719244 -68.202556) (xy 42.719244 -68.202302) (xy 42.701599 -68.181374) (xy 42.671887 -68.135401)
			(xy 42.649051 -68.085652) (xy 42.633562 -68.033151) (xy 42.625736 -67.978974) (xy 42.625264 -67.951604)
			(xy 42.625781 -67.924354) (xy 42.633537 -67.870409) (xy 42.64889 -67.818117) (xy 42.671529 -67.768541)
			(xy 42.700992 -67.722692) (xy 42.73668 -67.681503) (xy 42.777866 -67.645811) (xy 42.823713 -67.616344)
			(xy 42.873287 -67.593701) (xy 42.925578 -67.578343) (xy 42.979522 -67.570584) (xy 43.006772 -67.570096)
			(xy 43.033088 -67.570517) (xy 43.085218 -67.577761) (xy 43.135862 -67.59209) (xy 43.18406 -67.613231)
			(xy 43.228903 -67.640785) (xy 43.269541 -67.674231) (xy 43.287696 -67.693286) (xy 43.295219 -67.700686)
			(xy 43.314498 -67.709212) (xy 43.325034 -67.709796) (xy 43.39971 -67.709796) (xy 43.410262 -67.709287)
			(xy 43.429557 -67.700738) (xy 43.437048 -67.693286) (xy 43.455184 -67.674212) (xy 43.495819 -67.640757)
			(xy 43.540663 -67.6132) (xy 43.588867 -67.592065) (xy 43.639518 -67.577752) (xy 43.691655 -67.570532)
			(xy 43.717972 -67.570096) (xy 43.745342 -67.570579) (xy 43.79952 -67.578393) (xy 43.852023 -67.593878)
			(xy 43.90177 -67.616716) (xy 43.947738 -67.646437) (xy 43.96867 -67.664076) (xy 43.968924 -67.66433)
			(xy 43.975997 -67.669936) (xy 43.992924 -67.67617) (xy 44.001944 -67.676522) (xy 44.069 -67.676522)
			(xy 44.078016 -67.67616) (xy 44.094933 -67.669915) (xy 44.10202 -67.66433) (xy 44.10202 -67.664076)
			(xy 44.102274 -67.664076) (xy 44.123202 -67.646432) (xy 44.169176 -67.616722) (xy 44.218925 -67.593887)
			(xy 44.271426 -67.578397) (xy 44.325603 -67.57057) (xy 44.352972 -67.570096) (xy 44.380224 -67.570581)
			(xy 44.434175 -67.578335) (xy 44.486472 -67.593687) (xy 44.536053 -67.616327) (xy 44.581906 -67.645792)
			(xy 44.623099 -67.681484) (xy 44.658793 -67.722675) (xy 44.688262 -67.768526) (xy 44.710904 -67.818105)
			(xy 44.72626 -67.870402) (xy 44.734017 -67.924352) (xy 44.73448 -67.951604) (xy 44.734021 -67.978975)
			(xy 44.726202 -68.033154) (xy 44.710712 -68.085658) (xy 44.687868 -68.135404) (xy 44.658142 -68.181371)
			(xy 44.6405 -68.202302) (xy 44.640246 -68.202556) (xy 44.634665 -68.209646) (xy 44.628416 -68.22656)
			(xy 44.628054 -68.235576) (xy 44.628054 -68.302632) (xy 44.628384 -68.311652) (xy 44.634649 -68.328569)
			(xy 44.640246 -68.335652) (xy 44.6405 -68.335652) (xy 44.6405 -68.335906) (xy 44.658155 -68.356825)
			(xy 44.687865 -68.402801) (xy 44.710698 -68.452552) (xy 44.726185 -68.505056) (xy 44.734008 -68.559234)
			(xy 44.73448 -68.586604) (xy 44.734048 -68.613858) (xy 44.72629 -68.667812) (xy 44.710932 -68.720112)
			(xy 44.694299 -68.75653) (xy 48.170338 -68.75653) (xy 48.170812 -68.72916) (xy 48.178627 -68.674981)
			(xy 48.194113 -68.622477) (xy 48.216954 -68.57273) (xy 48.246677 -68.526764) (xy 48.264318 -68.505832)
			(xy 48.264572 -68.505578) (xy 48.270182 -68.498508) (xy 48.276413 -68.481578) (xy 48.276764 -68.472558)
			(xy 48.276764 -68.405502) (xy 48.276414 -68.396484) (xy 48.270162 -68.379567) (xy 48.264572 -68.372482)
			(xy 48.264318 -68.372482) (xy 48.264318 -68.372228) (xy 48.246681 -68.351294) (xy 48.216969 -68.305322)
			(xy 48.194132 -68.255575) (xy 48.17864 -68.203075) (xy 48.170812 -68.148899) (xy 48.170338 -68.12153)
			(xy 48.170783 -68.094276) (xy 48.178537 -68.040322) (xy 48.193892 -67.988021) (xy 48.216534 -67.938438)
			(xy 48.246004 -67.892582) (xy 48.281699 -67.851388) (xy 48.322895 -67.815694) (xy 48.368752 -67.786227)
			(xy 48.418336 -67.763586) (xy 48.470637 -67.748234) (xy 48.524592 -67.740482) (xy 48.551846 -67.740022)
			(xy 48.579215 -67.740514) (xy 48.633394 -67.748325) (xy 48.685897 -67.763808) (xy 48.735644 -67.786644)
			(xy 48.781612 -67.816363) (xy 48.802544 -67.834002) (xy 48.802798 -67.834256) (xy 48.809876 -67.839855)
			(xy 48.8268 -67.846093) (xy 48.835818 -67.846448) (xy 48.902874 -67.846448) (xy 48.911891 -67.84609)
			(xy 48.928809 -67.839844) (xy 48.935894 -67.834256) (xy 48.935894 -67.834002) (xy 48.936148 -67.834002)
			(xy 48.957089 -67.816374) (xy 49.003059 -67.786661) (xy 49.052805 -67.763822) (xy 49.105303 -67.748329)
			(xy 49.159477 -67.740498) (xy 49.186846 -67.740022) (xy 49.213161 -67.740452) (xy 49.265292 -67.747693)
			(xy 49.315935 -67.762019) (xy 49.364134 -67.783159) (xy 49.408977 -67.810712) (xy 49.449615 -67.844157)
			(xy 49.46777 -67.863212) (xy 49.475299 -67.870604) (xy 49.494574 -67.879134) (xy 49.505108 -67.879722)
			(xy 49.579784 -67.879722) (xy 49.590333 -67.879191) (xy 49.609628 -67.870657) (xy 49.617122 -67.863212)
			(xy 49.635276 -67.844155) (xy 49.675906 -67.810698) (xy 49.720746 -67.783138) (xy 49.768948 -67.762)
			(xy 49.819595 -67.747683) (xy 49.87173 -67.74046) (xy 49.898046 -67.740022) (xy 49.9253 -67.740435)
			(xy 49.979252 -67.748199) (xy 50.03155 -67.763561) (xy 50.081129 -67.78621) (xy 50.126981 -67.815684)
			(xy 50.168171 -67.851383) (xy 50.203862 -67.89258) (xy 50.233327 -67.938438) (xy 50.255965 -67.988022)
			(xy 50.271318 -68.040323) (xy 50.27907 -68.094276) (xy 50.279554 -68.12153) (xy 50.279117 -68.148901)
			(xy 50.271294 -68.203082) (xy 50.255798 -68.255586) (xy 50.23295 -68.305332) (xy 50.203219 -68.351298)
			(xy 50.185574 -68.372228) (xy 50.18532 -68.372482) (xy 50.179725 -68.379563) (xy 50.173486 -68.396484)
			(xy 50.173128 -68.405502) (xy 50.173128 -68.472558) (xy 50.173499 -68.481574) (xy 50.179736 -68.498491)
			(xy 50.18532 -68.505578) (xy 50.185574 -68.505578) (xy 50.185574 -68.505832) (xy 50.203191 -68.526782)
			(xy 50.232907 -68.57275) (xy 50.255747 -68.622492) (xy 50.271244 -68.674989) (xy 50.279077 -68.729162)
			(xy 50.279554 -68.75653) (xy 50.27905 -68.78378) (xy 50.271291 -68.837725) (xy 50.255934 -68.890016)
			(xy 50.233293 -68.93959) (xy 50.203828 -68.985438) (xy 50.168138 -69.026627) (xy 50.126951 -69.062318)
			(xy 50.081105 -69.091785) (xy 50.031531 -69.114429) (xy 49.97924 -69.129787) (xy 49.925296 -69.137549)
			(xy 49.898046 -69.138038) (xy 49.87173 -69.137626) (xy 49.819598 -69.130383) (xy 49.768954 -69.116054)
			(xy 49.720754 -69.094911) (xy 49.675912 -69.067355) (xy 49.635276 -69.033905) (xy 49.617122 -69.014848)
			(xy 49.609588 -69.007461) (xy 49.590318 -68.998927) (xy 49.579784 -68.998338) (xy 49.505108 -68.998338)
			(xy 49.494556 -68.998847) (xy 49.47526 -69.007395) (xy 49.46777 -69.014848) (xy 49.449631 -69.03392)
			(xy 49.408997 -69.067374) (xy 49.364153 -69.09493) (xy 49.315949 -69.116065) (xy 49.265299 -69.130379)
			(xy 49.213163 -69.137601) (xy 49.186846 -69.138038) (xy 49.159476 -69.13756) (xy 49.105297 -69.129747)
			(xy 49.052793 -69.114262) (xy 49.003046 -69.091422) (xy 48.957079 -69.061699) (xy 48.936148 -69.044058)
			(xy 48.935894 -69.043804) (xy 48.928813 -69.038209) (xy 48.911892 -69.031967) (xy 48.902874 -69.031612)
			(xy 48.835818 -69.031612) (xy 48.826802 -69.031975) (xy 48.809884 -69.038218) (xy 48.802798 -69.043804)
			(xy 48.802798 -69.044058) (xy 48.802544 -69.044058) (xy 48.781601 -69.061683) (xy 48.735632 -69.091399)
			(xy 48.685887 -69.114238) (xy 48.633389 -69.129732) (xy 48.579215 -69.137563) (xy 48.551846 -69.138038)
			(xy 48.524596 -69.137502) (xy 48.470649 -69.129752) (xy 48.418354 -69.114403) (xy 48.368776 -69.091768)
			(xy 48.322924 -69.062308) (xy 48.281732 -69.026622) (xy 48.246038 -68.985437) (xy 48.216568 -68.939591)
			(xy 48.193923 -68.890017) (xy 48.178564 -68.837725) (xy 48.170803 -68.78378) (xy 48.170338 -68.75653)
			(xy 44.694299 -68.75653) (xy 44.688287 -68.769694) (xy 44.658816 -68.815548) (xy 44.623119 -68.856742)
			(xy 44.581923 -68.892435) (xy 44.536066 -68.921902) (xy 44.486482 -68.944543) (xy 44.43418 -68.959897)
			(xy 44.380226 -68.967651) (xy 44.352972 -68.968112) (xy 44.325601 -68.967659) (xy 44.271422 -68.959838)
			(xy 44.218919 -68.944345) (xy 44.169172 -68.921501) (xy 44.123206 -68.891774) (xy 44.102274 -68.874132)
			(xy 44.10202 -68.873878) (xy 44.094934 -68.868291) (xy 44.078017 -68.862045) (xy 44.069 -68.861686)
			(xy 44.001944 -68.861686) (xy 43.99293 -68.862067) (xy 43.976013 -68.868298) (xy 43.968924 -68.873878)
			(xy 43.968924 -68.874132) (xy 43.96867 -68.874132) (xy 43.947726 -68.891757) (xy 43.901756 -68.92147)
			(xy 43.852012 -68.944308) (xy 43.799514 -68.959802) (xy 43.74534 -68.967635) (xy 43.717972 -68.968112)
			(xy 43.691658 -68.967659) (xy 43.639529 -68.960421) (xy 43.588886 -68.946099) (xy 43.540687 -68.924963)
			(xy 43.495844 -68.897415) (xy 43.455204 -68.863974) (xy 43.437048 -68.844922) (xy 43.429545 -68.837499)
			(xy 43.410251 -68.828986) (xy 43.39971 -68.828412) (xy 43.325034 -68.828412) (xy 43.314484 -68.828942)
			(xy 43.295189 -68.837476) (xy 43.287696 -68.844922) (xy 43.26954 -68.863977) (xy 43.22891 -68.897433)
			(xy 43.184069 -68.924992) (xy 43.135869 -68.94613) (xy 43.085222 -68.960448) (xy 43.033088 -68.967673)
			(xy 43.006772 -68.968112) (xy 42.97952 -68.967648) (xy 42.925572 -68.959888) (xy 42.873277 -68.94453)
			(xy 42.8237 -68.921885) (xy 42.77785 -68.892417) (xy 42.73666 -68.856723) (xy 42.700969 -68.815531)
			(xy 42.671503 -68.769679) (xy 42.648862 -68.7201) (xy 42.633507 -68.667805) (xy 42.62575 -68.613856)
			(xy 42.625264 -68.586604) (xy 40.746128 -68.586604) (xy 40.83431 -69.685916) (xy 40.984456 -71.555864)
			(xy 45.194472 -71.555864) (xy 45.198543 -71.500242) (xy 45.210669 -71.445805) (xy 45.230592 -71.393714)
			(xy 45.257888 -71.345079) (xy 45.291974 -71.300936) (xy 45.332123 -71.262227) (xy 45.377481 -71.229776)
			(xy 45.427081 -71.204275) (xy 45.479865 -71.186268) (xy 45.534708 -71.176138) (xy 45.590442 -71.174101)
			(xy 45.645879 -71.180201) (xy 45.699836 -71.194307) (xy 45.751165 -71.216119) (xy 45.798771 -71.245173)
			(xy 45.841639 -71.280848) (xy 45.878856 -71.322385) (xy 45.909629 -71.368898) (xy 45.933301 -71.419395)
			(xy 45.949369 -71.472802) (xy 45.957489 -71.527978) (xy 45.957998 -71.555864) (xy 45.957489 -71.58375)
			(xy 45.95165 -71.623428) (xy 46.703486 -71.623428) (xy 46.707557 -71.567806) (xy 46.719683 -71.513369)
			(xy 46.739606 -71.461278) (xy 46.766902 -71.412643) (xy 46.800988 -71.3685) (xy 46.841137 -71.329791)
			(xy 46.886495 -71.29734) (xy 46.936095 -71.271839) (xy 46.988879 -71.253832) (xy 47.043722 -71.243702)
			(xy 47.099456 -71.241665) (xy 47.154893 -71.247765) (xy 47.20885 -71.261871) (xy 47.260179 -71.283683)
			(xy 47.307785 -71.312737) (xy 47.350653 -71.348412) (xy 47.38787 -71.389949) (xy 47.418643 -71.436462)
			(xy 47.442315 -71.486959) (xy 47.458383 -71.540366) (xy 47.466503 -71.595542) (xy 47.467012 -71.623428)
			(xy 47.466503 -71.651314) (xy 47.458383 -71.70649) (xy 47.442315 -71.759897) (xy 47.418643 -71.810394)
			(xy 47.38787 -71.856907) (xy 47.350653 -71.898444) (xy 47.307785 -71.934119) (xy 47.260179 -71.963173)
			(xy 47.20885 -71.984985) (xy 47.154893 -71.999091) (xy 47.099456 -72.005191) (xy 47.043722 -72.003154)
			(xy 46.988879 -71.993024) (xy 46.936095 -71.975017) (xy 46.886495 -71.949516) (xy 46.841137 -71.917065)
			(xy 46.800988 -71.878356) (xy 46.766902 -71.834213) (xy 46.739606 -71.785578) (xy 46.719683 -71.733487)
			(xy 46.707557 -71.67905) (xy 46.703486 -71.623428) (xy 45.95165 -71.623428) (xy 45.949369 -71.638926)
			(xy 45.933301 -71.692333) (xy 45.909629 -71.74283) (xy 45.878856 -71.789343) (xy 45.841639 -71.83088)
			(xy 45.798771 -71.866555) (xy 45.751165 -71.895609) (xy 45.699836 -71.917421) (xy 45.645879 -71.931527)
			(xy 45.590442 -71.937627) (xy 45.534708 -71.93559) (xy 45.479865 -71.92546) (xy 45.427081 -71.907453)
			(xy 45.377481 -71.881952) (xy 45.332123 -71.849501) (xy 45.291974 -71.810792) (xy 45.257888 -71.766649)
			(xy 45.230592 -71.718014) (xy 45.210669 -71.665923) (xy 45.198543 -71.611486) (xy 45.194472 -71.555864)
			(xy 40.984456 -71.555864) (xy 41.516554 -78.182724) (xy 41.518435 -78.194474) (xy 41.531302 -78.214455)
			(xy 41.541192 -78.221078) (xy 41.572942 -78.239366) (xy 41.581187 -78.243705) (xy 41.599559 -78.246696)
			(xy 41.608756 -78.245208) (xy 41.620694 -78.242668) (xy 41.625774 -78.240382) (xy 41.649202 -78.230391)
			(xy 41.698063 -78.216011) (xy 41.748402 -78.208262) (xy 41.773856 -78.207362) (xy 41.786048 -78.207362)
			(xy 41.813109 -78.208122) (xy 41.866615 -78.216344) (xy 41.918422 -78.232048) (xy 41.967488 -78.254918)
			(xy 42.012828 -78.284495) (xy 42.053531 -78.320185) (xy 42.088779 -78.361271) (xy 42.117865 -78.406928)
			(xy 42.140204 -78.456238) (xy 42.155348 -78.508211) (xy 42.162991 -78.561803) (xy 42.163492 -78.58887)
			(xy 42.163031 -78.616124) (xy 42.155277 -78.670077) (xy 42.139924 -78.722378) (xy 42.117283 -78.771961)
			(xy 42.087815 -78.817816) (xy 42.052121 -78.859011) (xy 42.010928 -78.894707) (xy 41.965073 -78.924176)
			(xy 41.915491 -78.946819) (xy 41.863191 -78.962174) (xy 41.809238 -78.96993) (xy 41.781984 -78.970378)
			(xy 41.78173 -78.970378) (xy 41.757326 -78.969972) (xy 41.708918 -78.963731) (xy 41.68521 -78.957932)
			(xy 41.684194 -78.957678) (xy 41.681908 -78.95717) (xy 41.67632 -78.955646) (xy 41.664561 -78.953403)
			(xy 41.641244 -78.958693) (xy 41.631616 -78.965806) (xy 41.602914 -78.989428) (xy 41.594277 -78.997184)
			(xy 41.584499 -79.018211) (xy 41.584118 -79.029814) (xy 41.594925 -79.164434) (xy 42.852592 -79.164434)
			(xy 42.856663 -79.108812) (xy 42.868789 -79.054375) (xy 42.888712 -79.002284) (xy 42.916008 -78.953649)
			(xy 42.950094 -78.909506) (xy 42.990243 -78.870797) (xy 43.035601 -78.838346) (xy 43.085201 -78.812845)
			(xy 43.137985 -78.794838) (xy 43.192828 -78.784708) (xy 43.248562 -78.782671) (xy 43.303999 -78.788771)
			(xy 43.357956 -78.802877) (xy 43.409285 -78.824689) (xy 43.456891 -78.853743) (xy 43.499759 -78.889418)
			(xy 43.536976 -78.930955) (xy 43.567749 -78.977468) (xy 43.591421 -79.027965) (xy 43.607489 -79.081372)
			(xy 43.615609 -79.136548) (xy 43.616118 -79.164434) (xy 43.615609 -79.19232) (xy 43.607489 -79.247496)
			(xy 43.591421 -79.300903) (xy 43.567749 -79.3514) (xy 43.536976 -79.397913) (xy 43.499759 -79.43945)
			(xy 43.456891 -79.475125) (xy 43.409285 -79.504179) (xy 43.357956 -79.525991) (xy 43.303999 -79.540097)
			(xy 43.248562 -79.546197) (xy 43.192828 -79.54416) (xy 43.137985 -79.53403) (xy 43.085201 -79.516023)
			(xy 43.035601 -79.490522) (xy 42.990243 -79.458071) (xy 42.950094 -79.419362) (xy 42.916008 -79.375219)
			(xy 42.888712 -79.326584) (xy 42.868789 -79.274493) (xy 42.856663 -79.220056) (xy 42.852592 -79.164434)
			(xy 41.594925 -79.164434) (xy 41.640132 -79.727552) (xy 58.25185 -79.727552) (xy 58.255921 -79.67193)
			(xy 58.268047 -79.617493) (xy 58.28797 -79.565402) (xy 58.315266 -79.516767) (xy 58.349352 -79.472624)
			(xy 58.389501 -79.433915) (xy 58.434859 -79.401464) (xy 58.484459 -79.375963) (xy 58.537243 -79.357956)
			(xy 58.592086 -79.347826) (xy 58.64782 -79.345789) (xy 58.703257 -79.351889) (xy 58.757214 -79.365995)
			(xy 58.808543 -79.387807) (xy 58.856149 -79.416861) (xy 58.899017 -79.452536) (xy 58.936234 -79.494073)
			(xy 58.967007 -79.540586) (xy 58.990679 -79.591083) (xy 59.006747 -79.64449) (xy 59.014867 -79.699666)
			(xy 59.015376 -79.727552) (xy 59.014867 -79.755438) (xy 59.006747 -79.810614) (xy 58.990679 -79.864021)
			(xy 58.967007 -79.914518) (xy 58.936234 -79.961031) (xy 58.899017 -80.002568) (xy 58.856149 -80.038243)
			(xy 58.808543 -80.067297) (xy 58.757214 -80.089109) (xy 58.703257 -80.103215) (xy 58.64782 -80.109315)
			(xy 58.592086 -80.107278) (xy 58.537243 -80.097148) (xy 58.484459 -80.079141) (xy 58.434859 -80.05364)
			(xy 58.389501 -80.021189) (xy 58.349352 -79.98248) (xy 58.315266 -79.938337) (xy 58.28797 -79.889702)
			(xy 58.268047 -79.837611) (xy 58.255921 -79.783174) (xy 58.25185 -79.727552) (xy 41.640132 -79.727552)
			(xy 42.06545 -85.025538) (xy 44.856389 -85.025538) (xy 44.856389 -84.896398) (xy 44.864339 -84.767503)
			(xy 44.880209 -84.639343) (xy 44.903938 -84.512402) (xy 44.935437 -84.387163) (xy 44.974586 -84.2641)
			(xy 45.021237 -84.143681) (xy 45.075212 -84.026362) (xy 45.136307 -83.912588) (xy 45.20429 -83.802791)
			(xy 45.278904 -83.697388) (xy 45.359865 -83.596778) (xy 45.446865 -83.501343) (xy 45.539576 -83.411444)
			(xy 45.637646 -83.327423) (xy 45.740701 -83.249599) (xy 45.848352 -83.178267) (xy 45.960191 -83.113697)
			(xy 46.075792 -83.056135) (xy 46.194717 -83.005798) (xy 46.316516 -82.962878) (xy 46.440726 -82.927537)
			(xy 46.566875 -82.89991) (xy 46.694487 -82.880101) (xy 46.823076 -82.868185) (xy 46.952154 -82.864209)
			(xy 47.081232 -82.868185) (xy 47.209821 -82.880101) (xy 47.337433 -82.89991) (xy 47.463582 -82.927537)
			(xy 47.587792 -82.962878) (xy 47.709591 -83.005798) (xy 47.828516 -83.056135) (xy 47.944117 -83.113697)
			(xy 48.055956 -83.178267) (xy 48.163607 -83.249599) (xy 48.266662 -83.327423) (xy 48.364732 -83.411444)
			(xy 48.457443 -83.501343) (xy 48.544443 -83.596778) (xy 48.625404 -83.697388) (xy 48.700018 -83.802791)
			(xy 48.768001 -83.912588) (xy 48.829096 -84.026362) (xy 48.883071 -84.143681) (xy 48.929722 -84.2641)
			(xy 48.968871 -84.387163) (xy 49.00037 -84.512402) (xy 49.024099 -84.639343) (xy 49.039969 -84.767503)
			(xy 49.047919 -84.896398) (xy 49.048416 -84.960968) (xy 49.047919 -85.025538) (xy 49.039969 -85.154433)
			(xy 49.024099 -85.282593) (xy 49.00037 -85.409534) (xy 48.968871 -85.534773) (xy 48.929722 -85.657836)
			(xy 48.883071 -85.778255) (xy 48.829096 -85.895574) (xy 48.768001 -86.009348) (xy 48.700018 -86.119145)
			(xy 48.625404 -86.224548) (xy 48.544443 -86.325158) (xy 48.457443 -86.420593) (xy 48.364732 -86.510492)
			(xy 48.266662 -86.594513) (xy 48.163607 -86.672337) (xy 48.055956 -86.743669) (xy 47.944117 -86.808239)
			(xy 47.828516 -86.865801) (xy 47.709591 -86.916138) (xy 47.587792 -86.959058) (xy 47.463582 -86.994399)
			(xy 47.337433 -87.022026) (xy 47.209821 -87.041835) (xy 47.081232 -87.053751) (xy 46.952154 -87.057728)
			(xy 46.823076 -87.053751) (xy 46.694487 -87.041835) (xy 46.566875 -87.022026) (xy 46.440726 -86.994399)
			(xy 46.316516 -86.959058) (xy 46.194717 -86.916138) (xy 46.075792 -86.865801) (xy 45.960191 -86.808239)
			(xy 45.848352 -86.743669) (xy 45.740701 -86.672337) (xy 45.637646 -86.594513) (xy 45.539576 -86.510492)
			(xy 45.446865 -86.420593) (xy 45.359865 -86.325158) (xy 45.278904 -86.224548) (xy 45.20429 -86.119145)
			(xy 45.136307 -86.009348) (xy 45.075212 -85.895574) (xy 45.021237 -85.778255) (xy 44.974586 -85.657836)
			(xy 44.935437 -85.534773) (xy 44.903938 -85.409534) (xy 44.880209 -85.282593) (xy 44.864339 -85.154433)
			(xy 44.856389 -85.025538) (xy 42.06545 -85.025538) (xy 42.355262 -88.635586) (xy 42.883374 -95.214948)
			(xy 47.274239 -95.214948) (xy 47.278194 -95.123111) (xy 47.290029 -95.031954) (xy 47.309656 -94.942151)
			(xy 47.33693 -94.854369) (xy 47.37165 -94.769255) (xy 47.413558 -94.687442) (xy 47.462344 -94.609534)
			(xy 47.517647 -94.536109) (xy 47.579057 -94.467709) (xy 47.646119 -94.404842) (xy 47.718338 -94.347972)
			(xy 47.795178 -94.297521) (xy 47.876071 -94.253862) (xy 47.960417 -94.217319) (xy 48.047593 -94.188162)
			(xy 48.136952 -94.166608) (xy 48.227833 -94.152814) (xy 48.319564 -94.146884) (xy 48.411465 -94.148862)
			(xy 48.502856 -94.158733) (xy 48.59306 -94.176423) (xy 48.681409 -94.201803) (xy 48.767249 -94.234683)
			(xy 48.849945 -94.274821) (xy 48.928885 -94.32192) (xy 49.003483 -94.37563) (xy 49.073189 -94.435554)
			(xy 49.137484 -94.501248) (xy 49.195895 -94.572226) (xy 49.247987 -94.647963) (xy 49.293376 -94.727898)
			(xy 49.331726 -94.811438) (xy 49.362751 -94.897966) (xy 49.386224 -94.986841) (xy 49.40197 -95.077405)
			(xy 49.409872 -95.168987) (xy 49.410366 -95.214948) (xy 49.409872 -95.260909) (xy 49.40197 -95.352491)
			(xy 49.386224 -95.443055) (xy 49.362751 -95.53193) (xy 49.331726 -95.618458) (xy 49.293376 -95.701998)
			(xy 49.247987 -95.781933) (xy 49.195895 -95.85767) (xy 49.137484 -95.928648) (xy 49.073189 -95.994342)
			(xy 49.003483 -96.054266) (xy 48.928885 -96.107976) (xy 48.849945 -96.155075) (xy 48.767249 -96.195213)
			(xy 48.681409 -96.228093) (xy 48.59306 -96.253473) (xy 48.502856 -96.271163) (xy 48.411465 -96.281034)
			(xy 48.319564 -96.283012) (xy 48.227833 -96.277082) (xy 48.136952 -96.263288) (xy 48.047593 -96.241734)
			(xy 47.960417 -96.212577) (xy 47.876071 -96.176034) (xy 47.795178 -96.132375) (xy 47.718338 -96.081924)
			(xy 47.646119 -96.025054) (xy 47.579057 -95.962187) (xy 47.517647 -95.893787) (xy 47.462344 -95.820362)
			(xy 47.413558 -95.742454) (xy 47.37165 -95.660641) (xy 47.33693 -95.575527) (xy 47.309656 -95.487745)
			(xy 47.290029 -95.397942) (xy 47.278194 -95.306785) (xy 47.274239 -95.214948) (xy 42.883374 -95.214948)
			(xy 43.031126 -97.055686) (xy 51.605432 -97.055686) (xy 51.609503 -97.000064) (xy 51.621629 -96.945627)
			(xy 51.641552 -96.893536) (xy 51.668848 -96.844901) (xy 51.702934 -96.800758) (xy 51.743083 -96.762049)
			(xy 51.788441 -96.729598) (xy 51.838041 -96.704097) (xy 51.890825 -96.68609) (xy 51.945668 -96.67596)
			(xy 52.001402 -96.673923) (xy 52.056839 -96.680023) (xy 52.110796 -96.694129) (xy 52.162125 -96.715941)
			(xy 52.209731 -96.744995) (xy 52.252599 -96.78067) (xy 52.289816 -96.822207) (xy 52.320589 -96.86872)
			(xy 52.344261 -96.919217) (xy 52.360329 -96.972624) (xy 52.368449 -97.0278) (xy 52.368958 -97.055686)
			(xy 52.368449 -97.083572) (xy 52.360329 -97.138748) (xy 52.344261 -97.192155) (xy 52.320589 -97.242652)
			(xy 52.289816 -97.289165) (xy 52.252599 -97.330702) (xy 52.209731 -97.366377) (xy 52.162125 -97.395431)
			(xy 52.110796 -97.417243) (xy 52.056839 -97.431349) (xy 52.001402 -97.437449) (xy 51.945668 -97.435412)
			(xy 51.890825 -97.425282) (xy 51.838041 -97.407275) (xy 51.788441 -97.381774) (xy 51.743083 -97.349323)
			(xy 51.702934 -97.310614) (xy 51.668848 -97.266471) (xy 51.641552 -97.217836) (xy 51.621629 -97.165745)
			(xy 51.609503 -97.111308) (xy 51.605432 -97.055686) (xy 43.031126 -97.055686) (xy 43.281614 -100.17633)
			(xy 53.639212 -100.17633) (xy 53.639212 -99.31273) (xy 53.639702 -99.282762) (xy 53.647525 -99.22334)
			(xy 53.663038 -99.165447) (xy 53.685974 -99.110074) (xy 53.715941 -99.058168) (xy 53.752428 -99.010618)
			(xy 53.794808 -98.968238) (xy 53.842358 -98.931751) (xy 53.894264 -98.901784) (xy 53.949637 -98.878848)
			(xy 54.00753 -98.863335) (xy 54.066952 -98.855512) (xy 54.126888 -98.855512) (xy 54.18631 -98.863335)
			(xy 54.244203 -98.878848) (xy 54.299576 -98.901784) (xy 54.351482 -98.931751) (xy 54.399032 -98.968238)
			(xy 54.441412 -99.010618) (xy 54.477899 -99.058168) (xy 54.507866 -99.110074) (xy 54.530802 -99.165447)
			(xy 54.546315 -99.22334) (xy 54.554138 -99.282762) (xy 54.554628 -99.31273) (xy 54.554628 -100.17633)
			(xy 54.554138 -100.206298) (xy 54.546315 -100.26572) (xy 54.530802 -100.323613) (xy 54.507866 -100.378986)
			(xy 54.477899 -100.430892) (xy 54.441412 -100.478442) (xy 54.399032 -100.520822) (xy 54.351482 -100.557309)
			(xy 54.299576 -100.587276) (xy 54.244203 -100.610212) (xy 54.18631 -100.625725) (xy 54.126888 -100.633548)
			(xy 54.066952 -100.633548) (xy 54.00753 -100.625725) (xy 53.949637 -100.610212) (xy 53.894264 -100.587276)
			(xy 53.842358 -100.557309) (xy 53.794808 -100.520822) (xy 53.752428 -100.478442) (xy 53.715941 -100.430892)
			(xy 53.685974 -100.378986) (xy 53.663038 -100.323613) (xy 53.647525 -100.26572) (xy 53.639702 -100.206298)
			(xy 53.639212 -100.17633) (xy 43.281614 -100.17633) (xy 43.426104 -101.976428) (xy 51.785012 -101.976428)
			(xy 51.785012 -101.112828) (xy 51.785502 -101.08286) (xy 51.793325 -101.023438) (xy 51.808838 -100.965545)
			(xy 51.831774 -100.910172) (xy 51.861741 -100.858266) (xy 51.898228 -100.810716) (xy 51.940608 -100.768336)
			(xy 51.988158 -100.731849) (xy 52.040064 -100.701882) (xy 52.095437 -100.678946) (xy 52.15333 -100.663433)
			(xy 52.212752 -100.65561) (xy 52.272688 -100.65561) (xy 52.33211 -100.663433) (xy 52.390003 -100.678946)
			(xy 52.445376 -100.701882) (xy 52.497282 -100.731849) (xy 52.542273 -100.766372) (xy 57.5978 -100.766372)
			(xy 57.601871 -100.71075) (xy 57.613997 -100.656313) (xy 57.63392 -100.604222) (xy 57.661216 -100.555587)
			(xy 57.695302 -100.511444) (xy 57.735451 -100.472735) (xy 57.780809 -100.440284) (xy 57.830409 -100.414783)
			(xy 57.883193 -100.396776) (xy 57.938036 -100.386646) (xy 57.99377 -100.384609) (xy 58.049207 -100.390709)
			(xy 58.103164 -100.404815) (xy 58.154493 -100.426627) (xy 58.202099 -100.455681) (xy 58.244967 -100.491356)
			(xy 58.282184 -100.532893) (xy 58.312957 -100.579406) (xy 58.336629 -100.629903) (xy 58.352697 -100.68331)
			(xy 58.360817 -100.738486) (xy 58.361326 -100.766372) (xy 58.360817 -100.794258) (xy 58.352697 -100.849434)
			(xy 58.336629 -100.902841) (xy 58.312957 -100.953338) (xy 58.282184 -100.999851) (xy 58.244967 -101.041388)
			(xy 58.202099 -101.077063) (xy 58.154493 -101.106117) (xy 58.103164 -101.127929) (xy 58.049207 -101.142035)
			(xy 57.99377 -101.148135) (xy 57.938036 -101.146098) (xy 57.883193 -101.135968) (xy 57.830409 -101.117961)
			(xy 57.780809 -101.09246) (xy 57.735451 -101.060009) (xy 57.695302 -101.0213) (xy 57.661216 -100.977157)
			(xy 57.63392 -100.928522) (xy 57.613997 -100.876431) (xy 57.601871 -100.821994) (xy 57.5978 -100.766372)
			(xy 52.542273 -100.766372) (xy 52.544832 -100.768336) (xy 52.587212 -100.810716) (xy 52.623699 -100.858266)
			(xy 52.653666 -100.910172) (xy 52.676602 -100.965545) (xy 52.692115 -101.023438) (xy 52.699938 -101.08286)
			(xy 52.700428 -101.112828) (xy 52.700428 -101.976428) (xy 52.699938 -102.006396) (xy 52.692115 -102.065818)
			(xy 52.676602 -102.123711) (xy 52.653666 -102.179084) (xy 52.623699 -102.23099) (xy 52.587212 -102.27854)
			(xy 52.544832 -102.32092) (xy 52.497282 -102.357407) (xy 52.445376 -102.387374) (xy 52.390003 -102.41031)
			(xy 52.33211 -102.425823) (xy 52.272688 -102.433646) (xy 52.212752 -102.433646) (xy 52.15333 -102.425823)
			(xy 52.095437 -102.41031) (xy 52.040064 -102.387374) (xy 51.988158 -102.357407) (xy 51.940608 -102.32092)
			(xy 51.898228 -102.27854) (xy 51.861741 -102.23099) (xy 51.831774 -102.179084) (xy 51.808838 -102.123711)
			(xy 51.793325 -102.065818) (xy 51.785502 -102.006396) (xy 51.785012 -101.976428) (xy 43.426104 -101.976428)
			(xy 43.570574 -103.776272) (xy 53.639212 -103.776272) (xy 53.639212 -102.912672) (xy 53.639702 -102.882704)
			(xy 53.647525 -102.823282) (xy 53.663038 -102.765389) (xy 53.685974 -102.710016) (xy 53.715941 -102.65811)
			(xy 53.752428 -102.61056) (xy 53.794808 -102.56818) (xy 53.842358 -102.531693) (xy 53.894264 -102.501726)
			(xy 53.949637 -102.47879) (xy 54.00753 -102.463277) (xy 54.066952 -102.455454) (xy 54.126888 -102.455454)
			(xy 54.18631 -102.463277) (xy 54.244203 -102.47879) (xy 54.299576 -102.501726) (xy 54.351482 -102.531693)
			(xy 54.399032 -102.56818) (xy 54.441412 -102.61056) (xy 54.477899 -102.65811) (xy 54.507866 -102.710016)
			(xy 54.530802 -102.765389) (xy 54.546315 -102.823282) (xy 54.554138 -102.882704) (xy 54.554628 -102.912672)
			(xy 54.554628 -103.776272) (xy 54.554138 -103.80624) (xy 54.546315 -103.865662) (xy 54.530802 -103.923555)
			(xy 54.507866 -103.978928) (xy 54.477899 -104.030834) (xy 54.441412 -104.078384) (xy 54.399032 -104.120764)
			(xy 54.351482 -104.157251) (xy 54.299576 -104.187218) (xy 54.244203 -104.210154) (xy 54.18631 -104.225667)
			(xy 54.126888 -104.23349) (xy 54.066952 -104.23349) (xy 54.00753 -104.225667) (xy 53.949637 -104.210154)
			(xy 53.894264 -104.187218) (xy 53.842358 -104.157251) (xy 53.794808 -104.120764) (xy 53.752428 -104.078384)
			(xy 53.715941 -104.030834) (xy 53.685974 -103.978928) (xy 53.663038 -103.923555) (xy 53.647525 -103.865662)
			(xy 53.639702 -103.80624) (xy 53.639212 -103.776272) (xy 43.570574 -103.776272) (xy 43.606212 -104.220264)
			(xy 43.609006 -104.269794) (xy 43.648619 -105.57637) (xy 51.785012 -105.57637) (xy 51.785012 -104.71277)
			(xy 51.785502 -104.682802) (xy 51.793325 -104.62338) (xy 51.808838 -104.565487) (xy 51.831774 -104.510114)
			(xy 51.861741 -104.458208) (xy 51.898228 -104.410658) (xy 51.940608 -104.368278) (xy 51.988158 -104.331791)
			(xy 52.040064 -104.301824) (xy 52.095437 -104.278888) (xy 52.15333 -104.263375) (xy 52.212752 -104.255552)
			(xy 52.272688 -104.255552) (xy 52.33211 -104.263375) (xy 52.390003 -104.278888) (xy 52.445376 -104.301824)
			(xy 52.497282 -104.331791) (xy 52.544832 -104.368278) (xy 52.587212 -104.410658) (xy 52.623699 -104.458208)
			(xy 52.653666 -104.510114) (xy 52.676602 -104.565487) (xy 52.692115 -104.62338) (xy 52.699938 -104.682802)
			(xy 52.700428 -104.71277) (xy 52.700428 -105.57637) (xy 52.699938 -105.606338) (xy 52.692115 -105.66576)
			(xy 52.676602 -105.723653) (xy 52.653666 -105.779026) (xy 52.623699 -105.830932) (xy 52.587212 -105.878482)
			(xy 52.544832 -105.920862) (xy 52.497282 -105.957349) (xy 52.445376 -105.987316) (xy 52.390003 -106.010252)
			(xy 52.33211 -106.025765) (xy 52.272688 -106.033588) (xy 52.212752 -106.033588) (xy 52.15333 -106.025765)
			(xy 52.095437 -106.010252) (xy 52.040064 -105.987316) (xy 51.988158 -105.957349) (xy 51.940608 -105.920862)
			(xy 51.898228 -105.878482) (xy 51.861741 -105.830932) (xy 51.831774 -105.779026) (xy 51.808838 -105.723653)
			(xy 51.793325 -105.66576) (xy 51.785502 -105.606338) (xy 51.785012 -105.57637) (xy 43.648619 -105.57637)
			(xy 43.703187 -107.376214) (xy 53.639212 -107.376214) (xy 53.639212 -106.512614) (xy 53.639702 -106.482646)
			(xy 53.647525 -106.423224) (xy 53.663038 -106.365331) (xy 53.685974 -106.309958) (xy 53.715941 -106.258052)
			(xy 53.752428 -106.210502) (xy 53.794808 -106.168122) (xy 53.842358 -106.131635) (xy 53.894264 -106.101668)
			(xy 53.949637 -106.078732) (xy 54.00753 -106.063219) (xy 54.066952 -106.055396) (xy 54.126888 -106.055396)
			(xy 54.18631 -106.063219) (xy 54.244203 -106.078732) (xy 54.299576 -106.101668) (xy 54.351482 -106.131635)
			(xy 54.399032 -106.168122) (xy 54.441412 -106.210502) (xy 54.477899 -106.258052) (xy 54.507866 -106.309958)
			(xy 54.530802 -106.365331) (xy 54.546315 -106.423224) (xy 54.554138 -106.482646) (xy 54.554628 -106.512614)
			(xy 54.554628 -107.376214) (xy 54.554138 -107.406182) (xy 54.546315 -107.465604) (xy 54.530802 -107.523497)
			(xy 54.507866 -107.57887) (xy 54.477899 -107.630776) (xy 54.441412 -107.678326) (xy 54.399032 -107.720706)
			(xy 54.351482 -107.757193) (xy 54.299576 -107.78716) (xy 54.244203 -107.810096) (xy 54.18631 -107.825609)
			(xy 54.126888 -107.833432) (xy 54.066952 -107.833432) (xy 54.00753 -107.825609) (xy 53.949637 -107.810096)
			(xy 53.894264 -107.78716) (xy 53.842358 -107.757193) (xy 53.794808 -107.720706) (xy 53.752428 -107.678326)
			(xy 53.715941 -107.630776) (xy 53.685974 -107.57887) (xy 53.663038 -107.523497) (xy 53.647525 -107.465604)
			(xy 53.639702 -107.406182) (xy 53.639212 -107.376214) (xy 43.703187 -107.376214) (xy 43.757763 -109.176312)
			(xy 51.785012 -109.176312) (xy 51.785012 -108.312712) (xy 51.785502 -108.282744) (xy 51.793325 -108.223322)
			(xy 51.808838 -108.165429) (xy 51.831774 -108.110056) (xy 51.861741 -108.05815) (xy 51.898228 -108.0106)
			(xy 51.940608 -107.96822) (xy 51.988158 -107.931733) (xy 52.040064 -107.901766) (xy 52.095437 -107.87883)
			(xy 52.15333 -107.863317) (xy 52.212752 -107.855494) (xy 52.272688 -107.855494) (xy 52.33211 -107.863317)
			(xy 52.390003 -107.87883) (xy 52.445376 -107.901766) (xy 52.497282 -107.931733) (xy 52.544832 -107.96822)
			(xy 52.587212 -108.0106) (xy 52.623699 -108.05815) (xy 52.653666 -108.110056) (xy 52.676602 -108.165429)
			(xy 52.692115 -108.223322) (xy 52.699938 -108.282744) (xy 52.700428 -108.312712) (xy 52.700428 -109.176312)
			(xy 52.699938 -109.20628) (xy 52.692115 -109.265702) (xy 52.676602 -109.323595) (xy 52.653666 -109.378968)
			(xy 52.623699 -109.430874) (xy 52.587212 -109.478424) (xy 52.544832 -109.520804) (xy 52.497282 -109.557291)
			(xy 52.445376 -109.587258) (xy 52.390003 -109.610194) (xy 52.33211 -109.625707) (xy 52.272688 -109.63353)
			(xy 52.212752 -109.63353) (xy 52.15333 -109.625707) (xy 52.095437 -109.610194) (xy 52.040064 -109.587258)
			(xy 51.988158 -109.557291) (xy 51.940608 -109.520804) (xy 51.898228 -109.478424) (xy 51.861741 -109.430874)
			(xy 51.831774 -109.378968) (xy 51.808838 -109.323595) (xy 51.793325 -109.265702) (xy 51.785502 -109.20628)
			(xy 51.785012 -109.176312) (xy 43.757763 -109.176312) (xy 43.812339 -110.97641) (xy 53.639212 -110.97641)
			(xy 53.639212 -110.11281) (xy 53.639702 -110.082842) (xy 53.647525 -110.02342) (xy 53.663038 -109.965527)
			(xy 53.685974 -109.910154) (xy 53.715941 -109.858248) (xy 53.752428 -109.810698) (xy 53.794808 -109.768318)
			(xy 53.842358 -109.731831) (xy 53.894264 -109.701864) (xy 53.949637 -109.678928) (xy 54.00753 -109.663415)
			(xy 54.066952 -109.655592) (xy 54.126888 -109.655592) (xy 54.18631 -109.663415) (xy 54.244203 -109.678928)
			(xy 54.299576 -109.701864) (xy 54.351482 -109.731831) (xy 54.399032 -109.768318) (xy 54.441412 -109.810698)
			(xy 54.477899 -109.858248) (xy 54.507866 -109.910154) (xy 54.530802 -109.965527) (xy 54.546315 -110.02342)
			(xy 54.554138 -110.082842) (xy 54.554628 -110.11281) (xy 54.554628 -110.97641) (xy 54.554138 -111.006378)
			(xy 54.546315 -111.0658) (xy 54.530802 -111.123693) (xy 54.507866 -111.179066) (xy 54.477899 -111.230972)
			(xy 54.441412 -111.278522) (xy 54.399032 -111.320902) (xy 54.351482 -111.357389) (xy 54.299576 -111.387356)
			(xy 54.244203 -111.410292) (xy 54.18631 -111.425805) (xy 54.126888 -111.433628) (xy 54.066952 -111.433628)
			(xy 54.00753 -111.425805) (xy 53.949637 -111.410292) (xy 53.894264 -111.387356) (xy 53.842358 -111.357389)
			(xy 53.794808 -111.320902) (xy 53.752428 -111.278522) (xy 53.715941 -111.230972) (xy 53.685974 -111.179066)
			(xy 53.663038 -111.123693) (xy 53.647525 -111.0658) (xy 53.639702 -111.006378) (xy 53.639212 -110.97641)
			(xy 43.812339 -110.97641) (xy 43.866914 -112.776508) (xy 51.785012 -112.776508) (xy 51.785012 -111.912908)
			(xy 51.785502 -111.88294) (xy 51.793325 -111.823518) (xy 51.808838 -111.765625) (xy 51.831774 -111.710252)
			(xy 51.861741 -111.658346) (xy 51.898228 -111.610796) (xy 51.940608 -111.568416) (xy 51.988158 -111.531929)
			(xy 52.040064 -111.501962) (xy 52.095437 -111.479026) (xy 52.15333 -111.463513) (xy 52.212752 -111.45569)
			(xy 52.272688 -111.45569) (xy 52.33211 -111.463513) (xy 52.390003 -111.479026) (xy 52.445376 -111.501962)
			(xy 52.497282 -111.531929) (xy 52.544832 -111.568416) (xy 52.587212 -111.610796) (xy 52.623699 -111.658346)
			(xy 52.653666 -111.710252) (xy 52.676602 -111.765625) (xy 52.692115 -111.823518) (xy 52.699938 -111.88294)
			(xy 52.700428 -111.912908) (xy 52.700428 -112.776508) (xy 52.699938 -112.806476) (xy 52.692115 -112.865898)
			(xy 52.676602 -112.923791) (xy 52.653666 -112.979164) (xy 52.623699 -113.03107) (xy 52.587212 -113.07862)
			(xy 52.544832 -113.121) (xy 52.497282 -113.157487) (xy 52.445376 -113.187454) (xy 52.390003 -113.21039)
			(xy 52.33211 -113.225903) (xy 52.272688 -113.233726) (xy 52.212752 -113.233726) (xy 52.15333 -113.225903)
			(xy 52.095437 -113.21039) (xy 52.040064 -113.187454) (xy 51.988158 -113.157487) (xy 51.940608 -113.121)
			(xy 51.898228 -113.07862) (xy 51.861741 -113.03107) (xy 51.831774 -112.979164) (xy 51.808838 -112.923791)
			(xy 51.793325 -112.865898) (xy 51.785502 -112.806476) (xy 51.785012 -112.776508) (xy 43.866914 -112.776508)
			(xy 43.951792 -115.576096) (xy 55.847232 -115.576096) (xy 55.851303 -115.520474) (xy 55.863429 -115.466037)
			(xy 55.883352 -115.413946) (xy 55.910648 -115.365311) (xy 55.944734 -115.321168) (xy 55.984883 -115.282459)
			(xy 56.030241 -115.250008) (xy 56.079841 -115.224507) (xy 56.132625 -115.2065) (xy 56.187468 -115.19637)
			(xy 56.243202 -115.194333) (xy 56.298639 -115.200433) (xy 56.352596 -115.214539) (xy 56.403925 -115.236351)
			(xy 56.451531 -115.265405) (xy 56.494399 -115.30108) (xy 56.531616 -115.342617) (xy 56.562389 -115.38913)
			(xy 56.586061 -115.439627) (xy 56.602129 -115.493034) (xy 56.610249 -115.54821) (xy 56.610758 -115.576096)
			(xy 56.610249 -115.603982) (xy 56.602129 -115.659158) (xy 56.586061 -115.712565) (xy 56.562389 -115.763062)
			(xy 56.531616 -115.809575) (xy 56.494399 -115.851112) (xy 56.451531 -115.886787) (xy 56.403925 -115.915841)
			(xy 56.352596 -115.937653) (xy 56.298639 -115.951759) (xy 56.243202 -115.957859) (xy 56.187468 -115.955822)
			(xy 56.132625 -115.945692) (xy 56.079841 -115.927685) (xy 56.030241 -115.902184) (xy 55.984883 -115.869733)
			(xy 55.944734 -115.831024) (xy 55.910648 -115.786881) (xy 55.883352 -115.738246) (xy 55.863429 -115.686155)
			(xy 55.851303 -115.631718) (xy 55.847232 -115.576096) (xy 43.951792 -115.576096) (xy 44.033405 -118.267988)
			(xy 55.586628 -118.267988) (xy 55.590699 -118.212366) (xy 55.602825 -118.157929) (xy 55.622748 -118.105838)
			(xy 55.650044 -118.057203) (xy 55.68413 -118.01306) (xy 55.724279 -117.974351) (xy 55.769637 -117.9419)
			(xy 55.819237 -117.916399) (xy 55.872021 -117.898392) (xy 55.926864 -117.888262) (xy 55.982598 -117.886225)
			(xy 56.038035 -117.892325) (xy 56.091992 -117.906431) (xy 56.143321 -117.928243) (xy 56.190927 -117.957297)
			(xy 56.233795 -117.992972) (xy 56.271012 -118.034509) (xy 56.301785 -118.081022) (xy 56.325457 -118.131519)
			(xy 56.341525 -118.184926) (xy 56.349645 -118.240102) (xy 56.350154 -118.267988) (xy 56.349645 -118.295874)
			(xy 56.341525 -118.35105) (xy 56.325457 -118.404457) (xy 56.301785 -118.454954) (xy 56.271012 -118.501467)
			(xy 56.233795 -118.543004) (xy 56.190927 -118.578679) (xy 56.143321 -118.607733) (xy 56.091992 -118.629545)
			(xy 56.038035 -118.643651) (xy 55.982598 -118.649751) (xy 55.926864 -118.647714) (xy 55.872021 -118.637584)
			(xy 55.819237 -118.619577) (xy 55.769637 -118.594076) (xy 55.724279 -118.561625) (xy 55.68413 -118.522916)
			(xy 55.650044 -118.478773) (xy 55.622748 -118.430138) (xy 55.602825 -118.378047) (xy 55.590699 -118.32361)
			(xy 55.586628 -118.267988) (xy 44.033405 -118.267988) (xy 44.071794 -119.534178) (xy 44.072048 -119.545608)
			(xy 44.072048 -119.551196) (xy 44.072048 -119.56415) (xy 44.072048 -119.575072) (xy 44.066547 -120.086374)
			(xy 53.639212 -120.086374) (xy 53.639212 -119.222774) (xy 53.639702 -119.192806) (xy 53.647525 -119.133384)
			(xy 53.663038 -119.075491) (xy 53.685974 -119.020118) (xy 53.715941 -118.968212) (xy 53.752428 -118.920662)
			(xy 53.794808 -118.878282) (xy 53.842358 -118.841795) (xy 53.894264 -118.811828) (xy 53.949637 -118.788892)
			(xy 54.00753 -118.773379) (xy 54.066952 -118.765556) (xy 54.126888 -118.765556) (xy 54.18631 -118.773379)
			(xy 54.244203 -118.788892) (xy 54.299576 -118.811828) (xy 54.351482 -118.841795) (xy 54.399032 -118.878282)
			(xy 54.441412 -118.920662) (xy 54.477899 -118.968212) (xy 54.507866 -119.020118) (xy 54.530802 -119.075491)
			(xy 54.546315 -119.133384) (xy 54.554138 -119.192806) (xy 54.554628 -119.222774) (xy 54.554628 -120.086374)
			(xy 54.554138 -120.116342) (xy 54.546315 -120.175764) (xy 54.530802 -120.233657) (xy 54.507866 -120.28903)
			(xy 54.477899 -120.340936) (xy 54.441412 -120.388486) (xy 54.399032 -120.430866) (xy 54.351482 -120.467353)
			(xy 54.299576 -120.49732) (xy 54.244203 -120.520256) (xy 54.18631 -120.535769) (xy 54.126888 -120.543592)
			(xy 54.066952 -120.543592) (xy 54.00753 -120.535769) (xy 53.949637 -120.520256) (xy 53.894264 -120.49732)
			(xy 53.842358 -120.467353) (xy 53.794808 -120.430866) (xy 53.752428 -120.388486) (xy 53.715941 -120.340936)
			(xy 53.685974 -120.28903) (xy 53.663038 -120.233657) (xy 53.647525 -120.175764) (xy 53.639702 -120.116342)
			(xy 53.639212 -120.086374) (xy 44.066547 -120.086374) (xy 44.047178 -121.886472) (xy 51.785012 -121.886472)
			(xy 51.785012 -121.022872) (xy 51.785502 -120.992904) (xy 51.793325 -120.933482) (xy 51.808838 -120.875589)
			(xy 51.831774 -120.820216) (xy 51.861741 -120.76831) (xy 51.898228 -120.72076) (xy 51.940608 -120.67838)
			(xy 51.988158 -120.641893) (xy 52.040064 -120.611926) (xy 52.095437 -120.58899) (xy 52.15333 -120.573477)
			(xy 52.212752 -120.565654) (xy 52.272688 -120.565654) (xy 52.33211 -120.573477) (xy 52.390003 -120.58899)
			(xy 52.445376 -120.611926) (xy 52.497282 -120.641893) (xy 52.544832 -120.67838) (xy 52.587212 -120.72076)
			(xy 52.623699 -120.76831) (xy 52.653666 -120.820216) (xy 52.676602 -120.875589) (xy 52.692115 -120.933482)
			(xy 52.699938 -120.992904) (xy 52.700428 -121.022872) (xy 52.700428 -121.886472) (xy 52.699938 -121.91644)
			(xy 52.692115 -121.975862) (xy 52.676602 -122.033755) (xy 52.653666 -122.089128) (xy 52.623699 -122.141034)
			(xy 52.587212 -122.188584) (xy 52.544832 -122.230964) (xy 52.497282 -122.267451) (xy 52.445376 -122.297418)
			(xy 52.390003 -122.320354) (xy 52.33211 -122.335867) (xy 52.272688 -122.34369) (xy 52.212752 -122.34369)
			(xy 52.15333 -122.335867) (xy 52.095437 -122.320354) (xy 52.040064 -122.297418) (xy 51.988158 -122.267451)
			(xy 51.940608 -122.230964) (xy 51.898228 -122.188584) (xy 51.861741 -122.141034) (xy 51.831774 -122.089128)
			(xy 51.808838 -122.033755) (xy 51.793325 -121.975862) (xy 51.785502 -121.91644) (xy 51.785012 -121.886472)
			(xy 44.047178 -121.886472) (xy 44.027812 -123.686316) (xy 53.639212 -123.686316) (xy 53.639212 -122.822716)
			(xy 53.639702 -122.792748) (xy 53.647525 -122.733326) (xy 53.663038 -122.675433) (xy 53.685974 -122.62006)
			(xy 53.715941 -122.568154) (xy 53.752428 -122.520604) (xy 53.794808 -122.478224) (xy 53.842358 -122.441737)
			(xy 53.894264 -122.41177) (xy 53.949637 -122.388834) (xy 54.00753 -122.373321) (xy 54.066952 -122.365498)
			(xy 54.126888 -122.365498) (xy 54.18631 -122.373321) (xy 54.244203 -122.388834) (xy 54.299576 -122.41177)
			(xy 54.351482 -122.441737) (xy 54.399032 -122.478224) (xy 54.441412 -122.520604) (xy 54.477899 -122.568154)
			(xy 54.507866 -122.62006) (xy 54.530802 -122.675433) (xy 54.546315 -122.733326) (xy 54.554138 -122.792748)
			(xy 54.554628 -122.822716) (xy 54.554628 -123.686316) (xy 54.554138 -123.716284) (xy 54.546315 -123.775706)
			(xy 54.530802 -123.833599) (xy 54.507866 -123.888972) (xy 54.477899 -123.940878) (xy 54.441412 -123.988428)
			(xy 54.399032 -124.030808) (xy 54.351482 -124.067295) (xy 54.299576 -124.097262) (xy 54.244203 -124.120198)
			(xy 54.18631 -124.135711) (xy 54.126888 -124.143534) (xy 54.066952 -124.143534) (xy 54.00753 -124.135711)
			(xy 53.949637 -124.120198) (xy 53.894264 -124.097262) (xy 53.842358 -124.067295) (xy 53.794808 -124.030808)
			(xy 53.752428 -123.988428) (xy 53.715941 -123.940878) (xy 53.685974 -123.888972) (xy 53.663038 -123.833599)
			(xy 53.647525 -123.775706) (xy 53.639702 -123.716284) (xy 53.639212 -123.686316) (xy 44.027812 -123.686316)
			(xy 44.017946 -124.603256) (xy 44.008458 -125.486414) (xy 51.785012 -125.486414) (xy 51.785012 -124.622814)
			(xy 51.785502 -124.592846) (xy 51.793325 -124.533424) (xy 51.808838 -124.475531) (xy 51.831774 -124.420158)
			(xy 51.861741 -124.368252) (xy 51.898228 -124.320702) (xy 51.940608 -124.278322) (xy 51.988158 -124.241835)
			(xy 52.040064 -124.211868) (xy 52.095437 -124.188932) (xy 52.15333 -124.173419) (xy 52.212752 -124.165596)
			(xy 52.272688 -124.165596) (xy 52.33211 -124.173419) (xy 52.390003 -124.188932) (xy 52.445376 -124.211868)
			(xy 52.497282 -124.241835) (xy 52.544832 -124.278322) (xy 52.587212 -124.320702) (xy 52.623699 -124.368252)
			(xy 52.653666 -124.420158) (xy 52.676602 -124.475531) (xy 52.692115 -124.533424) (xy 52.699938 -124.592846)
			(xy 52.700428 -124.622814) (xy 52.700428 -125.486414) (xy 52.699938 -125.516382) (xy 52.692115 -125.575804)
			(xy 52.676602 -125.633697) (xy 52.653666 -125.68907) (xy 52.623699 -125.740976) (xy 52.587212 -125.788526)
			(xy 52.544832 -125.830906) (xy 52.497282 -125.867393) (xy 52.445376 -125.89736) (xy 52.390003 -125.920296)
			(xy 52.33211 -125.935809) (xy 52.272688 -125.943632) (xy 52.212752 -125.943632) (xy 52.15333 -125.935809)
			(xy 52.095437 -125.920296) (xy 52.040064 -125.89736) (xy 51.988158 -125.867393) (xy 51.940608 -125.830906)
			(xy 51.898228 -125.788526) (xy 51.861741 -125.740976) (xy 51.831774 -125.68907) (xy 51.808838 -125.633697)
			(xy 51.793325 -125.575804) (xy 51.785502 -125.516382) (xy 51.785012 -125.486414) (xy 44.008458 -125.486414)
			(xy 43.995086 -126.731014) (xy 43.945916 -131.29641) (xy 53.639212 -131.29641) (xy 53.639212 -130.43281)
			(xy 53.639702 -130.402842) (xy 53.647525 -130.34342) (xy 53.663038 -130.285527) (xy 53.685974 -130.230154)
			(xy 53.715941 -130.178248) (xy 53.752428 -130.130698) (xy 53.794808 -130.088318) (xy 53.842358 -130.051831)
			(xy 53.894264 -130.021864) (xy 53.949637 -129.998928) (xy 54.00753 -129.983415) (xy 54.066952 -129.975592)
			(xy 54.126888 -129.975592) (xy 54.18631 -129.983415) (xy 54.244203 -129.998928) (xy 54.299576 -130.021864)
			(xy 54.351482 -130.051831) (xy 54.399032 -130.088318) (xy 54.441412 -130.130698) (xy 54.477899 -130.178248)
			(xy 54.507866 -130.230154) (xy 54.530802 -130.285527) (xy 54.546315 -130.34342) (xy 54.554138 -130.402842)
			(xy 54.554628 -130.43281) (xy 54.554628 -131.29641) (xy 54.554138 -131.326378) (xy 54.546315 -131.3858)
			(xy 54.530802 -131.443693) (xy 54.507866 -131.499066) (xy 54.477899 -131.550972) (xy 54.441412 -131.598522)
			(xy 54.399032 -131.640902) (xy 54.351482 -131.677389) (xy 54.299576 -131.707356) (xy 54.244203 -131.730292)
			(xy 54.18631 -131.745805) (xy 54.126888 -131.753628) (xy 54.066952 -131.753628) (xy 54.00753 -131.745805)
			(xy 53.949637 -131.730292) (xy 53.894264 -131.707356) (xy 53.842358 -131.677389) (xy 53.794808 -131.640902)
			(xy 53.752428 -131.598522) (xy 53.715941 -131.550972) (xy 53.685974 -131.499066) (xy 53.663038 -131.443693)
			(xy 53.647525 -131.3858) (xy 53.639702 -131.326378) (xy 53.639212 -131.29641) (xy 43.945916 -131.29641)
			(xy 43.926528 -133.096508) (xy 51.785012 -133.096508) (xy 51.785012 -132.232908) (xy 51.785502 -132.20294)
			(xy 51.793325 -132.143518) (xy 51.808838 -132.085625) (xy 51.831774 -132.030252) (xy 51.861741 -131.978346)
			(xy 51.898228 -131.930796) (xy 51.940608 -131.888416) (xy 51.988158 -131.851929) (xy 52.040064 -131.821962)
			(xy 52.095437 -131.799026) (xy 52.15333 -131.783513) (xy 52.212752 -131.77569) (xy 52.272688 -131.77569)
			(xy 52.33211 -131.783513) (xy 52.390003 -131.799026) (xy 52.445376 -131.821962) (xy 52.497282 -131.851929)
			(xy 52.544832 -131.888416) (xy 52.587212 -131.930796) (xy 52.623699 -131.978346) (xy 52.653666 -132.030252)
			(xy 52.676602 -132.085625) (xy 52.692115 -132.143518) (xy 52.699938 -132.20294) (xy 52.700428 -132.232908)
			(xy 52.700428 -133.096508) (xy 52.699938 -133.126476) (xy 52.692115 -133.185898) (xy 52.676602 -133.243791)
			(xy 52.653666 -133.299164) (xy 52.623699 -133.35107) (xy 52.587212 -133.39862) (xy 52.544832 -133.441)
			(xy 52.497282 -133.477487) (xy 52.445376 -133.507454) (xy 52.390003 -133.53039) (xy 52.33211 -133.545903)
			(xy 52.272688 -133.553726) (xy 52.212752 -133.553726) (xy 52.15333 -133.545903) (xy 52.095437 -133.53039)
			(xy 52.040064 -133.507454) (xy 51.988158 -133.477487) (xy 51.940608 -133.441) (xy 51.898228 -133.39862)
			(xy 51.861741 -133.35107) (xy 51.831774 -133.299164) (xy 51.808838 -133.243791) (xy 51.793325 -133.185898)
			(xy 51.785502 -133.126476) (xy 51.785012 -133.096508) (xy 43.926528 -133.096508) (xy 43.907143 -134.896352)
			(xy 53.639212 -134.896352) (xy 53.639212 -134.032752) (xy 53.639702 -134.002784) (xy 53.647525 -133.943362)
			(xy 53.663038 -133.885469) (xy 53.685974 -133.830096) (xy 53.715941 -133.77819) (xy 53.752428 -133.73064)
			(xy 53.794808 -133.68826) (xy 53.842358 -133.651773) (xy 53.894264 -133.621806) (xy 53.949637 -133.59887)
			(xy 54.00753 -133.583357) (xy 54.066952 -133.575534) (xy 54.126888 -133.575534) (xy 54.18631 -133.583357)
			(xy 54.244203 -133.59887) (xy 54.299576 -133.621806) (xy 54.351482 -133.651773) (xy 54.399032 -133.68826)
			(xy 54.441412 -133.73064) (xy 54.477899 -133.77819) (xy 54.507866 -133.830096) (xy 54.530802 -133.885469)
			(xy 54.546315 -133.943362) (xy 54.554138 -134.002784) (xy 54.554628 -134.032752) (xy 54.554628 -134.896352)
			(xy 54.554138 -134.92632) (xy 54.546315 -134.985742) (xy 54.530802 -135.043635) (xy 54.507866 -135.099008)
			(xy 54.477899 -135.150914) (xy 54.441412 -135.198464) (xy 54.399032 -135.240844) (xy 54.351482 -135.277331)
			(xy 54.299576 -135.307298) (xy 54.244203 -135.330234) (xy 54.18631 -135.345747) (xy 54.126888 -135.35357)
			(xy 54.066952 -135.35357) (xy 54.00753 -135.345747) (xy 53.949637 -135.330234) (xy 53.894264 -135.307298)
			(xy 53.842358 -135.277331) (xy 53.794808 -135.240844) (xy 53.752428 -135.198464) (xy 53.715941 -135.150914)
			(xy 53.685974 -135.099008) (xy 53.663038 -135.043635) (xy 53.647525 -134.985742) (xy 53.639702 -134.92632)
			(xy 53.639212 -134.896352) (xy 43.907143 -134.896352) (xy 43.887756 -136.69645) (xy 51.785012 -136.69645)
			(xy 51.785012 -135.83285) (xy 51.785502 -135.802882) (xy 51.793325 -135.74346) (xy 51.808838 -135.685567)
			(xy 51.831774 -135.630194) (xy 51.861741 -135.578288) (xy 51.898228 -135.530738) (xy 51.940608 -135.488358)
			(xy 51.988158 -135.451871) (xy 52.040064 -135.421904) (xy 52.095437 -135.398968) (xy 52.15333 -135.383455)
			(xy 52.212752 -135.375632) (xy 52.272688 -135.375632) (xy 52.33211 -135.383455) (xy 52.390003 -135.398968)
			(xy 52.445376 -135.421904) (xy 52.497282 -135.451871) (xy 52.544832 -135.488358) (xy 52.587212 -135.530738)
			(xy 52.623699 -135.578288) (xy 52.653666 -135.630194) (xy 52.676602 -135.685567) (xy 52.692115 -135.74346)
			(xy 52.699938 -135.802882) (xy 52.700428 -135.83285) (xy 52.700428 -136.69645) (xy 52.699938 -136.726418)
			(xy 52.692115 -136.78584) (xy 52.676602 -136.843733) (xy 52.653666 -136.899106) (xy 52.623699 -136.951012)
			(xy 52.587212 -136.998562) (xy 52.544832 -137.040942) (xy 52.497282 -137.077429) (xy 52.445376 -137.107396)
			(xy 52.390003 -137.130332) (xy 52.33211 -137.145845) (xy 52.272688 -137.153668) (xy 52.212752 -137.153668)
			(xy 52.15333 -137.145845) (xy 52.095437 -137.130332) (xy 52.040064 -137.107396) (xy 51.988158 -137.077429)
			(xy 51.940608 -137.040942) (xy 51.898228 -136.998562) (xy 51.861741 -136.951012) (xy 51.831774 -136.899106)
			(xy 51.808838 -136.843733) (xy 51.793325 -136.78584) (xy 51.785502 -136.726418) (xy 51.785012 -136.69645)
			(xy 43.887756 -136.69645) (xy 43.881294 -137.296398) (xy 43.881431 -137.303545) (xy 43.885171 -137.317337)
			(xy 43.88866 -137.323576) (xy 43.893656 -137.33092) (xy 43.907555 -137.341958) (xy 43.915838 -137.345166)
			(xy 44.008802 -137.376408) (xy 44.012337 -137.377427) (xy 44.019603 -137.378577) (xy 44.02328 -137.378694)
			(xy 44.053506 -137.363708) (xy 44.05849 -137.361046) (xy 44.067208 -137.353863) (xy 44.070778 -137.349484)
			(xy 44.088441 -137.327768) (xy 44.128203 -137.288367) (xy 44.172469 -137.254102) (xy 44.220579 -137.225484)
			(xy 44.246038 -137.213848) (xy 44.270693 -137.203415) (xy 44.321877 -137.187714) (xy 44.374542 -137.178087)
			(xy 44.401232 -137.176002) (xy 44.4119 -137.17524) (xy 44.430188 -137.174986) (xy 44.430696 -137.174986)
			(xy 44.460656 -137.175494) (xy 44.52006 -137.183348) (xy 44.577931 -137.198884) (xy 44.633282 -137.221835)
			(xy 44.685166 -137.25181) (xy 44.732697 -137.288296) (xy 44.775063 -137.33067) (xy 44.81154 -137.378209)
			(xy 44.841505 -137.430099) (xy 44.864445 -137.485454) (xy 44.879969 -137.543329) (xy 44.887812 -137.602734)
			(xy 44.888404 -137.632694) (xy 44.888404 -138.496548) (xy 44.887914 -138.526532) (xy 44.882966 -138.564112)
			(xy 46.691294 -138.564112) (xy 46.695365 -138.50849) (xy 46.707491 -138.454053) (xy 46.727414 -138.401962)
			(xy 46.75471 -138.353327) (xy 46.788796 -138.309184) (xy 46.828945 -138.270475) (xy 46.874303 -138.238024)
			(xy 46.923903 -138.212523) (xy 46.976687 -138.194516) (xy 47.03153 -138.184386) (xy 47.087264 -138.182349)
			(xy 47.142701 -138.188449) (xy 47.196658 -138.202555) (xy 47.247987 -138.224367) (xy 47.295593 -138.253421)
			(xy 47.338461 -138.289096) (xy 47.375678 -138.330633) (xy 47.406451 -138.377146) (xy 47.430123 -138.427643)
			(xy 47.446191 -138.48105) (xy 47.454311 -138.536226) (xy 47.45482 -138.564112) (xy 47.454311 -138.591998)
			(xy 47.446191 -138.647174) (xy 47.430123 -138.700581) (xy 47.406451 -138.751078) (xy 47.375678 -138.797591)
			(xy 47.338461 -138.839128) (xy 47.295593 -138.874803) (xy 47.247987 -138.903857) (xy 47.196658 -138.925669)
			(xy 47.142701 -138.939775) (xy 47.087264 -138.945875) (xy 47.03153 -138.943838) (xy 46.976687 -138.933708)
			(xy 46.923903 -138.915701) (xy 46.874303 -138.8902) (xy 46.828945 -138.857749) (xy 46.788796 -138.81904)
			(xy 46.75471 -138.774897) (xy 46.727414 -138.726262) (xy 46.707491 -138.674171) (xy 46.695365 -138.619734)
			(xy 46.691294 -138.564112) (xy 44.882966 -138.564112) (xy 44.880086 -138.585988) (xy 44.864565 -138.643913)
			(xy 44.841616 -138.699317) (xy 44.811632 -138.751251) (xy 44.775126 -138.798827) (xy 44.732721 -138.841232)
			(xy 44.685145 -138.877738) (xy 44.633211 -138.907722) (xy 44.577807 -138.930671) (xy 44.519882 -138.946192)
			(xy 44.460426 -138.95402) (xy 44.400458 -138.95402) (xy 44.341002 -138.946192) (xy 44.283077 -138.930671)
			(xy 44.227673 -138.907722) (xy 44.175739 -138.877738) (xy 44.128163 -138.841232) (xy 44.085758 -138.798827)
			(xy 44.049252 -138.751251) (xy 44.019268 -138.699317) (xy 43.996319 -138.643913) (xy 43.980798 -138.585988)
			(xy 43.97297 -138.526532) (xy 43.97248 -138.496548) (xy 43.97248 -138.284458) (xy 43.97248 -138.284204)
			(xy 43.971947 -138.274269) (xy 43.964282 -138.25593) (xy 43.950218 -138.241883) (xy 43.93187 -138.23424)
			(xy 43.921934 -138.233658) (xy 43.921172 -138.233658) (xy 43.911255 -138.234172) (xy 43.892931 -138.241776)
			(xy 43.878858 -138.25576) (xy 43.871137 -138.274035) (xy 43.870626 -138.28395) (xy 43.86834 -138.498326)
			(xy 43.862244 -139.05611) (xy 43.857164 -139.510516) (xy 43.858688 -139.51204) (xy 43.888406 -139.53871)
			(xy 43.892499 -139.542225) (xy 43.901854 -139.547596) (xy 43.906948 -139.549378) (xy 43.916854 -139.55268)
			(xy 43.92803 -139.55141) (xy 43.938787 -139.550239) (xy 43.96039 -139.548968) (xy 43.97121 -139.54887)
			(xy 43.983948 -139.548949) (xy 44.009369 -139.550603) (xy 44.02201 -139.552172) (xy 44.047364 -139.556003)
			(xy 44.096812 -139.569578) (xy 44.144001 -139.589642) (xy 44.188083 -139.615835) (xy 44.208446 -139.63142)
			(xy 44.213526 -139.635484) (xy 44.2214 -139.63904) (xy 44.226028 -139.640814) (xy 44.235749 -139.642734)
			(xy 44.240704 -139.64285) (xy 44.26204 -139.64285) (xy 44.267479 -139.642995) (xy 44.278109 -139.645306)
			(xy 44.283122 -139.647422) (xy 44.296584 -139.653518) (xy 44.305246 -139.65714) (xy 44.323967 -139.658374)
			(xy 44.341866 -139.652747) (xy 44.349416 -139.647168) (xy 44.356528 -139.64158) (xy 44.3611 -139.638024)
			(xy 44.361862 -139.637516) (xy 44.382503 -139.620875) (xy 44.427516 -139.592856) (xy 44.475974 -139.571339)
			(xy 44.526945 -139.556739) (xy 44.579446 -139.549337) (xy 44.605956 -139.54887) (xy 44.60621 -139.54887)
			(xy 44.606718 -139.54887) (xy 44.633867 -139.549364) (xy 44.687612 -139.557093) (xy 44.739719 -139.572363)
			(xy 44.789134 -139.594867) (xy 44.83486 -139.62415) (xy 44.875972 -139.659619) (xy 44.91164 -139.700559)
			(xy 44.926758 -139.723114) (xy 44.927774 -139.724638) (xy 44.940678 -139.745536) (xy 44.961592 -139.789978)
			(xy 44.976616 -139.836741) (xy 44.985502 -139.885048) (xy 44.98721 -139.90955) (xy 44.987718 -139.92606)
			(xy 44.987718 -139.939522) (xy 44.987464 -139.942316) (xy 44.986088 -139.970766) (xy 44.975938 -140.02681)
			(xy 44.957557 -140.080718) (xy 44.931355 -140.131289) (xy 44.915074 -140.15466) (xy 44.908724 -140.163042)
			(xy 44.904914 -140.167868) (xy 44.89958 -140.176504) (xy 44.899072 -140.17752) (xy 44.89661 -140.182846)
			(xy 44.893914 -140.194262) (xy 44.893738 -140.200126) (xy 44.893738 -140.221208) (xy 44.893597 -140.226648)
			(xy 44.891291 -140.237281) (xy 44.889166 -140.24229) (xy 44.88307 -140.255752) (xy 44.879442 -140.264415)
			(xy 44.878197 -140.283142) (xy 44.883816 -140.30105) (xy 44.88942 -140.308584) (xy 44.895008 -140.315696)
			(xy 44.898564 -140.320268) (xy 44.899072 -140.32103) (xy 44.900596 -140.322808) (xy 44.919487 -140.346676)
			(xy 44.950241 -140.399203) (xy 44.972273 -140.455943) (xy 44.985027 -140.515459) (xy 44.98721 -140.54582)
			(xy 44.987718 -140.564362) (xy 44.987718 -140.565378) (xy 44.987246 -140.592458) (xy 44.97959 -140.646073)
			(xy 44.964429 -140.698066) (xy 44.942067 -140.747393) (xy 44.912954 -140.793062) (xy 44.877675 -140.834155)
			(xy 44.83694 -140.869846) (xy 44.791567 -140.899417) (xy 44.742467 -140.922275) (xy 44.690629 -140.937959)
			(xy 44.637094 -140.946154) (xy 44.61002 -140.946886) (xy 44.605702 -140.946886) (xy 44.575792 -140.946282)
			(xy 44.516708 -140.936911) (xy 44.459808 -140.918443) (xy 44.406483 -140.891332) (xy 44.381928 -140.874242)
			(xy 44.373546 -140.867892) (xy 44.36872 -140.864082) (xy 44.360084 -140.858748) (xy 44.359068 -140.85824)
			(xy 44.353743 -140.855776) (xy 44.342327 -140.853079) (xy 44.336462 -140.852906) (xy 44.31538 -140.852906)
			(xy 44.30994 -140.852764) (xy 44.299307 -140.850459) (xy 44.294298 -140.848334) (xy 44.280836 -140.842238)
			(xy 44.272173 -140.838614) (xy 44.253448 -140.837374) (xy 44.235543 -140.842993) (xy 44.228004 -140.848588)
			(xy 44.220892 -140.854176) (xy 44.21632 -140.857732) (xy 44.215558 -140.85824) (xy 44.194957 -140.87485)
			(xy 44.150038 -140.902826) (xy 44.101684 -140.924327) (xy 44.050823 -140.93894) (xy 43.99843 -140.946385)
			(xy 43.971972 -140.946886) (xy 43.970448 -140.946886) (xy 43.95649 -140.946759) (xy 43.928649 -140.944728)
			(xy 43.914822 -140.942822) (xy 43.912028 -140.942314) (xy 43.906948 -140.94206) (xy 43.897363 -140.941987)
			(xy 43.879224 -140.948133) (xy 43.871642 -140.953998) (xy 43.859196 -140.964666) (xy 43.851293 -140.97195)
			(xy 43.841948 -140.991285) (xy 43.841162 -141.002004) (xy 43.823987 -142.60068) (xy 51.605688 -142.60068)
			(xy 51.606137 -142.573274) (xy 51.61399 -142.519029) (xy 51.629529 -142.466466) (xy 51.652436 -142.416671)
			(xy 51.682238 -142.37067) (xy 51.699922 -142.349728) (xy 51.700176 -142.349474) (xy 51.705747 -142.342377)
			(xy 51.712001 -142.325468) (xy 51.712368 -142.316454) (xy 51.712368 -142.249144) (xy 51.711997 -142.240128)
			(xy 51.70576 -142.223211) (xy 51.700176 -142.216124) (xy 51.699668 -142.215616) (xy 51.682018 -142.194693)
			(xy 51.652309 -142.148717) (xy 51.629476 -142.098967) (xy 51.613987 -142.046465) (xy 51.606161 -141.992288)
			(xy 51.605688 -141.964918) (xy 51.606174 -141.937667) (xy 51.61393 -141.883719) (xy 51.629285 -141.831424)
			(xy 51.651927 -141.781847) (xy 51.681393 -141.735997) (xy 51.717084 -141.694806) (xy 51.758275 -141.659115)
			(xy 51.804125 -141.629649) (xy 51.853702 -141.607007) (xy 51.905997 -141.591652) (xy 51.959945 -141.583896)
			(xy 52.014447 -141.583896) (xy 52.068395 -141.591652) (xy 52.12069 -141.607007) (xy 52.170267 -141.629649)
			(xy 52.216117 -141.659115) (xy 52.257308 -141.694806) (xy 52.292999 -141.735997) (xy 52.322465 -141.781847)
			(xy 52.345107 -141.831424) (xy 52.360462 -141.883719) (xy 52.368218 -141.937667) (xy 52.368704 -141.964918)
			(xy 52.368256 -141.992324) (xy 52.360403 -142.04657) (xy 52.344863 -142.099132) (xy 52.321956 -142.148927)
			(xy 52.292154 -142.194928) (xy 52.27447 -142.21587) (xy 52.274216 -142.216124) (xy 52.268615 -142.223201)
			(xy 52.262376 -142.240125) (xy 52.262024 -142.249144) (xy 52.262024 -142.316454) (xy 52.262398 -142.325469)
			(xy 52.268633 -142.342387) (xy 52.274216 -142.349474) (xy 52.274724 -142.349982) (xy 52.292372 -142.370907)
			(xy 52.322082 -142.416882) (xy 52.344915 -142.466631) (xy 52.360405 -142.519134) (xy 52.368231 -142.57331)
			(xy 52.368704 -142.60068) (xy 52.368218 -142.627931) (xy 52.360462 -142.681879) (xy 52.345107 -142.734174)
			(xy 52.322465 -142.783751) (xy 52.292999 -142.829601) (xy 52.257308 -142.870792) (xy 52.216117 -142.906483)
			(xy 52.170267 -142.935949) (xy 52.12069 -142.958591) (xy 52.068395 -142.973946) (xy 52.014447 -142.981702)
			(xy 51.959945 -142.981702) (xy 51.905997 -142.973946) (xy 51.853702 -142.958591) (xy 51.804125 -142.935949)
			(xy 51.758275 -142.906483) (xy 51.717084 -142.870792) (xy 51.681393 -142.829601) (xy 51.651927 -142.783751)
			(xy 51.629285 -142.734174) (xy 51.61393 -142.681879) (xy 51.606174 -142.627931) (xy 51.605688 -142.60068)
			(xy 43.823987 -142.60068) (xy 43.817032 -143.248126) (xy 43.810174 -143.885158) (xy 43.805856 -144.27962)
			(xy 43.806051 -144.288515) (xy 43.811898 -144.305306) (xy 43.817286 -144.312386) (xy 43.867324 -144.367758)
			(xy 43.873598 -144.373464) (xy 43.888908 -144.380734) (xy 43.897296 -144.381982) (xy 43.898058 -144.381982)
			(xy 43.909996 -144.383252) (xy 43.91025 -144.383252) (xy 43.918959 -144.383904) (xy 43.935973 -144.380017)
			(xy 43.943524 -144.375632) (xy 44.002706 -144.33423) (xy 44.008978 -144.329291) (xy 44.018303 -144.316345)
			(xy 44.020994 -144.30883) (xy 44.021756 -144.305274) (xy 44.028774 -144.277745) (xy 44.049849 -144.224988)
			(xy 44.078515 -144.175941) (xy 44.114138 -144.131686) (xy 44.155929 -144.093204) (xy 44.202965 -144.061344)
			(xy 44.254205 -144.036812) (xy 44.308517 -144.02015) (xy 44.364699 -144.011726) (xy 44.393104 -144.011142)
			(xy 44.417818 -144.011534) (xy 44.466833 -144.017919) (xy 44.514613 -144.030582) (xy 44.53763 -144.03959)
			(xy 44.543168 -144.041649) (xy 44.554843 -144.043444) (xy 44.560744 -144.043146) (xy 44.57192 -144.042384)
			(xy 44.654724 -143.993108) (xy 44.663132 -143.986807) (xy 44.674401 -143.9691) (xy 44.676568 -143.958818)
			(xy 44.676822 -143.956786) (xy 44.676822 -143.956532) (xy 44.680487 -143.928973) (xy 44.694769 -143.875246)
			(xy 44.716696 -143.824159) (xy 44.745805 -143.776795) (xy 44.781479 -143.734157) (xy 44.822963 -143.697147)
			(xy 44.869379 -143.66655) (xy 44.919743 -143.643012) (xy 44.972991 -143.627032) (xy 45.027993 -143.618948)
			(xy 45.05579 -143.618458) (xy 45.083031 -143.618942) (xy 45.136959 -143.626691) (xy 45.189237 -143.642032)
			(xy 45.238801 -143.664653) (xy 45.284643 -143.694095) (xy 45.32583 -143.729759) (xy 45.361526 -143.770919)
			(xy 45.391003 -143.816737) (xy 45.413664 -143.866283) (xy 45.429046 -143.918549) (xy 45.436836 -143.972471)
			(xy 45.437298 -143.999712) (xy 45.437298 -143.999966) (xy 45.43679 -144.021302) (xy 45.437044 -144.02689)
			(xy 45.438556 -144.03909) (xy 45.440207 -144.06362) (xy 45.440346 -144.075912) (xy 45.440346 -144.076166)
			(xy 45.439895 -144.102887) (xy 45.43244 -144.155808) (xy 45.417684 -144.207173) (xy 45.395915 -144.255981)
			(xy 45.367558 -144.301281) (xy 45.333166 -144.342187) (xy 45.3136 -144.360392) (xy 45.305472 -144.367758)
			(xy 45.301154 -144.37741) (xy 45.297852 -144.384522) (xy 45.29455 -144.411192) (xy 45.294296 -144.412716)
			(xy 45.304202 -144.42821) (xy 45.318501 -144.451371) (xy 45.341104 -144.500887) (xy 45.356437 -144.553113)
			(xy 45.36419 -144.606989) (xy 45.364654 -144.634204) (xy 45.364146 -144.656048) (xy 45.3644 -144.66316)
			(xy 45.365715 -144.674735) (xy 45.367115 -144.697992) (xy 45.367194 -144.709642) (xy 45.367194 -144.710404)
			(xy 45.366705 -144.737826) (xy 45.358904 -144.792113) (xy 45.343459 -144.844737) (xy 45.320686 -144.89463)
			(xy 45.291048 -144.940776) (xy 45.255147 -144.982237) (xy 45.213714 -145.01817) (xy 45.16759 -145.047844)
			(xy 45.117715 -145.070655) (xy 45.065102 -145.08614) (xy 45.010822 -145.093984) (xy 44.9834 -145.094452)
			(xy 44.983146 -145.094452) (xy 44.972771 -145.094306) (xy 44.952059 -145.093034) (xy 44.941744 -145.091912)
			(xy 44.931838 -145.090896) (xy 44.922948 -145.093182) (xy 44.919187 -145.094264) (xy 44.912042 -145.097456)
			(xy 44.908724 -145.099532) (xy 44.871132 -145.127218) (xy 44.87037 -145.12798) (xy 44.86402 -145.13306)
			(xy 44.8564 -145.141442) (xy 44.854368 -145.144744) (xy 44.852373 -145.148012) (xy 44.849308 -145.155028)
			(xy 44.848272 -145.158714) (xy 44.843628 -145.186375) (xy 44.82754 -145.240106) (xy 44.803998 -145.291014)
			(xy 44.773479 -145.338071) (xy 44.736598 -145.380328) (xy 44.6941 -145.416931) (xy 44.646844 -145.447141)
			(xy 44.595783 -145.470348) (xy 44.541948 -145.486084) (xy 44.486426 -145.494031) (xy 44.458382 -145.494502)
			(xy 44.429194 -145.493972) (xy 44.371458 -145.485359) (xy 44.315623 -145.468323) (xy 44.262913 -145.443237)
			(xy 44.214479 -145.41065) (xy 44.171383 -145.371275) (xy 44.134565 -145.325973) (xy 44.104834 -145.275737)
			(xy 44.093384 -145.248884) (xy 44.092622 -145.246852) (xy 44.090844 -145.243296) (xy 44.086894 -145.236769)
			(xy 44.075918 -145.226184) (xy 44.069254 -145.222468) (xy 44.047156 -145.212816) (xy 44.046648 -145.212816)
			(xy 44.034202 -145.207482) (xy 44.029771 -145.205691) (xy 44.020434 -145.203651) (xy 44.01566 -145.203418)
			(xy 44.006262 -145.203164) (xy 43.997118 -145.206466) (xy 43.961558 -145.217642) (xy 43.959526 -145.21815)
			(xy 43.95597 -145.219166) (xy 43.951906 -145.220182) (xy 43.944794 -145.225262) (xy 43.941201 -145.227928)
			(xy 43.934934 -145.234311) (xy 43.932348 -145.237962) (xy 43.903646 -145.283174) (xy 43.903646 -145.283682)
			(xy 43.901614 -145.28673) (xy 43.901614 -145.30578) (xy 43.90009 -145.339054) (xy 43.899836 -145.341594)
			(xy 43.899836 -145.343626) (xy 43.90009 -145.34769) (xy 43.901614 -145.381218) (xy 43.901614 -145.38198)
			(xy 43.901121 -145.410294) (xy 43.892791 -145.466305) (xy 43.876268 -145.520468) (xy 43.851914 -145.57159)
			(xy 43.820265 -145.618548) (xy 43.801538 -145.63979) (xy 43.80103 -145.640298) (xy 43.791124 -145.651474)
			(xy 43.791124 -145.661888) (xy 43.781218 -146.5707) (xy 43.77944 -146.72564) (xy 43.77944 -146.729196)
			(xy 43.819064 -147.3708) (xy 44.058068 -151.257) (xy 52.576982 -151.257) (xy 52.581053 -151.201378)
			(xy 52.593179 -151.146941) (xy 52.613102 -151.09485) (xy 52.640398 -151.046215) (xy 52.674484 -151.002072)
			(xy 52.714633 -150.963363) (xy 52.759991 -150.930912) (xy 52.809591 -150.905411) (xy 52.862375 -150.887404)
			(xy 52.917218 -150.877274) (xy 52.972952 -150.875237) (xy 53.028389 -150.881337) (xy 53.082346 -150.895443)
			(xy 53.133675 -150.917255) (xy 53.181281 -150.946309) (xy 53.224149 -150.981984) (xy 53.261366 -151.023521)
			(xy 53.292139 -151.070034) (xy 53.315811 -151.120531) (xy 53.331879 -151.173938) (xy 53.339999 -151.229114)
			(xy 53.340508 -151.257) (xy 53.339999 -151.284886) (xy 53.331879 -151.340062) (xy 53.315811 -151.393469)
			(xy 53.292139 -151.443966) (xy 53.261366 -151.490479) (xy 53.224149 -151.532016) (xy 53.181281 -151.567691)
			(xy 53.133675 -151.596745) (xy 53.082346 -151.618557) (xy 53.028389 -151.632663) (xy 52.972952 -151.638763)
			(xy 52.917218 -151.636726) (xy 52.862375 -151.626596) (xy 52.809591 -151.608589) (xy 52.759991 -151.583088)
			(xy 52.714633 -151.550637) (xy 52.674484 -151.511928) (xy 52.640398 -151.467785) (xy 52.613102 -151.41915)
			(xy 52.593179 -151.367059) (xy 52.581053 -151.312622) (xy 52.576982 -151.257) (xy 44.058068 -151.257)
			(xy 44.168822 -153.05786) (xy 44.168822 -153.058876) (xy 44.20791 -153.560018) (xy 52.449982 -153.560018)
			(xy 52.454053 -153.504396) (xy 52.466179 -153.449959) (xy 52.486102 -153.397868) (xy 52.513398 -153.349233)
			(xy 52.547484 -153.30509) (xy 52.587633 -153.266381) (xy 52.632991 -153.23393) (xy 52.682591 -153.208429)
			(xy 52.735375 -153.190422) (xy 52.790218 -153.180292) (xy 52.845952 -153.178255) (xy 52.901389 -153.184355)
			(xy 52.955346 -153.198461) (xy 53.006675 -153.220273) (xy 53.054281 -153.249327) (xy 53.097149 -153.285002)
			(xy 53.134366 -153.326539) (xy 53.165139 -153.373052) (xy 53.188811 -153.423549) (xy 53.204879 -153.476956)
			(xy 53.212999 -153.532132) (xy 53.213508 -153.560018) (xy 53.212999 -153.587904) (xy 53.204879 -153.64308)
			(xy 53.188811 -153.696487) (xy 53.165139 -153.746984) (xy 53.134366 -153.793497) (xy 53.097149 -153.835034)
			(xy 53.054281 -153.870709) (xy 53.006675 -153.899763) (xy 52.955346 -153.921575) (xy 52.901389 -153.935681)
			(xy 52.845952 -153.941781) (xy 52.790218 -153.939744) (xy 52.735375 -153.929614) (xy 52.682591 -153.911607)
			(xy 52.632991 -153.886106) (xy 52.587633 -153.853655) (xy 52.547484 -153.814946) (xy 52.513398 -153.770803)
			(xy 52.486102 -153.722168) (xy 52.466179 -153.670077) (xy 52.454053 -153.61564) (xy 52.449982 -153.560018)
			(xy 44.20791 -153.560018) (xy 44.254704 -154.159966) (xy 51.306982 -154.159966) (xy 51.311053 -154.104344)
			(xy 51.323179 -154.049907) (xy 51.343102 -153.997816) (xy 51.370398 -153.949181) (xy 51.404484 -153.905038)
			(xy 51.444633 -153.866329) (xy 51.489991 -153.833878) (xy 51.539591 -153.808377) (xy 51.592375 -153.79037)
			(xy 51.647218 -153.78024) (xy 51.702952 -153.778203) (xy 51.758389 -153.784303) (xy 51.812346 -153.798409)
			(xy 51.863675 -153.820221) (xy 51.911281 -153.849275) (xy 51.954149 -153.88495) (xy 51.991366 -153.926487)
			(xy 52.022139 -153.973) (xy 52.045811 -154.023497) (xy 52.061879 -154.076904) (xy 52.069999 -154.13208)
			(xy 52.070508 -154.159966) (xy 52.069999 -154.187852) (xy 52.061879 -154.243028) (xy 52.045811 -154.296435)
			(xy 52.022139 -154.346932) (xy 51.991366 -154.393445) (xy 51.954149 -154.434982) (xy 51.911281 -154.470657)
			(xy 51.863675 -154.499711) (xy 51.812346 -154.521523) (xy 51.758389 -154.535629) (xy 51.702952 -154.541729)
			(xy 51.647218 -154.539692) (xy 51.592375 -154.529562) (xy 51.539591 -154.511555) (xy 51.489991 -154.486054)
			(xy 51.444633 -154.453603) (xy 51.404484 -154.414894) (xy 51.370398 -154.370751) (xy 51.343102 -154.322116)
			(xy 51.323179 -154.270025) (xy 51.311053 -154.215588) (xy 51.306982 -154.159966) (xy 44.254704 -154.159966)
			(xy 44.323469 -155.0416) (xy 48.163732 -155.0416) (xy 48.167803 -154.985978) (xy 48.179929 -154.931541)
			(xy 48.199852 -154.87945) (xy 48.227148 -154.830815) (xy 48.261234 -154.786672) (xy 48.301383 -154.747963)
			(xy 48.346741 -154.715512) (xy 48.396341 -154.690011) (xy 48.449125 -154.672004) (xy 48.503968 -154.661874)
			(xy 48.559702 -154.659837) (xy 48.615139 -154.665937) (xy 48.669096 -154.680043) (xy 48.720425 -154.701855)
			(xy 48.768031 -154.730909) (xy 48.810899 -154.766584) (xy 48.848116 -154.808121) (xy 48.878889 -154.854634)
			(xy 48.902561 -154.905131) (xy 48.918554 -154.958288) (xy 52.744114 -154.958288) (xy 52.748185 -154.902666)
			(xy 52.760311 -154.848229) (xy 52.780234 -154.796138) (xy 52.80753 -154.747503) (xy 52.841616 -154.70336)
			(xy 52.881765 -154.664651) (xy 52.927123 -154.6322) (xy 52.976723 -154.606699) (xy 53.029507 -154.588692)
			(xy 53.08435 -154.578562) (xy 53.140084 -154.576525) (xy 53.195521 -154.582625) (xy 53.249478 -154.596731)
			(xy 53.300807 -154.618543) (xy 53.348413 -154.647597) (xy 53.391281 -154.683272) (xy 53.428498 -154.724809)
			(xy 53.459271 -154.771322) (xy 53.482943 -154.821819) (xy 53.499011 -154.875226) (xy 53.507131 -154.930402)
			(xy 53.50764 -154.958288) (xy 53.507131 -154.986174) (xy 53.499011 -155.04135) (xy 53.482943 -155.094757)
			(xy 53.459271 -155.145254) (xy 53.428498 -155.191767) (xy 53.391281 -155.233304) (xy 53.348413 -155.268979)
			(xy 53.300807 -155.298033) (xy 53.249478 -155.319845) (xy 53.195521 -155.333951) (xy 53.140084 -155.340051)
			(xy 53.08435 -155.338014) (xy 53.029507 -155.327884) (xy 52.976723 -155.309877) (xy 52.927123 -155.284376)
			(xy 52.881765 -155.251925) (xy 52.841616 -155.213216) (xy 52.80753 -155.169073) (xy 52.780234 -155.120438)
			(xy 52.760311 -155.068347) (xy 52.748185 -155.01391) (xy 52.744114 -154.958288) (xy 48.918554 -154.958288)
			(xy 48.918629 -154.958538) (xy 48.926749 -155.013714) (xy 48.927258 -155.0416) (xy 48.926749 -155.069486)
			(xy 48.918629 -155.124662) (xy 48.902561 -155.178069) (xy 48.878889 -155.228566) (xy 48.848116 -155.275079)
			(xy 48.810899 -155.316616) (xy 48.768031 -155.352291) (xy 48.720425 -155.381345) (xy 48.669096 -155.403157)
			(xy 48.615139 -155.417263) (xy 48.559702 -155.423363) (xy 48.503968 -155.421326) (xy 48.449125 -155.411196)
			(xy 48.396341 -155.393189) (xy 48.346741 -155.367688) (xy 48.301383 -155.335237) (xy 48.261234 -155.296528)
			(xy 48.227148 -155.252385) (xy 48.199852 -155.20375) (xy 48.179929 -155.151659) (xy 48.167803 -155.097222)
			(xy 48.163732 -155.0416) (xy 44.323469 -155.0416) (xy 44.366895 -155.598368) (xy 51.368196 -155.598368)
			(xy 51.372267 -155.542746) (xy 51.384393 -155.488309) (xy 51.404316 -155.436218) (xy 51.431612 -155.387583)
			(xy 51.465698 -155.34344) (xy 51.505847 -155.304731) (xy 51.551205 -155.27228) (xy 51.600805 -155.246779)
			(xy 51.653589 -155.228772) (xy 51.708432 -155.218642) (xy 51.764166 -155.216605) (xy 51.819603 -155.222705)
			(xy 51.87356 -155.236811) (xy 51.924889 -155.258623) (xy 51.972495 -155.287677) (xy 52.015363 -155.323352)
			(xy 52.05258 -155.364889) (xy 52.083353 -155.411402) (xy 52.107025 -155.461899) (xy 52.123093 -155.515306)
			(xy 52.131213 -155.570482) (xy 52.131722 -155.598368) (xy 52.131213 -155.626254) (xy 52.123093 -155.68143)
			(xy 52.107025 -155.734837) (xy 52.083353 -155.785334) (xy 52.05258 -155.831847) (xy 52.015363 -155.873384)
			(xy 51.972495 -155.909059) (xy 51.924889 -155.938113) (xy 51.87356 -155.959925) (xy 51.819603 -155.974031)
			(xy 51.764166 -155.980131) (xy 51.708432 -155.978094) (xy 51.653589 -155.967964) (xy 51.600805 -155.949957)
			(xy 51.551205 -155.924456) (xy 51.505847 -155.892005) (xy 51.465698 -155.853296) (xy 51.431612 -155.809153)
			(xy 51.404316 -155.760518) (xy 51.384393 -155.708427) (xy 51.372267 -155.65399) (xy 51.368196 -155.598368)
			(xy 44.366895 -155.598368) (xy 44.440692 -156.544518) (xy 52.727858 -156.544518) (xy 52.731929 -156.488896)
			(xy 52.744055 -156.434459) (xy 52.763978 -156.382368) (xy 52.791274 -156.333733) (xy 52.82536 -156.28959)
			(xy 52.865509 -156.250881) (xy 52.910867 -156.21843) (xy 52.960467 -156.192929) (xy 53.013251 -156.174922)
			(xy 53.068094 -156.164792) (xy 53.123828 -156.162755) (xy 53.179265 -156.168855) (xy 53.233222 -156.182961)
			(xy 53.284551 -156.204773) (xy 53.332157 -156.233827) (xy 53.375025 -156.269502) (xy 53.412242 -156.311039)
			(xy 53.443015 -156.357552) (xy 53.466687 -156.408049) (xy 53.482755 -156.461456) (xy 53.490875 -156.516632)
			(xy 53.491384 -156.544518) (xy 53.490875 -156.572404) (xy 53.482755 -156.62758) (xy 53.466687 -156.680987)
			(xy 53.443015 -156.731484) (xy 53.412242 -156.777997) (xy 53.375025 -156.819534) (xy 53.332157 -156.855209)
			(xy 53.284551 -156.884263) (xy 53.233222 -156.906075) (xy 53.179265 -156.920181) (xy 53.123828 -156.926281)
			(xy 53.068094 -156.924244) (xy 53.013251 -156.914114) (xy 52.960467 -156.896107) (xy 52.910867 -156.870606)
			(xy 52.865509 -156.838155) (xy 52.82536 -156.799446) (xy 52.791274 -156.755303) (xy 52.763978 -156.706668)
			(xy 52.744055 -156.654577) (xy 52.731929 -156.60014) (xy 52.727858 -156.544518) (xy 44.440692 -156.544518)
			(xy 44.481959 -157.0736) (xy 51.296822 -157.0736) (xy 51.300893 -157.017978) (xy 51.313019 -156.963541)
			(xy 51.332942 -156.91145) (xy 51.360238 -156.862815) (xy 51.394324 -156.818672) (xy 51.434473 -156.779963)
			(xy 51.479831 -156.747512) (xy 51.529431 -156.722011) (xy 51.582215 -156.704004) (xy 51.637058 -156.693874)
			(xy 51.692792 -156.691837) (xy 51.748229 -156.697937) (xy 51.802186 -156.712043) (xy 51.853515 -156.733855)
			(xy 51.901121 -156.762909) (xy 51.943989 -156.798584) (xy 51.981206 -156.840121) (xy 52.011979 -156.886634)
			(xy 52.035651 -156.937131) (xy 52.051719 -156.990538) (xy 52.059839 -157.045714) (xy 52.060348 -157.0736)
			(xy 52.059839 -157.101486) (xy 52.051719 -157.156662) (xy 52.035651 -157.210069) (xy 52.011979 -157.260566)
			(xy 51.981206 -157.307079) (xy 51.943989 -157.348616) (xy 51.901121 -157.384291) (xy 51.853515 -157.413345)
			(xy 51.802186 -157.435157) (xy 51.748229 -157.449263) (xy 51.692792 -157.455363) (xy 51.637058 -157.453326)
			(xy 51.582215 -157.443196) (xy 51.529431 -157.425189) (xy 51.479831 -157.399688) (xy 51.434473 -157.367237)
			(xy 51.394324 -157.328528) (xy 51.360238 -157.284385) (xy 51.332942 -157.23575) (xy 51.313019 -157.183659)
			(xy 51.300893 -157.129222) (xy 51.296822 -157.0736) (xy 44.481959 -157.0736) (xy 44.545177 -157.884114)
			(xy 52.587142 -157.884114) (xy 52.591213 -157.828492) (xy 52.603339 -157.774055) (xy 52.623262 -157.721964)
			(xy 52.650558 -157.673329) (xy 52.684644 -157.629186) (xy 52.724793 -157.590477) (xy 52.770151 -157.558026)
			(xy 52.819751 -157.532525) (xy 52.872535 -157.514518) (xy 52.927378 -157.504388) (xy 52.983112 -157.502351)
			(xy 53.038549 -157.508451) (xy 53.092506 -157.522557) (xy 53.143835 -157.544369) (xy 53.191441 -157.573423)
			(xy 53.234309 -157.609098) (xy 53.271526 -157.650635) (xy 53.302299 -157.697148) (xy 53.325971 -157.747645)
			(xy 53.342039 -157.801052) (xy 53.350159 -157.856228) (xy 53.350668 -157.884114) (xy 53.350159 -157.912)
			(xy 53.342039 -157.967176) (xy 53.325971 -158.020583) (xy 53.302299 -158.07108) (xy 53.271526 -158.117593)
			(xy 53.234309 -158.15913) (xy 53.191441 -158.194805) (xy 53.143835 -158.223859) (xy 53.092506 -158.245671)
			(xy 53.038549 -158.259777) (xy 52.983112 -158.265877) (xy 52.927378 -158.26384) (xy 52.872535 -158.25371)
			(xy 52.819751 -158.235703) (xy 52.770151 -158.210202) (xy 52.724793 -158.177751) (xy 52.684644 -158.139042)
			(xy 52.650558 -158.094899) (xy 52.623262 -158.046264) (xy 52.603339 -157.994173) (xy 52.591213 -157.939736)
			(xy 52.587142 -157.884114) (xy 44.545177 -157.884114) (xy 44.724648 -160.1851) (xy 45.524179 -160.1851)
			(xy 45.528134 -160.093263) (xy 45.539969 -160.002106) (xy 45.559596 -159.912303) (xy 45.58687 -159.824521)
			(xy 45.62159 -159.739407) (xy 45.663498 -159.657594) (xy 45.712284 -159.579686) (xy 45.767587 -159.506261)
			(xy 45.828997 -159.437861) (xy 45.896059 -159.374994) (xy 45.968278 -159.318124) (xy 46.045118 -159.267673)
			(xy 46.126011 -159.224014) (xy 46.210357 -159.187471) (xy 46.297533 -159.158314) (xy 46.386892 -159.13676)
			(xy 46.477773 -159.122966) (xy 46.569504 -159.117036) (xy 46.661405 -159.119014) (xy 46.752796 -159.128885)
			(xy 46.843 -159.146575) (xy 46.931349 -159.171955) (xy 47.017189 -159.204835) (xy 47.099885 -159.244973)
			(xy 47.178825 -159.292072) (xy 47.253423 -159.345782) (xy 47.323129 -159.405706) (xy 47.387424 -159.4714)
			(xy 47.445835 -159.542378) (xy 47.497927 -159.618115) (xy 47.543316 -159.69805) (xy 47.581666 -159.78159)
			(xy 47.612691 -159.868118) (xy 47.636164 -159.956993) (xy 47.65191 -160.047557) (xy 47.659812 -160.139139)
			(xy 47.660306 -160.1851) (xy 47.659812 -160.231061) (xy 47.65191 -160.322643) (xy 47.636164 -160.413207)
			(xy 47.612691 -160.502082) (xy 47.581666 -160.58861) (xy 47.543316 -160.67215) (xy 47.497927 -160.752085)
			(xy 47.445835 -160.827822) (xy 47.387424 -160.8988) (xy 47.323129 -160.964494) (xy 47.253423 -161.024418)
			(xy 47.178825 -161.078128) (xy 47.099885 -161.125227) (xy 47.017189 -161.165365) (xy 46.931349 -161.198245)
			(xy 46.843 -161.223625) (xy 46.752796 -161.241315) (xy 46.661405 -161.251186) (xy 46.569504 -161.253164)
			(xy 46.477773 -161.247234) (xy 46.386892 -161.23344) (xy 46.297533 -161.211886) (xy 46.210357 -161.182729)
			(xy 46.126011 -161.146186) (xy 46.045118 -161.102527) (xy 45.968278 -161.052076) (xy 45.896059 -160.995206)
			(xy 45.828997 -160.932339) (xy 45.767587 -160.863939) (xy 45.712284 -160.790514) (xy 45.663498 -160.712606)
			(xy 45.62159 -160.630793) (xy 45.58687 -160.545679) (xy 45.559596 -160.457897) (xy 45.539969 -160.368094)
			(xy 45.528134 -160.276937) (xy 45.524179 -160.1851) (xy 44.724648 -160.1851) (xy 45.483103 -169.909236)
			(xy 51.926996 -169.909236) (xy 51.931067 -169.853614) (xy 51.943193 -169.799177) (xy 51.963116 -169.747086)
			(xy 51.990412 -169.698451) (xy 52.024498 -169.654308) (xy 52.064647 -169.615599) (xy 52.110005 -169.583148)
			(xy 52.159605 -169.557647) (xy 52.212389 -169.53964) (xy 52.267232 -169.52951) (xy 52.322966 -169.527473)
			(xy 52.378403 -169.533573) (xy 52.43236 -169.547679) (xy 52.483689 -169.569491) (xy 52.531295 -169.598545)
			(xy 52.574163 -169.63422) (xy 52.61138 -169.675757) (xy 52.642153 -169.72227) (xy 52.665825 -169.772767)
			(xy 52.681893 -169.826174) (xy 52.690013 -169.88135) (xy 52.690522 -169.909236) (xy 52.690013 -169.937122)
			(xy 52.681893 -169.992298) (xy 52.665825 -170.045705) (xy 52.642153 -170.096202) (xy 52.61138 -170.142715)
			(xy 52.574163 -170.184252) (xy 52.531295 -170.219927) (xy 52.483689 -170.248981) (xy 52.43236 -170.270793)
			(xy 52.378403 -170.284899) (xy 52.322966 -170.290999) (xy 52.267232 -170.288962) (xy 52.212389 -170.278832)
			(xy 52.159605 -170.260825) (xy 52.110005 -170.235324) (xy 52.064647 -170.202873) (xy 52.024498 -170.164164)
			(xy 51.990412 -170.120021) (xy 51.963116 -170.071386) (xy 51.943193 -170.019295) (xy 51.931067 -169.964858)
			(xy 51.926996 -169.909236) (xy 45.483103 -169.909236) (xy 46.013142 -176.704855) (xy 50.702129 -176.704855)
			(xy 50.702129 -176.650345) (xy 50.709887 -176.596389) (xy 50.725244 -176.544087) (xy 50.747889 -176.494503)
			(xy 50.77736 -176.448646) (xy 50.813057 -176.40745) (xy 50.854254 -176.371754) (xy 50.900112 -176.342284)
			(xy 50.949696 -176.319641) (xy 51.001999 -176.304285) (xy 51.055955 -176.296528) (xy 51.08321 -176.296066)
			(xy 51.089052 -176.296066) (xy 51.102338 -176.295857) (xy 51.128101 -176.289393) (xy 51.151322 -176.276498)
			(xy 51.170429 -176.258047) (xy 51.184126 -176.23529) (xy 51.191485 -176.209768) (xy 51.192176 -176.196498)
			(xy 51.193121 -176.169592) (xy 51.201734 -176.116446) (xy 51.217731 -176.065038) (xy 51.240794 -176.016389)
			(xy 51.270465 -175.971464) (xy 51.306156 -175.931155) (xy 51.347157 -175.896262) (xy 51.392656 -175.867477)
			(xy 51.441748 -175.845373) (xy 51.49346 -175.830388) (xy 51.546764 -175.822819) (xy 51.573684 -175.822356)
			(xy 51.600935 -175.82289) (xy 51.654883 -175.830645) (xy 51.707177 -175.845998) (xy 51.756755 -175.868637)
			(xy 51.802606 -175.898102) (xy 51.843796 -175.933792) (xy 51.879488 -175.974981) (xy 51.908955 -176.020831)
			(xy 51.931597 -176.070408) (xy 51.946952 -176.122702) (xy 51.954709 -176.176649) (xy 51.954709 -176.231151)
			(xy 51.946952 -176.285098) (xy 51.931597 -176.337392) (xy 51.908955 -176.386969) (xy 51.879488 -176.432819)
			(xy 51.843796 -176.474008) (xy 51.802606 -176.509698) (xy 51.756755 -176.539163) (xy 51.707177 -176.561802)
			(xy 51.654883 -176.577155) (xy 51.600935 -176.58491) (xy 51.573684 -176.585372) (xy 51.567842 -176.585372)
			(xy 51.55456 -176.585636) (xy 51.528806 -176.592097) (xy 51.505591 -176.604983) (xy 51.486486 -176.623422)
			(xy 51.472785 -176.646166) (xy 51.465416 -176.671675) (xy 51.464718 -176.68494) (xy 51.463814 -176.711848)
			(xy 51.455195 -176.764996) (xy 51.439193 -176.816404) (xy 51.416126 -176.865054) (xy 51.38645 -176.909979)
			(xy 51.350755 -176.950288) (xy 51.30975 -176.98518) (xy 51.264248 -177.013964) (xy 51.215152 -177.036067)
			(xy 51.163438 -177.051051) (xy 51.110131 -177.058619) (xy 51.08321 -177.059082) (xy 51.055955 -177.058672)
			(xy 51.001999 -177.050915) (xy 50.949696 -177.035559) (xy 50.900112 -177.012916) (xy 50.854254 -176.983446)
			(xy 50.813057 -176.94775) (xy 50.77736 -176.906554) (xy 50.747889 -176.860697) (xy 50.725244 -176.811113)
			(xy 50.709887 -176.758811) (xy 50.702129 -176.704855) (xy 46.013142 -176.704855) (xy 46.792134 -186.692286)
			(xy 49.122584 -216.566496) (xy 49.128369 -216.570705) (xy 49.14165 -216.576003) (xy 49.148746 -216.57691)
			(xy 49.153318 -216.577164) (xy 52.92344 -216.577164) (xy 52.927758 -216.57691) (xy 52.937132 -216.575387)
			(xy 52.953852 -216.566407) (xy 52.966148 -216.551952) (xy 52.969668 -216.543128) (xy 52.9717 -216.537032)
			(xy 52.974494 -216.523062) (xy 55.082186 -176.033938) (xy 55.896764 -160.379664) (xy 55.896852 -160.370579)
			(xy 55.891391 -160.353264) (xy 55.886096 -160.345882) (xy 55.880508 -160.33877) (xy 55.865268 -160.329372)
			(xy 55.856632 -160.327594) (xy 55.854092 -160.326832) (xy 55.852822 -160.326578) (xy 55.825621 -160.319307)
			(xy 55.773563 -160.297858) (xy 55.725224 -160.268989) (xy 55.681655 -160.233327) (xy 55.643801 -160.191647)
			(xy 55.612487 -160.144856) (xy 55.588391 -160.093969) (xy 55.572038 -160.040093) (xy 55.563783 -159.984398)
			(xy 55.563262 -159.956246) (xy 55.563745 -159.928676) (xy 55.571678 -159.874109) (xy 55.587385 -159.821254)
			(xy 55.61054 -159.771211) (xy 55.640658 -159.725023) (xy 55.677113 -159.683653) (xy 55.719146 -159.647964)
			(xy 55.765879 -159.618699) (xy 55.816338 -159.596467) (xy 55.869474 -159.581733) (xy 55.896764 -159.577786)
			(xy 55.900574 -159.577278) (xy 55.908372 -159.575365) (xy 55.922351 -159.567483) (xy 55.928006 -159.561784)
			(xy 55.933848 -159.555434) (xy 55.93715 -159.547814) (xy 55.938568 -159.544333) (xy 55.940473 -159.537063)
			(xy 55.94096 -159.533336) (xy 56.049418 -157.437836) (xy 56.048402 -157.430216) (xy 56.037226 -157.408118)
			(xy 56.033416 -157.402784) (xy 56.030114 -157.39872) (xy 55.993538 -157.358334) (xy 55.99303 -157.357826)
			(xy 55.987442 -157.35173) (xy 55.983963 -157.348154) (xy 55.975904 -157.342274) (xy 55.97144 -157.340046)
			(xy 55.96255 -157.335982) (xy 55.951882 -157.335474) (xy 55.925238 -157.33414) (xy 55.872687 -157.324953)
			(xy 55.821928 -157.308536) (xy 55.773951 -157.285209) (xy 55.72969 -157.255427) (xy 55.69001 -157.21977)
			(xy 55.655682 -157.178933) (xy 55.627377 -157.133714) (xy 55.605647 -157.084992) (xy 55.590914 -157.033719)
			(xy 55.583467 -156.980894) (xy 55.583074 -156.95422) (xy 55.583535 -156.926966) (xy 55.59129 -156.873012)
			(xy 55.606644 -156.82071) (xy 55.629285 -156.771126) (xy 55.658753 -156.725269) (xy 55.694446 -156.684073)
			(xy 55.735639 -156.648375) (xy 55.781493 -156.618904) (xy 55.831075 -156.596257) (xy 55.883374 -156.580898)
			(xy 55.937328 -156.573138) (xy 55.964582 -156.572712) (xy 55.992014 -156.573728) (xy 56.000142 -156.574236)
			(xy 56.002174 -156.57449) (xy 56.011826 -156.571188) (xy 56.016241 -156.56959) (xy 56.024428 -156.564993)
			(xy 56.028082 -156.562044) (xy 56.03748 -156.553662) (xy 56.08574 -156.510482) (xy 56.086248 -156.509974)
			(xy 56.08955 -156.50591) (xy 56.095646 -156.49575) (xy 56.098694 -156.487368) (xy 56.098694 -156.48686)
			(xy 56.099964 -156.481018) (xy 56.204358 -154.476958) (xy 56.201564 -154.468322) (xy 56.20004 -154.463242)
			(xy 56.196484 -154.454352) (xy 56.188247 -154.432171) (xy 56.176693 -154.386287) (xy 56.170898 -154.339327)
			(xy 56.170576 -154.315668) (xy 56.170576 -154.309572) (xy 56.171686 -154.278847) (xy 56.18251 -154.21833)
			(xy 56.202893 -154.160329) (xy 56.217058 -154.133042) (xy 56.219852 -154.127962) (xy 56.2229 -154.11704)
			(xy 56.284622 -152.934162) (xy 56.343296 -151.803862) (xy 56.343296 -151.799544) (xy 56.342963 -151.793635)
			(xy 56.339885 -151.782212) (xy 56.3372 -151.776938) (xy 56.333644 -151.770842) (xy 56.292242 -151.72309)
			(xy 56.288178 -151.718264) (xy 56.285384 -151.715216) (xy 56.275986 -151.71039) (xy 56.261 -151.70912)
			(xy 56.226481 -151.705726) (xy 56.158522 -151.691833) (xy 56.09268 -151.670009) (xy 56.029877 -151.64056)
			(xy 55.970993 -151.603899) (xy 55.916852 -151.560538) (xy 55.892192 -151.536146) (xy 55.891684 -151.535638)
			(xy 52.23256 -147.87626) (xy 52.227973 -147.87197) (xy 52.217183 -147.865546) (xy 52.211224 -147.86356)
			(xy 52.207683 -147.862596) (xy 52.200416 -147.861578) (xy 52.196746 -147.861528) (xy 49.827688 -147.861528)
			(xy 49.794832 -147.861073) (xy 49.729533 -147.853725) (xy 49.665467 -147.839113) (xy 49.60344 -147.81742)
			(xy 49.544231 -147.788919) (xy 49.488586 -147.753968) (xy 49.437204 -147.713007) (xy 49.413668 -147.690078)
			(xy 48.877728 -147.154392) (xy 48.851017 -147.126817) (xy 48.804302 -147.065895) (xy 48.765945 -146.999392)
			(xy 48.750728 -146.964146) (xy 48.736696 -146.92874) (xy 48.716871 -146.855205) (xy 48.706747 -146.77972)
			(xy 48.706024 -146.741642) (xy 48.706024 -146.739864) (xy 48.706499 -146.70647) (xy 48.7141 -146.640117)
			(xy 48.729198 -146.575058) (xy 48.751597 -146.512139) (xy 48.781008 -146.452176) (xy 48.817047 -146.395946)
			(xy 48.859248 -146.344181) (xy 48.882808 -146.32051) (xy 48.883316 -146.320002) (xy 49.313592 -145.889726)
			(xy 49.337157 -145.866831) (xy 49.388542 -145.825883) (xy 49.444186 -145.790941) (xy 49.50339 -145.762444)
			(xy 49.56541 -145.740749) (xy 49.629468 -145.726129) (xy 49.694759 -145.718768) (xy 49.727612 -145.718276)
			(xy 51.1302 -145.718276) (xy 51.167855 -145.718858) (xy 51.242544 -145.728511) (xy 51.31538 -145.747657)
			(xy 51.385161 -145.775981) (xy 51.450736 -145.813015) (xy 51.481228 -145.835116) (xy 51.489866 -145.840969)
			(xy 51.510139 -145.845819) (xy 51.530669 -145.84221) (xy 51.539648 -145.836894) (xy 51.563165 -145.82195)
			(xy 51.613618 -145.798308) (xy 51.666976 -145.782264) (xy 51.722101 -145.774161) (xy 51.74996 -145.773648)
			(xy 51.777214 -145.774131) (xy 51.831169 -145.781883) (xy 51.883471 -145.797234) (xy 51.933056 -145.819872)
			(xy 51.978914 -145.849337) (xy 52.020113 -145.885028) (xy 52.055813 -145.926218) (xy 52.085288 -145.97207)
			(xy 52.107937 -146.02165) (xy 52.123299 -146.073949) (xy 52.131063 -146.127902) (xy 52.131468 -146.155156)
			(xy 52.131468 -146.162776) (xy 52.4383 -146.162776) (xy 52.470053 -146.163187) (xy 52.533187 -146.170056)
			(xy 52.564284 -146.176492) (xy 52.575588 -146.178506) (xy 52.597941 -146.173361) (xy 52.60721 -146.166586)
			(xy 52.668678 -146.117056) (xy 52.677196 -146.109426) (xy 52.687105 -146.088849) (xy 52.687728 -146.077432)
			(xy 52.687728 -141.677644) (xy 52.68756 -141.671634) (xy 52.684737 -141.659952) (xy 52.68214 -141.65453)
			(xy 52.680304 -141.651053) (xy 52.675718 -141.644667) (xy 52.672996 -141.64183) (xy 51.572922 -140.541756)
			(xy 51.550013 -140.518178) (xy 51.509042 -140.466763) (xy 51.474083 -140.411085) (xy 51.445576 -140.351844)
			(xy 51.42388 -140.289784) (xy 51.409267 -140.225685) (xy 51.401921 -140.160354) (xy 51.401472 -140.127482)
			(xy 51.401218 -140.11529) (xy 51.402469 -140.080364) (xy 51.412256 -140.011164) (xy 51.4302 -139.943617)
			(xy 51.456047 -139.878683) (xy 51.489431 -139.817282) (xy 51.529876 -139.760286) (xy 51.576811 -139.708501)
			(xy 51.629569 -139.662664) (xy 51.687403 -139.623423) (xy 51.749491 -139.591336) (xy 51.814953 -139.566857)
			(xy 51.882861 -139.550335) (xy 51.952252 -139.542002) (xy 51.987196 -139.541504) (xy 51.99634 -139.541504)
			(xy 52.033637 -139.542684) (xy 52.107494 -139.553342) (xy 52.179399 -139.573296) (xy 52.214018 -139.587224)
			(xy 52.248764 -139.602446) (xy 52.314352 -139.640561) (xy 52.37448 -139.686813) (xy 52.401724 -139.713208)
			(xy 53.68798 -140.999464) (xy 53.710926 -141.023019) (xy 53.751946 -141.074418) (xy 53.786949 -141.130089)
			(xy 53.815494 -141.189331) (xy 53.837223 -141.251399) (xy 53.851861 -141.31551) (xy 53.859224 -141.380857)
			(xy 53.859684 -141.413738) (xy 53.859684 -146.635978) (xy 53.8607 -146.64563) (xy 53.862324 -146.652876)
			(xy 53.869158 -146.666052) (xy 53.874162 -146.671538) (xy 56.341772 -149.139148) (xy 56.34778 -149.144695)
			(xy 56.36242 -149.151961) (xy 56.370474 -149.153372) (xy 56.383926 -149.154834) (xy 56.410759 -149.151427)
			(xy 56.435753 -149.141088) (xy 56.457154 -149.124546) (xy 56.473456 -149.102962) (xy 56.483513 -149.077853)
			(xy 56.485536 -149.064472) (xy 56.48579 -149.061424) (xy 56.597296 -146.921982) (xy 56.71312 -144.693894)
			(xy 56.71312 -144.69364) (xy 56.713239 -144.684814) (xy 56.708179 -144.667917) (xy 56.703214 -144.66062)
			(xy 56.698134 -144.653762) (xy 56.68391 -144.64411) (xy 56.67502 -144.641824) (xy 56.647309 -144.634241)
			(xy 56.594383 -144.611897) (xy 56.545403 -144.581873) (xy 56.501476 -144.544849) (xy 56.463593 -144.501659)
			(xy 56.432611 -144.45328) (xy 56.409228 -144.400804) (xy 56.393975 -144.345416) (xy 56.390032 -144.316958)
			(xy 56.390032 -144.316704) (xy 56.389016 -144.308322) (xy 56.387492 -144.27581) (xy 56.387492 -144.272)
			(xy 56.387492 -144.270476) (xy 56.388072 -144.243324) (xy 56.395972 -144.189593) (xy 56.41141 -144.137525)
			(xy 56.434073 -144.088172) (xy 56.463505 -144.04253) (xy 56.49911 -144.001522) (xy 56.540169 -143.965976)
			(xy 56.585853 -143.93661) (xy 56.635239 -143.914017) (xy 56.687329 -143.898654) (xy 56.714136 -143.894302)
			(xy 56.723026 -143.892524) (xy 56.735726 -143.886682) (xy 56.741314 -143.881602) (xy 56.746307 -143.876653)
			(xy 56.753661 -143.864678) (xy 56.755792 -143.85798) (xy 56.756808 -143.853408) (xy 56.757062 -143.850614)
			(xy 56.76392 -143.72336) (xy 56.778652 -143.441166) (xy 56.778652 -143.437102) (xy 56.776366 -143.422116)
			(xy 56.774334 -143.415512) (xy 56.77027 -143.409162) (xy 56.759602 -143.392906) (xy 56.633618 -143.200628)
			(xy 56.633364 -143.200374) (xy 56.631586 -143.198342) (xy 56.631332 -143.198088) (xy 56.613552 -143.17599)
			(xy 56.602884 -143.161766) (xy 56.594652 -143.157016) (xy 56.576005 -143.153411) (xy 56.55733 -143.156866)
			(xy 56.549036 -143.161512) (xy 56.522874 -143.177514) (xy 56.508679 -143.151542) (xy 56.486347 -143.096726)
			(xy 56.47125 -143.039494) (xy 56.463638 -142.980795) (xy 56.463184 -142.9512) (xy 56.463735 -142.919224)
			(xy 56.472601 -142.855891) (xy 56.490162 -142.794398) (xy 56.516078 -142.735933) (xy 56.549849 -142.681626)
			(xy 56.590823 -142.632525) (xy 56.638208 -142.589578) (xy 56.69109 -142.553616) (xy 56.748447 -142.525332)
			(xy 56.778652 -142.514828) (xy 56.779414 -142.514574) (xy 56.786231 -142.51194) (xy 56.798098 -142.50342)
			(xy 56.802782 -142.49781) (xy 56.819292 -142.476982) (xy 56.823833 -142.470717) (xy 56.829276 -142.45624)
			(xy 56.82996 -142.448534) (xy 56.83504 -142.35303) (xy 56.83504 -142.343378) (xy 56.831992 -142.333472)
			(xy 56.826658 -142.322296) (xy 56.822086 -142.315184) (xy 56.809132 -142.305278) (xy 56.799734 -142.301976)
			(xy 56.773625 -142.29388) (xy 56.723862 -142.27126) (xy 56.677833 -142.241777) (xy 56.636477 -142.206032)
			(xy 56.600639 -142.164757) (xy 56.571052 -142.118794) (xy 56.54832 -142.069082) (xy 56.532907 -142.016638)
			(xy 56.525128 -141.962531) (xy 56.524652 -141.9352) (xy 56.525197 -141.90613) (xy 56.534011 -141.848661)
			(xy 56.551435 -141.793193) (xy 56.577066 -141.741007) (xy 56.610313 -141.69331) (xy 56.650406 -141.651205)
			(xy 56.696419 -141.615664) (xy 56.747288 -141.587509) (xy 56.801837 -141.567392) (xy 56.830214 -141.561058)
			(xy 56.836818 -141.559534) (xy 56.853074 -141.551406) (xy 56.863765 -141.544781) (xy 56.877471 -141.523729)
			(xy 56.879236 -141.511274) (xy 56.884316 -141.408912) (xy 56.886348 -141.365986) (xy 56.886348 -141.361414)
			(xy 56.885594 -141.351967) (xy 56.878035 -141.334602) (xy 56.871616 -141.327632) (xy 56.864504 -141.32052)
			(xy 56.85155 -141.311376) (xy 56.848248 -141.309598) (xy 56.825195 -141.297236) (xy 56.782402 -141.267152)
			(xy 56.744114 -141.231509) (xy 56.71105 -141.190975) (xy 56.683826 -141.146307) (xy 56.662953 -141.098342)
			(xy 56.648822 -141.047977) (xy 56.641697 -140.996155) (xy 56.641238 -140.97) (xy 56.642762 -140.93698)
			(xy 56.644032 -140.925296) (xy 56.647936 -140.896297) (xy 56.663484 -140.839889) (xy 56.687463 -140.786518)
			(xy 56.719312 -140.737434) (xy 56.758284 -140.69379) (xy 56.803464 -140.65661) (xy 56.853791 -140.626766)
			(xy 56.88076 -140.615416) (xy 56.883808 -140.614146) (xy 56.887872 -140.61186) (xy 56.897524 -140.607034)
			(xy 56.91505 -140.583666) (xy 56.915812 -140.582142) (xy 56.918352 -140.579094) (xy 56.922924 -140.57249)
			(xy 56.924947 -140.568534) (xy 56.927757 -140.560105) (xy 56.928512 -140.555726) (xy 56.939942 -140.340842)
			(xy 56.950864 -140.126212) (xy 56.95061 -140.120878) (xy 56.949848 -140.117068) (xy 56.949594 -140.116052)
			(xy 56.949086 -140.114528) (xy 56.948832 -140.113258) (xy 56.948578 -140.113004) (xy 56.947816 -140.11021)
			(xy 56.946348 -140.106242) (xy 56.94226 -140.098837) (xy 56.939688 -140.095478) (xy 56.93283 -140.087604)
			(xy 56.924702 -140.078206) (xy 56.920638 -140.074142) (xy 56.910986 -140.067284) (xy 56.899302 -140.060934)
			(xy 56.89854 -140.060426) (xy 56.887872 -140.054584) (xy 56.879236 -140.05306) (xy 56.850932 -140.04783)
			(xy 56.796052 -140.030476) (xy 56.744143 -140.005608) (xy 56.696228 -139.973715) (xy 56.653251 -139.935427)
			(xy 56.616061 -139.891497) (xy 56.585388 -139.842792) (xy 56.561839 -139.790271) (xy 56.545876 -139.734971)
			(xy 56.537816 -139.677979) (xy 56.537352 -139.6492) (xy 56.537772 -139.622408) (xy 56.544768 -139.569284)
			(xy 56.558641 -139.517528) (xy 56.579152 -139.468026) (xy 56.605952 -139.421626) (xy 56.63858 -139.379123)
			(xy 56.65724 -139.359894) (xy 56.664602 -139.351693) (xy 56.672219 -139.331035) (xy 56.671972 -139.320016)
			(xy 56.669432 -139.285726) (xy 56.66867 -139.275566) (xy 56.659018 -139.256262) (xy 56.65089 -139.249404)
			(xy 56.629934 -139.231178) (xy 56.593003 -139.1897) (xy 56.562477 -139.143305) (xy 56.539001 -139.092973)
			(xy 56.523072 -139.03977) (xy 56.515025 -138.984819) (xy 56.514492 -138.95705) (xy 56.514952 -138.929795)
			(xy 56.522703 -138.875838) (xy 56.538055 -138.823535) (xy 56.560694 -138.773948) (xy 56.590161 -138.728089)
			(xy 56.625855 -138.68689) (xy 56.667049 -138.651191) (xy 56.712904 -138.621718) (xy 56.762488 -138.599072)
			(xy 56.81479 -138.583714) (xy 56.868745 -138.575955) (xy 56.896 -138.575542) (xy 56.898794 -138.575542)
			(xy 56.928258 -138.576558) (xy 56.935116 -138.577066) (xy 56.936386 -138.577066) (xy 56.938418 -138.57732)
			(xy 56.947816 -138.574272) (xy 56.952299 -138.572608) (xy 56.96061 -138.567882) (xy 56.964326 -138.564874)
			(xy 56.986932 -138.545316) (xy 56.990742 -138.542268) (xy 57.020206 -138.515852) (xy 57.023857 -138.512467)
			(xy 57.029868 -138.504532) (xy 57.032144 -138.500104) (xy 57.036462 -138.490706) (xy 57.050432 -138.220196)
			(xy 57.077102 -137.704576) (xy 57.077102 -137.700258) (xy 57.075832 -137.690352) (xy 57.073348 -137.681746)
			(xy 57.063333 -137.666909) (xy 57.056274 -137.661396) (xy 57.047384 -137.656062) (xy 57.045352 -137.655046)
			(xy 57.043066 -137.654284) (xy 57.016913 -137.646182) (xy 56.967066 -137.62354) (xy 56.920955 -137.594022)
			(xy 56.879524 -137.558232) (xy 56.843618 -137.516901) (xy 56.813972 -137.470873) (xy 56.79119 -137.421088)
			(xy 56.775739 -137.368565) (xy 56.767934 -137.314375) (xy 56.767476 -137.287) (xy 56.768002 -137.258484)
			(xy 56.776468 -137.202084) (xy 56.793211 -137.147565) (xy 56.817861 -137.096135) (xy 56.849873 -137.048934)
			(xy 56.888535 -137.007007) (xy 56.932993 -136.971284) (xy 56.982261 -136.942555) (xy 57.035248 -136.921458)
			(xy 57.062878 -136.914382) (xy 57.064656 -136.913874) (xy 57.069736 -136.91235) (xy 57.08142 -136.907778)
			(xy 57.085738 -136.905238) (xy 57.104026 -136.88441) (xy 57.105042 -136.88314) (xy 57.106312 -136.88187)
			(xy 57.11317 -136.875012) (xy 57.117234 -136.866122) (xy 57.118768 -136.862469) (xy 57.12081 -136.854814)
			(xy 57.121298 -136.850882) (xy 57.18048 -135.720582) (xy 57.215786 -135.035036) (xy 57.215111 -135.027741)
			(xy 57.210215 -135.013941) (xy 57.206134 -135.007858) (xy 57.201695 -135.002099) (xy 57.190216 -134.993184)
			(xy 57.183528 -134.990332) (xy 57.17794 -134.988808) (xy 57.151339 -134.981163) (xy 57.100513 -134.959254)
			(xy 57.053385 -134.930233) (xy 57.010943 -134.894709) (xy 56.974078 -134.853427) (xy 56.943563 -134.807252)
			(xy 56.920038 -134.757153) (xy 56.903997 -134.704182) (xy 56.895776 -134.649449) (xy 56.895238 -134.621778)
			(xy 56.895238 -134.62) (xy 56.895707 -134.592973) (xy 56.903329 -134.53946) (xy 56.918422 -134.487556)
			(xy 56.940684 -134.438299) (xy 56.969669 -134.392674) (xy 57.004798 -134.351592) (xy 57.04537 -134.315874)
			(xy 57.090573 -134.286235) (xy 57.139504 -134.263267) (xy 57.191185 -134.247428) (xy 57.217818 -134.24281)
			(xy 57.218072 -134.24281) (xy 57.236106 -134.232396) (xy 57.239948 -134.229918) (xy 57.24672 -134.22378)
			(xy 57.249568 -134.220204) (xy 57.253584 -134.214545) (xy 57.258749 -134.201672) (xy 57.259728 -134.194804)
			(xy 59.15533 -97.775014) (xy 59.471306 -91.705176) (xy 59.471306 -91.701874) (xy 59.470654 -91.691464)
			(xy 59.462148 -91.67244) (xy 59.454796 -91.665044) (xy 59.391296 -91.613736) (xy 59.384438 -91.608148)
			(xy 59.376564 -91.605354) (xy 59.372385 -91.603944) (xy 59.363701 -91.602409) (xy 59.359292 -91.602306)
			(xy 59.344814 -91.602306) (xy 59.338718 -91.60383) (xy 59.31646 -91.60893) (xy 59.271126 -91.614401)
			(xy 59.248294 -91.614752) (xy 59.247532 -91.614752) (xy 59.220274 -91.614291) (xy 59.166314 -91.606537)
			(xy 59.114006 -91.591182) (xy 59.064416 -91.568539) (xy 59.018554 -91.539068) (xy 58.977352 -91.50337)
			(xy 58.941651 -91.462172) (xy 58.912177 -91.416312) (xy 58.889529 -91.366724) (xy 58.87417 -91.314417)
			(xy 58.866411 -91.260457) (xy 58.866411 -91.205943) (xy 58.87417 -91.151983) (xy 58.889529 -91.099676)
			(xy 58.912177 -91.050088) (xy 58.941651 -91.004228) (xy 58.977352 -90.96303) (xy 59.018554 -90.927332)
			(xy 59.064416 -90.897861) (xy 59.114006 -90.875218) (xy 59.166314 -90.859863) (xy 59.220274 -90.852109)
			(xy 59.247532 -90.851736) (xy 59.282022 -90.852481) (xy 59.349878 -90.864883) (xy 59.382406 -90.876374)
			(xy 59.38266 -90.876374) (xy 59.388224 -90.878311) (xy 59.399899 -90.879859) (xy 59.405774 -90.879422)
			(xy 59.417712 -90.878152) (xy 59.468766 -90.844624) (xy 59.471921 -90.842672) (xy 59.47868 -90.839612)
			(xy 59.482228 -90.838528) (xy 59.491951 -90.835261) (xy 59.507873 -90.822358) (xy 59.517466 -90.804248)
			(xy 59.518804 -90.794078) (xy 59.522106 -90.732356) (xy 59.523376 -90.707972) (xy 59.539886 -90.389456)
			(xy 59.630564 -88.648032) (xy 59.704224 -87.232236) (xy 59.701684 -87.22106) (xy 59.695334 -87.207852)
			(xy 59.691016 -87.201502) (xy 59.690508 -87.20074) (xy 59.69 -87.200232) (xy 59.69 -87.199978) (xy 59.686952 -87.19566)
			(xy 59.682888 -87.188548) (xy 59.670188 -87.166385) (xy 59.650176 -87.119387) (xy 59.63661 -87.07014)
			(xy 59.629733 -87.019524) (xy 59.629294 -86.993984) (xy 59.629548 -86.983824) (xy 59.630605 -86.95809)
			(xy 59.638787 -86.90724) (xy 59.653737 -86.857953) (xy 59.675182 -86.811126) (xy 59.702734 -86.76761)
			(xy 59.718956 -86.747604) (xy 59.71921 -86.74735) (xy 59.723782 -86.741762) (xy 59.727084 -86.734396)
			(xy 59.727846 -86.732872) (xy 59.731148 -86.719156) (xy 59.736736 -86.608158) (xy 59.741054 -86.5251)
			(xy 59.741054 -86.524592) (xy 59.742324 -86.49843) (xy 59.74207 -86.493096) (xy 59.7408 -86.484714)
			(xy 59.730132 -86.463378) (xy 59.726068 -86.458806) (xy 59.708731 -86.437932) (xy 59.679512 -86.392208)
			(xy 59.65706 -86.342809) (xy 59.641827 -86.290729) (xy 59.63412 -86.237017) (xy 59.633612 -86.209886)
			(xy 59.633612 -86.209378) (xy 59.634065 -86.183132) (xy 59.641297 -86.131138) (xy 59.655592 -86.080629)
			(xy 59.676681 -86.032558) (xy 59.704165 -85.987835) (xy 59.737525 -85.947304) (xy 59.756548 -85.929216)
			(xy 59.759088 -85.926676) (xy 59.764838 -85.920484) (xy 59.772237 -85.905303) (xy 59.773566 -85.896958)
			(xy 59.774328 -85.88756) (xy 59.775598 -85.860128) (xy 59.775598 -85.85962) (xy 59.776106 -85.848952)
			(xy 59.772296 -85.8393) (xy 59.770272 -85.83437) (xy 59.764509 -85.825409) (xy 59.760866 -85.82152)
			(xy 59.745372 -85.806026) (xy 59.734704 -85.80247) (xy 59.732418 -85.800946) (xy 59.730386 -85.799676)
			(xy 59.722258 -85.792818) (xy 59.72048 -85.79104) (xy 59.716924 -85.78723) (xy 59.704986 -85.77453)
			(xy 59.696604 -85.770974) (xy 59.685428 -85.766656) (xy 59.676284 -85.766402) (xy 59.64864 -85.765176)
			(xy 59.594117 -85.755737) (xy 59.541529 -85.738522) (xy 59.491979 -85.713893) (xy 59.446505 -85.682367)
			(xy 59.40606 -85.644603) (xy 59.371494 -85.601395) (xy 59.343529 -85.553647) (xy 59.322754 -85.502362)
			(xy 59.309602 -85.448614) (xy 59.304351 -85.39353) (xy 59.30711 -85.338265) (xy 59.317821 -85.283978)
			(xy 59.336259 -85.231807) (xy 59.362039 -85.182845) (xy 59.39462 -85.13812) (xy 59.433318 -85.098569)
			(xy 59.477322 -85.065021) (xy 59.52571 -85.03818) (xy 59.577467 -85.018608) (xy 59.604402 -85.012276)
			(xy 59.623594 -85.008304) (xy 59.662533 -85.003846) (xy 59.682126 -85.003386) (xy 59.689238 -85.003386)
			(xy 59.712606 -85.004402) (xy 59.720734 -85.004402) (xy 59.729361 -85.004025) (xy 59.745598 -84.998182)
			(xy 59.752484 -84.992972) (xy 59.757056 -84.989162) (xy 59.758326 -84.987892) (xy 59.80811 -84.94395)
			(xy 59.815395 -84.936926) (xy 59.824188 -84.918718) (xy 59.825128 -84.908644) (xy 60.760356 -66.940938)
			(xy 60.888118 -64.487298) (xy 60.888118 -64.48425) (xy 60.882276 -62.87389) (xy 60.880752 -62.42177)
			(xy 60.8798 -62.412103) (xy 60.871619 -62.394502) (xy 60.857478 -62.381208) (xy 60.839406 -62.37413)
			(xy 60.829698 -62.373764) (xy 60.816236 -62.373764) (xy 60.804552 -62.380622) (xy 60.804044 -62.380622)
			(xy 60.788296 -62.389512) (xy 60.781438 -62.392814) (xy 60.763397 -62.401581) (xy 60.725853 -62.415705)
			(xy 60.706508 -62.421008) (xy 60.702444 -62.422024) (xy 60.680622 -62.427036) (xy 60.636184 -62.432517)
			(xy 60.613798 -62.432946) (xy 60.60821 -62.432946) (xy 60.587979 -62.432611) (xy 60.54776 -62.428156)
			(xy 60.527946 -62.424056) (xy 60.526422 -62.423802) (xy 60.522358 -62.422786) (xy 60.522104 -62.422786)
			(xy 60.517024 -62.421516) (xy 60.508896 -62.4205) (xy 60.498682 -62.420151) (xy 60.479302 -62.426582)
			(xy 60.471304 -62.432946) (xy 60.466224 -62.438026) (xy 60.410344 -62.50305) (xy 60.405234 -62.509975)
			(xy 60.399529 -62.526201) (xy 60.399168 -62.5348) (xy 60.399168 -62.54877) (xy 60.401962 -62.563502)
			(xy 60.404248 -62.57163) (xy 60.40501 -62.573662) (xy 60.415808 -62.604965) (xy 60.427691 -62.670102)
			(xy 60.428632 -62.703202) (xy 60.428632 -62.708282) (xy 60.427991 -62.735427) (xy 60.419972 -62.789129)
			(xy 60.404421 -62.841152) (xy 60.381651 -62.890445) (xy 60.352123 -62.936011) (xy 60.316433 -62.976932)
			(xy 60.275302 -63.012379) (xy 60.229562 -63.041636) (xy 60.180135 -63.064114) (xy 60.128021 -63.079358)
			(xy 60.074273 -63.087059) (xy 60.047124 -63.087504) (xy 60.01987 -63.087042) (xy 59.965917 -63.079288)
			(xy 59.913617 -63.063934) (xy 59.864035 -63.041294) (xy 59.818179 -63.011826) (xy 59.776984 -62.976133)
			(xy 59.741288 -62.93494) (xy 59.711818 -62.889087) (xy 59.689174 -62.839505) (xy 59.673817 -62.787206)
			(xy 59.666059 -62.733254) (xy 59.666059 -62.678746) (xy 59.673817 -62.624794) (xy 59.689174 -62.572495)
			(xy 59.711818 -62.522913) (xy 59.741288 -62.47706) (xy 59.776984 -62.435867) (xy 59.818179 -62.400174)
			(xy 59.864035 -62.370706) (xy 59.913617 -62.348066) (xy 59.965917 -62.332712) (xy 60.01987 -62.324958)
			(xy 60.047124 -62.324488) (xy 60.04814 -62.324488) (xy 60.070773 -62.324822) (xy 60.115723 -62.330166)
			(xy 60.137802 -62.335156) (xy 60.141866 -62.336172) (xy 60.148978 -62.336934) (xy 60.16031 -62.337279)
			(xy 60.181527 -62.329368) (xy 60.189872 -62.321694) (xy 60.191396 -62.319916) (xy 60.19165 -62.319662)
			(xy 60.212224 -62.295786) (xy 60.252102 -62.249558) (xy 60.256233 -62.243875) (xy 60.261501 -62.230857)
			(xy 60.262516 -62.223904) (xy 60.26277 -62.222126) (xy 60.26404 -62.21095) (xy 60.26023 -62.201552)
			(xy 60.253909 -62.186343) (xy 60.243606 -62.155058) (xy 60.239656 -62.139068) (xy 60.235958 -62.122642)
			(xy 60.231125 -62.089319) (xy 60.230004 -62.07252) (xy 60.229496 -62.055756) (xy 60.229496 -62.050168)
			(xy 60.230055 -62.023207) (xy 60.237833 -61.969845) (xy 60.253046 -61.91811) (xy 60.27539 -61.869032)
			(xy 60.304422 -61.823588) (xy 60.339561 -61.782683) (xy 60.38011 -61.747133) (xy 60.425259 -61.717646)
			(xy 60.47411 -61.694808) (xy 60.525689 -61.679075) (xy 60.57897 -61.670759) (xy 60.605924 -61.66993)
			(xy 60.61202 -61.66993) (xy 60.612528 -61.66993) (xy 60.644525 -61.670671) (xy 60.707596 -61.681532)
			(xy 60.738004 -61.69152) (xy 60.741306 -61.69279) (xy 60.757054 -61.695838) (xy 60.760864 -61.695838)
			(xy 60.764928 -61.695584) (xy 60.771061 -61.694634) (xy 60.782626 -61.69014) (xy 60.787788 -61.686694)
			(xy 60.788042 -61.686694) (xy 60.842906 -61.648086) (xy 60.857638 -61.637672) (xy 60.864242 -61.631576)
			(xy 60.86729 -61.62802) (xy 60.871831 -61.62163) (xy 60.877123 -61.606883) (xy 60.877704 -61.599064)
			(xy 60.87745 -61.548518) (xy 60.875672 -60.998608) (xy 60.875672 -60.979558) (xy 60.875672 -60.978542)
			(xy 60.877704 -60.845954) (xy 60.872878 -60.83808) (xy 60.85751 -60.812858) (xy 60.8339 -60.758723)
			(xy 60.818915 -60.701597) (xy 60.812913 -60.642843) (xy 60.816036 -60.583866) (xy 60.82821 -60.526075)
			(xy 60.849144 -60.470851) (xy 60.863226 -60.444888) (xy 60.877196 -60.422028) (xy 60.880498 -60.416948)
			(xy 60.88253 -60.410344) (xy 60.884562 -60.396374) (xy 60.91047 -58.728356) (xy 60.910484 -58.723966)
			(xy 60.909215 -58.715281) (xy 60.90793 -58.711084) (xy 60.904882 -58.702448) (xy 60.898024 -58.694574)
			(xy 60.881425 -58.674019) (xy 60.853452 -58.6292) (xy 60.831922 -58.580954) (xy 60.817247 -58.530201)
			(xy 60.809707 -58.47791) (xy 60.809124 -58.451496) (xy 60.809378 -58.441336) (xy 60.810376 -58.415081)
			(xy 60.818689 -58.363203) (xy 60.834035 -58.312955) (xy 60.844684 -58.288936) (xy 60.850526 -58.276998)
			(xy 60.86295 -58.253363) (xy 60.89342 -58.209515) (xy 60.911232 -58.189622) (xy 60.91174 -58.189114)
			(xy 60.912756 -58.188098) (xy 60.919614 -58.170826) (xy 60.96127 -55.495444) (xy 60.96127 -55.492904)
			(xy 60.91301 -54.262274) (xy 60.745624 -49.986946) (xy 60.744909 -49.977953) (xy 60.738021 -49.961293)
			(xy 60.732162 -49.954434) (xy 60.725304 -49.947576) (xy 60.650374 -49.906936) (xy 60.645802 -49.904904)
			(xy 60.641484 -49.902618) (xy 60.637325 -49.900713) (xy 60.628506 -49.898285) (xy 60.623958 -49.897792)
			(xy 60.61456 -49.89703) (xy 60.593224 -49.903126) (xy 60.587382 -49.906428) (xy 60.565788 -49.918255)
			(xy 60.520206 -49.936866) (xy 60.472608 -49.949456) (xy 60.423785 -49.955815) (xy 60.399168 -49.956212)
			(xy 60.395358 -49.956212) (xy 60.357004 -49.953926) (xy 60.33053 -49.950553) (xy 60.278817 -49.937357)
			(xy 60.229449 -49.917083) (xy 60.183387 -49.890127) (xy 60.162186 -49.873916) (xy 60.15736 -49.870106)
			(xy 60.151772 -49.867566) (xy 60.146438 -49.864772) (xy 60.135262 -49.862232) (xy 60.108084 -49.862232)
			(xy 60.102644 -49.86209) (xy 60.092013 -49.859783) (xy 60.087002 -49.85766) (xy 60.07354 -49.851564)
			(xy 60.064877 -49.847938) (xy 60.046152 -49.846696) (xy 60.028246 -49.852316) (xy 60.020708 -49.857914)
			(xy 60.013596 -49.863502) (xy 60.009024 -49.867058) (xy 60.008262 -49.867566) (xy 59.987621 -49.884209)
			(xy 59.94261 -49.912232) (xy 59.894152 -49.933753) (xy 59.843181 -49.948357) (xy 59.790678 -49.955763)
			(xy 59.764168 -49.956212) (xy 59.754262 -49.956212) (xy 59.725542 -49.954968) (xy 59.668945 -49.944908)
			(xy 59.614503 -49.926456) (xy 59.563452 -49.900031) (xy 59.539886 -49.883568) (xy 59.53125 -49.877472)
			(xy 59.52617 -49.873154) (xy 59.518804 -49.868582) (xy 59.516772 -49.867566) (xy 59.511447 -49.865101)
			(xy 59.500031 -49.862402) (xy 59.494166 -49.862232) (xy 59.473084 -49.862232) (xy 59.467644 -49.86209)
			(xy 59.457013 -49.859783) (xy 59.452002 -49.85766) (xy 59.43854 -49.851564) (xy 59.429877 -49.847938)
			(xy 59.411152 -49.846696) (xy 59.393246 -49.852316) (xy 59.385708 -49.857914) (xy 59.378596 -49.863502)
			(xy 59.374024 -49.867058) (xy 59.373262 -49.867566) (xy 59.352621 -49.884209) (xy 59.30761 -49.912232)
			(xy 59.259152 -49.933753) (xy 59.208181 -49.948357) (xy 59.155678 -49.955763) (xy 59.129168 -49.956212)
			(xy 59.119262 -49.956212) (xy 59.090542 -49.954968) (xy 59.033945 -49.944908) (xy 58.979503 -49.926456)
			(xy 58.928452 -49.900031) (xy 58.904886 -49.883568) (xy 58.89625 -49.877472) (xy 58.89117 -49.873154)
			(xy 58.883804 -49.868582) (xy 58.881772 -49.867566) (xy 58.876447 -49.865101) (xy 58.865031 -49.862402)
			(xy 58.859166 -49.862232) (xy 58.838084 -49.862232) (xy 58.832644 -49.86209) (xy 58.822013 -49.859783)
			(xy 58.817002 -49.85766) (xy 58.80354 -49.851564) (xy 58.794877 -49.847938) (xy 58.776152 -49.846696)
			(xy 58.758246 -49.852316) (xy 58.750708 -49.857914) (xy 58.743596 -49.863502) (xy 58.739024 -49.867058)
			(xy 58.738262 -49.867566) (xy 58.717621 -49.884209) (xy 58.67261 -49.912232) (xy 58.624152 -49.933753)
			(xy 58.573181 -49.948357) (xy 58.520678 -49.955763) (xy 58.494168 -49.956212) (xy 58.493914 -49.956212)
			(xy 58.46666 -49.95575) (xy 58.412707 -49.947994) (xy 58.360407 -49.932639) (xy 58.310825 -49.909997)
			(xy 58.264969 -49.880529) (xy 58.223775 -49.844835) (xy 58.188079 -49.803642) (xy 58.158609 -49.757788)
			(xy 58.135966 -49.708206) (xy 58.120609 -49.655906) (xy 58.112851 -49.601954) (xy 58.112851 -49.547446)
			(xy 58.120609 -49.493494) (xy 58.135966 -49.441194) (xy 58.158609 -49.391612) (xy 58.188079 -49.345758)
			(xy 58.223775 -49.304565) (xy 58.264969 -49.268871) (xy 58.310825 -49.239403) (xy 58.360407 -49.216761)
			(xy 58.412707 -49.201406) (xy 58.46666 -49.19365) (xy 58.493914 -49.193196) (xy 58.494168 -49.193196)
			(xy 58.519786 -49.193603) (xy 58.570562 -49.200452) (xy 58.619963 -49.214044) (xy 58.667096 -49.234134)
			(xy 58.711111 -49.260359) (xy 58.731404 -49.276) (xy 58.73623 -49.27981) (xy 58.743596 -49.283112)
			(xy 58.748335 -49.284982) (xy 58.758315 -49.287028) (xy 58.763408 -49.287176) (xy 58.784744 -49.287176)
			(xy 58.790183 -49.28732) (xy 58.800814 -49.289629) (xy 58.805826 -49.291748) (xy 58.819288 -49.297844)
			(xy 58.82795 -49.301464) (xy 58.846671 -49.302697) (xy 58.864568 -49.297071) (xy 58.87212 -49.291494)
			(xy 58.879232 -49.285906) (xy 58.883804 -49.28235) (xy 58.884566 -49.281842) (xy 58.905207 -49.2652)
			(xy 58.950219 -49.23718) (xy 58.998677 -49.215662) (xy 59.049648 -49.201061) (xy 59.10215 -49.193659)
			(xy 59.12866 -49.193196) (xy 59.138566 -49.193196) (xy 59.169354 -49.194565) (xy 59.22991 -49.205998)
			(xy 59.287843 -49.227008) (xy 59.341651 -49.25705) (xy 59.36615 -49.275746) (xy 59.37123 -49.27981)
			(xy 59.379104 -49.283366) (xy 59.383732 -49.285139) (xy 59.393453 -49.287057) (xy 59.398408 -49.287176)
			(xy 59.419744 -49.287176) (xy 59.425183 -49.28732) (xy 59.435814 -49.289629) (xy 59.440826 -49.291748)
			(xy 59.454288 -49.297844) (xy 59.46295 -49.301464) (xy 59.481671 -49.302697) (xy 59.499568 -49.297071)
			(xy 59.50712 -49.291494) (xy 59.514232 -49.285906) (xy 59.518804 -49.28235) (xy 59.519566 -49.281842)
			(xy 59.540207 -49.2652) (xy 59.585219 -49.23718) (xy 59.633677 -49.215662) (xy 59.684648 -49.201061)
			(xy 59.73715 -49.193659) (xy 59.76366 -49.193196) (xy 59.773566 -49.193196) (xy 59.804354 -49.194565)
			(xy 59.86491 -49.205998) (xy 59.922843 -49.227008) (xy 59.976651 -49.25705) (xy 60.00115 -49.275746)
			(xy 60.00623 -49.27981) (xy 60.014104 -49.283366) (xy 60.018732 -49.285139) (xy 60.028453 -49.287057)
			(xy 60.033408 -49.287176) (xy 60.054744 -49.287176) (xy 60.059356 -49.287279) (xy 60.068428 -49.288944)
			(xy 60.072778 -49.290478) (xy 60.07354 -49.290732) (xy 60.074556 -49.29124) (xy 60.075826 -49.291748)
			(xy 60.07608 -49.291748) (xy 60.089542 -49.297844) (xy 60.099217 -49.301375) (xy 60.119794 -49.301251)
			(xy 60.12942 -49.29759) (xy 60.14212 -49.290986) (xy 60.144152 -49.28997) (xy 60.147708 -49.287176)
			(xy 60.149994 -49.285398) (xy 60.150756 -49.284636) (xy 60.171617 -49.267462) (xy 60.217257 -49.238539)
			(xy 60.266512 -49.216324) (xy 60.318403 -49.201261) (xy 60.371897 -49.193647) (xy 60.398914 -49.193196)
			(xy 60.404756 -49.193196) (xy 60.431985 -49.194057) (xy 60.485787 -49.202601) (xy 60.511944 -49.210214)
			(xy 60.527946 -49.215548) (xy 60.550552 -49.224438) (xy 60.554108 -49.226216) (xy 60.555632 -49.226724)
			(xy 60.557664 -49.22774) (xy 60.560966 -49.229264) (xy 60.566046 -49.23155) (xy 60.581032 -49.234852)
			(xy 60.588652 -49.23536) (xy 60.600844 -49.234852) (xy 60.6171 -49.228756) (xy 60.621926 -49.225454)
			(xy 60.68949 -49.18075) (xy 60.699356 -49.173376) (xy 60.711291 -49.151875) (xy 60.71235 -49.139602)
			(xy 60.698634 -48.786542) (xy 60.622688 -46.85284) (xy 60.622434 -46.848014) (xy 59.686444 -39.919656)
			(xy 59.682682 -39.890264) (xy 59.678234 -39.83117) (xy 59.677554 -39.801546) (xy 59.67222 -39.470076)
			(xy 59.66968 -39.4589) (xy 59.66714 -39.454074) (xy 59.647894 -39.414111) (xy 59.615754 -39.331432)
			(xy 59.591087 -39.246224) (xy 59.574091 -39.159162) (xy 59.564898 -39.070933) (xy 59.563762 -39.026592)
			(xy 59.557158 -38.60165) (xy 59.557158 -38.601396) (xy 59.555888 -38.55212) (xy 59.555888 -38.551358)
			(xy 59.556142 -38.530784) (xy 59.556142 -38.528244) (xy 59.555888 -38.516052) (xy 59.555888 -38.515544)
			(xy 59.556042 -38.491757) (xy 59.558326 -38.444239) (xy 59.56046 -38.420548) (xy 59.564268 -38.384897)
			(xy 59.576348 -38.314217) (xy 59.58459 -38.279324) (xy 59.58459 -38.27907) (xy 59.586876 -38.26891)
			(xy 59.571128 -38.172136) (xy 59.565286 -38.13048) (xy 59.562038 -38.101252) (xy 59.558604 -38.042539)
			(xy 59.558428 -38.013132) (xy 59.558428 -37.991542) (xy 59.558428 -37.99078) (xy 59.558682 -37.981636)
			(xy 59.55792 -37.97681) (xy 59.552451 -37.941044) (xy 59.546093 -37.868963) (xy 59.54522 -37.832792)
			(xy 59.5376 -37.338254) (xy 59.5376 -37.321998) (xy 59.5376 -37.32149) (xy 59.538118 -37.275693)
			(xy 59.546513 -37.184484) (xy 59.563231 -37.094429) (xy 59.575192 -37.050218) (xy 59.576208 -37.046916)
			(xy 59.576208 -37.046662) (xy 59.577986 -37.040312) (xy 59.578748 -37.010594) (xy 59.578748 -37.010086)
			(xy 59.57951 -36.971478) (xy 59.579523 -36.967616) (xy 59.578506 -36.95996) (xy 59.577478 -36.956238)
			(xy 59.575954 -36.952428) (xy 59.575954 -36.952174) (xy 59.575192 -36.950142) (xy 59.572144 -36.943284)
			(xy 59.57189 -36.94303) (xy 59.57062 -36.939728) (xy 59.567572 -36.932108) (xy 59.54649 -36.908232)
			(xy 59.538362 -36.902644) (xy 59.51855 -36.892738) (xy 59.513224 -36.890276) (xy 59.501808 -36.887583)
			(xy 59.495944 -36.887404) (xy 59.4868 -36.887404) (xy 59.477402 -36.88842) (xy 59.473846 -36.889182)
			(xy 59.471052 -36.88969) (xy 59.469274 -36.890198) (xy 59.451352 -36.893434) (xy 59.415094 -36.896868)
			(xy 59.396884 -36.897056) (xy 59.395614 -36.897056) (xy 59.368384 -36.896537) (xy 59.314487 -36.888725)
			(xy 59.262247 -36.873328) (xy 59.212728 -36.85066) (xy 59.166935 -36.821181) (xy 59.125799 -36.785491)
			(xy 59.090156 -36.744314) (xy 59.06073 -36.698487) (xy 59.038118 -36.648942) (xy 59.022782 -36.596685)
			(xy 59.015031 -36.542778) (xy 59.014614 -36.515548) (xy 59.015096 -36.488307) (xy 59.022841 -36.434377)
			(xy 59.038179 -36.382098) (xy 59.060799 -36.332533) (xy 59.090241 -36.286691) (xy 59.125905 -36.245503)
			(xy 59.167066 -36.209809) (xy 59.212887 -36.180334) (xy 59.262436 -36.157677) (xy 59.314703 -36.1423)
			(xy 59.368627 -36.134516) (xy 59.395868 -36.13404) (xy 59.396122 -36.13404) (xy 59.41568 -36.134548)
			(xy 59.417458 -36.134548) (xy 59.436762 -36.127436) (xy 59.444128 -36.120578) (xy 59.446414 -36.118546)
			(xy 59.446922 -36.118038) (xy 59.495436 -36.074604) (xy 59.501584 -36.06867) (xy 59.509883 -36.053745)
			(xy 59.511692 -36.045394) (xy 59.511946 -36.04133) (xy 59.516518 -36.000436) (xy 59.516518 -35.999928)
			(xy 59.520836 -35.969448) (xy 59.520836 -35.969194) (xy 59.521344 -35.966146) (xy 59.522106 -35.961828)
			(xy 59.52489 -35.945864) (xy 59.531367 -35.914107) (xy 59.53506 -35.898328) (xy 59.546007 -35.85477)
			(xy 59.574751 -35.769674) (xy 59.592464 -35.728402) (xy 59.59475 -35.723322) (xy 59.597036 -35.712908)
			(xy 59.598814 -35.6997) (xy 59.597036 -35.687508) (xy 59.577986 -35.616134) (xy 59.575954 -35.60826)
			(xy 59.572398 -35.595306) (xy 59.572398 -35.594798) (xy 59.56173 -35.556444) (xy 59.558936 -35.546284)
			(xy 59.5503 -35.535616) (xy 59.54014 -35.526726) (xy 59.520836 -35.514788) (xy 59.520074 -35.514534)
			(xy 59.49188 -35.49777) (xy 59.486004 -35.494623) (xy 59.473141 -35.491143) (xy 59.46648 -35.490912)
			(xy 59.455304 -35.490912) (xy 59.44235 -35.49269) (xy 59.404356 -35.501351) (xy 59.327366 -35.513439)
			(xy 59.249669 -35.519495) (xy 59.210702 -35.519868) (xy 59.206384 -35.519868) (xy 59.159711 -35.519126)
			(xy 59.066807 -35.510006) (xy 58.975163 -35.49224) (xy 58.885581 -35.465985) (xy 58.798846 -35.431469)
			(xy 58.715717 -35.388996) (xy 58.676032 -35.36442) (xy 58.674 -35.364928) (xy 58.669936 -35.36569)
			(xy 58.652937 -35.368564) (xy 58.618595 -35.371615) (xy 58.601356 -35.371786) (xy 58.600848 -35.371786)
			(xy 58.57377 -35.371309) (xy 58.520159 -35.363645) (xy 58.468171 -35.348478) (xy 58.418849 -35.326113)
			(xy 58.373184 -35.296999) (xy 58.332095 -35.261721) (xy 58.296406 -35.220989) (xy 58.266834 -35.175619)
			(xy 58.243974 -35.126524) (xy 58.228286 -35.074691) (xy 58.220083 -35.02116) (xy 58.21934 -34.994088)
			(xy 58.21934 -34.990024) (xy 58.219849 -34.96277) (xy 58.227639 -34.908821) (xy 58.243008 -34.856523)
			(xy 58.253884 -34.831528) (xy 58.25617 -34.826448) (xy 58.257948 -34.818066) (xy 58.243749 -34.770172)
			(xy 58.22387 -34.672268) (xy 58.213869 -34.572869) (xy 58.213244 -34.522918) (xy 58.213244 -34.52241)
			(xy 58.213678 -34.479823) (xy 58.220917 -34.394958) (xy 58.235368 -34.31102) (xy 58.256927 -34.22862)
			(xy 58.285435 -34.14836) (xy 58.302652 -34.109406) (xy 58.305836 -34.100273) (xy 58.305839 -34.080946)
			(xy 58.302652 -34.071814) (xy 58.285443 -34.032858) (xy 58.256948 -33.952594) (xy 58.235395 -33.870195)
			(xy 58.220942 -33.786258) (xy 58.213692 -33.701396) (xy 58.213244 -33.65881) (xy 58.213244 -33.657794)
			(xy 58.213872 -33.607927) (xy 58.223879 -33.508696) (xy 58.243752 -33.410962) (xy 58.257948 -33.363154)
			(xy 58.256932 -33.358582) (xy 58.253376 -33.348168) (xy 58.25236 -33.345882) (xy 58.242156 -33.321857)
			(xy 58.227619 -33.271726) (xy 58.220036 -33.220083) (xy 58.21934 -33.19399) (xy 58.21934 -33.188656)
			(xy 58.219923 -33.161579) (xy 58.227798 -33.107997) (xy 58.24317 -33.056066) (xy 58.26573 -33.006831)
			(xy 58.295026 -32.961281) (xy 58.330468 -32.920331) (xy 58.371345 -32.884803) (xy 58.416834 -32.855413)
			(xy 58.466022 -32.83275) (xy 58.51792 -32.81727) (xy 58.571486 -32.809283) (xy 58.598562 -32.808672)
			(xy 58.601356 -32.808672) (xy 58.618596 -32.808829) (xy 58.652939 -32.811883) (xy 58.669936 -32.814768)
			(xy 58.676794 -32.816038) (xy 58.716134 -32.791744) (xy 58.798499 -32.749718) (xy 58.884401 -32.715497)
			(xy 58.973103 -32.689375) (xy 59.063841 -32.671578) (xy 59.155838 -32.662258) (xy 59.202066 -32.661352)
			(xy 59.214258 -32.661352) (xy 59.260875 -32.662083) (xy 59.353671 -32.671165) (xy 59.445214 -32.688869)
			(xy 59.534704 -32.715043) (xy 59.62136 -32.749455) (xy 59.704426 -32.791808) (xy 59.744102 -32.816292)
			(xy 59.745118 -32.816038) (xy 59.750452 -32.815022) (xy 59.753246 -32.814514) (xy 59.765946 -32.812482)
			(xy 59.766454 -32.812482) (xy 59.780596 -32.810528) (xy 59.809074 -32.808492) (xy 59.82335 -32.808418)
			(xy 59.825128 -32.808418) (xy 59.842146 -32.808926) (xy 59.865649 -32.810593) (xy 59.912011 -32.818999)
			(xy 59.934602 -32.82569) (xy 59.936634 -32.826198) (xy 59.939174 -32.827214) (xy 59.942984 -32.828484)
			(xy 59.951112 -32.829754) (xy 59.960942 -32.830832) (xy 59.980157 -32.826251) (xy 59.98845 -32.820864)
			(xy 60.034424 -32.788098) (xy 60.059062 -32.770572) (xy 60.06211 -32.76727) (xy 60.067952 -32.759904)
			(xy 60.067444 -32.741108) (xy 60.067444 -32.722312) (xy 60.067878 -32.679725) (xy 60.075117 -32.59486)
			(xy 60.089568 -32.510922) (xy 60.111126 -32.428522) (xy 60.139634 -32.348262) (xy 60.156852 -32.309308)
			(xy 60.160036 -32.300175) (xy 60.16004 -32.280848) (xy 60.156852 -32.271716) (xy 60.139652 -32.232783)
			(xy 60.11117 -32.152569) (xy 60.089622 -32.070221) (xy 60.075164 -31.986337) (xy 60.067901 -31.901526)
			(xy 60.067444 -31.858966) (xy 60.067444 -31.858458) (xy 60.067698 -31.829756) (xy 60.068714 -31.803848)
			(xy 60.06973 -31.784798) (xy 60.065158 -31.778448) (xy 60.046362 -31.75635) (xy 60.044076 -31.753556)
			(xy 60.03417 -31.745428) (xy 60.032392 -31.744666) (xy 60.032138 -31.744412) (xy 60.021724 -31.738824)
			(xy 60.011818 -31.737808) (xy 59.994038 -31.735776) (xy 59.980322 -31.736538) (xy 59.955088 -31.747683)
			(xy 59.902215 -31.763407) (xy 59.847629 -31.771356) (xy 59.820048 -31.771844) (xy 59.81065 -31.771844)
			(xy 59.796089 -31.771363) (xy 59.767101 -31.768441) (xy 59.752738 -31.766002) (xy 59.74588 -31.764732)
			(xy 59.744864 -31.764478) (xy 59.704879 -31.7892) (xy 59.621104 -31.831867) (xy 59.533687 -31.866465)
			(xy 59.443403 -31.892687) (xy 59.351053 -31.9103) (xy 59.257455 -31.919148) (xy 59.210448 -31.919672)
			(xy 59.20105 -31.919926) (xy 59.157117 -31.919021) (xy 59.069656 -31.910443) (xy 58.983289 -31.894202)
			(xy 58.898687 -31.870426) (xy 58.816504 -31.839299) (xy 58.737378 -31.801061) (xy 58.6994 -31.778956)
			(xy 58.695844 -31.77667) (xy 58.690669 -31.77441) (xy 58.679645 -31.771975) (xy 58.674 -31.771844)
			(xy 58.600848 -31.771844) (xy 58.573702 -31.771362) (xy 58.519959 -31.763659) (xy 58.467851 -31.748415)
			(xy 58.41843 -31.725938) (xy 58.372694 -31.696683) (xy 58.331568 -31.661239) (xy 58.29588 -31.620324)
			(xy 58.266354 -31.574763) (xy 58.243583 -31.525477) (xy 58.22803 -31.473461) (xy 58.220006 -31.419764)
			(xy 58.21934 -31.392622) (xy 58.21934 -31.389828) (xy 58.219832 -31.361597) (xy 58.228119 -31.305748)
			(xy 58.244546 -31.25173) (xy 58.25617 -31.225998) (xy 58.257948 -31.218632) (xy 58.24391 -31.171265)
			(xy 58.224147 -31.074463) (xy 58.214034 -30.976183) (xy 58.213244 -30.926786) (xy 58.213244 -30.922468)
			(xy 58.21368 -30.879882) (xy 58.220922 -30.795018) (xy 58.235377 -30.711081) (xy 58.256938 -30.628683)
			(xy 58.28545 -30.548424) (xy 58.302652 -30.509464) (xy 58.305828 -30.500331) (xy 58.305817 -30.48101)
			(xy 58.302652 -30.471872) (xy 58.285441 -30.432916) (xy 58.256941 -30.352653) (xy 58.235383 -30.270254)
			(xy 58.220925 -30.186317) (xy 58.213671 -30.101454) (xy 58.213244 -30.058868) (xy 58.213244 -30.05836)
			(xy 58.213888 -30.008319) (xy 58.223962 -29.908744) (xy 58.243944 -29.810676) (xy 58.258202 -29.762704)
			(xy 58.256424 -29.755084) (xy 58.254138 -29.750258) (xy 58.24313 -29.725168) (xy 58.227618 -29.672622)
			(xy 58.219796 -29.618394) (xy 58.21934 -29.591) (xy 58.21934 -29.590238) (xy 58.219801 -29.562985)
			(xy 58.227554 -29.509032) (xy 58.242907 -29.456732) (xy 58.265548 -29.407151) (xy 58.295016 -29.361296)
			(xy 58.33071 -29.320103) (xy 58.371904 -29.28441) (xy 58.417759 -29.254943) (xy 58.467342 -29.232303)
			(xy 58.519642 -29.216951) (xy 58.573595 -29.2092) (xy 58.600848 -29.20873) (xy 58.601864 -29.20873)
			(xy 58.61833 -29.208881) (xy 58.651142 -29.21168) (xy 58.667396 -29.214318) (xy 58.677048 -29.216096)
			(xy 58.716976 -29.191468) (xy 58.800614 -29.148966) (xy 58.887871 -29.114498) (xy 58.977978 -29.088369)
			(xy 59.070138 -29.07081) (xy 59.163539 -29.061975) (xy 59.210448 -29.06141) (xy 59.25736 -29.061942)
			(xy 59.35077 -29.070746) (xy 59.442939 -29.08829) (xy 59.533051 -29.11442) (xy 59.620308 -29.148903)
			(xy 59.703938 -29.191435) (xy 59.743848 -29.216096) (xy 59.750198 -29.214826) (xy 59.767508 -29.211884)
			(xy 59.80249 -29.208834) (xy 59.820048 -29.20873) (xy 59.824112 -29.20873) (xy 59.853317 -29.209561)
			(xy 59.910973 -29.219003) (xy 59.93892 -29.227526) (xy 59.939428 -29.22778) (xy 59.94273 -29.228796)
			(xy 59.948572 -29.230066) (xy 59.959414 -29.231687) (xy 59.98074 -29.226699) (xy 59.98972 -29.220414)
			(xy 59.989974 -29.22016) (xy 59.99099 -29.219652) (xy 60.05703 -29.1719) (xy 60.060172 -29.169319)
			(xy 60.065654 -29.163316) (xy 60.067952 -29.159962) (xy 60.067444 -29.14142) (xy 60.067444 -29.12237)
			(xy 60.06788 -29.079784) (xy 60.075122 -28.99492) (xy 60.089576 -28.910983) (xy 60.111138 -28.828584)
			(xy 60.139649 -28.748326) (xy 60.156852 -28.709366) (xy 60.160028 -28.700233) (xy 60.160018 -28.680912)
			(xy 60.156852 -28.671774) (xy 60.13964 -28.632818) (xy 60.111141 -28.552555) (xy 60.089583 -28.470156)
			(xy 60.075124 -28.386219) (xy 60.06787 -28.301356) (xy 60.067444 -28.25877) (xy 60.067932 -28.211623)
			(xy 60.076706 -28.117738) (xy 60.08497 -28.071318) (xy 60.088618 -28.052831) (xy 60.097128 -28.016118)
			(xy 60.101988 -27.997912) (xy 60.112148 -27.96286) (xy 60.112148 -27.962606) (xy 60.11037 -27.954224)
			(xy 60.108084 -27.949144) (xy 60.10783 -27.948636) (xy 60.097287 -27.924428) (xy 60.08223 -27.873818)
			(xy 60.074312 -27.821614) (xy 60.07354 -27.79522) (xy 60.07354 -27.789886) (xy 60.074041 -27.762646)
			(xy 60.081822 -27.708724) (xy 60.097197 -27.656458) (xy 60.11985 -27.606911) (xy 60.149323 -27.561091)
			(xy 60.185015 -27.51993) (xy 60.226201 -27.484266) (xy 60.272041 -27.454825) (xy 60.321604 -27.432205)
			(xy 60.37388 -27.416867) (xy 60.427808 -27.409122) (xy 60.455048 -27.408632) (xy 60.472605 -27.408753)
			(xy 60.507585 -27.411809) (xy 60.524898 -27.414728) (xy 60.52693 -27.415236) (xy 60.52947 -27.415744)
			(xy 60.530232 -27.415744) (xy 60.531502 -27.415998) (xy 60.574428 -27.39009) (xy 60.575444 -27.389582)
			(xy 60.578746 -27.387804) (xy 60.596272 -27.378152) (xy 60.59932 -27.370786) (xy 60.61964 -27.295348)
			(xy 60.619386 -27.281632) (xy 60.617608 -27.275028) (xy 60.61329 -27.259534) (xy 60.610242 -27.2542)
			(xy 60.598548 -27.232664) (xy 60.580131 -27.187249) (xy 60.567672 -27.139852) (xy 60.561375 -27.091251)
			(xy 60.560966 -27.066748) (xy 60.560966 -27.057604) (xy 60.56122 -27.05354) (xy 60.56122 -27.052778)
			(xy 60.563506 -27.022552) (xy 60.56661 -26.998918) (xy 60.577956 -26.952619) (xy 60.594999 -26.908102)
			(xy 60.605924 -26.886916) (xy 60.618755 -26.8638) (xy 60.649827 -26.821025) (xy 60.686509 -26.782953)
			(xy 60.707016 -26.766266) (xy 60.709048 -26.764742) (xy 60.71616 -26.757884) (xy 60.729114 -26.742136)
			(xy 60.731654 -26.736802) (xy 60.734194 -26.725118) (xy 60.73013 -26.647394) (xy 60.729622 -26.634948)
			(xy 60.714636 -26.609294) (xy 60.706762 -26.59888) (xy 60.699396 -26.591514) (xy 60.691268 -26.584656)
			(xy 60.688982 -26.583132) (xy 60.667083 -26.567859) (xy 60.627371 -26.532173) (xy 60.59302 -26.491301)
			(xy 60.564698 -26.446041) (xy 60.542959 -26.397277) (xy 60.528227 -26.345959) (xy 60.520788 -26.293089)
			(xy 60.520326 -26.266394) (xy 60.520812 -26.239125) (xy 60.528574 -26.185141) (xy 60.543939 -26.132811)
			(xy 60.566596 -26.083201) (xy 60.596082 -26.03732) (xy 60.631797 -25.996103) (xy 60.673014 -25.960388)
			(xy 60.718895 -25.930902) (xy 60.768505 -25.908245) (xy 60.820835 -25.89288) (xy 60.874819 -25.885118)
			(xy 60.929357 -25.885118) (xy 60.983341 -25.89288) (xy 61.035671 -25.908245) (xy 61.085281 -25.930902)
			(xy 61.131162 -25.960388) (xy 61.172379 -25.996103) (xy 61.208094 -26.03732) (xy 61.23758 -26.083201)
			(xy 61.260237 -26.132811) (xy 61.275602 -26.185141) (xy 61.283364 -26.239125) (xy 61.28385 -26.266394)
			(xy 61.283313 -26.295751) (xy 61.274326 -26.353774) (xy 61.256563 -26.409737) (xy 61.230444 -26.462322)
			(xy 61.196583 -26.510289) (xy 61.155778 -26.552507) (xy 61.13272 -26.570686) (xy 61.129418 -26.573226)
			(xy 61.125608 -26.577036) (xy 61.119512 -26.58491) (xy 61.115783 -26.591021) (xy 61.111538 -26.604686)
			(xy 61.11113 -26.611834) (xy 61.11494 -26.69667) (xy 61.119766 -26.706068) (xy 61.120782 -26.708354)
			(xy 61.129672 -26.72334) (xy 61.133228 -26.729182) (xy 61.148976 -26.745438) (xy 61.155326 -26.749756)
			(xy 61.177184 -26.764969) (xy 61.21683 -26.800525) (xy 61.251141 -26.841252) (xy 61.27945 -26.886359)
			(xy 61.301204 -26.934967) (xy 61.315982 -26.98613) (xy 61.323494 -27.038852) (xy 61.323982 -27.065478)
			(xy 61.323982 -27.07132) (xy 61.323755 -27.083298) (xy 61.321975 -27.107192) (xy 61.320426 -27.119072)
			(xy 61.320426 -27.11958) (xy 61.319918 -27.122628) (xy 61.319918 -27.122882) (xy 61.319156 -27.1272)
			(xy 61.319156 -27.127454) (xy 61.318648 -27.130502) (xy 61.317632 -27.13609) (xy 61.317632 -27.136598)
			(xy 61.31687 -27.140408) (xy 61.315854 -27.14498) (xy 61.313442 -27.15605) (xy 61.307467 -27.177909)
			(xy 61.303916 -27.188668) (xy 61.300614 -27.19832) (xy 61.30163 -27.217116) (xy 61.304678 -27.223974)
			(xy 61.335666 -27.28595) (xy 61.338714 -27.290776) (xy 61.34481 -27.297634) (xy 61.351668 -27.303476)
			(xy 61.363606 -27.307286) (xy 61.403405 -27.320228) (xy 61.458732 -27.342846) (xy 68.523612 -27.342846)
			(xy 68.523612 -26.479246) (xy 68.524102 -26.449278) (xy 68.531925 -26.389856) (xy 68.547438 -26.331963)
			(xy 68.570374 -26.27659) (xy 68.600341 -26.224684) (xy 68.636828 -26.177134) (xy 68.679208 -26.134754)
			(xy 68.726758 -26.098267) (xy 68.778664 -26.0683) (xy 68.834037 -26.045364) (xy 68.89193 -26.029851)
			(xy 68.951352 -26.022028) (xy 69.011288 -26.022028) (xy 69.07071 -26.029851) (xy 69.128603 -26.045364)
			(xy 69.183976 -26.0683) (xy 69.235882 -26.098267) (xy 69.283432 -26.134754) (xy 69.325812 -26.177134)
			(xy 69.362299 -26.224684) (xy 69.392266 -26.27659) (xy 69.415202 -26.331963) (xy 69.422951 -26.360882)
			(xy 71.089518 -26.360882) (xy 71.093589 -26.30526) (xy 71.105715 -26.250823) (xy 71.125638 -26.198732)
			(xy 71.152934 -26.150097) (xy 71.18702 -26.105954) (xy 71.227169 -26.067245) (xy 71.272527 -26.034794)
			(xy 71.322127 -26.009293) (xy 71.374911 -25.991286) (xy 71.429754 -25.981156) (xy 71.485488 -25.979119)
			(xy 71.540925 -25.985219) (xy 71.594882 -25.999325) (xy 71.646211 -26.021137) (xy 71.693817 -26.050191)
			(xy 71.736685 -26.085866) (xy 71.773902 -26.127403) (xy 71.804675 -26.173916) (xy 71.828347 -26.224413)
			(xy 71.844415 -26.27782) (xy 71.850583 -26.319734) (xy 76.841856 -26.319734) (xy 76.845927 -26.264112)
			(xy 76.858053 -26.209675) (xy 76.877976 -26.157584) (xy 76.905272 -26.108949) (xy 76.939358 -26.064806)
			(xy 76.979507 -26.026097) (xy 77.024865 -25.993646) (xy 77.074465 -25.968145) (xy 77.127249 -25.950138)
			(xy 77.182092 -25.940008) (xy 77.237826 -25.937971) (xy 77.293263 -25.944071) (xy 77.34722 -25.958177)
			(xy 77.398549 -25.979989) (xy 77.446155 -26.009043) (xy 77.47582 -26.03373) (xy 83.267802 -26.03373)
			(xy 83.271873 -25.978108) (xy 83.283999 -25.923671) (xy 83.303922 -25.87158) (xy 83.331218 -25.822945)
			(xy 83.365304 -25.778802) (xy 83.405453 -25.740093) (xy 83.450811 -25.707642) (xy 83.500411 -25.682141)
			(xy 83.553195 -25.664134) (xy 83.608038 -25.654004) (xy 83.663772 -25.651967) (xy 83.719209 -25.658067)
			(xy 83.773166 -25.672173) (xy 83.824495 -25.693985) (xy 83.872101 -25.723039) (xy 83.914969 -25.758714)
			(xy 83.952186 -25.800251) (xy 83.982959 -25.846764) (xy 84.006631 -25.897261) (xy 84.022699 -25.950668)
			(xy 84.030819 -26.005844) (xy 84.031328 -26.03373) (xy 84.030819 -26.061616) (xy 84.022699 -26.116792)
			(xy 84.006631 -26.170199) (xy 83.982959 -26.220696) (xy 83.952186 -26.267209) (xy 83.914969 -26.308746)
			(xy 83.872101 -26.344421) (xy 83.824495 -26.373475) (xy 83.773166 -26.395287) (xy 83.719209 -26.409393)
			(xy 83.663772 -26.415493) (xy 83.608038 -26.413456) (xy 83.553195 -26.403326) (xy 83.500411 -26.385319)
			(xy 83.450811 -26.359818) (xy 83.405453 -26.327367) (xy 83.365304 -26.288658) (xy 83.331218 -26.244515)
			(xy 83.303922 -26.19588) (xy 83.283999 -26.143789) (xy 83.271873 -26.089352) (xy 83.267802 -26.03373)
			(xy 77.47582 -26.03373) (xy 77.489023 -26.044718) (xy 77.52624 -26.086255) (xy 77.557013 -26.132768)
			(xy 77.580685 -26.183265) (xy 77.596753 -26.236672) (xy 77.604873 -26.291848) (xy 77.605382 -26.319734)
			(xy 77.604873 -26.34762) (xy 77.596753 -26.402796) (xy 77.580685 -26.456203) (xy 77.557013 -26.5067)
			(xy 77.52624 -26.553213) (xy 77.489023 -26.59475) (xy 77.446155 -26.630425) (xy 77.398549 -26.659479)
			(xy 77.34722 -26.681291) (xy 77.293263 -26.695397) (xy 77.237826 -26.701497) (xy 77.182092 -26.69946)
			(xy 77.127249 -26.68933) (xy 77.074465 -26.671323) (xy 77.024865 -26.645822) (xy 76.979507 -26.613371)
			(xy 76.939358 -26.574662) (xy 76.905272 -26.530519) (xy 76.877976 -26.481884) (xy 76.858053 -26.429793)
			(xy 76.845927 -26.375356) (xy 76.841856 -26.319734) (xy 71.850583 -26.319734) (xy 71.852535 -26.332996)
			(xy 71.853044 -26.360882) (xy 71.852535 -26.388768) (xy 71.844415 -26.443944) (xy 71.828347 -26.497351)
			(xy 71.804675 -26.547848) (xy 71.773902 -26.594361) (xy 71.736685 -26.635898) (xy 71.693817 -26.671573)
			(xy 71.646211 -26.700627) (xy 71.594882 -26.722439) (xy 71.540925 -26.736545) (xy 71.485488 -26.742645)
			(xy 71.429754 -26.740608) (xy 71.374911 -26.730478) (xy 71.322127 -26.712471) (xy 71.272527 -26.68697)
			(xy 71.227169 -26.654519) (xy 71.18702 -26.61581) (xy 71.152934 -26.571667) (xy 71.125638 -26.523032)
			(xy 71.105715 -26.470941) (xy 71.093589 -26.416504) (xy 71.089518 -26.360882) (xy 69.422951 -26.360882)
			(xy 69.430715 -26.389856) (xy 69.438538 -26.449278) (xy 69.439028 -26.479246) (xy 69.439028 -26.971244)
			(xy 72.851008 -26.971244) (xy 72.855079 -26.915622) (xy 72.867205 -26.861185) (xy 72.887128 -26.809094)
			(xy 72.914424 -26.760459) (xy 72.94851 -26.716316) (xy 72.988659 -26.677607) (xy 73.034017 -26.645156)
			(xy 73.083617 -26.619655) (xy 73.136401 -26.601648) (xy 73.191244 -26.591518) (xy 73.246978 -26.589481)
			(xy 73.302415 -26.595581) (xy 73.356372 -26.609687) (xy 73.407701 -26.631499) (xy 73.455307 -26.660553)
			(xy 73.498175 -26.696228) (xy 73.535392 -26.737765) (xy 73.566165 -26.784278) (xy 73.589837 -26.834775)
			(xy 73.605905 -26.888182) (xy 73.614025 -26.943358) (xy 73.614534 -26.971244) (xy 73.614025 -26.99913)
			(xy 73.605905 -27.054306) (xy 73.589837 -27.107713) (xy 73.566165 -27.15821) (xy 73.535392 -27.204723)
			(xy 73.498175 -27.24626) (xy 73.455307 -27.281935) (xy 73.407701 -27.310989) (xy 73.356372 -27.332801)
			(xy 73.302415 -27.346907) (xy 73.246978 -27.353007) (xy 73.191244 -27.35097) (xy 73.136401 -27.34084)
			(xy 73.083617 -27.322833) (xy 73.034017 -27.297332) (xy 72.988659 -27.264881) (xy 72.94851 -27.226172)
			(xy 72.914424 -27.182029) (xy 72.887128 -27.133394) (xy 72.867205 -27.081303) (xy 72.855079 -27.026866)
			(xy 72.851008 -26.971244) (xy 69.439028 -26.971244) (xy 69.439028 -27.342846) (xy 69.438538 -27.372814)
			(xy 69.430715 -27.432236) (xy 69.415202 -27.490129) (xy 69.392266 -27.545502) (xy 69.362299 -27.597408)
			(xy 69.325812 -27.644958) (xy 69.283432 -27.687338) (xy 69.235882 -27.723825) (xy 69.183976 -27.753792)
			(xy 69.128603 -27.776728) (xy 69.07071 -27.792241) (xy 69.011288 -27.800064) (xy 68.951352 -27.800064)
			(xy 68.89193 -27.792241) (xy 68.834037 -27.776728) (xy 68.778664 -27.753792) (xy 68.726758 -27.723825)
			(xy 68.679208 -27.687338) (xy 68.636828 -27.644958) (xy 68.600341 -27.597408) (xy 68.570374 -27.545502)
			(xy 68.547438 -27.490129) (xy 68.531925 -27.432236) (xy 68.524102 -27.372814) (xy 68.523612 -27.342846)
			(xy 61.458732 -27.342846) (xy 61.480877 -27.351899) (xy 61.555422 -27.389953) (xy 61.59119 -27.41168)
			(xy 61.599826 -27.41168) (xy 61.612026 -27.410168) (xy 61.636556 -27.408515) (xy 61.648848 -27.408378)
			(xy 61.668152 -27.408886) (xy 61.677804 -27.409648) (xy 61.704811 -27.412184) (xy 61.757768 -27.423922)
			(xy 61.80853 -27.44304) (xy 61.856073 -27.469153) (xy 61.89944 -27.501734) (xy 61.937758 -27.540127)
			(xy 61.95441 -27.56154) (xy 61.956442 -27.56408) (xy 62.000837 -27.571476) (xy 62.088175 -27.59324)
			(xy 62.173198 -27.622783) (xy 62.255213 -27.659866) (xy 62.333554 -27.704186) (xy 62.407584 -27.755383)
			(xy 62.476701 -27.813041) (xy 62.508892 -27.844496) (xy 63.778868 -29.114242) (xy 70.847204 -29.114242)
			(xy 70.847204 -28.250642) (xy 70.847694 -28.220658) (xy 70.855522 -28.161202) (xy 70.871043 -28.103277)
			(xy 70.893992 -28.047873) (xy 70.923976 -27.995939) (xy 70.960482 -27.948363) (xy 71.002887 -27.905958)
			(xy 71.050463 -27.869452) (xy 71.102397 -27.839468) (xy 71.157801 -27.816519) (xy 71.215726 -27.800998)
			(xy 71.275182 -27.79317) (xy 71.33515 -27.79317) (xy 71.394606 -27.800998) (xy 71.452531 -27.816519)
			(xy 71.507935 -27.839468) (xy 71.559869 -27.869452) (xy 71.607445 -27.905958) (xy 71.64985 -27.948363)
			(xy 71.686356 -27.995939) (xy 71.71634 -28.047873) (xy 71.739289 -28.103277) (xy 71.75481 -28.161202)
			(xy 71.762638 -28.220658) (xy 71.763128 -28.250642) (xy 71.763128 -28.469082) (xy 75.75245 -28.469082)
			(xy 75.756521 -28.41346) (xy 75.768647 -28.359023) (xy 75.78857 -28.306932) (xy 75.815866 -28.258297)
			(xy 75.849952 -28.214154) (xy 75.890101 -28.175445) (xy 75.935459 -28.142994) (xy 75.985059 -28.117493)
			(xy 76.037843 -28.099486) (xy 76.092686 -28.089356) (xy 76.14842 -28.087319) (xy 76.203857 -28.093419)
			(xy 76.257814 -28.107525) (xy 76.309143 -28.129337) (xy 76.325199 -28.139136) (xy 80.397856 -28.139136)
			(xy 80.401927 -28.083514) (xy 80.414053 -28.029077) (xy 80.433976 -27.976986) (xy 80.461272 -27.928351)
			(xy 80.495358 -27.884208) (xy 80.535507 -27.845499) (xy 80.580865 -27.813048) (xy 80.630465 -27.787547)
			(xy 80.683249 -27.76954) (xy 80.738092 -27.75941) (xy 80.793826 -27.757373) (xy 80.849263 -27.763473)
			(xy 80.90322 -27.777579) (xy 80.954549 -27.799391) (xy 81.002155 -27.828445) (xy 81.045023 -27.86412)
			(xy 81.08224 -27.905657) (xy 81.113013 -27.95217) (xy 81.136685 -28.002667) (xy 81.152753 -28.056074)
			(xy 81.160873 -28.11125) (xy 81.161382 -28.139136) (xy 81.667856 -28.139136) (xy 81.671927 -28.083514)
			(xy 81.684053 -28.029077) (xy 81.703976 -27.976986) (xy 81.731272 -27.928351) (xy 81.765358 -27.884208)
			(xy 81.805507 -27.845499) (xy 81.850865 -27.813048) (xy 81.900465 -27.787547) (xy 81.953249 -27.76954)
			(xy 82.008092 -27.75941) (xy 82.063826 -27.757373) (xy 82.119263 -27.763473) (xy 82.17322 -27.777579)
			(xy 82.224549 -27.799391) (xy 82.272155 -27.828445) (xy 82.315023 -27.86412) (xy 82.35224 -27.905657)
			(xy 82.383013 -27.95217) (xy 82.406685 -28.002667) (xy 82.422753 -28.056074) (xy 82.430873 -28.11125)
			(xy 82.431382 -28.139136) (xy 82.430873 -28.167022) (xy 82.422753 -28.222198) (xy 82.406685 -28.275605)
			(xy 82.383013 -28.326102) (xy 82.35224 -28.372615) (xy 82.315023 -28.414152) (xy 82.272155 -28.449827)
			(xy 82.224549 -28.478881) (xy 82.17322 -28.500693) (xy 82.119263 -28.514799) (xy 82.063826 -28.520899)
			(xy 82.008092 -28.518862) (xy 81.953249 -28.508732) (xy 81.900465 -28.490725) (xy 81.850865 -28.465224)
			(xy 81.805507 -28.432773) (xy 81.765358 -28.394064) (xy 81.731272 -28.349921) (xy 81.703976 -28.301286)
			(xy 81.684053 -28.249195) (xy 81.671927 -28.194758) (xy 81.667856 -28.139136) (xy 81.161382 -28.139136)
			(xy 81.160873 -28.167022) (xy 81.152753 -28.222198) (xy 81.136685 -28.275605) (xy 81.113013 -28.326102)
			(xy 81.08224 -28.372615) (xy 81.045023 -28.414152) (xy 81.002155 -28.449827) (xy 80.954549 -28.478881)
			(xy 80.90322 -28.500693) (xy 80.849263 -28.514799) (xy 80.793826 -28.520899) (xy 80.738092 -28.518862)
			(xy 80.683249 -28.508732) (xy 80.630465 -28.490725) (xy 80.580865 -28.465224) (xy 80.535507 -28.432773)
			(xy 80.495358 -28.394064) (xy 80.461272 -28.349921) (xy 80.433976 -28.301286) (xy 80.414053 -28.249195)
			(xy 80.401927 -28.194758) (xy 80.397856 -28.139136) (xy 76.325199 -28.139136) (xy 76.356749 -28.158391)
			(xy 76.399617 -28.194066) (xy 76.436834 -28.235603) (xy 76.467607 -28.282116) (xy 76.491279 -28.332613)
			(xy 76.507347 -28.38602) (xy 76.515467 -28.441196) (xy 76.515976 -28.469082) (xy 76.515467 -28.496968)
			(xy 76.507347 -28.552144) (xy 76.491279 -28.605551) (xy 76.467607 -28.656048) (xy 76.436834 -28.702561)
			(xy 76.399617 -28.744098) (xy 76.356749 -28.779773) (xy 76.309143 -28.808827) (xy 76.257814 -28.830639)
			(xy 76.203857 -28.844745) (xy 76.14842 -28.850845) (xy 76.092686 -28.848808) (xy 76.037843 -28.838678)
			(xy 75.985059 -28.820671) (xy 75.935459 -28.79517) (xy 75.890101 -28.762719) (xy 75.849952 -28.72401)
			(xy 75.815866 -28.679867) (xy 75.78857 -28.631232) (xy 75.768647 -28.579141) (xy 75.756521 -28.524704)
			(xy 75.75245 -28.469082) (xy 71.763128 -28.469082) (xy 71.763128 -29.114242) (xy 71.762638 -29.144226)
			(xy 71.75481 -29.203682) (xy 71.739289 -29.261607) (xy 71.71634 -29.317011) (xy 71.686356 -29.368945)
			(xy 71.64985 -29.416521) (xy 71.607445 -29.458926) (xy 71.559869 -29.495432) (xy 71.507935 -29.525416)
			(xy 71.452531 -29.548365) (xy 71.394606 -29.563886) (xy 71.33515 -29.571714) (xy 71.275182 -29.571714)
			(xy 71.215726 -29.563886) (xy 71.157801 -29.548365) (xy 71.102397 -29.525416) (xy 71.050463 -29.495432)
			(xy 71.002887 -29.458926) (xy 70.960482 -29.416521) (xy 70.923976 -29.368945) (xy 70.893992 -29.317011)
			(xy 70.871043 -29.261607) (xy 70.855522 -29.203682) (xy 70.847694 -29.144226) (xy 70.847204 -29.114242)
			(xy 63.778868 -29.114242) (xy 63.910972 -29.246322) (xy 63.91402 -29.247846) (xy 63.917068 -29.24937)
			(xy 63.918084 -29.249878) (xy 63.944574 -29.263993) (xy 63.993138 -29.299263) (xy 64.035584 -29.3417)
			(xy 64.070865 -29.390257) (xy 64.084962 -29.416756) (xy 64.08547 -29.417772) (xy 64.086994 -29.42082)
			(xy 64.088518 -29.423868) (xy 64.207898 -29.543248) (xy 65.407794 -30.743398) (xy 65.432453 -30.768434)
			(xy 65.478595 -30.821443) (xy 65.499996 -30.849316) (xy 65.515145 -30.869694) (xy 65.543607 -30.911751)
			(xy 65.549095 -30.92069) (xy 73.489312 -30.92069) (xy 73.489312 -30.05709) (xy 73.489802 -30.027106)
			(xy 73.49763 -29.96765) (xy 73.513151 -29.909725) (xy 73.5361 -29.854321) (xy 73.566084 -29.802387)
			(xy 73.60259 -29.754811) (xy 73.644995 -29.712406) (xy 73.692571 -29.6759) (xy 73.744505 -29.645916)
			(xy 73.799909 -29.622967) (xy 73.857834 -29.607446) (xy 73.91729 -29.599618) (xy 73.977258 -29.599618)
			(xy 74.036714 -29.607446) (xy 74.094639 -29.622967) (xy 74.150043 -29.645916) (xy 74.201977 -29.6759)
			(xy 74.249553 -29.712406) (xy 74.291958 -29.754811) (xy 74.328464 -29.802387) (xy 74.358448 -29.854321)
			(xy 74.381397 -29.909725) (xy 74.396918 -29.96765) (xy 74.404746 -30.027106) (xy 74.405236 -30.05709)
			(xy 74.405236 -30.376876) (xy 78.888844 -30.376876) (xy 78.8894 -30.34796) (xy 78.898119 -30.29079)
			(xy 78.915369 -30.235591) (xy 78.940753 -30.183629) (xy 78.973691 -30.136094) (xy 79.013427 -30.094077)
			(xy 79.03591 -30.075886) (xy 79.044715 -30.068277) (xy 79.054899 -30.047378) (xy 79.055468 -30.035754)
			(xy 79.055468 -29.955998) (xy 79.054927 -29.944366) (xy 79.044741 -29.923456) (xy 79.03591 -29.915866)
			(xy 79.013412 -29.897692) (xy 78.973678 -29.855669) (xy 78.94074 -29.80813) (xy 78.915354 -29.756166)
			(xy 78.898101 -29.700965) (xy 78.889376 -29.643793) (xy 78.888844 -29.614876) (xy 78.88933 -29.587625)
			(xy 78.897086 -29.533677) (xy 78.912441 -29.481382) (xy 78.935083 -29.431805) (xy 78.964549 -29.385955)
			(xy 79.00024 -29.344764) (xy 79.041431 -29.309073) (xy 79.087281 -29.279607) (xy 79.136858 -29.256965)
			(xy 79.189153 -29.24161) (xy 79.243101 -29.233854) (xy 79.297603 -29.233854) (xy 79.351551 -29.24161)
			(xy 79.403846 -29.256965) (xy 79.453423 -29.279607) (xy 79.499273 -29.309073) (xy 79.540464 -29.344764)
			(xy 79.576155 -29.385955) (xy 79.605621 -29.431805) (xy 79.628263 -29.481382) (xy 79.643618 -29.533677)
			(xy 79.651374 -29.587625) (xy 79.65186 -29.614876) (xy 79.65134 -29.643793) (xy 79.642613 -29.700965)
			(xy 79.625357 -29.756164) (xy 79.599965 -29.808126) (xy 79.567022 -29.85566) (xy 79.52728 -29.897676)
			(xy 79.504794 -29.915866) (xy 79.496011 -29.923497) (xy 79.485815 -29.94438) (xy 79.485236 -29.955998)
			(xy 79.485236 -30.035754) (xy 79.485746 -30.04739) (xy 79.495954 -30.0683) (xy 79.504794 -30.075886)
			(xy 79.52727 -30.094086) (xy 79.567005 -30.136104) (xy 79.599946 -30.183637) (xy 79.625335 -30.235596)
			(xy 79.642593 -30.290792) (xy 79.651324 -30.347961) (xy 79.65186 -30.376876) (xy 81.92897 -30.376876)
			(xy 81.929517 -30.34796) (xy 81.938236 -30.290789) (xy 81.955487 -30.235589) (xy 81.980873 -30.183627)
			(xy 82.013813 -30.136093) (xy 82.053552 -30.094076) (xy 82.076036 -30.075886) (xy 82.084846 -30.068281)
			(xy 82.095026 -30.047379) (xy 82.095594 -30.035754) (xy 82.095594 -29.955998) (xy 82.095044 -29.944367)
			(xy 82.084863 -29.923458) (xy 82.076036 -29.915866) (xy 82.053544 -29.897685) (xy 82.013807 -29.855664)
			(xy 81.980868 -29.808128) (xy 81.955481 -29.756164) (xy 81.938227 -29.700964) (xy 81.929502 -29.643793)
			(xy 81.92897 -29.614876) (xy 81.929456 -29.587625) (xy 81.937212 -29.533677) (xy 81.952567 -29.481382)
			(xy 81.975209 -29.431805) (xy 82.004675 -29.385955) (xy 82.040366 -29.344764) (xy 82.081557 -29.309073)
			(xy 82.127407 -29.279607) (xy 82.176984 -29.256965) (xy 82.229279 -29.24161) (xy 82.283227 -29.233854)
			(xy 82.337729 -29.233854) (xy 82.391677 -29.24161) (xy 82.443972 -29.256965) (xy 82.493549 -29.279607)
			(xy 82.539399 -29.309073) (xy 82.58059 -29.344764) (xy 82.616281 -29.385955) (xy 82.645747 -29.431805)
			(xy 82.668389 -29.481382) (xy 82.683744 -29.533677) (xy 82.6915 -29.587625) (xy 82.691986 -29.614876)
			(xy 82.691456 -29.643793) (xy 82.68273 -29.700963) (xy 82.665475 -29.756162) (xy 82.640085 -29.808124)
			(xy 82.607144 -29.855658) (xy 82.567405 -29.897676) (xy 82.54492 -29.915866) (xy 82.536125 -29.923484)
			(xy 82.525938 -29.944377) (xy 82.525362 -29.955998) (xy 82.525362 -30.035754) (xy 82.525863 -30.047391)
			(xy 82.536076 -30.068302) (xy 82.54492 -30.075886) (xy 82.567401 -30.09408) (xy 82.607135 -30.1361)
			(xy 82.640074 -30.183634) (xy 82.665463 -30.235595) (xy 82.68272 -30.290791) (xy 82.69145 -30.34796)
			(xy 82.691986 -30.376876) (xy 82.6915 -30.404127) (xy 82.683744 -30.458075) (xy 82.668389 -30.51037)
			(xy 82.645747 -30.559947) (xy 82.616281 -30.605797) (xy 82.58059 -30.646988) (xy 82.539399 -30.682679)
			(xy 82.493549 -30.712145) (xy 82.443972 -30.734787) (xy 82.391677 -30.750142) (xy 82.337729 -30.757898)
			(xy 82.283227 -30.757898) (xy 82.229279 -30.750142) (xy 82.176984 -30.734787) (xy 82.127407 -30.712145)
			(xy 82.081557 -30.682679) (xy 82.040366 -30.646988) (xy 82.004675 -30.605797) (xy 81.975209 -30.559947)
			(xy 81.952567 -30.51037) (xy 81.937212 -30.458075) (xy 81.929456 -30.404127) (xy 81.92897 -30.376876)
			(xy 79.65186 -30.376876) (xy 79.651374 -30.404127) (xy 79.643618 -30.458075) (xy 79.628263 -30.51037)
			(xy 79.605621 -30.559947) (xy 79.576155 -30.605797) (xy 79.540464 -30.646988) (xy 79.499273 -30.682679)
			(xy 79.453423 -30.712145) (xy 79.403846 -30.734787) (xy 79.351551 -30.750142) (xy 79.297603 -30.757898)
			(xy 79.243101 -30.757898) (xy 79.189153 -30.750142) (xy 79.136858 -30.734787) (xy 79.087281 -30.712145)
			(xy 79.041431 -30.682679) (xy 79.00024 -30.646988) (xy 78.964549 -30.605797) (xy 78.935083 -30.559947)
			(xy 78.912441 -30.51037) (xy 78.897086 -30.458075) (xy 78.88933 -30.404127) (xy 78.888844 -30.376876)
			(xy 74.405236 -30.376876) (xy 74.405236 -30.92069) (xy 74.404746 -30.950674) (xy 74.396918 -31.01013)
			(xy 74.381397 -31.068055) (xy 74.358448 -31.123459) (xy 74.328464 -31.175393) (xy 74.291958 -31.222969)
			(xy 74.249553 -31.265374) (xy 74.201977 -31.30188) (xy 74.150043 -31.331864) (xy 74.094639 -31.354813)
			(xy 74.036714 -31.370334) (xy 73.977258 -31.378162) (xy 73.91729 -31.378162) (xy 73.857834 -31.370334)
			(xy 73.799909 -31.354813) (xy 73.744505 -31.331864) (xy 73.692571 -31.30188) (xy 73.644995 -31.265374)
			(xy 73.60259 -31.222969) (xy 73.566084 -31.175393) (xy 73.5361 -31.123459) (xy 73.513151 -31.068055)
			(xy 73.49763 -31.01013) (xy 73.489802 -30.950674) (xy 73.489312 -30.92069) (xy 65.549095 -30.92069)
			(xy 65.556892 -30.93339) (xy 65.557908 -30.935168) (xy 65.564004 -30.94355) (xy 65.57784 -30.958748)
			(xy 65.60439 -30.990128) (xy 65.61709 -31.006288) (xy 65.630193 -31.023208) (xy 65.655094 -31.058018)
			(xy 65.666874 -31.075884) (xy 65.683384 -31.1023) (xy 65.6844 -31.104332) (xy 65.685924 -31.106618)
			(xy 65.69202 -31.116778) (xy 65.700148 -31.130748) (xy 65.700148 -31.131002) (xy 65.706244 -31.142178)
			(xy 65.70726 -31.14421) (xy 65.719217 -31.166691) (xy 65.741071 -31.212689) (xy 65.750948 -31.236158)
			(xy 66.341244 -32.660844) (xy 66.363384 -32.714184) (xy 70.847204 -32.714184) (xy 70.847204 -31.850584)
			(xy 70.847694 -31.8206) (xy 70.855522 -31.761144) (xy 70.871043 -31.703219) (xy 70.893992 -31.647815)
			(xy 70.923976 -31.595881) (xy 70.960482 -31.548305) (xy 71.002887 -31.5059) (xy 71.050463 -31.469394)
			(xy 71.102397 -31.43941) (xy 71.157801 -31.416461) (xy 71.215726 -31.40094) (xy 71.275182 -31.393112)
			(xy 71.33515 -31.393112) (xy 71.394606 -31.40094) (xy 71.452531 -31.416461) (xy 71.507935 -31.43941)
			(xy 71.559869 -31.469394) (xy 71.607445 -31.5059) (xy 71.64985 -31.548305) (xy 71.664872 -31.567882)
			(xy 78.99857 -31.567882) (xy 79.002641 -31.51226) (xy 79.014767 -31.457823) (xy 79.03469 -31.405732)
			(xy 79.061986 -31.357097) (xy 79.096072 -31.312954) (xy 79.136221 -31.274245) (xy 79.181579 -31.241794)
			(xy 79.231179 -31.216293) (xy 79.283963 -31.198286) (xy 79.338806 -31.188156) (xy 79.39454 -31.186119)
			(xy 79.449977 -31.192219) (xy 79.503934 -31.206325) (xy 79.555263 -31.228137) (xy 79.602869 -31.257191)
			(xy 79.645737 -31.292866) (xy 79.682954 -31.334403) (xy 79.713727 -31.380916) (xy 79.737399 -31.431413)
			(xy 79.753467 -31.48482) (xy 79.761587 -31.539996) (xy 79.762096 -31.567882) (xy 79.761587 -31.595768)
			(xy 79.753467 -31.650944) (xy 79.737399 -31.704351) (xy 79.730407 -31.719266) (xy 80.285334 -31.719266)
			(xy 80.289405 -31.663644) (xy 80.301531 -31.609207) (xy 80.321454 -31.557116) (xy 80.34875 -31.508481)
			(xy 80.382836 -31.464338) (xy 80.422985 -31.425629) (xy 80.468343 -31.393178) (xy 80.517943 -31.367677)
			(xy 80.570727 -31.34967) (xy 80.62557 -31.33954) (xy 80.681304 -31.337503) (xy 80.736741 -31.343603)
			(xy 80.790698 -31.357709) (xy 80.842027 -31.379521) (xy 80.889633 -31.408575) (xy 80.932501 -31.44425)
			(xy 80.969718 -31.485787) (xy 81.000491 -31.5323) (xy 81.024163 -31.582797) (xy 81.040231 -31.636204)
			(xy 81.044381 -31.664402) (xy 81.560922 -31.664402) (xy 81.564993 -31.60878) (xy 81.577119 -31.554343)
			(xy 81.597042 -31.502252) (xy 81.624338 -31.453617) (xy 81.658424 -31.409474) (xy 81.698573 -31.370765)
			(xy 81.743931 -31.338314) (xy 81.793531 -31.312813) (xy 81.846315 -31.294806) (xy 81.901158 -31.284676)
			(xy 81.956892 -31.282639) (xy 82.012329 -31.288739) (xy 82.066286 -31.302845) (xy 82.117615 -31.324657)
			(xy 82.165221 -31.353711) (xy 82.208089 -31.389386) (xy 82.245306 -31.430923) (xy 82.276079 -31.477436)
			(xy 82.299751 -31.527933) (xy 82.315819 -31.58134) (xy 82.323939 -31.636516) (xy 82.324448 -31.664402)
			(xy 82.323939 -31.692288) (xy 82.315819 -31.747464) (xy 82.306879 -31.777178) (xy 82.826096 -31.777178)
			(xy 82.830167 -31.721556) (xy 82.842293 -31.667119) (xy 82.862216 -31.615028) (xy 82.889512 -31.566393)
			(xy 82.923598 -31.52225) (xy 82.963747 -31.483541) (xy 83.009105 -31.45109) (xy 83.058705 -31.425589)
			(xy 83.111489 -31.407582) (xy 83.166332 -31.397452) (xy 83.222066 -31.395415) (xy 83.277503 -31.401515)
			(xy 83.33146 -31.415621) (xy 83.382789 -31.437433) (xy 83.430395 -31.466487) (xy 83.473263 -31.502162)
			(xy 83.51048 -31.543699) (xy 83.541253 -31.590212) (xy 83.564925 -31.640709) (xy 83.580993 -31.694116)
			(xy 83.589113 -31.749292) (xy 83.589622 -31.777178) (xy 83.589113 -31.805064) (xy 83.580993 -31.86024)
			(xy 83.564925 -31.913647) (xy 83.541253 -31.964144) (xy 83.51048 -32.010657) (xy 83.473263 -32.052194)
			(xy 83.430395 -32.087869) (xy 83.382789 -32.116923) (xy 83.33146 -32.138735) (xy 83.277503 -32.152841)
			(xy 83.222066 -32.158941) (xy 83.166332 -32.156904) (xy 83.111489 -32.146774) (xy 83.058705 -32.128767)
			(xy 83.009105 -32.103266) (xy 82.963747 -32.070815) (xy 82.923598 -32.032106) (xy 82.889512 -31.987963)
			(xy 82.862216 -31.939328) (xy 82.842293 -31.887237) (xy 82.830167 -31.8328) (xy 82.826096 -31.777178)
			(xy 82.306879 -31.777178) (xy 82.299751 -31.800871) (xy 82.276079 -31.851368) (xy 82.245306 -31.897881)
			(xy 82.208089 -31.939418) (xy 82.165221 -31.975093) (xy 82.117615 -32.004147) (xy 82.066286 -32.025959)
			(xy 82.012329 -32.040065) (xy 81.956892 -32.046165) (xy 81.901158 -32.044128) (xy 81.846315 -32.033998)
			(xy 81.793531 -32.015991) (xy 81.743931 -31.99049) (xy 81.698573 -31.958039) (xy 81.658424 -31.91933)
			(xy 81.624338 -31.875187) (xy 81.597042 -31.826552) (xy 81.577119 -31.774461) (xy 81.564993 -31.720024)
			(xy 81.560922 -31.664402) (xy 81.044381 -31.664402) (xy 81.048351 -31.69138) (xy 81.04886 -31.719266)
			(xy 81.048351 -31.747152) (xy 81.040231 -31.802328) (xy 81.024163 -31.855735) (xy 81.000491 -31.906232)
			(xy 80.969718 -31.952745) (xy 80.932501 -31.994282) (xy 80.889633 -32.029957) (xy 80.842027 -32.059011)
			(xy 80.790698 -32.080823) (xy 80.736741 -32.094929) (xy 80.681304 -32.101029) (xy 80.62557 -32.098992)
			(xy 80.570727 -32.088862) (xy 80.517943 -32.070855) (xy 80.468343 -32.045354) (xy 80.422985 -32.012903)
			(xy 80.382836 -31.974194) (xy 80.34875 -31.930051) (xy 80.321454 -31.881416) (xy 80.301531 -31.829325)
			(xy 80.289405 -31.774888) (xy 80.285334 -31.719266) (xy 79.730407 -31.719266) (xy 79.713727 -31.754848)
			(xy 79.682954 -31.801361) (xy 79.645737 -31.842898) (xy 79.602869 -31.878573) (xy 79.555263 -31.907627)
			(xy 79.503934 -31.929439) (xy 79.449977 -31.943545) (xy 79.39454 -31.949645) (xy 79.338806 -31.947608)
			(xy 79.283963 -31.937478) (xy 79.231179 -31.919471) (xy 79.181579 -31.89397) (xy 79.136221 -31.861519)
			(xy 79.096072 -31.82281) (xy 79.061986 -31.778667) (xy 79.03469 -31.730032) (xy 79.014767 -31.677941)
			(xy 79.002641 -31.623504) (xy 78.99857 -31.567882) (xy 71.664872 -31.567882) (xy 71.686356 -31.595881)
			(xy 71.71634 -31.647815) (xy 71.739289 -31.703219) (xy 71.75481 -31.761144) (xy 71.762638 -31.8206)
			(xy 71.763128 -31.850584) (xy 71.763128 -32.714184) (xy 71.762638 -32.744168) (xy 71.75481 -32.803624)
			(xy 71.739289 -32.861549) (xy 71.71634 -32.916953) (xy 71.686356 -32.968887) (xy 71.64985 -33.016463)
			(xy 71.607445 -33.058868) (xy 71.559869 -33.095374) (xy 71.507935 -33.125358) (xy 71.452531 -33.148307)
			(xy 71.394606 -33.163828) (xy 71.33515 -33.171656) (xy 71.275182 -33.171656) (xy 71.215726 -33.163828)
			(xy 71.157801 -33.148307) (xy 71.102397 -33.125358) (xy 71.050463 -33.095374) (xy 71.002887 -33.058868)
			(xy 70.960482 -33.016463) (xy 70.923976 -32.968887) (xy 70.893992 -32.916953) (xy 70.871043 -32.861549)
			(xy 70.855522 -32.803624) (xy 70.847694 -32.744168) (xy 70.847204 -32.714184) (xy 66.363384 -32.714184)
			(xy 66.412618 -32.832802) (xy 66.414245 -32.836438) (xy 66.418456 -32.843199) (xy 66.421 -32.846264)
			(xy 66.425826 -32.852106) (xy 66.434462 -32.856932) (xy 66.459428 -32.871452) (xy 66.505066 -32.906844)
			(xy 66.544849 -32.948709) (xy 66.577871 -32.99609) (xy 66.603376 -33.047907) (xy 66.620782 -33.102974)
			(xy 66.629692 -33.160036) (xy 66.630296 -33.18891) (xy 66.630296 -33.192974) (xy 66.629534 -33.215834)
			(xy 66.629534 -33.216342) (xy 66.628158 -33.233161) (xy 66.622818 -33.266484) (xy 66.618866 -33.28289)
			(xy 66.617342 -33.288986) (xy 66.614802 -33.299908) (xy 66.61404 -33.307782) (xy 66.614802 -33.320482)
			(xy 67.111874 -34.520886) (xy 73.489312 -34.520886) (xy 73.489312 -33.657286) (xy 73.489802 -33.627302)
			(xy 73.49763 -33.567846) (xy 73.513151 -33.509921) (xy 73.5361 -33.454517) (xy 73.566084 -33.402583)
			(xy 73.60259 -33.355007) (xy 73.644995 -33.312602) (xy 73.692571 -33.276096) (xy 73.744505 -33.246112)
			(xy 73.799909 -33.223163) (xy 73.857834 -33.207642) (xy 73.91729 -33.199814) (xy 73.977258 -33.199814)
			(xy 74.036714 -33.207642) (xy 74.094639 -33.223163) (xy 74.150043 -33.246112) (xy 74.201977 -33.276096)
			(xy 74.249553 -33.312602) (xy 74.291958 -33.355007) (xy 74.328464 -33.402583) (xy 74.358448 -33.454517)
			(xy 74.381397 -33.509921) (xy 74.396918 -33.567846) (xy 74.404746 -33.627302) (xy 74.405236 -33.657286)
			(xy 74.405236 -34.520886) (xy 74.404746 -34.55087) (xy 74.396918 -34.610326) (xy 74.381397 -34.668251)
			(xy 74.358448 -34.723655) (xy 74.328464 -34.775589) (xy 74.291958 -34.823165) (xy 74.249553 -34.86557)
			(xy 74.201977 -34.902076) (xy 74.150043 -34.93206) (xy 74.094639 -34.955009) (xy 74.036714 -34.97053)
			(xy 73.977258 -34.978358) (xy 73.91729 -34.978358) (xy 73.857834 -34.97053) (xy 73.799909 -34.955009)
			(xy 73.744505 -34.93206) (xy 73.692571 -34.902076) (xy 73.644995 -34.86557) (xy 73.60259 -34.823165)
			(xy 73.566084 -34.775589) (xy 73.5361 -34.723655) (xy 73.513151 -34.668251) (xy 73.49763 -34.610326)
			(xy 73.489802 -34.55087) (xy 73.489312 -34.520886) (xy 67.111874 -34.520886) (xy 67.403218 -35.224466)
			(xy 67.419945 -35.264852) (xy 81.902298 -35.264852) (xy 81.906369 -35.20923) (xy 81.918495 -35.154793)
			(xy 81.938418 -35.102702) (xy 81.965714 -35.054067) (xy 81.9998 -35.009924) (xy 82.039949 -34.971215)
			(xy 82.085307 -34.938764) (xy 82.134907 -34.913263) (xy 82.187691 -34.895256) (xy 82.242534 -34.885126)
			(xy 82.298268 -34.883089) (xy 82.353705 -34.889189) (xy 82.407662 -34.903295) (xy 82.458991 -34.925107)
			(xy 82.506597 -34.954161) (xy 82.549465 -34.989836) (xy 82.586682 -35.031373) (xy 82.617455 -35.077886)
			(xy 82.641127 -35.128383) (xy 82.657195 -35.18179) (xy 82.665315 -35.236966) (xy 82.665824 -35.264852)
			(xy 82.665315 -35.292738) (xy 82.657195 -35.347914) (xy 82.641127 -35.401321) (xy 82.617455 -35.451818)
			(xy 82.586682 -35.498331) (xy 82.549465 -35.539868) (xy 82.506597 -35.575543) (xy 82.458991 -35.604597)
			(xy 82.407662 -35.626409) (xy 82.353705 -35.640515) (xy 82.298268 -35.646615) (xy 82.242534 -35.644578)
			(xy 82.187691 -35.634448) (xy 82.134907 -35.616441) (xy 82.085307 -35.59094) (xy 82.039949 -35.558489)
			(xy 81.9998 -35.51978) (xy 81.965714 -35.475637) (xy 81.938418 -35.427002) (xy 81.918495 -35.374911)
			(xy 81.906369 -35.320474) (xy 81.902298 -35.264852) (xy 67.419945 -35.264852) (xy 67.673378 -35.876738)
			(xy 70.717154 -35.876738) (xy 70.721225 -35.821116) (xy 70.733351 -35.766679) (xy 70.753274 -35.714588)
			(xy 70.78057 -35.665953) (xy 70.814656 -35.62181) (xy 70.854805 -35.583101) (xy 70.900163 -35.55065)
			(xy 70.949763 -35.525149) (xy 71.002547 -35.507142) (xy 71.05739 -35.497012) (xy 71.113124 -35.494975)
			(xy 71.168561 -35.501075) (xy 71.222518 -35.515181) (xy 71.273847 -35.536993) (xy 71.321453 -35.566047)
			(xy 71.364321 -35.601722) (xy 71.401538 -35.643259) (xy 71.432311 -35.689772) (xy 71.455983 -35.740269)
			(xy 71.472051 -35.793676) (xy 71.480171 -35.848852) (xy 71.48068 -35.876738) (xy 74.788774 -35.876738)
			(xy 74.792845 -35.821116) (xy 74.804971 -35.766679) (xy 74.824894 -35.714588) (xy 74.85219 -35.665953)
			(xy 74.886276 -35.62181) (xy 74.926425 -35.583101) (xy 74.971783 -35.55065) (xy 75.021383 -35.525149)
			(xy 75.074167 -35.507142) (xy 75.12901 -35.497012) (xy 75.184744 -35.494975) (xy 75.240181 -35.501075)
			(xy 75.294138 -35.515181) (xy 75.345467 -35.536993) (xy 75.393073 -35.566047) (xy 75.435941 -35.601722)
			(xy 75.473158 -35.643259) (xy 75.503931 -35.689772) (xy 75.527603 -35.740269) (xy 75.543671 -35.793676)
			(xy 75.551791 -35.848852) (xy 75.5523 -35.876738) (xy 75.551791 -35.904624) (xy 75.543671 -35.9598)
			(xy 75.527603 -36.013207) (xy 75.503931 -36.063704) (xy 75.473158 -36.110217) (xy 75.435941 -36.151754)
			(xy 75.393073 -36.187429) (xy 75.345467 -36.216483) (xy 75.294138 -36.238295) (xy 75.240181 -36.252401)
			(xy 75.184744 -36.258501) (xy 75.12901 -36.256464) (xy 75.074167 -36.246334) (xy 75.021383 -36.228327)
			(xy 74.971783 -36.202826) (xy 74.926425 -36.170375) (xy 74.886276 -36.131666) (xy 74.85219 -36.087523)
			(xy 74.824894 -36.038888) (xy 74.804971 -35.986797) (xy 74.792845 -35.93236) (xy 74.788774 -35.876738)
			(xy 71.48068 -35.876738) (xy 71.480171 -35.904624) (xy 71.472051 -35.9598) (xy 71.455983 -36.013207)
			(xy 71.432311 -36.063704) (xy 71.401538 -36.110217) (xy 71.364321 -36.151754) (xy 71.321453 -36.187429)
			(xy 71.273847 -36.216483) (xy 71.222518 -36.238295) (xy 71.168561 -36.252401) (xy 71.113124 -36.258501)
			(xy 71.05739 -36.256464) (xy 71.002547 -36.246334) (xy 70.949763 -36.228327) (xy 70.900163 -36.202826)
			(xy 70.854805 -36.170375) (xy 70.814656 -36.131666) (xy 70.78057 -36.087523) (xy 70.753274 -36.038888)
			(xy 70.733351 -35.986797) (xy 70.721225 -35.93236) (xy 70.717154 -35.876738) (xy 67.673378 -35.876738)
			(xy 67.935647 -36.50996) (xy 72.613772 -36.50996) (xy 72.617843 -36.454338) (xy 72.629969 -36.399901)
			(xy 72.649892 -36.34781) (xy 72.677188 -36.299175) (xy 72.711274 -36.255032) (xy 72.751423 -36.216323)
			(xy 72.796781 -36.183872) (xy 72.846381 -36.158371) (xy 72.899165 -36.140364) (xy 72.954008 -36.130234)
			(xy 73.009742 -36.128197) (xy 73.065179 -36.134297) (xy 73.119136 -36.148403) (xy 73.170465 -36.170215)
			(xy 73.218071 -36.199269) (xy 73.260939 -36.234944) (xy 73.298156 -36.276481) (xy 73.328929 -36.322994)
			(xy 73.352601 -36.373491) (xy 73.368669 -36.426898) (xy 73.372594 -36.453572) (xy 75.928472 -36.453572)
			(xy 75.932543 -36.39795) (xy 75.944669 -36.343513) (xy 75.964592 -36.291422) (xy 75.991888 -36.242787)
			(xy 76.025974 -36.198644) (xy 76.066123 -36.159935) (xy 76.111481 -36.127484) (xy 76.161081 -36.101983)
			(xy 76.213865 -36.083976) (xy 76.268708 -36.073846) (xy 76.324442 -36.071809) (xy 76.379879 -36.077909)
			(xy 76.433836 -36.092015) (xy 76.485165 -36.113827) (xy 76.532771 -36.142881) (xy 76.575639 -36.178556)
			(xy 76.612856 -36.220093) (xy 76.643629 -36.266606) (xy 76.653165 -36.286948) (xy 83.200238 -36.286948)
			(xy 83.204309 -36.231326) (xy 83.216435 -36.176889) (xy 83.236358 -36.124798) (xy 83.263654 -36.076163)
			(xy 83.29774 -36.03202) (xy 83.337889 -35.993311) (xy 83.383247 -35.96086) (xy 83.432847 -35.935359)
			(xy 83.485631 -35.917352) (xy 83.540474 -35.907222) (xy 83.596208 -35.905185) (xy 83.651645 -35.911285)
			(xy 83.705602 -35.925391) (xy 83.756931 -35.947203) (xy 83.804537 -35.976257) (xy 83.847405 -36.011932)
			(xy 83.884622 -36.053469) (xy 83.915395 -36.099982) (xy 83.939067 -36.150479) (xy 83.955135 -36.203886)
			(xy 83.963255 -36.259062) (xy 83.963764 -36.286948) (xy 83.963255 -36.314834) (xy 83.955135 -36.37001)
			(xy 83.939067 -36.423417) (xy 83.915395 -36.473914) (xy 83.884622 -36.520427) (xy 83.847405 -36.561964)
			(xy 83.804537 -36.597639) (xy 83.756931 -36.626693) (xy 83.705602 -36.648505) (xy 83.651645 -36.662611)
			(xy 83.596208 -36.668711) (xy 83.540474 -36.666674) (xy 83.485631 -36.656544) (xy 83.432847 -36.638537)
			(xy 83.383247 -36.613036) (xy 83.337889 -36.580585) (xy 83.29774 -36.541876) (xy 83.263654 -36.497733)
			(xy 83.236358 -36.449098) (xy 83.216435 -36.397007) (xy 83.204309 -36.34257) (xy 83.200238 -36.286948)
			(xy 76.653165 -36.286948) (xy 76.667301 -36.317103) (xy 76.683369 -36.37051) (xy 76.691489 -36.425686)
			(xy 76.691998 -36.453572) (xy 76.691489 -36.481458) (xy 76.683369 -36.536634) (xy 76.667301 -36.590041)
			(xy 76.643629 -36.640538) (xy 76.612856 -36.687051) (xy 76.575639 -36.728588) (xy 76.532771 -36.764263)
			(xy 76.485165 -36.793317) (xy 76.433836 -36.815129) (xy 76.379879 -36.829235) (xy 76.324442 -36.835335)
			(xy 76.268708 -36.833298) (xy 76.213865 -36.823168) (xy 76.161081 -36.805161) (xy 76.111481 -36.77966)
			(xy 76.066123 -36.747209) (xy 76.025974 -36.7085) (xy 75.991888 -36.664357) (xy 75.964592 -36.615722)
			(xy 75.944669 -36.563631) (xy 75.932543 -36.509194) (xy 75.928472 -36.453572) (xy 73.372594 -36.453572)
			(xy 73.376789 -36.482074) (xy 73.377298 -36.50996) (xy 73.376789 -36.537846) (xy 73.368669 -36.593022)
			(xy 73.352601 -36.646429) (xy 73.328929 -36.696926) (xy 73.298156 -36.743439) (xy 73.260939 -36.784976)
			(xy 73.218071 -36.820651) (xy 73.170465 -36.849705) (xy 73.119136 -36.871517) (xy 73.065179 -36.885623)
			(xy 73.009742 -36.891723) (xy 72.954008 -36.889686) (xy 72.899165 -36.879556) (xy 72.846381 -36.861549)
			(xy 72.796781 -36.836048) (xy 72.751423 -36.803597) (xy 72.711274 -36.764888) (xy 72.677188 -36.720745)
			(xy 72.649892 -36.67211) (xy 72.629969 -36.620019) (xy 72.617843 -36.565582) (xy 72.613772 -36.50996)
			(xy 67.935647 -36.50996) (xy 68.17614 -37.090604) (xy 68.190204 -37.125598) (xy 68.213597 -37.197305)
			(xy 68.222876 -37.23386) (xy 68.223638 -37.236654) (xy 68.2244 -37.239194) (xy 68.23329 -37.260022)
			(xy 68.23329 -37.26053) (xy 68.244974 -37.28847) (xy 68.245228 -37.28847) (xy 68.250308 -37.300662)
			(xy 68.250308 -37.30117) (xy 68.26902 -37.347187) (xy 68.29829 -37.442121) (xy 68.304972 -37.47516)
			(xy 69.759066 -37.47516) (xy 69.763137 -37.419538) (xy 69.775263 -37.365101) (xy 69.795186 -37.31301)
			(xy 69.822482 -37.264375) (xy 69.856568 -37.220232) (xy 69.896717 -37.181523) (xy 69.942075 -37.149072)
			(xy 69.991675 -37.123571) (xy 70.044459 -37.105564) (xy 70.099302 -37.095434) (xy 70.155036 -37.093397)
			(xy 70.210473 -37.099497) (xy 70.26443 -37.113603) (xy 70.315759 -37.135415) (xy 70.363365 -37.164469)
			(xy 70.406233 -37.200144) (xy 70.44345 -37.241681) (xy 70.474223 -37.288194) (xy 70.497895 -37.338691)
			(xy 70.513963 -37.392098) (xy 70.522083 -37.447274) (xy 70.522592 -37.47516) (xy 70.522083 -37.503046)
			(xy 70.513963 -37.558222) (xy 70.497895 -37.611629) (xy 70.474223 -37.662126) (xy 70.47407 -37.662358)
			(xy 71.948292 -37.662358) (xy 71.952363 -37.606736) (xy 71.964489 -37.552299) (xy 71.984412 -37.500208)
			(xy 72.011708 -37.451573) (xy 72.045794 -37.40743) (xy 72.085943 -37.368721) (xy 72.131301 -37.33627)
			(xy 72.180901 -37.310769) (xy 72.233685 -37.292762) (xy 72.288528 -37.282632) (xy 72.344262 -37.280595)
			(xy 72.399699 -37.286695) (xy 72.453656 -37.300801) (xy 72.504985 -37.322613) (xy 72.552591 -37.351667)
			(xy 72.595459 -37.387342) (xy 72.632676 -37.428879) (xy 72.663449 -37.475392) (xy 72.687121 -37.525889)
			(xy 72.703189 -37.579296) (xy 72.711309 -37.634472) (xy 72.711818 -37.662358) (xy 72.711309 -37.690244)
			(xy 72.703189 -37.74542) (xy 72.694555 -37.774118) (xy 83.464652 -37.774118) (xy 83.468723 -37.718496)
			(xy 83.480849 -37.664059) (xy 83.500772 -37.611968) (xy 83.528068 -37.563333) (xy 83.562154 -37.51919)
			(xy 83.602303 -37.480481) (xy 83.647661 -37.44803) (xy 83.697261 -37.422529) (xy 83.750045 -37.404522)
			(xy 83.804888 -37.394392) (xy 83.860622 -37.392355) (xy 83.916059 -37.398455) (xy 83.970016 -37.412561)
			(xy 84.021345 -37.434373) (xy 84.068951 -37.463427) (xy 84.111819 -37.499102) (xy 84.149036 -37.540639)
			(xy 84.179809 -37.587152) (xy 84.203481 -37.637649) (xy 84.219549 -37.691056) (xy 84.227669 -37.746232)
			(xy 84.228178 -37.774118) (xy 84.227669 -37.802004) (xy 84.219549 -37.85718) (xy 84.203481 -37.910587)
			(xy 84.179809 -37.961084) (xy 84.149036 -38.007597) (xy 84.111819 -38.049134) (xy 84.068951 -38.084809)
			(xy 84.021345 -38.113863) (xy 83.970016 -38.135675) (xy 83.916059 -38.149781) (xy 83.860622 -38.155881)
			(xy 83.804888 -38.153844) (xy 83.750045 -38.143714) (xy 83.697261 -38.125707) (xy 83.647661 -38.100206)
			(xy 83.602303 -38.067755) (xy 83.562154 -38.029046) (xy 83.528068 -37.984903) (xy 83.500772 -37.936268)
			(xy 83.480849 -37.884177) (xy 83.468723 -37.82974) (xy 83.464652 -37.774118) (xy 72.694555 -37.774118)
			(xy 72.687121 -37.798827) (xy 72.663449 -37.849324) (xy 72.632676 -37.895837) (xy 72.595459 -37.937374)
			(xy 72.552591 -37.973049) (xy 72.504985 -38.002103) (xy 72.453656 -38.023915) (xy 72.399699 -38.038021)
			(xy 72.344262 -38.044121) (xy 72.288528 -38.042084) (xy 72.233685 -38.031954) (xy 72.180901 -38.013947)
			(xy 72.131301 -37.988446) (xy 72.085943 -37.955995) (xy 72.045794 -37.917286) (xy 72.011708 -37.873143)
			(xy 71.984412 -37.824508) (xy 71.964489 -37.772417) (xy 71.952363 -37.71798) (xy 71.948292 -37.662358)
			(xy 70.47407 -37.662358) (xy 70.44345 -37.708639) (xy 70.406233 -37.750176) (xy 70.363365 -37.785851)
			(xy 70.315759 -37.814905) (xy 70.26443 -37.836717) (xy 70.210473 -37.850823) (xy 70.155036 -37.856923)
			(xy 70.099302 -37.854886) (xy 70.044459 -37.844756) (xy 69.991675 -37.826749) (xy 69.942075 -37.801248)
			(xy 69.896717 -37.768797) (xy 69.856568 -37.730088) (xy 69.822482 -37.685945) (xy 69.795186 -37.63731)
			(xy 69.775263 -37.585219) (xy 69.763137 -37.530782) (xy 69.759066 -37.47516) (xy 68.304972 -37.47516)
			(xy 68.317982 -37.539493) (xy 68.327902 -37.63834) (xy 68.32854 -37.688012) (xy 68.32854 -37.704522)
			(xy 68.32854 -37.705538) (xy 68.311544 -38.729948) (xy 75.70092 -38.729948) (xy 75.70092 -38.675452)
			(xy 75.708676 -38.621511) (xy 75.724028 -38.569223) (xy 75.746666 -38.519652) (xy 75.776128 -38.473807)
			(xy 75.811815 -38.432622) (xy 75.852999 -38.396934) (xy 75.898843 -38.367471) (xy 75.948414 -38.344832)
			(xy 76.000702 -38.329478) (xy 76.054642 -38.321721) (xy 76.08189 -38.321234) (xy 76.110195 -38.321716)
			(xy 76.166184 -38.330067) (xy 76.220324 -38.346603) (xy 76.271425 -38.370959) (xy 76.318365 -38.402601)
			(xy 76.360112 -38.440834) (xy 76.395749 -38.484818) (xy 76.410566 -38.50894) (xy 76.418111 -38.521011)
			(xy 76.438741 -38.540615) (xy 76.463984 -38.553756) (xy 76.491876 -38.559412) (xy 76.520244 -38.557141)
			(xy 76.54688 -38.54712) (xy 76.569711 -38.53013) (xy 76.578714 -38.5191) (xy 76.596897 -38.496221)
			(xy 76.639061 -38.455758) (xy 76.686897 -38.42219) (xy 76.73929 -38.396304) (xy 76.795015 -38.378702)
			(xy 76.852771 -38.369797) (xy 76.88199 -38.36924) (xy 76.909247 -38.369606) (xy 76.963206 -38.377363)
			(xy 77.015511 -38.39272) (xy 77.065099 -38.415365) (xy 77.110959 -38.444836) (xy 77.152158 -38.480535)
			(xy 77.187858 -38.521733) (xy 77.21733 -38.567592) (xy 77.239976 -38.617179) (xy 77.255335 -38.669485)
			(xy 77.263093 -38.723443) (xy 77.263093 -38.777957) (xy 77.255335 -38.831915) (xy 77.239976 -38.884221)
			(xy 77.21733 -38.933808) (xy 77.187858 -38.979667) (xy 77.152158 -39.020865) (xy 77.110959 -39.056564)
			(xy 77.065099 -39.086035) (xy 77.015511 -39.10868) (xy 76.963206 -39.124037) (xy 76.909247 -39.131794)
			(xy 76.88199 -39.132256) (xy 76.853685 -39.131795) (xy 76.797694 -39.12344) (xy 76.743553 -39.106902)
			(xy 76.692452 -39.082542) (xy 76.645512 -39.050896) (xy 76.603766 -39.01266) (xy 76.56813 -38.968674)
			(xy 76.553314 -38.94455) (xy 76.545665 -38.932552) (xy 76.525056 -38.912954) (xy 76.499835 -38.899812)
			(xy 76.471965 -38.894149) (xy 76.443615 -38.896405) (xy 76.416992 -38.906406) (xy 76.394168 -38.923372)
			(xy 76.385166 -38.93439) (xy 76.366991 -38.957276) (xy 76.324827 -38.99774) (xy 76.276988 -39.031306)
			(xy 76.224594 -39.057192) (xy 76.168868 -39.074792) (xy 76.11111 -39.083695) (xy 76.08189 -39.08425)
			(xy 76.054642 -39.083679) (xy 76.000702 -39.075922) (xy 75.948414 -39.060568) (xy 75.898843 -39.037929)
			(xy 75.852999 -39.008466) (xy 75.811815 -38.972778) (xy 75.776128 -38.931593) (xy 75.746666 -38.885748)
			(xy 75.724028 -38.836177) (xy 75.708676 -38.783889) (xy 75.70092 -38.729948) (xy 68.311544 -38.729948)
			(xy 68.308982 -38.884352) (xy 68.303902 -39.186104) (xy 68.302544 -39.233452) (xy 68.291983 -39.327591)
			(xy 68.28282 -39.374064) (xy 68.235068 -39.60241) (xy 68.157585 -39.97198) (xy 77.895702 -39.97198)
			(xy 77.899773 -39.916358) (xy 77.911899 -39.861921) (xy 77.931822 -39.80983) (xy 77.959118 -39.761195)
			(xy 77.993204 -39.717052) (xy 78.033353 -39.678343) (xy 78.078711 -39.645892) (xy 78.128311 -39.620391)
			(xy 78.181095 -39.602384) (xy 78.235938 -39.592254) (xy 78.291672 -39.590217) (xy 78.347109 -39.596317)
			(xy 78.401066 -39.610423) (xy 78.452395 -39.632235) (xy 78.500001 -39.661289) (xy 78.542869 -39.696964)
			(xy 78.580086 -39.738501) (xy 78.610859 -39.785014) (xy 78.634531 -39.835511) (xy 78.650599 -39.888918)
			(xy 78.658719 -39.944094) (xy 78.659228 -39.97198) (xy 78.658719 -39.999866) (xy 78.650599 -40.055042)
			(xy 78.634531 -40.108449) (xy 78.610859 -40.158946) (xy 78.580086 -40.205459) (xy 78.542869 -40.246996)
			(xy 78.500001 -40.282671) (xy 78.452395 -40.311725) (xy 78.401066 -40.333537) (xy 78.347109 -40.347643)
			(xy 78.291672 -40.353743) (xy 78.235938 -40.351706) (xy 78.181095 -40.341576) (xy 78.128311 -40.323569)
			(xy 78.078711 -40.298068) (xy 78.033353 -40.265617) (xy 77.993204 -40.226908) (xy 77.959118 -40.182765)
			(xy 77.931822 -40.13413) (xy 77.911899 -40.082039) (xy 77.899773 -40.027602) (xy 77.895702 -39.97198)
			(xy 68.157585 -39.97198) (xy 68.151248 -40.002206) (xy 67.993514 -40.756078) (xy 67.991685 -40.767636)
			(xy 67.997509 -40.790273) (xy 68.00469 -40.799512) (xy 68.0085 -40.803576) (xy 68.072 -40.862758)
			(xy 68.078638 -40.868508) (xy 68.094737 -40.875492) (xy 68.112252 -40.876582) (xy 68.120768 -40.874442)
			(xy 68.146269 -40.867674) (xy 68.198528 -40.86041) (xy 68.224908 -40.859964) (xy 68.253646 -40.860486)
			(xy 68.310473 -40.869111) (xy 68.365361 -40.886164) (xy 68.41707 -40.91126) (xy 68.464428 -40.943829)
			(xy 68.485766 -40.963088) (xy 68.48602 -40.963342) (xy 68.49 -40.966818) (xy 68.499089 -40.972202)
			(xy 68.504054 -40.97401) (xy 68.508061 -40.975296) (xy 68.516357 -40.976704) (xy 68.520564 -40.976804)
			(xy 68.589652 -40.976804) (xy 68.593862 -40.976727) (xy 68.602164 -40.975331) (xy 68.606162 -40.97401)
			(xy 68.61112 -40.972186) (xy 68.620208 -40.966807) (xy 68.624196 -40.963342) (xy 68.62445 -40.963088)
			(xy 68.645778 -40.943819) (xy 68.693141 -40.911258) (xy 68.744853 -40.88617) (xy 68.799743 -40.869123)
			(xy 68.85657 -40.860502) (xy 68.885308 -40.859964) (xy 68.912561 -40.86045) (xy 68.966512 -40.868208)
			(xy 69.018809 -40.883565) (xy 69.068389 -40.906209) (xy 69.114242 -40.935677) (xy 69.155434 -40.971371)
			(xy 69.191128 -41.012564) (xy 69.220595 -41.058418) (xy 69.243237 -41.107998) (xy 69.258593 -41.160296)
			(xy 69.26635 -41.214247) (xy 69.26635 -41.268753) (xy 69.258593 -41.322704) (xy 69.243237 -41.375002)
			(xy 69.220595 -41.424582) (xy 69.191128 -41.470436) (xy 69.155434 -41.511629) (xy 69.114242 -41.547323)
			(xy 69.068389 -41.576791) (xy 69.018809 -41.599435) (xy 68.966512 -41.614792) (xy 68.912561 -41.62255)
			(xy 68.885308 -41.62298) (xy 68.856569 -41.62246) (xy 68.799741 -41.613838) (xy 68.744849 -41.596788)
			(xy 68.693137 -41.571696) (xy 68.645775 -41.53913) (xy 68.62445 -41.519856) (xy 68.624196 -41.519602)
			(xy 68.620214 -41.51613) (xy 68.611121 -41.510755) (xy 68.606162 -41.508934) (xy 68.602155 -41.507648)
			(xy 68.593859 -41.506239) (xy 68.589652 -41.50614) (xy 68.520564 -41.50614) (xy 68.516356 -41.506224)
			(xy 68.508058 -41.507635) (xy 68.504054 -41.508934) (xy 68.499094 -41.510754) (xy 68.49 -41.516127)
			(xy 68.48602 -41.519602) (xy 68.485766 -41.519856) (xy 68.464438 -41.539124) (xy 68.417073 -41.571683)
			(xy 68.365361 -41.596771) (xy 68.310472 -41.613818) (xy 68.253646 -41.62244) (xy 68.224908 -41.62298)
			(xy 68.19864 -41.622541) (xy 68.146602 -41.615329) (xy 68.096046 -41.601041) (xy 68.047931 -41.579948)
			(xy 68.003167 -41.552448) (xy 67.982592 -41.536112) (xy 67.982084 -41.535604) (xy 67.98183 -41.535604)
			(xy 67.976727 -41.531664) (xy 67.965026 -41.52626) (xy 67.958716 -41.524936) (xy 67.952366 -41.52392)
			(xy 67.939412 -41.524936) (xy 67.85102 -41.555924) (xy 67.842957 -41.559146) (xy 67.829466 -41.570059)
			(xy 67.820386 -41.584846) (xy 67.818254 -41.593262) (xy 67.514978 -43.041062) (xy 67.459707 -43.305222)
			(xy 70.3072 -43.305222) (xy 70.307679 -43.277852) (xy 70.315494 -43.223674) (xy 70.33098 -43.171171)
			(xy 70.353819 -43.121424) (xy 70.38354 -43.075456) (xy 70.40118 -43.054524) (xy 70.401434 -43.05427)
			(xy 70.407001 -43.04717) (xy 70.413258 -43.030263) (xy 70.413626 -43.02125) (xy 70.413626 -42.954194)
			(xy 70.413266 -42.945178) (xy 70.40702 -42.928261) (xy 70.401434 -42.921174) (xy 70.40118 -42.921174)
			(xy 70.40118 -42.92092) (xy 70.383534 -42.899994) (xy 70.353824 -42.854019) (xy 70.330989 -42.80427)
			(xy 70.3155 -42.751768) (xy 70.307673 -42.697592) (xy 70.3072 -42.670222) (xy 70.307737 -42.641484)
			(xy 70.316356 -42.584657) (xy 70.333403 -42.529766) (xy 70.358492 -42.478054) (xy 70.391054 -42.430691)
			(xy 70.410324 -42.409364) (xy 70.416928 -42.402506) (xy 70.42404 -42.384472) (xy 70.42404 -42.295572)
			(xy 70.416928 -42.277538) (xy 70.410324 -42.27068) (xy 70.391075 -42.249334) (xy 70.358509 -42.201975)
			(xy 70.333416 -42.150266) (xy 70.316365 -42.095379) (xy 70.30774 -42.038554) (xy 70.307738 -41.981078)
			(xy 70.316357 -41.924253) (xy 70.333404 -41.869364) (xy 70.358493 -41.817653) (xy 70.391055 -41.770291)
			(xy 70.410324 -41.748964) (xy 70.416928 -41.742106) (xy 70.42404 -41.724072) (xy 70.42404 -41.635172)
			(xy 70.416928 -41.617138) (xy 70.410324 -41.61028) (xy 70.391061 -41.588946) (xy 70.358494 -41.541586)
			(xy 70.333401 -41.489876) (xy 70.316348 -41.434987) (xy 70.307723 -41.37816) (xy 70.3072 -41.349422)
			(xy 70.307686 -41.322171) (xy 70.315442 -41.268223) (xy 70.330797 -41.215928) (xy 70.353439 -41.166351)
			(xy 70.382905 -41.120501) (xy 70.418596 -41.07931) (xy 70.459787 -41.043619) (xy 70.505637 -41.014153)
			(xy 70.555214 -40.991511) (xy 70.607509 -40.976156) (xy 70.661457 -40.9684) (xy 70.715959 -40.9684)
			(xy 70.73908 -40.971724) (xy 78.593948 -40.971724) (xy 78.598019 -40.916102) (xy 78.610145 -40.861665)
			(xy 78.630068 -40.809574) (xy 78.657364 -40.760939) (xy 78.69145 -40.716796) (xy 78.731599 -40.678087)
			(xy 78.776957 -40.645636) (xy 78.826557 -40.620135) (xy 78.879341 -40.602128) (xy 78.934184 -40.591998)
			(xy 78.989918 -40.589961) (xy 79.045355 -40.596061) (xy 79.099312 -40.610167) (xy 79.150641 -40.631979)
			(xy 79.198247 -40.661033) (xy 79.241115 -40.696708) (xy 79.278332 -40.738245) (xy 79.309105 -40.784758)
			(xy 79.332777 -40.835255) (xy 79.348845 -40.888662) (xy 79.356965 -40.943838) (xy 79.357474 -40.971724)
			(xy 79.356965 -40.99961) (xy 79.348845 -41.054786) (xy 79.332777 -41.108193) (xy 79.309105 -41.15869)
			(xy 79.278332 -41.205203) (xy 79.241115 -41.24674) (xy 79.198247 -41.282415) (xy 79.150641 -41.311469)
			(xy 79.099312 -41.333281) (xy 79.045355 -41.347387) (xy 78.989918 -41.353487) (xy 78.934184 -41.35145)
			(xy 78.879341 -41.34132) (xy 78.826557 -41.323313) (xy 78.776957 -41.297812) (xy 78.731599 -41.265361)
			(xy 78.69145 -41.226652) (xy 78.657364 -41.182509) (xy 78.630068 -41.133874) (xy 78.610145 -41.081783)
			(xy 78.598019 -41.027346) (xy 78.593948 -40.971724) (xy 70.73908 -40.971724) (xy 70.769907 -40.976156)
			(xy 70.822202 -40.991511) (xy 70.871779 -41.014153) (xy 70.917629 -41.043619) (xy 70.95882 -41.07931)
			(xy 70.994511 -41.120501) (xy 71.023977 -41.166351) (xy 71.046619 -41.215928) (xy 71.061974 -41.268223)
			(xy 71.06973 -41.322171) (xy 71.070216 -41.349422) (xy 71.069701 -41.378161) (xy 71.061076 -41.434989)
			(xy 71.044023 -41.489879) (xy 71.01893 -41.541591) (xy 70.986363 -41.588953) (xy 70.967092 -41.61028)
			(xy 70.960488 -41.617138) (xy 70.953376 -41.635172) (xy 70.953376 -41.724072) (xy 70.960488 -41.742106)
			(xy 70.967092 -41.748964) (xy 70.986384 -41.770272) (xy 71.018947 -41.817638) (xy 71.044036 -41.869353)
			(xy 71.061084 -41.924247) (xy 71.069704 -41.981076) (xy 71.069702 -42.038556) (xy 71.061077 -42.095385)
			(xy 71.044025 -42.150277) (xy 71.018931 -42.201989) (xy 70.986364 -42.249353) (xy 70.967092 -42.27068)
			(xy 70.960488 -42.277538) (xy 70.953376 -42.295572) (xy 70.953376 -42.384472) (xy 70.960488 -42.402506)
			(xy 70.967092 -42.409364) (xy 70.986378 -42.430678) (xy 71.018941 -42.478044) (xy 71.04403 -42.529759)
			(xy 71.061077 -42.584652) (xy 71.069697 -42.641482) (xy 71.070216 -42.670222) (xy 71.069783 -42.697594)
			(xy 71.061961 -42.751775) (xy 71.046465 -42.804279) (xy 71.025906 -42.849038) (xy 72.891902 -42.849038)
			(xy 72.895973 -42.793416) (xy 72.908099 -42.738979) (xy 72.928022 -42.686888) (xy 72.955318 -42.638253)
			(xy 72.989404 -42.59411) (xy 73.029553 -42.555401) (xy 73.074911 -42.52295) (xy 73.124511 -42.497449)
			(xy 73.177295 -42.479442) (xy 73.232138 -42.469312) (xy 73.287872 -42.467275) (xy 73.343309 -42.473375)
			(xy 73.397266 -42.487481) (xy 73.448595 -42.509293) (xy 73.496201 -42.538347) (xy 73.539069 -42.574022)
			(xy 73.576286 -42.615559) (xy 73.607059 -42.662072) (xy 73.630731 -42.712569) (xy 73.646799 -42.765976)
			(xy 73.654919 -42.821152) (xy 73.65528 -42.84091) (xy 78.933038 -42.84091) (xy 78.937109 -42.785288)
			(xy 78.949235 -42.730851) (xy 78.969158 -42.67876) (xy 78.996454 -42.630125) (xy 79.03054 -42.585982)
			(xy 79.070689 -42.547273) (xy 79.116047 -42.514822) (xy 79.165647 -42.489321) (xy 79.218431 -42.471314)
			(xy 79.273274 -42.461184) (xy 79.329008 -42.459147) (xy 79.384445 -42.465247) (xy 79.438402 -42.479353)
			(xy 79.489731 -42.501165) (xy 79.537337 -42.530219) (xy 79.580205 -42.565894) (xy 79.617422 -42.607431)
			(xy 79.648195 -42.653944) (xy 79.671867 -42.704441) (xy 79.687935 -42.757848) (xy 79.696055 -42.813024)
			(xy 79.696564 -42.84091) (xy 79.696055 -42.868796) (xy 79.687935 -42.923972) (xy 79.671867 -42.977379)
			(xy 79.648195 -43.027876) (xy 79.617422 -43.074389) (xy 79.580205 -43.115926) (xy 79.537337 -43.151601)
			(xy 79.489731 -43.180655) (xy 79.438402 -43.202467) (xy 79.384445 -43.216573) (xy 79.329008 -43.222673)
			(xy 79.273274 -43.220636) (xy 79.218431 -43.210506) (xy 79.165647 -43.192499) (xy 79.116047 -43.166998)
			(xy 79.070689 -43.134547) (xy 79.03054 -43.095838) (xy 78.996454 -43.051695) (xy 78.969158 -43.00306)
			(xy 78.949235 -42.950969) (xy 78.937109 -42.896532) (xy 78.933038 -42.84091) (xy 73.65528 -42.84091)
			(xy 73.655428 -42.849038) (xy 73.654919 -42.876924) (xy 73.646799 -42.9321) (xy 73.630731 -42.985507)
			(xy 73.607059 -43.036004) (xy 73.576286 -43.082517) (xy 73.539069 -43.124054) (xy 73.496201 -43.159729)
			(xy 73.448595 -43.188783) (xy 73.397266 -43.210595) (xy 73.343309 -43.224701) (xy 73.287872 -43.230801)
			(xy 73.232138 -43.228764) (xy 73.177295 -43.218634) (xy 73.124511 -43.200627) (xy 73.074911 -43.175126)
			(xy 73.029553 -43.142675) (xy 72.989404 -43.103966) (xy 72.955318 -43.059823) (xy 72.928022 -43.011188)
			(xy 72.908099 -42.959097) (xy 72.895973 -42.90466) (xy 72.891902 -42.849038) (xy 71.025906 -42.849038)
			(xy 71.023615 -42.854026) (xy 70.993882 -42.89999) (xy 70.976236 -42.92092) (xy 70.975982 -42.921174)
			(xy 70.970398 -42.928262) (xy 70.96415 -42.945178) (xy 70.96379 -42.954194) (xy 70.96379 -43.02125)
			(xy 70.964173 -43.030264) (xy 70.970403 -43.047181) (xy 70.975982 -43.05427) (xy 70.976236 -43.05427)
			(xy 70.976236 -43.054524) (xy 70.993859 -43.075469) (xy 71.023572 -43.121439) (xy 71.04641 -43.171183)
			(xy 71.061905 -43.223681) (xy 71.069739 -43.277854) (xy 71.070216 -43.305222) (xy 71.06973 -43.332473)
			(xy 71.061974 -43.386421) (xy 71.046619 -43.438716) (xy 71.023977 -43.488293) (xy 70.994511 -43.534143)
			(xy 70.95882 -43.575334) (xy 70.917629 -43.611025) (xy 70.871779 -43.640491) (xy 70.822202 -43.663133)
			(xy 70.769907 -43.678488) (xy 70.715959 -43.686244) (xy 70.661457 -43.686244) (xy 70.607509 -43.678488)
			(xy 70.555214 -43.663133) (xy 70.505637 -43.640491) (xy 70.459787 -43.611025) (xy 70.418596 -43.575334)
			(xy 70.382905 -43.534143) (xy 70.353439 -43.488293) (xy 70.330797 -43.438716) (xy 70.315442 -43.386421)
			(xy 70.307686 -43.332473) (xy 70.3072 -43.305222) (xy 67.459707 -43.305222) (xy 67.36952 -43.73626)
			(xy 72.21296 -43.73626) (xy 72.217031 -43.680638) (xy 72.229157 -43.626201) (xy 72.24908 -43.57411)
			(xy 72.276376 -43.525475) (xy 72.310462 -43.481332) (xy 72.350611 -43.442623) (xy 72.395969 -43.410172)
			(xy 72.445569 -43.384671) (xy 72.498353 -43.366664) (xy 72.553196 -43.356534) (xy 72.60893 -43.354497)
			(xy 72.664367 -43.360597) (xy 72.718324 -43.374703) (xy 72.769653 -43.396515) (xy 72.817259 -43.425569)
			(xy 72.860127 -43.461244) (xy 72.897344 -43.502781) (xy 72.928117 -43.549294) (xy 72.951789 -43.599791)
			(xy 72.967857 -43.653198) (xy 72.975977 -43.708374) (xy 72.976486 -43.73626) (xy 72.975977 -43.764146)
			(xy 72.967857 -43.819322) (xy 72.956548 -43.85691) (xy 76.719682 -43.85691) (xy 76.723753 -43.801288)
			(xy 76.735879 -43.746851) (xy 76.755802 -43.69476) (xy 76.783098 -43.646125) (xy 76.817184 -43.601982)
			(xy 76.857333 -43.563273) (xy 76.902691 -43.530822) (xy 76.952291 -43.505321) (xy 77.005075 -43.487314)
			(xy 77.059918 -43.477184) (xy 77.115652 -43.475147) (xy 77.171089 -43.481247) (xy 77.225046 -43.495353)
			(xy 77.276375 -43.517165) (xy 77.323981 -43.546219) (xy 77.366849 -43.581894) (xy 77.404066 -43.623431)
			(xy 77.434839 -43.669944) (xy 77.458511 -43.720441) (xy 77.474579 -43.773848) (xy 77.482699 -43.829024)
			(xy 77.483208 -43.85691) (xy 77.482699 -43.884796) (xy 77.474579 -43.939972) (xy 77.458511 -43.993379)
			(xy 77.434839 -44.043876) (xy 77.404066 -44.090389) (xy 77.366849 -44.131926) (xy 77.323981 -44.167601)
			(xy 77.276375 -44.196655) (xy 77.225046 -44.218467) (xy 77.171089 -44.232573) (xy 77.115652 -44.238673)
			(xy 77.059918 -44.236636) (xy 77.005075 -44.226506) (xy 76.952291 -44.208499) (xy 76.902691 -44.182998)
			(xy 76.857333 -44.150547) (xy 76.817184 -44.111838) (xy 76.783098 -44.067695) (xy 76.755802 -44.01906)
			(xy 76.735879 -43.966969) (xy 76.723753 -43.912532) (xy 76.719682 -43.85691) (xy 72.956548 -43.85691)
			(xy 72.951789 -43.872729) (xy 72.928117 -43.923226) (xy 72.897344 -43.969739) (xy 72.860127 -44.011276)
			(xy 72.817259 -44.046951) (xy 72.769653 -44.076005) (xy 72.718324 -44.097817) (xy 72.664367 -44.111923)
			(xy 72.60893 -44.118023) (xy 72.553196 -44.115986) (xy 72.498353 -44.105856) (xy 72.445569 -44.087849)
			(xy 72.395969 -44.062348) (xy 72.350611 -44.029897) (xy 72.310462 -43.991188) (xy 72.276376 -43.947045)
			(xy 72.24908 -43.89841) (xy 72.229157 -43.846319) (xy 72.217031 -43.791882) (xy 72.21296 -43.73626)
			(xy 67.36952 -43.73626) (xy 67.354958 -43.805856) (xy 67.080989 -45.114464) (xy 72.065386 -45.114464)
			(xy 72.069457 -45.058842) (xy 72.081583 -45.004405) (xy 72.101506 -44.952314) (xy 72.128802 -44.903679)
			(xy 72.162888 -44.859536) (xy 72.203037 -44.820827) (xy 72.248395 -44.788376) (xy 72.297995 -44.762875)
			(xy 72.350779 -44.744868) (xy 72.405622 -44.734738) (xy 72.461356 -44.732701) (xy 72.516793 -44.738801)
			(xy 72.57075 -44.752907) (xy 72.622079 -44.774719) (xy 72.669685 -44.803773) (xy 72.712553 -44.839448)
			(xy 72.742535 -44.87291) (xy 78.933038 -44.87291) (xy 78.937109 -44.817288) (xy 78.949235 -44.762851)
			(xy 78.969158 -44.71076) (xy 78.996454 -44.662125) (xy 79.03054 -44.617982) (xy 79.070689 -44.579273)
			(xy 79.116047 -44.546822) (xy 79.165647 -44.521321) (xy 79.218431 -44.503314) (xy 79.273274 -44.493184)
			(xy 79.329008 -44.491147) (xy 79.384445 -44.497247) (xy 79.438402 -44.511353) (xy 79.489731 -44.533165)
			(xy 79.537337 -44.562219) (xy 79.580205 -44.597894) (xy 79.617422 -44.639431) (xy 79.648195 -44.685944)
			(xy 79.671867 -44.736441) (xy 79.687935 -44.789848) (xy 79.696055 -44.845024) (xy 79.696564 -44.87291)
			(xy 79.696055 -44.900796) (xy 79.687935 -44.955972) (xy 79.671867 -45.009379) (xy 79.648195 -45.059876)
			(xy 79.617422 -45.106389) (xy 79.580205 -45.147926) (xy 79.537337 -45.183601) (xy 79.489731 -45.212655)
			(xy 79.438402 -45.234467) (xy 79.384445 -45.248573) (xy 79.329008 -45.254673) (xy 79.273274 -45.252636)
			(xy 79.218431 -45.242506) (xy 79.165647 -45.224499) (xy 79.116047 -45.198998) (xy 79.070689 -45.166547)
			(xy 79.03054 -45.127838) (xy 78.996454 -45.083695) (xy 78.969158 -45.03506) (xy 78.949235 -44.982969)
			(xy 78.937109 -44.928532) (xy 78.933038 -44.87291) (xy 72.742535 -44.87291) (xy 72.74977 -44.880985)
			(xy 72.780543 -44.927498) (xy 72.804215 -44.977995) (xy 72.820283 -45.031402) (xy 72.828403 -45.086578)
			(xy 72.828912 -45.114464) (xy 72.828403 -45.14235) (xy 72.820283 -45.197526) (xy 72.804215 -45.250933)
			(xy 72.780543 -45.30143) (xy 72.74977 -45.347943) (xy 72.744128 -45.35424) (xy 76.70368 -45.35424)
			(xy 76.707751 -45.298618) (xy 76.719877 -45.244181) (xy 76.7398 -45.19209) (xy 76.767096 -45.143455)
			(xy 76.801182 -45.099312) (xy 76.841331 -45.060603) (xy 76.886689 -45.028152) (xy 76.936289 -45.002651)
			(xy 76.989073 -44.984644) (xy 77.043916 -44.974514) (xy 77.09965 -44.972477) (xy 77.155087 -44.978577)
			(xy 77.209044 -44.992683) (xy 77.260373 -45.014495) (xy 77.307979 -45.043549) (xy 77.350847 -45.079224)
			(xy 77.388064 -45.120761) (xy 77.418837 -45.167274) (xy 77.442509 -45.217771) (xy 77.458577 -45.271178)
			(xy 77.466697 -45.326354) (xy 77.467206 -45.35424) (xy 77.466697 -45.382126) (xy 77.458577 -45.437302)
			(xy 77.442509 -45.490709) (xy 77.418837 -45.541206) (xy 77.388064 -45.587719) (xy 77.350847 -45.629256)
			(xy 77.307979 -45.664931) (xy 77.260373 -45.693985) (xy 77.209044 -45.715797) (xy 77.155087 -45.729903)
			(xy 77.09965 -45.736003) (xy 77.043916 -45.733966) (xy 76.989073 -45.723836) (xy 76.936289 -45.705829)
			(xy 76.886689 -45.680328) (xy 76.841331 -45.647877) (xy 76.801182 -45.609168) (xy 76.767096 -45.565025)
			(xy 76.7398 -45.51639) (xy 76.719877 -45.464299) (xy 76.707751 -45.409862) (xy 76.70368 -45.35424)
			(xy 72.744128 -45.35424) (xy 72.712553 -45.38948) (xy 72.669685 -45.425155) (xy 72.622079 -45.454209)
			(xy 72.57075 -45.476021) (xy 72.516793 -45.490127) (xy 72.461356 -45.496227) (xy 72.405622 -45.49419)
			(xy 72.350779 -45.48406) (xy 72.297995 -45.466053) (xy 72.248395 -45.440552) (xy 72.203037 -45.408101)
			(xy 72.162888 -45.369392) (xy 72.128802 -45.325249) (xy 72.101506 -45.276614) (xy 72.081583 -45.224523)
			(xy 72.069457 -45.170086) (xy 72.065386 -45.114464) (xy 67.080989 -45.114464) (xy 66.878383 -46.082204)
			(xy 70.052438 -46.082204) (xy 70.052859 -46.054949) (xy 70.060617 -46.000994) (xy 70.075975 -45.948693)
			(xy 70.09862 -45.89911) (xy 70.128092 -45.853254) (xy 70.16379 -45.81206) (xy 70.204988 -45.776367)
			(xy 70.250847 -45.7469) (xy 70.300432 -45.72426) (xy 70.352735 -45.708908) (xy 70.406691 -45.701156)
			(xy 70.433946 -45.700696) (xy 70.46085 -45.701123) (xy 70.514121 -45.708701) (xy 70.5658 -45.723687)
			(xy 70.614862 -45.745783) (xy 70.660334 -45.77455) (xy 70.701315 -45.80942) (xy 70.736991 -45.8497)
			(xy 70.752208 -45.871892) (xy 70.75932 -45.882814) (xy 70.78218 -45.894752) (xy 70.894448 -45.89272)
			(xy 70.9168 -45.879766) (xy 70.923658 -45.86859) (xy 70.938554 -45.844971) (xy 70.974237 -45.80202)
			(xy 71.0158 -45.764728) (xy 71.062354 -45.733892) (xy 71.112906 -45.710172) (xy 71.166375 -45.694073)
			(xy 71.22162 -45.68594) (xy 71.24954 -45.685456) (xy 71.276534 -45.685894) (xy 71.329983 -45.693506)
			(xy 71.381827 -45.708571) (xy 71.431031 -45.73079) (xy 71.476614 -45.75972) (xy 71.497444 -45.776896)
			(xy 71.505572 -45.784008) (xy 71.526146 -45.790104) (xy 71.61149 -45.779182) (xy 71.622036 -45.777413)
			(xy 71.640318 -45.766355) (xy 71.646796 -45.757846) (xy 71.662158 -45.736622) (xy 71.697744 -45.698169)
			(xy 71.738259 -45.66495) (xy 71.782941 -45.637591) (xy 71.830948 -45.616606) (xy 71.881375 -45.602391)
			(xy 71.933274 -45.595214) (xy 71.95947 -45.594778) (xy 71.986723 -45.595267) (xy 72.040675 -45.60302)
			(xy 72.092975 -45.618373) (xy 72.142557 -45.641013) (xy 72.188412 -45.670479) (xy 72.229607 -45.706172)
			(xy 72.265303 -45.747364) (xy 72.294772 -45.793217) (xy 72.317416 -45.842797) (xy 72.332773 -45.895095)
			(xy 72.340531 -45.949047) (xy 72.340531 -46.003553) (xy 72.332773 -46.057505) (xy 72.317416 -46.109803)
			(xy 72.294772 -46.159383) (xy 72.265303 -46.205236) (xy 72.229607 -46.246428) (xy 72.188412 -46.282121)
			(xy 72.142557 -46.311587) (xy 72.092975 -46.334227) (xy 72.040675 -46.34958) (xy 71.986723 -46.357333)
			(xy 71.95947 -46.357794) (xy 71.932477 -46.357338) (xy 71.879029 -46.349729) (xy 71.827186 -46.334667)
			(xy 71.777981 -46.312452) (xy 71.732397 -46.283528) (xy 71.711566 -46.266354) (xy 71.703438 -46.259242)
			(xy 71.682864 -46.253146) (xy 71.59752 -46.264068) (xy 71.58698 -46.26586) (xy 71.568696 -46.276903)
			(xy 71.562214 -46.285404) (xy 71.544596 -46.3097) (xy 71.503004 -46.352962) (xy 71.47941 -46.37151)
			(xy 71.471536 -46.377352) (xy 71.461122 -46.394878) (xy 71.447914 -46.485302) (xy 71.45274 -46.504606)
			(xy 71.458582 -46.51248) (xy 71.458582 -46.512734) (xy 71.476086 -46.537478) (xy 71.503888 -46.591331)
			(xy 71.522824 -46.648903) (xy 71.530027 -46.693836) (xy 76.67625 -46.693836) (xy 76.676736 -46.666585)
			(xy 76.684492 -46.612637) (xy 76.699847 -46.560342) (xy 76.722489 -46.510765) (xy 76.751955 -46.464915)
			(xy 76.787646 -46.423724) (xy 76.828837 -46.388033) (xy 76.874687 -46.358567) (xy 76.924264 -46.335925)
			(xy 76.976559 -46.32057) (xy 77.030507 -46.312814) (xy 77.085009 -46.312814) (xy 77.138957 -46.32057)
			(xy 77.191252 -46.335925) (xy 77.240829 -46.358567) (xy 77.286679 -46.388033) (xy 77.32787 -46.423724)
			(xy 77.363561 -46.464915) (xy 77.393027 -46.510765) (xy 77.415669 -46.560342) (xy 77.431024 -46.612637)
			(xy 77.43878 -46.666585) (xy 77.439266 -46.693836) (xy 77.438798 -46.720264) (xy 77.431488 -46.772611)
			(xy 77.417013 -46.823446) (xy 77.395652 -46.871793) (xy 77.382116 -46.894496) (xy 77.381862 -46.89475)
			(xy 77.376525 -46.904768) (xy 77.374267 -46.927318) (xy 77.377544 -46.938184) (xy 77.403706 -47.01286)
			(xy 77.408066 -47.023388) (xy 77.424171 -47.039472) (xy 77.434694 -47.043848) (xy 77.434948 -47.043848)
			(xy 77.459457 -47.052916) (xy 77.50591 -47.076859) (xy 77.548661 -47.106915) (xy 77.586913 -47.142523)
			(xy 77.61995 -47.183016) (xy 77.647153 -47.227637) (xy 77.668015 -47.275552) (xy 77.682145 -47.325866)
			(xy 77.689279 -47.377636) (xy 77.68971 -47.403766) (xy 77.689224 -47.431017) (xy 77.687701 -47.441612)
			(xy 78.96174 -47.441612) (xy 78.965811 -47.38599) (xy 78.977937 -47.331553) (xy 78.99786 -47.279462)
			(xy 79.025156 -47.230827) (xy 79.059242 -47.186684) (xy 79.099391 -47.147975) (xy 79.144749 -47.115524)
			(xy 79.194349 -47.090023) (xy 79.247133 -47.072016) (xy 79.301976 -47.061886) (xy 79.35771 -47.059849)
			(xy 79.413147 -47.065949) (xy 79.467104 -47.080055) (xy 79.518433 -47.101867) (xy 79.566039 -47.130921)
			(xy 79.608907 -47.166596) (xy 79.646124 -47.208133) (xy 79.676897 -47.254646) (xy 79.700569 -47.305143)
			(xy 79.716637 -47.35855) (xy 79.724757 -47.413726) (xy 79.725266 -47.441612) (xy 79.724757 -47.469498)
			(xy 79.716637 -47.524674) (xy 79.700569 -47.578081) (xy 79.676897 -47.628578) (xy 79.646124 -47.675091)
			(xy 79.608907 -47.716628) (xy 79.566039 -47.752303) (xy 79.518433 -47.781357) (xy 79.467104 -47.803169)
			(xy 79.413147 -47.817275) (xy 79.35771 -47.823375) (xy 79.301976 -47.821338) (xy 79.247133 -47.811208)
			(xy 79.194349 -47.793201) (xy 79.144749 -47.7677) (xy 79.099391 -47.735249) (xy 79.059242 -47.69654)
			(xy 79.025156 -47.652397) (xy 78.99786 -47.603762) (xy 78.977937 -47.551671) (xy 78.965811 -47.497234)
			(xy 78.96174 -47.441612) (xy 77.687701 -47.441612) (xy 77.681468 -47.484965) (xy 77.666113 -47.53726)
			(xy 77.643471 -47.586837) (xy 77.614005 -47.632687) (xy 77.578314 -47.673878) (xy 77.537123 -47.709569)
			(xy 77.491273 -47.739035) (xy 77.441696 -47.761677) (xy 77.389401 -47.777032) (xy 77.335453 -47.784788)
			(xy 77.280951 -47.784788) (xy 77.227003 -47.777032) (xy 77.174708 -47.761677) (xy 77.125131 -47.739035)
			(xy 77.079281 -47.709569) (xy 77.03809 -47.673878) (xy 77.002399 -47.632687) (xy 76.972933 -47.586837)
			(xy 76.950291 -47.53726) (xy 76.934936 -47.484965) (xy 76.92718 -47.431017) (xy 76.926694 -47.403766)
			(xy 76.927168 -47.377339) (xy 76.934477 -47.324991) (xy 76.94895 -47.274156) (xy 76.970309 -47.225809)
			(xy 76.983844 -47.203106) (xy 76.984098 -47.202852) (xy 76.989433 -47.192833) (xy 76.991694 -47.170283)
			(xy 76.988416 -47.159418) (xy 76.962254 -47.084742) (xy 76.957866 -47.074228) (xy 76.94178 -47.058139)
			(xy 76.931266 -47.053754) (xy 76.931012 -47.053754) (xy 76.906495 -47.044706) (xy 76.860044 -47.020759)
			(xy 76.817293 -46.990699) (xy 76.779042 -46.955089) (xy 76.746007 -46.914593) (xy 76.718805 -46.86997)
			(xy 76.697944 -46.822053) (xy 76.683815 -46.771738) (xy 76.676681 -46.719966) (xy 76.67625 -46.693836)
			(xy 71.530027 -46.693836) (xy 71.532417 -46.708745) (xy 71.533004 -46.739048) (xy 71.532567 -46.766301)
			(xy 71.524804 -46.82025) (xy 71.509442 -46.872546) (xy 71.486795 -46.922124) (xy 71.457324 -46.967974)
			(xy 71.421627 -47.009164) (xy 71.380433 -47.044855) (xy 71.334578 -47.07432) (xy 71.284997 -47.09696)
			(xy 71.232699 -47.112315) (xy 71.178749 -47.120071) (xy 71.151496 -47.120556) (xy 71.125463 -47.120104)
			(xy 71.07388 -47.113017) (xy 71.023739 -47.098988) (xy 70.975968 -47.078278) (xy 70.931453 -47.051271)
			(xy 70.910958 -47.035212) (xy 70.903191 -47.029486) (xy 70.884788 -47.023736) (xy 70.875144 -47.024036)
			(xy 70.795388 -47.030386) (xy 70.777608 -47.039022) (xy 70.771258 -47.046388) (xy 70.753071 -47.066028)
			(xy 70.712165 -47.10055) (xy 70.666837 -47.12902) (xy 70.617977 -47.150879) (xy 70.566542 -47.165698)
			(xy 70.513541 -47.173186) (xy 70.486778 -47.173642) (xy 70.459528 -47.173143) (xy 70.405582 -47.165384)
			(xy 70.35329 -47.150028) (xy 70.303715 -47.127387) (xy 70.257866 -47.097921) (xy 70.216677 -47.062231)
			(xy 70.180986 -47.021043) (xy 70.151519 -46.975196) (xy 70.128876 -46.925621) (xy 70.113518 -46.873329)
			(xy 70.105758 -46.819384) (xy 70.10527 -46.792134) (xy 70.105803 -46.76336) (xy 70.114453 -46.706467)
			(xy 70.131548 -46.651517) (xy 70.156699 -46.599757) (xy 70.189337 -46.55236) (xy 70.208648 -46.531022)
			(xy 70.216014 -46.523148) (xy 70.223126 -46.503336) (xy 70.21576 -46.40707) (xy 70.205854 -46.388274)
			(xy 70.197472 -46.38167) (xy 70.175277 -46.363457) (xy 70.13607 -46.321518) (xy 70.103587 -46.274179)
			(xy 70.078561 -46.222509) (xy 70.061556 -46.167674) (xy 70.052956 -46.11091) (xy 70.052438 -46.082204)
			(xy 66.878383 -46.082204) (xy 66.877692 -46.085506) (xy 66.319062 -48.753014) (xy 73.168254 -48.753014)
			(xy 73.172325 -48.697392) (xy 73.184451 -48.642955) (xy 73.204374 -48.590864) (xy 73.23167 -48.542229)
			(xy 73.265756 -48.498086) (xy 73.305905 -48.459377) (xy 73.351263 -48.426926) (xy 73.400863 -48.401425)
			(xy 73.453647 -48.383418) (xy 73.50849 -48.373288) (xy 73.564224 -48.371251) (xy 73.619661 -48.377351)
			(xy 73.673618 -48.391457) (xy 73.724947 -48.413269) (xy 73.772553 -48.442323) (xy 73.815421 -48.477998)
			(xy 73.852638 -48.519535) (xy 73.883411 -48.566048) (xy 73.907083 -48.616545) (xy 73.923151 -48.669952)
			(xy 73.931271 -48.725128) (xy 73.93178 -48.753014) (xy 73.931271 -48.7809) (xy 73.923151 -48.836076)
			(xy 73.907083 -48.889483) (xy 73.892893 -48.919754) (xy 75.214938 -48.919754) (xy 75.214938 -48.865246)
			(xy 75.222695 -48.811294) (xy 75.238051 -48.758995) (xy 75.260694 -48.709413) (xy 75.290162 -48.663559)
			(xy 75.325856 -48.622364) (xy 75.367049 -48.586669) (xy 75.412903 -48.557199) (xy 75.462484 -48.534555)
			(xy 75.514782 -48.519197) (xy 75.568734 -48.511439) (xy 75.595988 -48.510952) (xy 75.622735 -48.511351)
			(xy 75.675703 -48.518842) (xy 75.727107 -48.533652) (xy 75.775942 -48.55549) (xy 75.821251 -48.58393)
			(xy 75.862148 -48.618414) (xy 75.897832 -48.658268) (xy 75.927606 -48.702711) (xy 75.93965 -48.726598)
			(xy 75.943618 -48.734179) (xy 75.955675 -48.746307) (xy 75.971069 -48.753753) (xy 75.979528 -48.755046)
			(xy 76.077826 -48.766222) (xy 76.101956 -48.75657) (xy 76.110084 -48.74641) (xy 76.128305 -48.724697)
			(xy 76.170056 -48.686361) (xy 76.21702 -48.654627) (xy 76.268163 -48.630191) (xy 76.32236 -48.613594)
			(xy 76.378416 -48.605199) (xy 76.406756 -48.604678) (xy 76.407518 -48.604678) (xy 76.425537 -48.604901)
			(xy 76.461412 -48.608334) (xy 76.479146 -48.611536) (xy 76.49337 -48.61433) (xy 76.519786 -48.604424)
			(xy 76.593192 -48.51019) (xy 76.596494 -48.481742) (xy 76.590398 -48.468788) (xy 76.579001 -48.443355)
			(xy 76.562925 -48.389993) (xy 76.554809 -48.334856) (xy 76.55433 -48.30699) (xy 76.554789 -48.27974)
			(xy 76.562546 -48.225796) (xy 76.577901 -48.173504) (xy 76.600542 -48.12393) (xy 76.630007 -48.078082)
			(xy 76.665697 -48.036894) (xy 76.706885 -48.001205) (xy 76.752733 -47.97174) (xy 76.802308 -47.9491)
			(xy 76.8546 -47.933745) (xy 76.908544 -47.925989) (xy 76.963044 -47.925988) (xy 77.016989 -47.933743)
			(xy 77.069281 -47.949096) (xy 77.118856 -47.971734) (xy 77.164705 -48.001198) (xy 77.205894 -48.036886)
			(xy 77.241585 -48.078073) (xy 77.271052 -48.123919) (xy 77.293694 -48.173493) (xy 77.309051 -48.225784)
			(xy 77.31681 -48.279728) (xy 77.316813 -48.334228) (xy 77.309061 -48.388173) (xy 77.29371 -48.440466)
			(xy 77.271073 -48.490042) (xy 77.241612 -48.535892) (xy 77.205925 -48.577083) (xy 77.16474 -48.612776)
			(xy 77.118895 -48.642244) (xy 77.069322 -48.664889) (xy 77.017032 -48.680248) (xy 76.963088 -48.688009)
			(xy 76.935838 -48.688498) (xy 76.935076 -48.688498) (xy 76.917057 -48.688277) (xy 76.881182 -48.684843)
			(xy 76.863448 -48.68164) (xy 76.849224 -48.678846) (xy 76.822808 -48.688752) (xy 76.749402 -48.782986)
			(xy 76.7461 -48.811434) (xy 76.752196 -48.824388) (xy 76.763585 -48.849824) (xy 76.779663 -48.903185)
			(xy 76.78463 -48.93691) (xy 78.933038 -48.93691) (xy 78.937109 -48.881288) (xy 78.949235 -48.826851)
			(xy 78.969158 -48.77476) (xy 78.996454 -48.726125) (xy 79.03054 -48.681982) (xy 79.070689 -48.643273)
			(xy 79.116047 -48.610822) (xy 79.165647 -48.585321) (xy 79.218431 -48.567314) (xy 79.273274 -48.557184)
			(xy 79.329008 -48.555147) (xy 79.384445 -48.561247) (xy 79.438402 -48.575353) (xy 79.489731 -48.597165)
			(xy 79.537337 -48.626219) (xy 79.580205 -48.661894) (xy 79.617422 -48.703431) (xy 79.648195 -48.749944)
			(xy 79.671867 -48.800441) (xy 79.687935 -48.853848) (xy 79.696055 -48.909024) (xy 79.696564 -48.93691)
			(xy 79.696055 -48.964796) (xy 79.687935 -49.019972) (xy 79.671867 -49.073379) (xy 79.648195 -49.123876)
			(xy 79.617422 -49.170389) (xy 79.580205 -49.211926) (xy 79.537337 -49.247601) (xy 79.489731 -49.276655)
			(xy 79.438402 -49.298467) (xy 79.384445 -49.312573) (xy 79.329008 -49.318673) (xy 79.273274 -49.316636)
			(xy 79.218431 -49.306506) (xy 79.165647 -49.288499) (xy 79.116047 -49.262998) (xy 79.070689 -49.230547)
			(xy 79.03054 -49.191838) (xy 78.996454 -49.147695) (xy 78.969158 -49.09906) (xy 78.949235 -49.046969)
			(xy 78.937109 -48.992532) (xy 78.933038 -48.93691) (xy 76.78463 -48.93691) (xy 76.787783 -48.958321)
			(xy 76.788264 -48.986186) (xy 76.787832 -49.013441) (xy 76.780075 -49.067395) (xy 76.764719 -49.119696)
			(xy 76.742075 -49.169279) (xy 76.712604 -49.215134) (xy 76.676907 -49.256328) (xy 76.63571 -49.292022)
			(xy 76.589853 -49.321489) (xy 76.540268 -49.344129) (xy 76.487965 -49.359482) (xy 76.434011 -49.367234)
			(xy 76.406756 -49.367694) (xy 76.380011 -49.367232) (xy 76.327047 -49.359748) (xy 76.275646 -49.344946)
			(xy 76.226813 -49.323116) (xy 76.181504 -49.294686) (xy 76.140606 -49.26021) (xy 76.104919 -49.220365)
			(xy 76.075141 -49.17593) (xy 76.063094 -49.152048) (xy 76.059082 -49.144493) (xy 76.047046 -49.132359)
			(xy 76.031668 -49.124901) (xy 76.023216 -49.1236) (xy 75.924918 -49.112424) (xy 75.900788 -49.122076)
			(xy 75.89266 -49.132236) (xy 75.874426 -49.153937) (xy 75.832677 -49.192272) (xy 75.785715 -49.224007)
			(xy 75.734574 -49.248443) (xy 75.680381 -49.265044) (xy 75.624327 -49.273444) (xy 75.595988 -49.273968)
			(xy 75.568734 -49.273561) (xy 75.514782 -49.265803) (xy 75.462484 -49.250445) (xy 75.412903 -49.227801)
			(xy 75.367049 -49.198331) (xy 75.325856 -49.162636) (xy 75.290162 -49.121441) (xy 75.260694 -49.075587)
			(xy 75.238051 -49.026005) (xy 75.222695 -48.973706) (xy 75.214938 -48.919754) (xy 73.892893 -48.919754)
			(xy 73.883411 -48.93998) (xy 73.852638 -48.986493) (xy 73.815421 -49.02803) (xy 73.772553 -49.063705)
			(xy 73.724947 -49.092759) (xy 73.673618 -49.114571) (xy 73.619661 -49.128677) (xy 73.564224 -49.134777)
			(xy 73.50849 -49.13274) (xy 73.453647 -49.12261) (xy 73.400863 -49.104603) (xy 73.351263 -49.079102)
			(xy 73.305905 -49.046651) (xy 73.265756 -49.007942) (xy 73.23167 -48.963799) (xy 73.204374 -48.915164)
			(xy 73.184451 -48.863073) (xy 73.172325 -48.808636) (xy 73.168254 -48.753014) (xy 66.319062 -48.753014)
			(xy 66.280284 -48.93818) (xy 66.279268 -48.948086) (xy 66.269101 -49.95291) (xy 78.933038 -49.95291)
			(xy 78.937109 -49.897288) (xy 78.949235 -49.842851) (xy 78.969158 -49.79076) (xy 78.996454 -49.742125)
			(xy 79.03054 -49.697982) (xy 79.070689 -49.659273) (xy 79.116047 -49.626822) (xy 79.165647 -49.601321)
			(xy 79.218431 -49.583314) (xy 79.273274 -49.573184) (xy 79.329008 -49.571147) (xy 79.384445 -49.577247)
			(xy 79.438402 -49.591353) (xy 79.463337 -49.601949) (xy 84.112882 -49.601949) (xy 84.112882 -49.547451)
			(xy 84.120637 -49.493507) (xy 84.13599 -49.441216) (xy 84.158628 -49.391642) (xy 84.188091 -49.345793)
			(xy 84.223778 -49.304605) (xy 84.264963 -49.268914) (xy 84.310808 -49.239447) (xy 84.36038 -49.216803)
			(xy 84.41267 -49.201445) (xy 84.466613 -49.193684) (xy 84.493862 -49.193196) (xy 84.521231 -49.193685)
			(xy 84.575409 -49.201498) (xy 84.627912 -49.216981) (xy 84.677659 -49.239818) (xy 84.723627 -49.269537)
			(xy 84.74456 -49.287176) (xy 84.744814 -49.28743) (xy 84.75189 -49.293032) (xy 84.768815 -49.299268)
			(xy 84.777834 -49.299622) (xy 84.84489 -49.299622) (xy 84.853906 -49.299255) (xy 84.870823 -49.293014)
			(xy 84.87791 -49.28743) (xy 84.87791 -49.287176) (xy 84.878164 -49.287176) (xy 84.899097 -49.269535)
			(xy 84.945065 -49.239811) (xy 84.994811 -49.216965) (xy 85.047313 -49.201469) (xy 85.101491 -49.19364)
			(xy 85.156233 -49.19364) (xy 85.210411 -49.201469) (xy 85.262913 -49.216965) (xy 85.312659 -49.239811)
			(xy 85.358627 -49.269535) (xy 85.37956 -49.287176) (xy 85.379814 -49.28743) (xy 85.38689 -49.293032)
			(xy 85.403815 -49.299268) (xy 85.412834 -49.299622) (xy 85.47989 -49.299622) (xy 85.488906 -49.299255)
			(xy 85.505823 -49.293014) (xy 85.51291 -49.28743) (xy 85.51291 -49.287176) (xy 85.513164 -49.287176)
			(xy 85.534097 -49.269535) (xy 85.580065 -49.239811) (xy 85.629811 -49.216965) (xy 85.682313 -49.201469)
			(xy 85.736491 -49.19364) (xy 85.791233 -49.19364) (xy 85.845411 -49.201469) (xy 85.897913 -49.216965)
			(xy 85.947659 -49.239811) (xy 85.993627 -49.269535) (xy 86.01456 -49.287176) (xy 86.014814 -49.28743)
			(xy 86.02189 -49.293032) (xy 86.038815 -49.299268) (xy 86.047834 -49.299622) (xy 86.11489 -49.299622)
			(xy 86.123906 -49.299255) (xy 86.140823 -49.293014) (xy 86.14791 -49.28743) (xy 86.14791 -49.287176)
			(xy 86.148164 -49.287176) (xy 86.169096 -49.269537) (xy 86.215069 -49.239826) (xy 86.264817 -49.21699)
			(xy 86.317317 -49.201499) (xy 86.371493 -49.19367) (xy 86.398862 -49.193196) (xy 86.426117 -49.193649)
			(xy 86.480073 -49.201401) (xy 86.532375 -49.216754) (xy 86.581961 -49.239395) (xy 86.627819 -49.268862)
			(xy 86.669017 -49.304556) (xy 86.704715 -49.34575) (xy 86.734187 -49.391606) (xy 86.756832 -49.441189)
			(xy 86.77219 -49.49349) (xy 86.779949 -49.547445) (xy 86.779949 -49.601955) (xy 86.77219 -49.65591)
			(xy 86.756832 -49.708211) (xy 86.734187 -49.757794) (xy 86.704715 -49.80365) (xy 86.669017 -49.844844)
			(xy 86.627819 -49.880538) (xy 86.581961 -49.910005) (xy 86.532375 -49.932646) (xy 86.480073 -49.947999)
			(xy 86.426117 -49.955751) (xy 86.398862 -49.956212) (xy 86.371493 -49.955707) (xy 86.317316 -49.947898)
			(xy 86.264813 -49.932418) (xy 86.215066 -49.909585) (xy 86.169097 -49.879869) (xy 86.148164 -49.862232)
			(xy 86.14791 -49.861978) (xy 86.140827 -49.856387) (xy 86.123907 -49.850144) (xy 86.11489 -49.849786)
			(xy 86.047834 -49.849786) (xy 86.038819 -49.850162) (xy 86.021902 -49.856397) (xy 86.014814 -49.861978)
			(xy 86.01456 -49.862232) (xy 85.993627 -49.879873) (xy 85.947659 -49.909597) (xy 85.897913 -49.932443)
			(xy 85.845411 -49.947939) (xy 85.791233 -49.955768) (xy 85.736491 -49.955768) (xy 85.682313 -49.947939)
			(xy 85.629811 -49.932443) (xy 85.580065 -49.909597) (xy 85.534097 -49.879873) (xy 85.513164 -49.862232)
			(xy 85.51291 -49.861978) (xy 85.505827 -49.856387) (xy 85.488907 -49.850144) (xy 85.47989 -49.849786)
			(xy 85.412834 -49.849786) (xy 85.403819 -49.850162) (xy 85.386902 -49.856397) (xy 85.379814 -49.861978)
			(xy 85.379814 -49.862232) (xy 85.37956 -49.862232) (xy 85.358627 -49.879873) (xy 85.312659 -49.909597)
			(xy 85.262913 -49.932443) (xy 85.210411 -49.947939) (xy 85.156233 -49.955768) (xy 85.101491 -49.955768)
			(xy 85.047313 -49.947939) (xy 84.994811 -49.932443) (xy 84.945065 -49.909597) (xy 84.899097 -49.879873)
			(xy 84.878164 -49.862232) (xy 84.87791 -49.861978) (xy 84.870827 -49.856387) (xy 84.853907 -49.850144)
			(xy 84.84489 -49.849786) (xy 84.777834 -49.849786) (xy 84.768819 -49.850162) (xy 84.751902 -49.856397)
			(xy 84.744814 -49.861978) (xy 84.744814 -49.862232) (xy 84.74456 -49.862232) (xy 84.72362 -49.879861)
			(xy 84.677649 -49.909574) (xy 84.627903 -49.932411) (xy 84.575405 -49.947904) (xy 84.521231 -49.955736)
			(xy 84.493862 -49.956212) (xy 84.466613 -49.955716) (xy 84.41267 -49.947955) (xy 84.36038 -49.932597)
			(xy 84.310808 -49.909953) (xy 84.264963 -49.880486) (xy 84.223778 -49.844795) (xy 84.188091 -49.803607)
			(xy 84.158628 -49.757758) (xy 84.13599 -49.708184) (xy 84.120637 -49.655893) (xy 84.112882 -49.601949)
			(xy 79.463337 -49.601949) (xy 79.489731 -49.613165) (xy 79.537337 -49.642219) (xy 79.580205 -49.677894)
			(xy 79.617422 -49.719431) (xy 79.648195 -49.765944) (xy 79.671867 -49.816441) (xy 79.687935 -49.869848)
			(xy 79.696055 -49.925024) (xy 79.696564 -49.95291) (xy 79.696055 -49.980796) (xy 79.687935 -50.035972)
			(xy 79.671867 -50.089379) (xy 79.648195 -50.139876) (xy 79.617422 -50.186389) (xy 79.580205 -50.227926)
			(xy 79.537337 -50.263601) (xy 79.489731 -50.292655) (xy 79.438402 -50.314467) (xy 79.384445 -50.328573)
			(xy 79.329008 -50.334673) (xy 79.273274 -50.332636) (xy 79.218431 -50.322506) (xy 79.165647 -50.304499)
			(xy 79.116047 -50.278998) (xy 79.070689 -50.246547) (xy 79.03054 -50.207838) (xy 78.996454 -50.163695)
			(xy 78.969158 -50.11506) (xy 78.949235 -50.062969) (xy 78.937109 -50.008532) (xy 78.933038 -49.95291)
			(xy 66.269101 -49.95291) (xy 66.26098 -50.75555) (xy 66.258322 -51.019456) (xy 76.7494 -51.019456)
			(xy 76.753471 -50.963834) (xy 76.765597 -50.909397) (xy 76.78552 -50.857306) (xy 76.812816 -50.808671)
			(xy 76.846902 -50.764528) (xy 76.887051 -50.725819) (xy 76.932409 -50.693368) (xy 76.982009 -50.667867)
			(xy 77.034793 -50.64986) (xy 77.089636 -50.63973) (xy 77.14537 -50.637693) (xy 77.200807 -50.643793)
			(xy 77.254764 -50.657899) (xy 77.306093 -50.679711) (xy 77.353699 -50.708765) (xy 77.396567 -50.74444)
			(xy 77.433784 -50.785977) (xy 77.464557 -50.83249) (xy 77.488229 -50.882987) (xy 77.504297 -50.936394)
			(xy 77.512417 -50.99157) (xy 77.512926 -51.019456) (xy 77.512417 -51.047342) (xy 77.504297 -51.102518)
			(xy 77.488229 -51.155925) (xy 77.464557 -51.206422) (xy 77.439701 -51.243992) (xy 85.132926 -51.243992)
			(xy 85.133381 -51.216621) (xy 85.141201 -51.162441) (xy 85.156692 -51.109938) (xy 85.179536 -51.060191)
			(xy 85.209263 -51.014225) (xy 85.226906 -50.993294) (xy 85.22716 -50.99304) (xy 85.232743 -50.985951)
			(xy 85.23899 -50.969036) (xy 85.239352 -50.96002) (xy 85.239352 -50.892964) (xy 85.239023 -50.883944)
			(xy 85.232757 -50.867027) (xy 85.22716 -50.859944) (xy 85.226906 -50.859944) (xy 85.226906 -50.85969)
			(xy 85.20925 -50.838772) (xy 85.17954 -50.792795) (xy 85.156708 -50.743044) (xy 85.141221 -50.69054)
			(xy 85.133397 -50.636362) (xy 85.132926 -50.608992) (xy 85.133348 -50.581737) (xy 85.141107 -50.527783)
			(xy 85.156466 -50.475483) (xy 85.179112 -50.4259) (xy 85.208584 -50.380045) (xy 85.244282 -50.338852)
			(xy 85.285479 -50.303158) (xy 85.331337 -50.273691) (xy 85.380922 -50.251051) (xy 85.433224 -50.235698)
			(xy 85.487179 -50.227945) (xy 85.514434 -50.227484) (xy 85.543351 -50.228018) (xy 85.600523 -50.236739)
			(xy 85.655722 -50.253992) (xy 85.707685 -50.279381) (xy 85.755219 -50.312323) (xy 85.797235 -50.352064)
			(xy 85.815424 -50.37455) (xy 85.823022 -50.383367) (xy 85.84393 -50.393543) (xy 85.855556 -50.394108)
			(xy 85.935312 -50.394108) (xy 85.946942 -50.393559) (xy 85.967852 -50.383377) (xy 85.975444 -50.37455)
			(xy 85.993598 -50.352035) (xy 86.035627 -50.312304) (xy 86.08317 -50.27937) (xy 86.135138 -50.253988)
			(xy 86.190342 -50.236738) (xy 86.247516 -50.228016) (xy 86.276434 -50.227484) (xy 86.303686 -50.227946)
			(xy 86.357634 -50.235707) (xy 86.409929 -50.251066) (xy 86.459505 -50.273711) (xy 86.505355 -50.30318)
			(xy 86.546545 -50.338874) (xy 86.582236 -50.380066) (xy 86.611702 -50.425917) (xy 86.634343 -50.475496)
			(xy 86.649698 -50.527792) (xy 86.657456 -50.58174) (xy 86.657942 -50.608992) (xy 86.657488 -50.635307)
			(xy 86.650253 -50.687436) (xy 86.635932 -50.73808) (xy 86.614798 -50.78628) (xy 86.587248 -50.831123)
			(xy 86.553806 -50.871761) (xy 86.534752 -50.889916) (xy 86.527349 -50.897437) (xy 86.518824 -50.916717)
			(xy 86.518242 -50.927254) (xy 86.518242 -51.00193) (xy 86.518783 -51.012479) (xy 86.527308 -51.031775)
			(xy 86.534752 -51.039268) (xy 86.553843 -51.057387) (xy 86.587295 -51.098026) (xy 86.614848 -51.142874)
			(xy 86.63598 -51.191082) (xy 86.65029 -51.241735) (xy 86.657507 -51.293874) (xy 86.657942 -51.320192)
			(xy 86.657415 -51.347442) (xy 86.64966 -51.401386) (xy 86.634308 -51.453678) (xy 86.61167 -51.503253)
			(xy 86.582208 -51.549102) (xy 86.546521 -51.590291) (xy 86.505335 -51.625983) (xy 86.45949 -51.65545)
			(xy 86.409917 -51.678093) (xy 86.357627 -51.693451) (xy 86.303683 -51.701212) (xy 86.276434 -51.7017)
			(xy 86.24877 -51.701161) (xy 86.194022 -51.693167) (xy 86.141001 -51.677355) (xy 86.090817 -51.654056)
			(xy 86.044521 -51.623759) (xy 86.003082 -51.587097) (xy 85.967368 -51.544839) (xy 85.95233 -51.521614)
			(xy 85.945689 -51.511941) (xy 85.925831 -51.499496) (xy 85.91423 -51.497738) (xy 85.83422 -51.489864)
			(xy 85.822582 -51.489248) (xy 85.800745 -51.497317) (xy 85.79231 -51.505358) (xy 85.792056 -51.505612)
			(xy 85.773981 -51.524199) (xy 85.733647 -51.556776) (xy 85.689272 -51.583588) (xy 85.641672 -51.60414)
			(xy 85.591727 -51.618052) (xy 85.540357 -51.625069) (xy 85.514434 -51.6255) (xy 85.487182 -51.625013)
			(xy 85.433231 -51.61726) (xy 85.380933 -51.601908) (xy 85.331353 -51.579269) (xy 85.285499 -51.549804)
			(xy 85.244306 -51.514113) (xy 85.208612 -51.472922) (xy 85.179143 -51.42707) (xy 85.156501 -51.377491)
			(xy 85.141145 -51.325194) (xy 85.133389 -51.271244) (xy 85.132926 -51.243992) (xy 77.439701 -51.243992)
			(xy 77.433784 -51.252935) (xy 77.396567 -51.294472) (xy 77.353699 -51.330147) (xy 77.306093 -51.359201)
			(xy 77.254764 -51.381013) (xy 77.200807 -51.395119) (xy 77.14537 -51.401219) (xy 77.089636 -51.399182)
			(xy 77.034793 -51.389052) (xy 76.982009 -51.371045) (xy 76.932409 -51.345544) (xy 76.887051 -51.313093)
			(xy 76.846902 -51.274384) (xy 76.812816 -51.230241) (xy 76.78552 -51.181606) (xy 76.765597 -51.129515)
			(xy 76.753471 -51.075078) (xy 76.7494 -51.019456) (xy 66.258322 -51.019456) (xy 66.248088 -52.035456)
			(xy 78.941166 -52.035456) (xy 78.945237 -51.979834) (xy 78.957363 -51.925397) (xy 78.977286 -51.873306)
			(xy 79.004582 -51.824671) (xy 79.038668 -51.780528) (xy 79.078817 -51.741819) (xy 79.124175 -51.709368)
			(xy 79.173775 -51.683867) (xy 79.226559 -51.66586) (xy 79.281402 -51.65573) (xy 79.337136 -51.653693)
			(xy 79.392573 -51.659793) (xy 79.44653 -51.673899) (xy 79.497859 -51.695711) (xy 79.545465 -51.724765)
			(xy 79.588333 -51.76044) (xy 79.62555 -51.801977) (xy 79.656323 -51.84849) (xy 79.679995 -51.898987)
			(xy 79.696063 -51.952394) (xy 79.704183 -52.00757) (xy 79.704692 -52.035456) (xy 79.704183 -52.063342)
			(xy 79.696063 -52.118518) (xy 79.679995 -52.171925) (xy 79.656323 -52.222422) (xy 79.62555 -52.268935)
			(xy 79.588333 -52.310472) (xy 79.545465 -52.346147) (xy 79.497859 -52.375201) (xy 79.44653 -52.397013)
			(xy 79.392573 -52.411119) (xy 79.337136 -52.417219) (xy 79.281402 -52.415182) (xy 79.226559 -52.405052)
			(xy 79.173775 -52.387045) (xy 79.124175 -52.361544) (xy 79.078817 -52.329093) (xy 79.038668 -52.290384)
			(xy 79.004582 -52.246241) (xy 78.977286 -52.197606) (xy 78.957363 -52.145515) (xy 78.945237 -52.091078)
			(xy 78.941166 -52.035456) (xy 66.248088 -52.035456) (xy 66.24193 -52.646834) (xy 66.243708 -52.650136)
			(xy 66.248534 -52.654708) (xy 66.251454 -52.657363) (xy 66.25796 -52.66183) (xy 66.261488 -52.663598)
			(xy 66.263774 -52.664614) (xy 66.2813 -52.668678) (xy 66.28877 -52.670716) (xy 66.302088 -52.678598)
			(xy 66.307462 -52.684172) (xy 66.314819 -52.693124) (xy 66.321314 -52.715343) (xy 66.319908 -52.726844)
			(xy 66.319908 -52.727352) (xy 66.319146 -52.7304) (xy 66.319146 -52.730654) (xy 66.318384 -52.733956)
			(xy 66.286634 -52.822856) (xy 66.286634 -52.831238) (xy 66.285697 -52.861106) (xy 66.275712 -52.920019)
			(xy 66.256722 -52.976675) (xy 66.243454 -53.00345) (xy 66.241676 -53.006752) (xy 66.240172 -53.010601)
			(xy 66.238264 -53.018641) (xy 66.237866 -53.022754) (xy 66.235072 -53.264308) (xy 66.235072 -53.274214)
			(xy 66.237866 -53.279548) (xy 66.252077 -53.307074) (xy 66.272369 -53.365601) (xy 66.282939 -53.426637)
			(xy 66.28384 -53.457602) (xy 66.283586 -53.47589) (xy 66.282824 -53.486812) (xy 66.280541 -53.514185)
			(xy 66.269101 -53.567908) (xy 66.250063 -53.619431) (xy 66.237358 -53.643784) (xy 66.237104 -53.644292)
			(xy 66.234746 -53.649003) (xy 66.23181 -53.659118) (xy 66.231262 -53.664358) (xy 66.228722 -53.885084)
			(xy 66.230754 -53.899054) (xy 66.232024 -53.904134) (xy 66.235326 -53.91023) (xy 66.241676 -53.922168)
			(xy 66.250312 -53.939186) (xy 66.259655 -53.960751) (xy 66.273598 -54.005633) (xy 66.281934 -54.051886)
			(xy 66.283586 -54.07533) (xy 66.283586 -54.08295) (xy 66.284094 -54.096158) (xy 66.284094 -54.096412)
			(xy 66.283468 -54.127118) (xy 66.273604 -54.187734) (xy 66.25415 -54.245985) (xy 66.240406 -54.27345)
			(xy 66.240406 -54.273958) (xy 66.231516 -54.28996) (xy 66.228214 -54.295548) (xy 66.224658 -54.308248)
			(xy 66.223134 -54.448964) (xy 66.222372 -54.522624) (xy 66.22669 -54.52999) (xy 66.227198 -54.530752)
			(xy 66.240641 -54.553451) (xy 66.261841 -54.601759) (xy 66.276195 -54.652524) (xy 66.28343 -54.70478)
			(xy 66.28384 -54.731158) (xy 66.28384 -54.737) (xy 66.283332 -54.744874) (xy 66.283332 -54.746906)
			(xy 66.281919 -54.77195) (xy 66.278596 -54.791102) (xy 68.176394 -54.791102) (xy 68.176863 -54.763732)
			(xy 68.18468 -54.709553) (xy 68.200169 -54.65705) (xy 68.22301 -54.607303) (xy 68.252733 -54.561336)
			(xy 68.270374 -54.540404) (xy 68.270628 -54.54015) (xy 68.276203 -54.533056) (xy 68.282456 -54.516145)
			(xy 68.28282 -54.50713) (xy 68.28282 -54.440074) (xy 68.282471 -54.431056) (xy 68.276218 -54.41414)
			(xy 68.270628 -54.407054) (xy 68.270374 -54.407054) (xy 68.270374 -54.4068) (xy 68.252733 -54.385867)
			(xy 68.223005 -54.3399) (xy 68.200157 -54.290154) (xy 68.184658 -54.237652) (xy 68.176828 -54.183473)
			(xy 68.176828 -54.12873) (xy 68.184657 -54.074551) (xy 68.200155 -54.022049) (xy 68.223003 -53.972303)
			(xy 68.252731 -53.926336) (xy 68.270374 -53.905404) (xy 68.270628 -53.90515) (xy 68.276203 -53.898056)
			(xy 68.282456 -53.881145) (xy 68.28282 -53.87213) (xy 68.28282 -53.805074) (xy 68.282471 -53.796056)
			(xy 68.276218 -53.77914) (xy 68.270628 -53.772054) (xy 68.270374 -53.772054) (xy 68.270374 -53.7718)
			(xy 68.252733 -53.750867) (xy 68.223005 -53.7049) (xy 68.200157 -53.655154) (xy 68.184658 -53.602652)
			(xy 68.176828 -53.548473) (xy 68.176828 -53.49373) (xy 68.184657 -53.439551) (xy 68.200155 -53.387049)
			(xy 68.223003 -53.337303) (xy 68.252731 -53.291336) (xy 68.270374 -53.270404) (xy 68.270628 -53.27015)
			(xy 68.276203 -53.263056) (xy 68.282456 -53.246145) (xy 68.28282 -53.23713) (xy 68.28282 -53.170074)
			(xy 68.282471 -53.161056) (xy 68.276218 -53.14414) (xy 68.270628 -53.137054) (xy 68.270374 -53.137054)
			(xy 68.270374 -53.1368) (xy 68.252717 -53.115882) (xy 68.223009 -53.069905) (xy 68.200177 -53.020154)
			(xy 68.18469 -52.96765) (xy 68.176866 -52.913472) (xy 68.176394 -52.886102) (xy 68.17688 -52.858851)
			(xy 68.184636 -52.804903) (xy 68.199991 -52.752608) (xy 68.222633 -52.703031) (xy 68.252099 -52.657181)
			(xy 68.28779 -52.61599) (xy 68.328981 -52.580299) (xy 68.374831 -52.550833) (xy 68.424408 -52.528191)
			(xy 68.476703 -52.512836) (xy 68.530651 -52.50508) (xy 68.585153 -52.50508) (xy 68.639101 -52.512836)
			(xy 68.691396 -52.528191) (xy 68.730496 -52.546048) (xy 73.679596 -52.546048) (xy 73.679596 -52.491552)
			(xy 73.687351 -52.437611) (xy 73.702703 -52.385322) (xy 73.72534 -52.33575) (xy 73.754801 -52.289903)
			(xy 73.790487 -52.248716) (xy 73.83167 -52.213027) (xy 73.877513 -52.183561) (xy 73.927082 -52.160918)
			(xy 73.979369 -52.14556) (xy 74.03331 -52.137799) (xy 74.060558 -52.13731) (xy 74.087927 -52.137798)
			(xy 74.142106 -52.14561) (xy 74.194609 -52.161094) (xy 74.244356 -52.183931) (xy 74.290324 -52.213651)
			(xy 74.311256 -52.23129) (xy 74.31151 -52.231544) (xy 74.318586 -52.237146) (xy 74.335511 -52.243382)
			(xy 74.34453 -52.243736) (xy 74.411586 -52.243736) (xy 74.420601 -52.243364) (xy 74.437518 -52.237126)
			(xy 74.444606 -52.231544) (xy 74.444606 -52.23129) (xy 74.44486 -52.23129) (xy 74.465793 -52.213649)
			(xy 74.511761 -52.183925) (xy 74.561507 -52.161079) (xy 74.614009 -52.145583) (xy 74.668187 -52.137754)
			(xy 74.722929 -52.137754) (xy 74.777107 -52.145583) (xy 74.829609 -52.161079) (xy 74.879355 -52.183925)
			(xy 74.925323 -52.213649) (xy 74.946256 -52.23129) (xy 74.94651 -52.231544) (xy 74.953586 -52.237146)
			(xy 74.970511 -52.243382) (xy 74.97953 -52.243736) (xy 75.046586 -52.243736) (xy 75.055601 -52.243364)
			(xy 75.072518 -52.237126) (xy 75.079606 -52.231544) (xy 75.079606 -52.23129) (xy 75.07986 -52.23129)
			(xy 75.100795 -52.213655) (xy 75.146767 -52.183943) (xy 75.196514 -52.161106) (xy 75.249014 -52.145614)
			(xy 75.303189 -52.137785) (xy 75.330558 -52.13731) (xy 75.357814 -52.137734) (xy 75.411772 -52.145487)
			(xy 75.464078 -52.16084) (xy 75.513665 -52.183481) (xy 75.559526 -52.212949) (xy 75.600726 -52.248645)
			(xy 75.636426 -52.28984) (xy 75.665899 -52.335698) (xy 75.688546 -52.385283) (xy 75.703905 -52.437587)
			(xy 75.711663 -52.491544) (xy 75.711663 -52.546056) (xy 75.705719 -52.587398) (xy 76.755242 -52.587398)
			(xy 76.759313 -52.531776) (xy 76.771439 -52.477339) (xy 76.791362 -52.425248) (xy 76.818658 -52.376613)
			(xy 76.852744 -52.33247) (xy 76.892893 -52.293761) (xy 76.938251 -52.26131) (xy 76.987851 -52.235809)
			(xy 77.040635 -52.217802) (xy 77.095478 -52.207672) (xy 77.151212 -52.205635) (xy 77.206649 -52.211735)
			(xy 77.260606 -52.225841) (xy 77.311935 -52.247653) (xy 77.359541 -52.276707) (xy 77.402409 -52.312382)
			(xy 77.439626 -52.353919) (xy 77.470399 -52.400432) (xy 77.494071 -52.450929) (xy 77.510139 -52.504336)
			(xy 77.517735 -52.555949) (xy 84.583802 -52.555949) (xy 84.583802 -52.501452) (xy 84.591558 -52.447509)
			(xy 84.606911 -52.39522) (xy 84.629549 -52.345647) (xy 84.659011 -52.299801) (xy 84.694698 -52.258614)
			(xy 84.735883 -52.222924) (xy 84.781728 -52.193459) (xy 84.831299 -52.170818) (xy 84.883588 -52.155462)
			(xy 84.93753 -52.147704) (xy 84.964778 -52.147216) (xy 84.992148 -52.147691) (xy 85.046327 -52.155506)
			(xy 85.09883 -52.170993) (xy 85.148577 -52.193833) (xy 85.194544 -52.223556) (xy 85.215476 -52.241196)
			(xy 85.21573 -52.24145) (xy 85.222828 -52.247019) (xy 85.239736 -52.253275) (xy 85.24875 -52.253642)
			(xy 85.315806 -52.253642) (xy 85.324825 -52.2533) (xy 85.341742 -52.247043) (xy 85.348826 -52.24145)
			(xy 85.348826 -52.241196) (xy 85.34908 -52.241196) (xy 85.370008 -52.223552) (xy 85.415982 -52.193841)
			(xy 85.465731 -52.171006) (xy 85.518232 -52.155516) (xy 85.572409 -52.147689) (xy 85.599778 -52.147216)
			(xy 85.627034 -52.147629) (xy 85.68099 -52.155384) (xy 85.733294 -52.170739) (xy 85.78288 -52.193382)
			(xy 85.828739 -52.222851) (xy 85.869937 -52.258547) (xy 85.905635 -52.299743) (xy 85.935107 -52.3456)
			(xy 85.957753 -52.395185) (xy 85.973111 -52.447488) (xy 85.980869 -52.501444) (xy 85.980869 -52.555956)
			(xy 85.973111 -52.609912) (xy 85.957753 -52.662215) (xy 85.935107 -52.7118) (xy 85.905635 -52.757657)
			(xy 85.869937 -52.798853) (xy 85.828739 -52.834549) (xy 85.78288 -52.864018) (xy 85.733294 -52.886661)
			(xy 85.68099 -52.902016) (xy 85.627034 -52.909771) (xy 85.599778 -52.910232) (xy 85.572407 -52.909795)
			(xy 85.518225 -52.901973) (xy 85.465721 -52.886478) (xy 85.415975 -52.863629) (xy 85.37001 -52.833897)
			(xy 85.34908 -52.816252) (xy 85.348826 -52.815998) (xy 85.341736 -52.810416) (xy 85.324822 -52.804167)
			(xy 85.315806 -52.803806) (xy 85.24875 -52.803806) (xy 85.239735 -52.804186) (xy 85.222818 -52.810418)
			(xy 85.21573 -52.815998) (xy 85.21573 -52.816252) (xy 85.215476 -52.816252) (xy 85.19452 -52.833861)
			(xy 85.148554 -52.863579) (xy 85.098813 -52.886422) (xy 85.046318 -52.90192) (xy 84.992146 -52.909755)
			(xy 84.964778 -52.910232) (xy 84.93753 -52.909696) (xy 84.883588 -52.901938) (xy 84.831299 -52.886582)
			(xy 84.781728 -52.863941) (xy 84.735883 -52.834476) (xy 84.694698 -52.798786) (xy 84.659011 -52.757599)
			(xy 84.629549 -52.711753) (xy 84.606911 -52.66218) (xy 84.591558 -52.609891) (xy 84.583802 -52.555949)
			(xy 77.517735 -52.555949) (xy 77.518259 -52.559512) (xy 77.518768 -52.587398) (xy 77.518259 -52.615284)
			(xy 77.510139 -52.67046) (xy 77.494071 -52.723867) (xy 77.470399 -52.774364) (xy 77.439626 -52.820877)
			(xy 77.402409 -52.862414) (xy 77.359541 -52.898089) (xy 77.311935 -52.927143) (xy 77.260606 -52.948955)
			(xy 77.206649 -52.963061) (xy 77.151212 -52.969161) (xy 77.095478 -52.967124) (xy 77.040635 -52.956994)
			(xy 76.987851 -52.938987) (xy 76.938251 -52.913486) (xy 76.892893 -52.881035) (xy 76.852744 -52.842326)
			(xy 76.818658 -52.798183) (xy 76.791362 -52.749548) (xy 76.771439 -52.697457) (xy 76.759313 -52.64302)
			(xy 76.755242 -52.587398) (xy 75.705719 -52.587398) (xy 75.703905 -52.600013) (xy 75.688546 -52.652317)
			(xy 75.665899 -52.701902) (xy 75.636426 -52.74776) (xy 75.600726 -52.788955) (xy 75.559526 -52.824651)
			(xy 75.513665 -52.854119) (xy 75.464078 -52.87676) (xy 75.411772 -52.892113) (xy 75.357814 -52.899866)
			(xy 75.330558 -52.900326) (xy 75.303188 -52.899844) (xy 75.249009 -52.892033) (xy 75.196505 -52.876548)
			(xy 75.146758 -52.85371) (xy 75.100791 -52.823987) (xy 75.07986 -52.806346) (xy 75.079606 -52.806092)
			(xy 75.072523 -52.800501) (xy 75.055603 -52.794257) (xy 75.046586 -52.7939) (xy 74.97953 -52.7939)
			(xy 74.970515 -52.794271) (xy 74.953597 -52.800509) (xy 74.94651 -52.806092) (xy 74.946256 -52.806346)
			(xy 74.925323 -52.823987) (xy 74.879355 -52.853711) (xy 74.829609 -52.876557) (xy 74.777107 -52.892053)
			(xy 74.722929 -52.899882) (xy 74.668187 -52.899882) (xy 74.614009 -52.892053) (xy 74.561507 -52.876557)
			(xy 74.511761 -52.853711) (xy 74.465793 -52.823987) (xy 74.44486 -52.806346) (xy 74.444606 -52.806092)
			(xy 74.437523 -52.800501) (xy 74.420603 -52.794257) (xy 74.411586 -52.7939) (xy 74.34453 -52.7939)
			(xy 74.335515 -52.794271) (xy 74.318597 -52.800509) (xy 74.31151 -52.806092) (xy 74.31151 -52.806346)
			(xy 74.311256 -52.806346) (xy 74.290307 -52.823964) (xy 74.244339 -52.853681) (xy 74.194596 -52.876522)
			(xy 74.142099 -52.892018) (xy 74.087926 -52.89985) (xy 74.060558 -52.900326) (xy 74.03331 -52.899801)
			(xy 73.979369 -52.89204) (xy 73.927082 -52.876682) (xy 73.877513 -52.854039) (xy 73.83167 -52.824573)
			(xy 73.790487 -52.788884) (xy 73.754801 -52.747697) (xy 73.72534 -52.70185) (xy 73.702703 -52.652278)
			(xy 73.687351 -52.599989) (xy 73.679596 -52.546048) (xy 68.730496 -52.546048) (xy 68.740973 -52.550833)
			(xy 68.786823 -52.580299) (xy 68.828014 -52.61599) (xy 68.863705 -52.657181) (xy 68.893171 -52.703031)
			(xy 68.915813 -52.752608) (xy 68.931168 -52.804903) (xy 68.938924 -52.858851) (xy 68.93941 -52.886102)
			(xy 68.938943 -52.913472) (xy 68.931125 -52.967651) (xy 68.915636 -53.020154) (xy 68.892794 -53.069901)
			(xy 68.863071 -53.115868) (xy 68.84543 -53.1368) (xy 68.845176 -53.137054) (xy 68.8396 -53.144148)
			(xy 68.833348 -53.161059) (xy 68.832984 -53.170074) (xy 68.832984 -53.23713) (xy 68.83333 -53.246148)
			(xy 68.839585 -53.263065) (xy 68.845176 -53.27015) (xy 68.84543 -53.27015) (xy 68.84543 -53.270404)
			(xy 68.863074 -53.291334) (xy 68.892802 -53.337301) (xy 68.91565 -53.387048) (xy 68.931148 -53.439551)
			(xy 68.938978 -53.49373) (xy 68.938977 -53.548473) (xy 68.931148 -53.602652) (xy 68.915649 -53.655155)
			(xy 68.892801 -53.704901) (xy 68.863073 -53.750868) (xy 68.8465 -53.77053) (xy 69.210682 -53.77053)
			(xy 69.211191 -53.741612) (xy 69.219917 -53.684439) (xy 69.237175 -53.629239) (xy 69.262568 -53.577276)
			(xy 69.295515 -53.529743) (xy 69.33526 -53.487728) (xy 69.357748 -53.46954) (xy 69.366535 -53.461914)
			(xy 69.376728 -53.441027) (xy 69.377306 -53.429408) (xy 69.377306 -53.349652) (xy 69.376778 -53.338019)
			(xy 69.366581 -53.31711) (xy 69.357748 -53.30952) (xy 69.335263 -53.291331) (xy 69.295531 -53.249309)
			(xy 69.262593 -53.201773) (xy 69.237206 -53.149812) (xy 69.219949 -53.094615) (xy 69.211218 -53.037446)
			(xy 69.210682 -53.00853) (xy 69.211183 -52.981278) (xy 69.218936 -52.927329) (xy 69.234288 -52.875033)
			(xy 69.256926 -52.825453) (xy 69.28639 -52.779601) (xy 69.32208 -52.738408) (xy 69.363269 -52.702714)
			(xy 69.409118 -52.673245) (xy 69.458695 -52.650602) (xy 69.51099 -52.635244) (xy 69.564938 -52.627486)
			(xy 69.59219 -52.627022) (xy 69.618504 -52.627489) (xy 69.670633 -52.634723) (xy 69.721276 -52.649042)
			(xy 69.769475 -52.670174) (xy 69.814318 -52.697721) (xy 69.854958 -52.73116) (xy 69.873114 -52.750212)
			(xy 69.880627 -52.757624) (xy 69.899914 -52.766142) (xy 69.910452 -52.766722) (xy 69.985128 -52.766722)
			(xy 69.995674 -52.766161) (xy 70.014969 -52.757648) (xy 70.022466 -52.750212) (xy 70.040599 -52.731134)
			(xy 70.081233 -52.697678) (xy 70.126078 -52.670122) (xy 70.174283 -52.648987) (xy 70.224935 -52.634675)
			(xy 70.277072 -52.627457) (xy 70.30339 -52.627022) (xy 70.330644 -52.627465) (xy 70.384597 -52.635221)
			(xy 70.436897 -52.650577) (xy 70.486479 -52.673221) (xy 70.532334 -52.702691) (xy 70.573528 -52.738387)
			(xy 70.609221 -52.779582) (xy 70.638689 -52.825438) (xy 70.66133 -52.875022) (xy 70.676683 -52.927322)
			(xy 70.684437 -52.981276) (xy 70.684898 -53.00853) (xy 70.68441 -53.036196) (xy 70.682179 -53.051456)
			(xy 78.941166 -53.051456) (xy 78.945237 -52.995834) (xy 78.957363 -52.941397) (xy 78.977286 -52.889306)
			(xy 79.004582 -52.840671) (xy 79.038668 -52.796528) (xy 79.078817 -52.757819) (xy 79.124175 -52.725368)
			(xy 79.173775 -52.699867) (xy 79.226559 -52.68186) (xy 79.281402 -52.67173) (xy 79.337136 -52.669693)
			(xy 79.392573 -52.675793) (xy 79.44653 -52.689899) (xy 79.497859 -52.711711) (xy 79.545465 -52.740765)
			(xy 79.588333 -52.77644) (xy 79.62555 -52.817977) (xy 79.656323 -52.86449) (xy 79.679995 -52.914987)
			(xy 79.696063 -52.968394) (xy 79.704183 -53.02357) (xy 79.704692 -53.051456) (xy 79.704183 -53.079342)
			(xy 79.696063 -53.134518) (xy 79.679995 -53.187925) (xy 79.656323 -53.238422) (xy 79.62555 -53.284935)
			(xy 79.588333 -53.326472) (xy 79.545465 -53.362147) (xy 79.497859 -53.391201) (xy 79.44653 -53.413013)
			(xy 79.392573 -53.427119) (xy 79.337136 -53.433219) (xy 79.281402 -53.431182) (xy 79.226559 -53.421052)
			(xy 79.173775 -53.403045) (xy 79.124175 -53.377544) (xy 79.078817 -53.345093) (xy 79.038668 -53.306384)
			(xy 79.004582 -53.262241) (xy 78.977286 -53.213606) (xy 78.957363 -53.161515) (xy 78.945237 -53.107078)
			(xy 78.941166 -53.051456) (xy 70.682179 -53.051456) (xy 70.676407 -53.090946) (xy 70.660586 -53.143969)
			(xy 70.637279 -53.194153) (xy 70.606974 -53.240448) (xy 70.570305 -53.281885) (xy 70.52804 -53.317598)
			(xy 70.504812 -53.332634) (xy 70.495114 -53.339245) (xy 70.482682 -53.359125) (xy 70.480936 -53.370734)
			(xy 70.473062 -53.450744) (xy 70.472407 -53.462383) (xy 70.480503 -53.484222) (xy 70.488556 -53.492654)
			(xy 70.48881 -53.492908) (xy 70.507379 -53.511001) (xy 70.539958 -53.55133) (xy 70.566773 -53.595702)
			(xy 70.587328 -53.643298) (xy 70.601244 -53.69324) (xy 70.608264 -53.744608) (xy 70.608698 -53.77053)
			(xy 70.60825 -53.797782) (xy 70.600489 -53.851732) (xy 70.58513 -53.904028) (xy 70.562484 -53.953606)
			(xy 70.533014 -53.999457) (xy 70.497319 -54.040647) (xy 70.456125 -54.076338) (xy 70.410271 -54.105804)
			(xy 70.360691 -54.128444) (xy 70.308393 -54.143798) (xy 70.254442 -54.151553) (xy 70.22719 -54.152038)
			(xy 70.199819 -54.151593) (xy 70.145638 -54.143772) (xy 70.093134 -54.128279) (xy 70.043388 -54.105432)
			(xy 69.997422 -54.075702) (xy 69.976492 -54.058058) (xy 69.976238 -54.057804) (xy 69.969144 -54.052228)
			(xy 69.952233 -54.045975) (xy 69.943218 -54.045612) (xy 69.876162 -54.045612) (xy 69.867143 -54.045948)
			(xy 69.850226 -54.05221) (xy 69.843142 -54.057804) (xy 69.843142 -54.058058) (xy 69.842888 -54.058058)
			(xy 69.821928 -54.075663) (xy 69.775964 -54.105381) (xy 69.726223 -54.128224) (xy 69.673728 -54.143723)
			(xy 69.619557 -54.15156) (xy 69.59219 -54.152038) (xy 69.56494 -54.151532) (xy 69.510994 -54.143775)
			(xy 69.458702 -54.12842) (xy 69.409127 -54.10578) (xy 69.363278 -54.076315) (xy 69.322088 -54.040626)
			(xy 69.286397 -53.999438) (xy 69.25693 -53.953591) (xy 69.234287 -53.904017) (xy 69.21893 -53.851725)
			(xy 69.21117 -53.79778) (xy 69.210682 -53.77053) (xy 68.8465 -53.77053) (xy 68.84543 -53.7718) (xy 68.845176 -53.772054)
			(xy 68.8396 -53.779148) (xy 68.833348 -53.796059) (xy 68.832984 -53.805074) (xy 68.832984 -53.87213)
			(xy 68.83333 -53.881148) (xy 68.839585 -53.898065) (xy 68.845176 -53.90515) (xy 68.84543 -53.90515)
			(xy 68.84543 -53.905404) (xy 68.863074 -53.926334) (xy 68.892802 -53.972301) (xy 68.91565 -54.022048)
			(xy 68.931148 -54.074551) (xy 68.938978 -54.12873) (xy 68.938977 -54.183473) (xy 68.931148 -54.237652)
			(xy 68.915649 -54.290155) (xy 68.901856 -54.320186) (xy 71.130414 -54.320186) (xy 71.130868 -54.292815)
			(xy 71.138689 -54.238636) (xy 71.15418 -54.186132) (xy 71.177025 -54.136386) (xy 71.206752 -54.090419)
			(xy 71.224394 -54.069488) (xy 71.224648 -54.069234) (xy 71.230232 -54.062146) (xy 71.236479 -54.04523)
			(xy 71.23684 -54.036214) (xy 71.23684 -53.969158) (xy 71.236468 -53.960142) (xy 71.230232 -53.943225)
			(xy 71.224648 -53.936138) (xy 71.224394 -53.936138) (xy 71.224394 -53.935884) (xy 71.20678 -53.914932)
			(xy 71.177065 -53.868964) (xy 71.154224 -53.819222) (xy 71.138727 -53.766726) (xy 71.130892 -53.712554)
			(xy 71.130414 -53.685186) (xy 71.1309 -53.657935) (xy 71.138656 -53.603987) (xy 71.154011 -53.551692)
			(xy 71.176653 -53.502115) (xy 71.206119 -53.456265) (xy 71.24181 -53.415074) (xy 71.283001 -53.379383)
			(xy 71.328851 -53.349917) (xy 71.378428 -53.327275) (xy 71.430723 -53.31192) (xy 71.484671 -53.304164)
			(xy 71.539173 -53.304164) (xy 71.593121 -53.31192) (xy 71.645416 -53.327275) (xy 71.694993 -53.349917)
			(xy 71.740843 -53.379383) (xy 71.782034 -53.415074) (xy 71.817725 -53.456265) (xy 71.843618 -53.496556)
			(xy 84.133341 -53.496556) (xy 84.133341 -53.442044) (xy 84.141099 -53.388088) (xy 84.156458 -53.335786)
			(xy 84.179104 -53.286201) (xy 84.208576 -53.240345) (xy 84.244275 -53.199149) (xy 84.285474 -53.163454)
			(xy 84.331333 -53.133986) (xy 84.380919 -53.111345) (xy 84.433224 -53.095992) (xy 84.48718 -53.088238)
			(xy 84.514436 -53.087778) (xy 84.541808 -53.088204) (xy 84.595989 -53.096029) (xy 84.648494 -53.111526)
			(xy 84.69824 -53.134377) (xy 84.744204 -53.164112) (xy 84.765134 -53.181758) (xy 84.765388 -53.182012)
			(xy 84.772473 -53.187601) (xy 84.789391 -53.193846) (xy 84.798408 -53.194204) (xy 84.865464 -53.194204)
			(xy 84.874479 -53.193829) (xy 84.891396 -53.187594) (xy 84.898484 -53.182012) (xy 84.898484 -53.181758)
			(xy 84.898738 -53.181758) (xy 84.919677 -53.164128) (xy 84.965648 -53.134416) (xy 85.015394 -53.111579)
			(xy 85.067893 -53.096085) (xy 85.122067 -53.088254) (xy 85.149436 -53.087778) (xy 85.176685 -53.088295)
			(xy 85.230626 -53.096055) (xy 85.282915 -53.111413) (xy 85.332486 -53.134055) (xy 85.37833 -53.163521)
			(xy 85.419514 -53.199211) (xy 85.4552 -53.240399) (xy 85.484662 -53.286246) (xy 85.5073 -53.335819)
			(xy 85.522653 -53.388109) (xy 85.530408 -53.442051) (xy 85.530408 -53.496549) (xy 85.522653 -53.550491)
			(xy 85.5073 -53.602781) (xy 85.484662 -53.652354) (xy 85.4552 -53.698201) (xy 85.419514 -53.739389)
			(xy 85.37833 -53.775079) (xy 85.332486 -53.804545) (xy 85.282915 -53.827187) (xy 85.230626 -53.842545)
			(xy 85.176685 -53.850305) (xy 85.149436 -53.850794) (xy 85.122066 -53.850308) (xy 85.067888 -53.842495)
			(xy 85.015385 -53.827011) (xy 84.965638 -53.804174) (xy 84.91967 -53.774453) (xy 84.898738 -53.756814)
			(xy 84.898484 -53.75656) (xy 84.89141 -53.750956) (xy 84.874483 -53.744721) (xy 84.865464 -53.744368)
			(xy 84.798408 -53.744368) (xy 84.789392 -53.744736) (xy 84.772476 -53.750977) (xy 84.765388 -53.75656)
			(xy 84.765388 -53.756814) (xy 84.765134 -53.756814) (xy 84.744202 -53.774453) (xy 84.698229 -53.804164)
			(xy 84.648481 -53.827) (xy 84.595981 -53.842491) (xy 84.541805 -53.85032) (xy 84.514436 -53.850794)
			(xy 84.48718 -53.850362) (xy 84.433224 -53.842608) (xy 84.380919 -53.827255) (xy 84.331333 -53.804614)
			(xy 84.285474 -53.775146) (xy 84.244275 -53.739451) (xy 84.208576 -53.698255) (xy 84.179104 -53.652399)
			(xy 84.156458 -53.602814) (xy 84.141099 -53.550512) (xy 84.133341 -53.496556) (xy 71.843618 -53.496556)
			(xy 71.847191 -53.502115) (xy 71.869833 -53.551692) (xy 71.885188 -53.603987) (xy 71.892944 -53.657935)
			(xy 71.89343 -53.685186) (xy 71.892973 -53.712557) (xy 71.885155 -53.766737) (xy 71.869665 -53.819241)
			(xy 71.846821 -53.868988) (xy 71.817093 -53.914953) (xy 71.79945 -53.935884) (xy 71.799196 -53.936138)
			(xy 71.793629 -53.943238) (xy 71.787371 -53.960144) (xy 71.787004 -53.969158) (xy 71.787004 -54.036214)
			(xy 71.787354 -54.045232) (xy 71.793606 -54.062149) (xy 71.799196 -54.069234) (xy 71.79945 -54.069234)
			(xy 71.79945 -54.069488) (xy 71.817089 -54.09042) (xy 71.846803 -54.136392) (xy 71.869639 -54.18614)
			(xy 71.88513 -54.238641) (xy 71.892957 -54.292817) (xy 71.89343 -54.320186) (xy 71.892944 -54.347437)
			(xy 71.885188 -54.401385) (xy 71.869833 -54.45368) (xy 71.847191 -54.503257) (xy 71.817725 -54.549107)
			(xy 71.782034 -54.590298) (xy 71.740843 -54.625989) (xy 71.694993 -54.655455) (xy 71.645416 -54.678097)
			(xy 71.593121 -54.693452) (xy 71.539173 -54.701208) (xy 71.484671 -54.701208) (xy 71.430723 -54.693452)
			(xy 71.378428 -54.678097) (xy 71.328851 -54.655455) (xy 71.283001 -54.625989) (xy 71.24181 -54.590298)
			(xy 71.206119 -54.549107) (xy 71.176653 -54.503257) (xy 71.154011 -54.45368) (xy 71.138656 -54.401385)
			(xy 71.1309 -54.347437) (xy 71.130414 -54.320186) (xy 68.901856 -54.320186) (xy 68.892801 -54.339901)
			(xy 68.863073 -54.385868) (xy 68.84543 -54.4068) (xy 68.845176 -54.407054) (xy 68.8396 -54.414148)
			(xy 68.833348 -54.431059) (xy 68.832984 -54.440074) (xy 68.832984 -54.50713) (xy 68.83333 -54.516148)
			(xy 68.839585 -54.533065) (xy 68.845176 -54.54015) (xy 68.84543 -54.54015) (xy 68.84543 -54.540404)
			(xy 68.863089 -54.56132) (xy 68.892797 -54.607298) (xy 68.915629 -54.657049) (xy 68.931115 -54.709553)
			(xy 68.938938 -54.763732) (xy 68.939055 -54.770528) (xy 72.070976 -54.770528) (xy 72.07144 -54.743157)
			(xy 72.079255 -54.688978) (xy 72.094744 -54.636474) (xy 72.117587 -54.586727) (xy 72.147313 -54.540761)
			(xy 72.164956 -54.51983) (xy 72.16521 -54.519576) (xy 72.170814 -54.512501) (xy 72.17705 -54.495575)
			(xy 72.177402 -54.486556) (xy 72.177402 -54.4195) (xy 72.177045 -54.410483) (xy 72.170797 -54.393566)
			(xy 72.16521 -54.38648) (xy 72.164956 -54.38648) (xy 72.164956 -54.386226) (xy 72.147308 -54.365301)
			(xy 72.117599 -54.319326) (xy 72.094766 -54.269576) (xy 72.079276 -54.217074) (xy 72.071449 -54.162898)
			(xy 72.070976 -54.135528) (xy 72.071462 -54.108277) (xy 72.079218 -54.054329) (xy 72.094573 -54.002034)
			(xy 72.117215 -53.952457) (xy 72.146681 -53.906607) (xy 72.182372 -53.865416) (xy 72.223563 -53.829725)
			(xy 72.269413 -53.800259) (xy 72.31899 -53.777617) (xy 72.371285 -53.762262) (xy 72.425233 -53.754506)
			(xy 72.479735 -53.754506) (xy 72.533683 -53.762262) (xy 72.585978 -53.777617) (xy 72.635555 -53.800259)
			(xy 72.681405 -53.829725) (xy 72.722596 -53.865416) (xy 72.758287 -53.906607) (xy 72.787753 -53.952457)
			(xy 72.792828 -53.96357) (xy 76.772006 -53.96357) (xy 76.776077 -53.907948) (xy 76.788203 -53.853511)
			(xy 76.808126 -53.80142) (xy 76.835422 -53.752785) (xy 76.869508 -53.708642) (xy 76.909657 -53.669933)
			(xy 76.955015 -53.637482) (xy 77.004615 -53.611981) (xy 77.057399 -53.593974) (xy 77.112242 -53.583844)
			(xy 77.167976 -53.581807) (xy 77.223413 -53.587907) (xy 77.27737 -53.602013) (xy 77.328699 -53.623825)
			(xy 77.376305 -53.652879) (xy 77.419173 -53.688554) (xy 77.45639 -53.730091) (xy 77.487163 -53.776604)
			(xy 77.510835 -53.827101) (xy 77.526903 -53.880508) (xy 77.535023 -53.935684) (xy 77.535532 -53.96357)
			(xy 77.535023 -53.991456) (xy 77.526903 -54.046632) (xy 77.510835 -54.100039) (xy 77.487163 -54.150536)
			(xy 77.45639 -54.197049) (xy 77.419173 -54.238586) (xy 77.376305 -54.274261) (xy 77.328699 -54.303315)
			(xy 77.27737 -54.325127) (xy 77.223413 -54.339233) (xy 77.167976 -54.345333) (xy 77.112242 -54.343296)
			(xy 77.057399 -54.333166) (xy 77.004615 -54.315159) (xy 76.955015 -54.289658) (xy 76.909657 -54.257207)
			(xy 76.869508 -54.218498) (xy 76.835422 -54.174355) (xy 76.808126 -54.12572) (xy 76.788203 -54.073629)
			(xy 76.776077 -54.019192) (xy 76.772006 -53.96357) (xy 72.792828 -53.96357) (xy 72.810395 -54.002034)
			(xy 72.82575 -54.054329) (xy 72.833506 -54.108277) (xy 72.833992 -54.135528) (xy 72.833544 -54.162899)
			(xy 72.825722 -54.217079) (xy 72.810229 -54.269582) (xy 72.787383 -54.319329) (xy 72.757655 -54.365295)
			(xy 72.740012 -54.386226) (xy 72.739758 -54.38648) (xy 72.734169 -54.393564) (xy 72.727925 -54.410483)
			(xy 72.727566 -54.4195) (xy 72.727566 -54.486556) (xy 72.727951 -54.49557) (xy 72.73418 -54.512487)
			(xy 72.739758 -54.519576) (xy 72.740012 -54.519576) (xy 72.740012 -54.51983) (xy 72.757634 -54.540776)
			(xy 72.787348 -54.586745) (xy 72.810187 -54.636489) (xy 72.825682 -54.688987) (xy 72.833515 -54.74316)
			(xy 72.833992 -54.770528) (xy 72.833506 -54.797779) (xy 72.82575 -54.851727) (xy 72.810395 -54.904022)
			(xy 72.787753 -54.953599) (xy 72.764967 -54.989055) (xy 81.900945 -54.989055) (xy 81.900945 -54.934545)
			(xy 81.908703 -54.88059) (xy 81.924061 -54.828288) (xy 81.946706 -54.778705) (xy 81.976178 -54.732849)
			(xy 82.011876 -54.691654) (xy 82.053073 -54.65596) (xy 82.098931 -54.626492) (xy 82.148516 -54.60385)
			(xy 82.200819 -54.588497) (xy 82.254775 -54.580743) (xy 82.28203 -54.580282) (xy 82.310122 -54.580753)
			(xy 82.365701 -54.588985) (xy 82.41947 -54.60528) (xy 82.470268 -54.629286) (xy 82.516994 -54.660485)
			(xy 82.558639 -54.6982) (xy 82.5943 -54.741616) (xy 82.609182 -54.765448) (xy 82.614516 -54.774338)
			(xy 82.631534 -54.78653) (xy 82.724752 -54.80685) (xy 82.745326 -54.802532) (xy 82.753962 -54.79669)
			(xy 82.778034 -54.780703) (xy 82.829963 -54.755357) (xy 82.885118 -54.738128) (xy 82.94224 -54.729409)
			(xy 82.971132 -54.728872) (xy 82.998383 -54.729348) (xy 83.05233 -54.737108) (xy 83.104624 -54.752467)
			(xy 83.1542 -54.77511) (xy 83.200049 -54.804578) (xy 83.241238 -54.84027) (xy 83.27693 -54.88146)
			(xy 83.306396 -54.927311) (xy 83.329038 -54.976887) (xy 83.344394 -55.029182) (xy 83.352153 -55.083129)
			(xy 83.35264 -55.11038) (xy 83.352177 -55.137751) (xy 83.344361 -55.19193) (xy 83.328872 -55.244434)
			(xy 83.306029 -55.294181) (xy 83.276302 -55.340147) (xy 83.25866 -55.361078) (xy 83.258406 -55.361332)
			(xy 83.252842 -55.368434) (xy 83.246582 -55.385339) (xy 83.246214 -55.394352) (xy 83.246214 -55.461408)
			(xy 83.246564 -55.470426) (xy 83.252816 -55.487343) (xy 83.258406 -55.494428) (xy 83.25866 -55.494428)
			(xy 83.25866 -55.494682) (xy 83.276282 -55.51563) (xy 83.306008 -55.561595) (xy 83.328856 -55.611339)
			(xy 83.344354 -55.663839) (xy 83.352185 -55.718015) (xy 83.352187 -55.772755) (xy 83.34436 -55.826932)
			(xy 83.328866 -55.879433) (xy 83.306023 -55.929178) (xy 83.2763 -55.975146) (xy 83.25866 -55.996078)
			(xy 83.258406 -55.996332) (xy 83.252842 -56.003434) (xy 83.246582 -56.020339) (xy 83.246214 -56.029352)
			(xy 83.246214 -56.096408) (xy 83.246564 -56.105426) (xy 83.252816 -56.122343) (xy 83.258406 -56.129428)
			(xy 83.25866 -56.129428) (xy 83.25866 -56.129682) (xy 83.276298 -56.150615) (xy 83.306011 -56.196587)
			(xy 83.328848 -56.246334) (xy 83.344339 -56.298835) (xy 83.352167 -56.353011) (xy 83.35264 -56.38038)
			(xy 83.352154 -56.407631) (xy 83.344398 -56.461579) (xy 83.329043 -56.513874) (xy 83.306401 -56.563451)
			(xy 83.276935 -56.609301) (xy 83.241244 -56.650492) (xy 83.200053 -56.686183) (xy 83.154203 -56.715649)
			(xy 83.104626 -56.738291) (xy 83.052331 -56.753646) (xy 82.998383 -56.761402) (xy 82.943881 -56.761402)
			(xy 82.889933 -56.753646) (xy 82.837638 -56.738291) (xy 82.788061 -56.715649) (xy 82.742211 -56.686183)
			(xy 82.70102 -56.650492) (xy 82.665329 -56.609301) (xy 82.635863 -56.563451) (xy 82.613221 -56.513874)
			(xy 82.597866 -56.461579) (xy 82.59011 -56.407631) (xy 82.589624 -56.38038) (xy 82.590072 -56.353009)
			(xy 82.597894 -56.298829) (xy 82.613387 -56.246325) (xy 82.636232 -56.196579) (xy 82.665961 -56.150613)
			(xy 82.683604 -56.129682) (xy 82.683858 -56.129428) (xy 82.689446 -56.122343) (xy 82.69569 -56.105425)
			(xy 82.69605 -56.096408) (xy 82.69605 -56.029352) (xy 82.695679 -56.020336) (xy 82.689442 -56.003419)
			(xy 82.683858 -55.996332) (xy 82.683604 -55.996332) (xy 82.683604 -55.996078) (xy 82.665945 -55.975161)
			(xy 82.636222 -55.92919) (xy 82.61338 -55.879441) (xy 82.597886 -55.826936) (xy 82.59006 -55.772756)
			(xy 82.590062 -55.718014) (xy 82.597892 -55.663834) (xy 82.61339 -55.611331) (xy 82.636237 -55.561584)
			(xy 82.665963 -55.515615) (xy 82.683604 -55.494682) (xy 82.683858 -55.494428) (xy 82.689446 -55.487343)
			(xy 82.69569 -55.470425) (xy 82.69605 -55.461408) (xy 82.69605 -55.394352) (xy 82.695679 -55.385336)
			(xy 82.689442 -55.368419) (xy 82.683858 -55.361332) (xy 82.683604 -55.360824) (xy 82.672661 -55.348089)
			(xy 82.652819 -55.320998) (xy 82.64398 -55.306722) (xy 82.638646 -55.297832) (xy 82.621628 -55.28564)
			(xy 82.52841 -55.26532) (xy 82.507836 -55.269638) (xy 82.4992 -55.27548) (xy 82.475136 -55.29148)
			(xy 82.423205 -55.316823) (xy 82.368047 -55.334049) (xy 82.310923 -55.342764) (xy 82.28203 -55.343298)
			(xy 82.254775 -55.342857) (xy 82.200819 -55.335103) (xy 82.148516 -55.31975) (xy 82.098931 -55.297108)
			(xy 82.053073 -55.26764) (xy 82.011876 -55.231946) (xy 81.976178 -55.190751) (xy 81.946706 -55.144895)
			(xy 81.924061 -55.095312) (xy 81.908703 -55.04301) (xy 81.900945 -54.989055) (xy 72.764967 -54.989055)
			(xy 72.758287 -54.999449) (xy 72.722596 -55.04064) (xy 72.681405 -55.076331) (xy 72.635555 -55.105797)
			(xy 72.585978 -55.128439) (xy 72.533683 -55.143794) (xy 72.479735 -55.15155) (xy 72.425233 -55.15155)
			(xy 72.371285 -55.143794) (xy 72.31899 -55.128439) (xy 72.269413 -55.105797) (xy 72.223563 -55.076331)
			(xy 72.182372 -55.04064) (xy 72.146681 -54.999449) (xy 72.117215 -54.953599) (xy 72.094573 -54.904022)
			(xy 72.079218 -54.851727) (xy 72.071462 -54.797779) (xy 72.070976 -54.770528) (xy 68.939055 -54.770528)
			(xy 68.93941 -54.791102) (xy 68.938924 -54.818353) (xy 68.931168 -54.872301) (xy 68.915813 -54.924596)
			(xy 68.893171 -54.974173) (xy 68.863705 -55.020023) (xy 68.828014 -55.061214) (xy 68.786823 -55.096905)
			(xy 68.740973 -55.126371) (xy 68.691396 -55.149013) (xy 68.639101 -55.164368) (xy 68.585153 -55.172124)
			(xy 68.530651 -55.172124) (xy 68.476703 -55.164368) (xy 68.424408 -55.149013) (xy 68.374831 -55.126371)
			(xy 68.328981 -55.096905) (xy 68.28779 -55.061214) (xy 68.252099 -55.020023) (xy 68.222633 -54.974173)
			(xy 68.199991 -54.924596) (xy 68.184636 -54.872301) (xy 68.17688 -54.818353) (xy 68.176394 -54.791102)
			(xy 66.278596 -54.791102) (xy 66.273344 -54.821374) (xy 66.258375 -54.869251) (xy 66.237272 -54.914758)
			(xy 66.22415 -54.936136) (xy 66.221864 -54.939692) (xy 66.220086 -54.946296) (xy 66.218054 -54.959758)
			(xy 66.211196 -55.625238) (xy 66.211196 -55.722266) (xy 77.83398 -55.722266) (xy 77.838051 -55.666644)
			(xy 77.850177 -55.612207) (xy 77.8701 -55.560116) (xy 77.897396 -55.511481) (xy 77.931482 -55.467338)
			(xy 77.971631 -55.428629) (xy 78.016989 -55.396178) (xy 78.066589 -55.370677) (xy 78.119373 -55.35267)
			(xy 78.174216 -55.34254) (xy 78.22995 -55.340503) (xy 78.285387 -55.346603) (xy 78.339344 -55.360709)
			(xy 78.390673 -55.382521) (xy 78.438279 -55.411575) (xy 78.44943 -55.420855) (xy 80.224545 -55.420855)
			(xy 80.224545 -55.366345) (xy 80.232303 -55.31239) (xy 80.247661 -55.260088) (xy 80.270306 -55.210505)
			(xy 80.299778 -55.164649) (xy 80.335476 -55.123454) (xy 80.376673 -55.08776) (xy 80.422531 -55.058292)
			(xy 80.472116 -55.03565) (xy 80.524419 -55.020297) (xy 80.578375 -55.012543) (xy 80.60563 -55.012082)
			(xy 80.631944 -55.012535) (xy 80.684073 -55.019774) (xy 80.734716 -55.034096) (xy 80.782915 -55.055231)
			(xy 80.827758 -55.082779) (xy 80.868397 -55.11622) (xy 80.886554 -55.135272) (xy 80.894057 -55.142695)
			(xy 80.913351 -55.151208) (xy 80.923892 -55.151782) (xy 80.998568 -55.151782) (xy 81.009118 -55.151255)
			(xy 81.028414 -55.142719) (xy 81.035906 -55.135272) (xy 81.05406 -55.116215) (xy 81.094691 -55.082759)
			(xy 81.139532 -55.055201) (xy 81.187733 -55.034063) (xy 81.23838 -55.019746) (xy 81.290514 -55.012521)
			(xy 81.31683 -55.012082) (xy 81.344079 -55.01259) (xy 81.398022 -55.02035) (xy 81.450312 -55.035707)
			(xy 81.499884 -55.05835) (xy 81.545729 -55.087816) (xy 81.586915 -55.123506) (xy 81.622602 -55.164695)
			(xy 81.652065 -55.210542) (xy 81.674703 -55.260116) (xy 81.690056 -55.312407) (xy 81.697812 -55.366351)
			(xy 81.697812 -55.420849) (xy 81.690056 -55.474793) (xy 81.674703 -55.527084) (xy 81.652065 -55.576658)
			(xy 81.622602 -55.622505) (xy 81.586915 -55.663694) (xy 81.545729 -55.699384) (xy 81.499884 -55.72885)
			(xy 81.450312 -55.751493) (xy 81.398022 -55.76685) (xy 81.344079 -55.77461) (xy 81.31683 -55.775098)
			(xy 81.290514 -55.774678) (xy 81.238384 -55.767433) (xy 81.18774 -55.753105) (xy 81.139541 -55.731964)
			(xy 81.094699 -55.704409) (xy 81.054061 -55.670963) (xy 81.035906 -55.651908) (xy 81.028383 -55.644508)
			(xy 81.009104 -55.635983) (xy 80.998568 -55.635398) (xy 80.923892 -55.635398) (xy 80.91334 -55.63591)
			(xy 80.894045 -55.644457) (xy 80.886554 -55.651908) (xy 80.868415 -55.67098) (xy 80.827782 -55.704436)
			(xy 80.782938 -55.731992) (xy 80.734734 -55.753128) (xy 80.684084 -55.767441) (xy 80.631947 -55.774662)
			(xy 80.60563 -55.775098) (xy 80.578375 -55.774657) (xy 80.524419 -55.766903) (xy 80.472116 -55.75155)
			(xy 80.422531 -55.728908) (xy 80.376673 -55.69944) (xy 80.335476 -55.663746) (xy 80.299778 -55.622551)
			(xy 80.270306 -55.576695) (xy 80.247661 -55.527112) (xy 80.232303 -55.47481) (xy 80.224545 -55.420855)
			(xy 78.44943 -55.420855) (xy 78.481147 -55.44725) (xy 78.518364 -55.488787) (xy 78.549137 -55.5353)
			(xy 78.572809 -55.585797) (xy 78.588877 -55.639204) (xy 78.596997 -55.69438) (xy 78.597506 -55.722266)
			(xy 78.596997 -55.750152) (xy 78.588877 -55.805328) (xy 78.572809 -55.858735) (xy 78.549137 -55.909232)
			(xy 78.518364 -55.955745) (xy 78.481147 -55.997282) (xy 78.438279 -56.032957) (xy 78.390673 -56.062011)
			(xy 78.339344 -56.083823) (xy 78.285387 -56.097929) (xy 78.22995 -56.104029) (xy 78.174216 -56.101992)
			(xy 78.119373 -56.091862) (xy 78.066589 -56.073855) (xy 78.016989 -56.048354) (xy 77.971631 -56.015903)
			(xy 77.931482 -55.977194) (xy 77.897396 -55.933051) (xy 77.8701 -55.884416) (xy 77.850177 -55.832325)
			(xy 77.838051 -55.777888) (xy 77.83398 -55.722266) (xy 66.211196 -55.722266) (xy 66.211196 -56.586628)
			(xy 66.211423 -56.594132) (xy 66.215808 -56.608484) (xy 66.219832 -56.614822) (xy 66.234328 -56.637445)
			(xy 66.257514 -56.685915) (xy 66.273674 -56.737157) (xy 66.282488 -56.79016) (xy 66.283586 -56.817006)
			(xy 66.283586 -56.84012) (xy 66.281989 -56.86926) (xy 66.271043 -56.926581) (xy 66.251492 -56.981565)
			(xy 66.239967 -57.002934) (xy 73.56348 -57.002934) (xy 73.564003 -56.974843) (xy 73.572225 -56.919268)
			(xy 73.588511 -56.865499) (xy 73.612509 -56.814702) (xy 73.6437 -56.767975) (xy 73.681408 -56.726329)
			(xy 73.724817 -56.690665) (xy 73.748646 -56.675782) (xy 73.757536 -56.670448) (xy 73.769728 -56.65343)
			(xy 73.790048 -56.560212) (xy 73.78573 -56.539638) (xy 73.779888 -56.531002) (xy 73.763885 -56.50694)
			(xy 73.738544 -56.455008) (xy 73.721319 -56.399849) (xy 73.712604 -56.342725) (xy 73.71207 -56.313832)
			(xy 73.712585 -56.286581) (xy 73.720337 -56.232633) (xy 73.735688 -56.180337) (xy 73.758325 -56.130759)
			(xy 73.787788 -56.084907) (xy 73.823476 -56.043714) (xy 73.864663 -56.00802) (xy 73.910511 -55.978551)
			(xy 73.960087 -55.955907) (xy 74.01238 -55.940549) (xy 74.066327 -55.932789) (xy 74.093578 -55.932324)
			(xy 74.120948 -55.932797) (xy 74.175127 -55.940612) (xy 74.22763 -55.956099) (xy 74.277377 -55.97894)
			(xy 74.323344 -56.008663) (xy 74.344276 -56.026304) (xy 74.34453 -56.026558) (xy 74.351627 -56.032128)
			(xy 74.368536 -56.038383) (xy 74.37755 -56.03875) (xy 74.444606 -56.03875) (xy 74.453624 -56.038406)
			(xy 74.470542 -56.032151) (xy 74.477626 -56.026558) (xy 74.477626 -56.026304) (xy 74.47788 -56.026304)
			(xy 74.498813 -56.008663) (xy 74.544781 -55.978939) (xy 74.594527 -55.956093) (xy 74.647029 -55.940597)
			(xy 74.701207 -55.932768) (xy 74.755949 -55.932768) (xy 74.810127 -55.940597) (xy 74.862629 -55.956093)
			(xy 74.912375 -55.978939) (xy 74.958343 -56.008663) (xy 74.979276 -56.026304) (xy 74.97953 -56.026558)
			(xy 74.986627 -56.032128) (xy 75.003536 -56.038383) (xy 75.01255 -56.03875) (xy 75.079606 -56.03875)
			(xy 75.088624 -56.038406) (xy 75.105542 -56.032151) (xy 75.112626 -56.026558) (xy 75.112626 -56.026304)
			(xy 75.11288 -56.026304) (xy 75.133809 -56.008661) (xy 75.179783 -55.97895) (xy 75.229531 -55.956115)
			(xy 75.282032 -55.940624) (xy 75.336209 -55.932797) (xy 75.363578 -55.932324) (xy 75.390834 -55.932721)
			(xy 75.444792 -55.940477) (xy 75.497097 -55.955832) (xy 75.546684 -55.978475) (xy 75.592544 -56.007945)
			(xy 75.633743 -56.043642) (xy 75.669442 -56.084838) (xy 75.698914 -56.130697) (xy 75.72156 -56.180282)
			(xy 75.736919 -56.232586) (xy 75.744677 -56.286544) (xy 75.744677 -56.297068) (xy 76.08646 -56.297068)
			(xy 76.090531 -56.241446) (xy 76.102657 -56.187009) (xy 76.12258 -56.134918) (xy 76.149876 -56.086283)
			(xy 76.183962 -56.04214) (xy 76.224111 -56.003431) (xy 76.269469 -55.97098) (xy 76.319069 -55.945479)
			(xy 76.371853 -55.927472) (xy 76.426696 -55.917342) (xy 76.48243 -55.915305) (xy 76.537867 -55.921405)
			(xy 76.591824 -55.935511) (xy 76.643153 -55.957323) (xy 76.690759 -55.986377) (xy 76.733627 -56.022052)
			(xy 76.770844 -56.063589) (xy 76.801617 -56.110102) (xy 76.825289 -56.160599) (xy 76.841357 -56.214006)
			(xy 76.849477 -56.269182) (xy 76.849986 -56.297068) (xy 76.849477 -56.324954) (xy 76.841357 -56.38013)
			(xy 76.825289 -56.433537) (xy 76.801617 -56.484034) (xy 76.770844 -56.530547) (xy 76.733627 -56.572084)
			(xy 76.690759 -56.607759) (xy 76.643153 -56.636813) (xy 76.591824 -56.658625) (xy 76.537867 -56.672731)
			(xy 76.48243 -56.678831) (xy 76.426696 -56.676794) (xy 76.371853 -56.666664) (xy 76.319069 -56.648657)
			(xy 76.269469 -56.623156) (xy 76.224111 -56.590705) (xy 76.183962 -56.551996) (xy 76.149876 -56.507853)
			(xy 76.12258 -56.459218) (xy 76.102657 -56.407127) (xy 76.090531 -56.35269) (xy 76.08646 -56.297068)
			(xy 75.744677 -56.297068) (xy 75.744677 -56.341056) (xy 75.736919 -56.395014) (xy 75.72156 -56.447318)
			(xy 75.698914 -56.496903) (xy 75.669442 -56.542762) (xy 75.633743 -56.583958) (xy 75.592544 -56.619655)
			(xy 75.546684 -56.649125) (xy 75.497097 -56.671768) (xy 75.444792 -56.687123) (xy 75.390834 -56.694879)
			(xy 75.363578 -56.69534) (xy 75.336207 -56.694901) (xy 75.282026 -56.687079) (xy 75.229522 -56.671585)
			(xy 75.179775 -56.648736) (xy 75.13381 -56.619005) (xy 75.11288 -56.60136) (xy 75.112626 -56.601106)
			(xy 75.105536 -56.595525) (xy 75.088622 -56.589275) (xy 75.079606 -56.588914) (xy 75.01255 -56.588914)
			(xy 75.003535 -56.589292) (xy 74.986618 -56.595525) (xy 74.97953 -56.601106) (xy 74.97953 -56.60136)
			(xy 74.979276 -56.60136) (xy 74.958343 -56.619001) (xy 74.912375 -56.648725) (xy 74.862629 -56.671571)
			(xy 74.810127 -56.687067) (xy 74.755949 -56.694896) (xy 74.701207 -56.694896) (xy 74.647029 -56.687067)
			(xy 74.594527 -56.671571) (xy 74.544781 -56.648725) (xy 74.498813 -56.619001) (xy 74.47788 -56.60136)
			(xy 74.477626 -56.601106) (xy 74.470536 -56.595525) (xy 74.453622 -56.589275) (xy 74.444606 -56.588914)
			(xy 74.37755 -56.588914) (xy 74.368535 -56.589292) (xy 74.351618 -56.595525) (xy 74.34453 -56.601106)
			(xy 74.344022 -56.60136) (xy 74.33129 -56.612307) (xy 74.304197 -56.632146) (xy 74.28992 -56.640984)
			(xy 74.28103 -56.646318) (xy 74.268838 -56.663336) (xy 74.248518 -56.756554) (xy 74.252836 -56.777128)
			(xy 74.258678 -56.785764) (xy 74.274662 -56.809838) (xy 74.300009 -56.861765) (xy 74.317239 -56.91692)
			(xy 74.325959 -56.974042) (xy 74.326496 -57.002934) (xy 74.32601 -57.030185) (xy 74.318254 -57.084133)
			(xy 74.302899 -57.136428) (xy 74.280257 -57.186005) (xy 74.250791 -57.231855) (xy 74.2151 -57.273046)
			(xy 74.173909 -57.308737) (xy 74.128059 -57.338203) (xy 74.078482 -57.360845) (xy 74.026187 -57.3762)
			(xy 73.972239 -57.383956) (xy 73.917737 -57.383956) (xy 73.863789 -57.3762) (xy 73.811494 -57.360845)
			(xy 73.761917 -57.338203) (xy 73.716067 -57.308737) (xy 73.674876 -57.273046) (xy 73.639185 -57.231855)
			(xy 73.609719 -57.186005) (xy 73.587077 -57.136428) (xy 73.571722 -57.084133) (xy 73.563966 -57.030185)
			(xy 73.56348 -57.002934) (xy 66.239967 -57.002934) (xy 66.223791 -57.032928) (xy 66.206624 -57.056528)
			(xy 66.20637 -57.057036) (xy 66.20215 -57.063009) (xy 66.196991 -57.076688) (xy 66.19621 -57.08396)
			(xy 66.19494 -57.198768) (xy 66.195001 -57.203041) (xy 66.19641 -57.211469) (xy 66.197734 -57.215532)
			(xy 66.20002 -57.222644) (xy 66.205354 -57.229502) (xy 66.217172 -57.24548) (xy 66.237793 -57.279456)
			(xy 66.246502 -57.29732) (xy 66.253918 -57.313313) (xy 66.266129 -57.346385) (xy 66.270886 -57.36336)
			(xy 66.271648 -57.366408) (xy 66.271902 -57.366916) (xy 66.271902 -57.36717) (xy 66.277397 -57.390339)
			(xy 66.283256 -57.437595) (xy 66.283586 -57.461404) (xy 66.283586 -57.473596) (xy 66.282998 -57.48528)
			(xy 82.605878 -57.48528) (xy 82.609949 -57.429658) (xy 82.622075 -57.375221) (xy 82.641998 -57.32313)
			(xy 82.669294 -57.274495) (xy 82.70338 -57.230352) (xy 82.743529 -57.191643) (xy 82.788887 -57.159192)
			(xy 82.838487 -57.133691) (xy 82.891271 -57.115684) (xy 82.946114 -57.105554) (xy 83.001848 -57.103517)
			(xy 83.057285 -57.109617) (xy 83.111242 -57.123723) (xy 83.162571 -57.145535) (xy 83.210177 -57.174589)
			(xy 83.253045 -57.210264) (xy 83.290262 -57.251801) (xy 83.321035 -57.298314) (xy 83.344707 -57.348811)
			(xy 83.360775 -57.402218) (xy 83.368895 -57.457394) (xy 83.369404 -57.48528) (xy 83.368895 -57.513166)
			(xy 83.360775 -57.568342) (xy 83.344707 -57.621749) (xy 83.321035 -57.672246) (xy 83.290262 -57.718759)
			(xy 83.253045 -57.760296) (xy 83.210177 -57.795971) (xy 83.162571 -57.825025) (xy 83.111242 -57.846837)
			(xy 83.057285 -57.860943) (xy 83.001848 -57.867043) (xy 82.946114 -57.865006) (xy 82.891271 -57.854876)
			(xy 82.838487 -57.836869) (xy 82.788887 -57.811368) (xy 82.743529 -57.778917) (xy 82.70338 -57.740208)
			(xy 82.669294 -57.696065) (xy 82.641998 -57.64743) (xy 82.622075 -57.595339) (xy 82.609949 -57.540902)
			(xy 82.605878 -57.48528) (xy 66.282998 -57.48528) (xy 66.282109 -57.502931) (xy 66.271264 -57.560656)
			(xy 66.251707 -57.616038) (xy 66.223898 -57.667772) (xy 66.206624 -57.691528) (xy 66.199766 -57.700672)
			(xy 66.195538 -57.706643) (xy 66.190362 -57.72032) (xy 66.189606 -57.727596) (xy 66.189098 -57.79389)
			(xy 66.18859 -57.844436) (xy 66.189606 -57.845706) (xy 66.194432 -57.851294) (xy 66.198242 -57.855866)
			(xy 66.20129 -57.859168) (xy 66.202052 -57.860438) (xy 66.20383 -57.862724) (xy 66.21611 -57.879083)
			(xy 66.237491 -57.913957) (xy 66.246502 -57.93232) (xy 66.253918 -57.948313) (xy 66.266129 -57.981385)
			(xy 66.270886 -57.99836) (xy 66.271648 -58.001408) (xy 66.271902 -58.001916) (xy 66.271902 -58.00217)
			(xy 66.277397 -58.025339) (xy 66.283256 -58.072595) (xy 66.283586 -58.096404) (xy 66.283586 -58.108342)
			(xy 66.282369 -58.133711) (xy 66.274057 -58.183817) (xy 66.259179 -58.232379) (xy 66.237998 -58.278542)
			(xy 66.210888 -58.321492) (xy 66.19494 -58.34126) (xy 66.186558 -58.35142) (xy 66.18478 -58.354214)
			(xy 66.183764 -58.355738) (xy 66.183256 -58.3565) (xy 66.183256 -58.359802) (xy 66.183002 -58.394092)
			(xy 66.18224 -58.469022) (xy 66.187066 -58.476896) (xy 66.18986 -58.480452) (xy 66.194432 -58.485786)
			(xy 66.211893 -58.507348) (xy 66.241053 -58.55455) (xy 66.263076 -58.605474) (xy 66.277498 -58.65905)
			(xy 66.279897 -58.679334) (xy 73.99528 -58.679334) (xy 73.99571 -58.653019) (xy 74.002953 -58.600889)
			(xy 74.01728 -58.550246) (xy 74.03842 -58.502047) (xy 74.065972 -58.457204) (xy 74.099416 -58.416566)
			(xy 74.11847 -58.39841) (xy 74.125865 -58.390883) (xy 74.134394 -58.371607) (xy 74.13498 -58.361072)
			(xy 74.13498 -58.286396) (xy 74.134472 -58.275844) (xy 74.125923 -58.256548) (xy 74.11847 -58.249058)
			(xy 74.099395 -58.230922) (xy 74.065941 -58.190287) (xy 74.038385 -58.145443) (xy 74.01725 -58.097238)
			(xy 74.002937 -58.046588) (xy 73.995716 -57.994451) (xy 73.99528 -57.968134) (xy 73.995766 -57.940883)
			(xy 74.003522 -57.886935) (xy 74.018877 -57.83464) (xy 74.041519 -57.785063) (xy 74.070985 -57.739213)
			(xy 74.106676 -57.698022) (xy 74.147867 -57.662331) (xy 74.193717 -57.632865) (xy 74.243294 -57.610223)
			(xy 74.295589 -57.594868) (xy 74.349537 -57.587112) (xy 74.404039 -57.587112) (xy 74.457987 -57.594868)
			(xy 74.510282 -57.610223) (xy 74.559859 -57.632865) (xy 74.605709 -57.662331) (xy 74.6469 -57.698022)
			(xy 74.682591 -57.739213) (xy 74.712057 -57.785063) (xy 74.734699 -57.83464) (xy 74.750054 -57.886935)
			(xy 74.75781 -57.940883) (xy 74.758296 -57.968134) (xy 74.757853 -57.994449) (xy 74.750613 -58.046578)
			(xy 74.743345 -58.072274) (xy 77.993492 -58.072274) (xy 77.997563 -58.016652) (xy 78.009689 -57.962215)
			(xy 78.029612 -57.910124) (xy 78.056908 -57.861489) (xy 78.090994 -57.817346) (xy 78.131143 -57.778637)
			(xy 78.176501 -57.746186) (xy 78.226101 -57.720685) (xy 78.278885 -57.702678) (xy 78.333728 -57.692548)
			(xy 78.389462 -57.690511) (xy 78.444899 -57.696611) (xy 78.498856 -57.710717) (xy 78.550185 -57.732529)
			(xy 78.597791 -57.761583) (xy 78.640659 -57.797258) (xy 78.677876 -57.838795) (xy 78.708649 -57.885308)
			(xy 78.732321 -57.935805) (xy 78.748389 -57.989212) (xy 78.756509 -58.044388) (xy 78.757018 -58.072274)
			(xy 78.756948 -58.076084) (xy 83.357972 -58.076084) (xy 83.362043 -58.020462) (xy 83.374169 -57.966025)
			(xy 83.394092 -57.913934) (xy 83.421388 -57.865299) (xy 83.455474 -57.821156) (xy 83.495623 -57.782447)
			(xy 83.540981 -57.749996) (xy 83.590581 -57.724495) (xy 83.643365 -57.706488) (xy 83.698208 -57.696358)
			(xy 83.753942 -57.694321) (xy 83.809379 -57.700421) (xy 83.863336 -57.714527) (xy 83.914665 -57.736339)
			(xy 83.962271 -57.765393) (xy 84.005139 -57.801068) (xy 84.042356 -57.842605) (xy 84.058692 -57.867296)
			(xy 85.642956 -57.867296) (xy 85.647027 -57.811674) (xy 85.659153 -57.757237) (xy 85.679076 -57.705146)
			(xy 85.706372 -57.656511) (xy 85.740458 -57.612368) (xy 85.780607 -57.573659) (xy 85.825965 -57.541208)
			(xy 85.875565 -57.515707) (xy 85.928349 -57.4977) (xy 85.983192 -57.48757) (xy 86.038926 -57.485533)
			(xy 86.094363 -57.491633) (xy 86.14832 -57.505739) (xy 86.199649 -57.527551) (xy 86.247255 -57.556605)
			(xy 86.290123 -57.59228) (xy 86.32734 -57.633817) (xy 86.358113 -57.68033) (xy 86.381785 -57.730827)
			(xy 86.397853 -57.784234) (xy 86.405973 -57.83941) (xy 86.406482 -57.867296) (xy 86.405973 -57.895182)
			(xy 86.397853 -57.950358) (xy 86.381785 -58.003765) (xy 86.358113 -58.054262) (xy 86.32734 -58.100775)
			(xy 86.290123 -58.142312) (xy 86.247255 -58.177987) (xy 86.199649 -58.207041) (xy 86.14832 -58.228853)
			(xy 86.094363 -58.242959) (xy 86.038926 -58.249059) (xy 85.983192 -58.247022) (xy 85.928349 -58.236892)
			(xy 85.875565 -58.218885) (xy 85.825965 -58.193384) (xy 85.780607 -58.160933) (xy 85.740458 -58.122224)
			(xy 85.706372 -58.078081) (xy 85.679076 -58.029446) (xy 85.659153 -57.977355) (xy 85.647027 -57.922918)
			(xy 85.642956 -57.867296) (xy 84.058692 -57.867296) (xy 84.073129 -57.889118) (xy 84.096801 -57.939615)
			(xy 84.112869 -57.993022) (xy 84.120989 -58.048198) (xy 84.121498 -58.076084) (xy 84.120989 -58.10397)
			(xy 84.112869 -58.159146) (xy 84.096801 -58.212553) (xy 84.073129 -58.26305) (xy 84.042356 -58.309563)
			(xy 84.005139 -58.3511) (xy 83.962271 -58.386775) (xy 83.914665 -58.415829) (xy 83.863336 -58.437641)
			(xy 83.809379 -58.451747) (xy 83.753942 -58.457847) (xy 83.698208 -58.45581) (xy 83.643365 -58.44568)
			(xy 83.590581 -58.427673) (xy 83.540981 -58.402172) (xy 83.495623 -58.369721) (xy 83.455474 -58.331012)
			(xy 83.421388 -58.286869) (xy 83.394092 -58.238234) (xy 83.374169 -58.186143) (xy 83.362043 -58.131706)
			(xy 83.357972 -58.076084) (xy 78.756948 -58.076084) (xy 78.756509 -58.10016) (xy 78.748389 -58.155336)
			(xy 78.732321 -58.208743) (xy 78.708649 -58.25924) (xy 78.677876 -58.305753) (xy 78.640659 -58.34729)
			(xy 78.597791 -58.382965) (xy 78.550185 -58.412019) (xy 78.498856 -58.433831) (xy 78.444899 -58.447937)
			(xy 78.389462 -58.454037) (xy 78.333728 -58.452) (xy 78.278885 -58.44187) (xy 78.226101 -58.423863)
			(xy 78.176501 -58.398362) (xy 78.131143 -58.365911) (xy 78.090994 -58.327202) (xy 78.056908 -58.283059)
			(xy 78.029612 -58.234424) (xy 78.009689 -58.182333) (xy 77.997563 -58.127896) (xy 77.993492 -58.072274)
			(xy 74.743345 -58.072274) (xy 74.736289 -58.097222) (xy 74.715152 -58.145421) (xy 74.687602 -58.190263)
			(xy 74.654159 -58.230902) (xy 74.635106 -58.249058) (xy 74.627722 -58.256594) (xy 74.619187 -58.275863)
			(xy 74.618596 -58.286396) (xy 74.618596 -58.361072) (xy 74.619128 -58.371621) (xy 74.627661 -58.390917)
			(xy 74.635106 -58.39841) (xy 74.654161 -58.416567) (xy 74.687618 -58.457196) (xy 74.715177 -58.502036)
			(xy 74.736315 -58.550237) (xy 74.739421 -58.561224) (xy 84.562186 -58.561224) (xy 84.566257 -58.505602)
			(xy 84.578383 -58.451165) (xy 84.598306 -58.399074) (xy 84.625602 -58.350439) (xy 84.659688 -58.306296)
			(xy 84.699837 -58.267587) (xy 84.745195 -58.235136) (xy 84.794795 -58.209635) (xy 84.847579 -58.191628)
			(xy 84.902422 -58.181498) (xy 84.958156 -58.179461) (xy 85.013593 -58.185561) (xy 85.06755 -58.199667)
			(xy 85.118879 -58.221479) (xy 85.166485 -58.250533) (xy 85.209353 -58.286208) (xy 85.24657 -58.327745)
			(xy 85.277343 -58.374258) (xy 85.301015 -58.424755) (xy 85.317083 -58.478162) (xy 85.325203 -58.533338)
			(xy 85.325712 -58.561224) (xy 85.325203 -58.58911) (xy 85.317083 -58.644286) (xy 85.301015 -58.697693)
			(xy 85.277343 -58.74819) (xy 85.24657 -58.794703) (xy 85.209353 -58.83624) (xy 85.166485 -58.871915)
			(xy 85.118879 -58.900969) (xy 85.06755 -58.922781) (xy 85.013593 -58.936887) (xy 84.958156 -58.942987)
			(xy 84.902422 -58.94095) (xy 84.847579 -58.93082) (xy 84.794795 -58.912813) (xy 84.745195 -58.887312)
			(xy 84.699837 -58.854861) (xy 84.659688 -58.816152) (xy 84.625602 -58.772009) (xy 84.598306 -58.723374)
			(xy 84.578383 -58.671283) (xy 84.566257 -58.616846) (xy 84.562186 -58.561224) (xy 74.739421 -58.561224)
			(xy 74.750633 -58.600884) (xy 74.757857 -58.653018) (xy 74.758296 -58.679334) (xy 74.75781 -58.706585)
			(xy 74.750054 -58.760533) (xy 74.734699 -58.812828) (xy 74.712057 -58.862405) (xy 74.682591 -58.908255)
			(xy 74.6469 -58.949446) (xy 74.605709 -58.985137) (xy 74.559859 -59.014603) (xy 74.510282 -59.037245)
			(xy 74.457987 -59.0526) (xy 74.404039 -59.060356) (xy 74.349537 -59.060356) (xy 74.295589 -59.0526)
			(xy 74.243294 -59.037245) (xy 74.193717 -59.014603) (xy 74.147867 -58.985137) (xy 74.106676 -58.949446)
			(xy 74.070985 -58.908255) (xy 74.041519 -58.862405) (xy 74.018877 -58.812828) (xy 74.003522 -58.760533)
			(xy 73.995766 -58.706585) (xy 73.99528 -58.679334) (xy 66.279897 -58.679334) (xy 66.284015 -58.714148)
			(xy 66.282491 -58.76961) (xy 66.272957 -58.824267) (xy 66.26479 -58.850784) (xy 66.256358 -58.874948)
			(xy 66.233972 -58.920971) (xy 66.205653 -58.963601) (xy 66.189098 -58.983118) (xy 66.183693 -58.989683)
			(xy 66.177195 -59.005386) (xy 66.176398 -59.013852) (xy 66.174763 -59.174634) (xy 83.09305 -59.174634)
			(xy 83.097121 -59.119012) (xy 83.109247 -59.064575) (xy 83.12917 -59.012484) (xy 83.156466 -58.963849)
			(xy 83.190552 -58.919706) (xy 83.230701 -58.880997) (xy 83.276059 -58.848546) (xy 83.325659 -58.823045)
			(xy 83.378443 -58.805038) (xy 83.433286 -58.794908) (xy 83.48902 -58.792871) (xy 83.544457 -58.798971)
			(xy 83.598414 -58.813077) (xy 83.649743 -58.834889) (xy 83.697349 -58.863943) (xy 83.740217 -58.899618)
			(xy 83.777434 -58.941155) (xy 83.808207 -58.987668) (xy 83.831879 -59.038165) (xy 83.847947 -59.091572)
			(xy 83.856067 -59.146748) (xy 83.856576 -59.174634) (xy 83.856067 -59.20252) (xy 83.847947 -59.257696)
			(xy 83.831879 -59.311103) (xy 83.808207 -59.3616) (xy 83.777434 -59.408113) (xy 83.740217 -59.44965)
			(xy 83.697349 -59.485325) (xy 83.649743 -59.514379) (xy 83.598414 -59.536191) (xy 83.544457 -59.550297)
			(xy 83.48902 -59.556397) (xy 83.433286 -59.55436) (xy 83.378443 -59.54423) (xy 83.325659 -59.526223)
			(xy 83.276059 -59.500722) (xy 83.230701 -59.468271) (xy 83.190552 -59.429562) (xy 83.156466 -59.385419)
			(xy 83.12917 -59.336784) (xy 83.109247 -59.284693) (xy 83.097121 -59.230256) (xy 83.09305 -59.174634)
			(xy 66.174763 -59.174634) (xy 66.166173 -60.019254) (xy 74.135661 -60.019254) (xy 74.135661 -59.964746)
			(xy 74.143419 -59.910792) (xy 74.158777 -59.858492) (xy 74.181423 -59.808909) (xy 74.210894 -59.763055)
			(xy 74.246592 -59.721862) (xy 74.287789 -59.686169) (xy 74.333646 -59.656702) (xy 74.383231 -59.634063)
			(xy 74.435533 -59.61871) (xy 74.489488 -59.610958) (xy 74.516742 -59.610498) (xy 74.544111 -59.610999)
			(xy 74.598289 -59.618808) (xy 74.650791 -59.634289) (xy 74.700539 -59.657123) (xy 74.746507 -59.68684)
			(xy 74.76744 -59.704478) (xy 74.767694 -59.704732) (xy 74.774775 -59.710326) (xy 74.791696 -59.716567)
			(xy 74.800714 -59.716924) (xy 74.86777 -59.716924) (xy 74.876785 -59.716547) (xy 74.893702 -59.710313)
			(xy 74.90079 -59.704732) (xy 74.90079 -59.704478) (xy 74.901044 -59.704478) (xy 74.921977 -59.686837)
			(xy 74.967945 -59.657113) (xy 75.017691 -59.634267) (xy 75.070193 -59.618771) (xy 75.124371 -59.610942)
			(xy 75.179113 -59.610942) (xy 75.233291 -59.618771) (xy 75.285793 -59.634267) (xy 75.335539 -59.657113)
			(xy 75.381507 -59.686837) (xy 75.40244 -59.704478) (xy 75.402694 -59.704732) (xy 75.409775 -59.710326)
			(xy 75.426696 -59.716567) (xy 75.435714 -59.716924) (xy 75.50277 -59.716924) (xy 75.511785 -59.716547)
			(xy 75.528702 -59.710313) (xy 75.53579 -59.704732) (xy 75.53579 -59.704478) (xy 75.536044 -59.704478)
			(xy 75.556984 -59.686848) (xy 75.602955 -59.657136) (xy 75.6527 -59.634298) (xy 75.705199 -59.618805)
			(xy 75.759373 -59.610974) (xy 75.786742 -59.610498) (xy 75.813992 -59.610975) (xy 75.867936 -59.618736)
			(xy 75.920226 -59.634095) (xy 75.969799 -59.656739) (xy 76.015645 -59.686207) (xy 76.056831 -59.721899)
			(xy 76.092518 -59.763089) (xy 76.121981 -59.808938) (xy 76.14462 -59.858513) (xy 76.159973 -59.910805)
			(xy 76.167728 -59.96475) (xy 76.167728 -60.01925) (xy 76.159973 -60.073195) (xy 76.14462 -60.125487)
			(xy 76.121981 -60.175062) (xy 76.092518 -60.220911) (xy 76.056831 -60.262101) (xy 76.015645 -60.297793)
			(xy 75.969799 -60.327261) (xy 75.920226 -60.349905) (xy 75.867936 -60.365264) (xy 75.813992 -60.373025)
			(xy 75.786742 -60.373514) (xy 75.759373 -60.37302) (xy 75.705195 -60.365208) (xy 75.652692 -60.349726)
			(xy 75.602945 -60.32689) (xy 75.556977 -60.297172) (xy 75.536044 -60.279534) (xy 75.53579 -60.27928)
			(xy 75.528712 -60.273681) (xy 75.511789 -60.267442) (xy 75.50277 -60.267088) (xy 75.435714 -60.267088)
			(xy 75.426698 -60.267454) (xy 75.409781 -60.273696) (xy 75.402694 -60.27928) (xy 75.40244 -60.279534)
			(xy 75.381507 -60.297175) (xy 75.335539 -60.326899) (xy 75.285793 -60.349745) (xy 75.233291 -60.365241)
			(xy 75.179113 -60.37307) (xy 75.124371 -60.37307) (xy 75.070193 -60.365241) (xy 75.017691 -60.349745)
			(xy 74.967945 -60.326899) (xy 74.921977 -60.297175) (xy 74.901044 -60.279534) (xy 74.90079 -60.27928)
			(xy 74.893712 -60.273681) (xy 74.876789 -60.267442) (xy 74.86777 -60.267088) (xy 74.800714 -60.267088)
			(xy 74.791698 -60.267454) (xy 74.774781 -60.273696) (xy 74.767694 -60.27928) (xy 74.767694 -60.279534)
			(xy 74.76744 -60.279534) (xy 74.746508 -60.297173) (xy 74.700535 -60.326884) (xy 74.650787 -60.349719)
			(xy 74.598287 -60.36521) (xy 74.544111 -60.373039) (xy 74.516742 -60.373514) (xy 74.489488 -60.373042)
			(xy 74.435533 -60.36529) (xy 74.383231 -60.349937) (xy 74.333646 -60.327298) (xy 74.287789 -60.297831)
			(xy 74.246592 -60.262138) (xy 74.210894 -60.220945) (xy 74.181423 -60.175091) (xy 74.158777 -60.125508)
			(xy 74.143419 -60.073208) (xy 74.135661 -60.019254) (xy 66.166173 -60.019254) (xy 66.159928 -60.633356)
			(xy 85.79688 -60.633356) (xy 85.800951 -60.577734) (xy 85.813077 -60.523297) (xy 85.833 -60.471206)
			(xy 85.860296 -60.422571) (xy 85.894382 -60.378428) (xy 85.934531 -60.339719) (xy 85.979889 -60.307268)
			(xy 86.029489 -60.281767) (xy 86.082273 -60.26376) (xy 86.137116 -60.25363) (xy 86.19285 -60.251593)
			(xy 86.248287 -60.257693) (xy 86.302244 -60.271799) (xy 86.353573 -60.293611) (xy 86.401179 -60.322665)
			(xy 86.444047 -60.35834) (xy 86.481264 -60.399877) (xy 86.512037 -60.44639) (xy 86.535709 -60.496887)
			(xy 86.551777 -60.550294) (xy 86.559897 -60.60547) (xy 86.560406 -60.633356) (xy 86.559897 -60.661242)
			(xy 86.551777 -60.716418) (xy 86.535709 -60.769825) (xy 86.512037 -60.820322) (xy 86.481264 -60.866835)
			(xy 86.444047 -60.908372) (xy 86.401179 -60.944047) (xy 86.353573 -60.973101) (xy 86.302244 -60.994913)
			(xy 86.248287 -61.009019) (xy 86.19285 -61.015119) (xy 86.137116 -61.013082) (xy 86.082273 -61.002952)
			(xy 86.029489 -60.984945) (xy 85.979889 -60.959444) (xy 85.934531 -60.926993) (xy 85.894382 -60.888284)
			(xy 85.860296 -60.844141) (xy 85.833 -60.795506) (xy 85.813077 -60.743415) (xy 85.800951 -60.688978)
			(xy 85.79688 -60.633356) (xy 66.159928 -60.633356) (xy 66.151238 -61.487812) (xy 84.304376 -61.487812)
			(xy 84.308447 -61.43219) (xy 84.320573 -61.377753) (xy 84.340496 -61.325662) (xy 84.367792 -61.277027)
			(xy 84.401878 -61.232884) (xy 84.442027 -61.194175) (xy 84.487385 -61.161724) (xy 84.536985 -61.136223)
			(xy 84.589769 -61.118216) (xy 84.644612 -61.108086) (xy 84.700346 -61.106049) (xy 84.755783 -61.112149)
			(xy 84.80974 -61.126255) (xy 84.861069 -61.148067) (xy 84.908675 -61.177121) (xy 84.951543 -61.212796)
			(xy 84.98876 -61.254333) (xy 85.019533 -61.300846) (xy 85.043205 -61.351343) (xy 85.059273 -61.40475)
			(xy 85.067393 -61.459926) (xy 85.067902 -61.487812) (xy 85.067393 -61.515698) (xy 85.059273 -61.570874)
			(xy 85.043205 -61.624281) (xy 85.019533 -61.674778) (xy 84.98876 -61.721291) (xy 84.951543 -61.762828)
			(xy 84.908675 -61.798503) (xy 84.861069 -61.827557) (xy 84.80974 -61.849369) (xy 84.755783 -61.863475)
			(xy 84.700346 -61.869575) (xy 84.644612 -61.867538) (xy 84.589769 -61.857408) (xy 84.536985 -61.839401)
			(xy 84.487385 -61.8139) (xy 84.442027 -61.781449) (xy 84.401878 -61.74274) (xy 84.367792 -61.698597)
			(xy 84.340496 -61.649962) (xy 84.320573 -61.597871) (xy 84.308447 -61.543434) (xy 84.304376 -61.487812)
			(xy 66.151238 -61.487812) (xy 66.144798 -62.121034) (xy 82.24215 -62.121034) (xy 82.246221 -62.065412)
			(xy 82.258347 -62.010975) (xy 82.27827 -61.958884) (xy 82.305566 -61.910249) (xy 82.339652 -61.866106)
			(xy 82.379801 -61.827397) (xy 82.425159 -61.794946) (xy 82.474759 -61.769445) (xy 82.527543 -61.751438)
			(xy 82.582386 -61.741308) (xy 82.63812 -61.739271) (xy 82.693557 -61.745371) (xy 82.747514 -61.759477)
			(xy 82.798843 -61.781289) (xy 82.846449 -61.810343) (xy 82.889317 -61.846018) (xy 82.926534 -61.887555)
			(xy 82.957307 -61.934068) (xy 82.980979 -61.984565) (xy 82.997047 -62.037972) (xy 83.005167 -62.093148)
			(xy 83.005676 -62.121034) (xy 83.005167 -62.14892) (xy 82.997047 -62.204096) (xy 82.980979 -62.257503)
			(xy 82.957307 -62.308) (xy 82.926534 -62.354513) (xy 82.889317 -62.39605) (xy 82.846449 -62.431725)
			(xy 82.798843 -62.460779) (xy 82.747514 -62.482591) (xy 82.693557 -62.496697) (xy 82.63812 -62.502797)
			(xy 82.582386 -62.50076) (xy 82.527543 -62.49063) (xy 82.474759 -62.472623) (xy 82.425159 -62.447122)
			(xy 82.379801 -62.414671) (xy 82.339652 -62.375962) (xy 82.305566 -62.331819) (xy 82.27827 -62.283184)
			(xy 82.258347 -62.231093) (xy 82.246221 -62.176656) (xy 82.24215 -62.121034) (xy 66.144798 -62.121034)
			(xy 66.133687 -63.213549) (xy 74.120788 -63.213549) (xy 74.120788 -63.159052) (xy 74.128543 -63.105109)
			(xy 74.143896 -63.052819) (xy 74.166533 -63.003246) (xy 74.195994 -62.957399) (xy 74.23168 -62.916211)
			(xy 74.272864 -62.880521) (xy 74.318708 -62.851054) (xy 74.368278 -62.828411) (xy 74.420566 -62.813053)
			(xy 74.474508 -62.805291) (xy 74.501756 -62.804802) (xy 74.529125 -62.805293) (xy 74.583303 -62.813105)
			(xy 74.635806 -62.828588) (xy 74.685553 -62.851424) (xy 74.731521 -62.881143) (xy 74.752454 -62.898782)
			(xy 74.752708 -62.899036) (xy 74.759785 -62.904636) (xy 74.776709 -62.910874) (xy 74.785728 -62.911228)
			(xy 74.852784 -62.911228) (xy 74.861799 -62.910857) (xy 74.878716 -62.904618) (xy 74.885804 -62.899036)
			(xy 74.885804 -62.898782) (xy 74.886058 -62.898782) (xy 74.906991 -62.881141) (xy 74.952959 -62.851417)
			(xy 75.002705 -62.828571) (xy 75.055207 -62.813075) (xy 75.109385 -62.805246) (xy 75.164127 -62.805246)
			(xy 75.218305 -62.813075) (xy 75.270807 -62.828571) (xy 75.320553 -62.851417) (xy 75.366521 -62.881141)
			(xy 75.387454 -62.898782) (xy 75.387708 -62.899036) (xy 75.394785 -62.904636) (xy 75.411709 -62.910874)
			(xy 75.420728 -62.911228) (xy 75.487784 -62.911228) (xy 75.496799 -62.910857) (xy 75.513716 -62.904618)
			(xy 75.520804 -62.899036) (xy 75.520804 -62.898782) (xy 75.521058 -62.898782) (xy 75.541993 -62.881146)
			(xy 75.587965 -62.851435) (xy 75.637712 -62.828598) (xy 75.690212 -62.813106) (xy 75.744387 -62.805277)
			(xy 75.771756 -62.804802) (xy 75.799012 -62.805242) (xy 75.852969 -62.812994) (xy 75.905273 -62.828347)
			(xy 75.95486 -62.850987) (xy 76.00072 -62.880455) (xy 76.041919 -62.916149) (xy 76.077619 -62.957344)
			(xy 76.107092 -63.003201) (xy 76.129738 -63.052785) (xy 76.13956 -63.086234) (xy 79.387444 -63.086234)
			(xy 79.391515 -63.030612) (xy 79.403641 -62.976175) (xy 79.423564 -62.924084) (xy 79.45086 -62.875449)
			(xy 79.484946 -62.831306) (xy 79.525095 -62.792597) (xy 79.570453 -62.760146) (xy 79.620053 -62.734645)
			(xy 79.672837 -62.716638) (xy 79.72768 -62.706508) (xy 79.783414 -62.704471) (xy 79.838851 -62.710571)
			(xy 79.892808 -62.724677) (xy 79.944137 -62.746489) (xy 79.991743 -62.775543) (xy 80.034611 -62.811218)
			(xy 80.071828 -62.852755) (xy 80.102601 -62.899268) (xy 80.126273 -62.949765) (xy 80.142341 -63.003172)
			(xy 80.150461 -63.058348) (xy 80.15097 -63.086234) (xy 80.150461 -63.11412) (xy 80.142341 -63.169296)
			(xy 80.126273 -63.222703) (xy 80.102601 -63.2732) (xy 80.102448 -63.273432) (xy 81.57667 -63.273432)
			(xy 81.580741 -63.21781) (xy 81.592867 -63.163373) (xy 81.61279 -63.111282) (xy 81.640086 -63.062647)
			(xy 81.674172 -63.018504) (xy 81.714321 -62.979795) (xy 81.759679 -62.947344) (xy 81.809279 -62.921843)
			(xy 81.862063 -62.903836) (xy 81.916906 -62.893706) (xy 81.97264 -62.891669) (xy 82.028077 -62.897769)
			(xy 82.082034 -62.911875) (xy 82.133363 -62.933687) (xy 82.180969 -62.962741) (xy 82.223837 -62.998416)
			(xy 82.261054 -63.039953) (xy 82.291827 -63.086466) (xy 82.315499 -63.136963) (xy 82.331567 -63.19037)
			(xy 82.339687 -63.245546) (xy 82.340196 -63.273432) (xy 82.339687 -63.301318) (xy 82.331567 -63.356494)
			(xy 82.315499 -63.409901) (xy 82.291827 -63.460398) (xy 82.261054 -63.506911) (xy 82.223837 -63.548448)
			(xy 82.180969 -63.584123) (xy 82.133363 -63.613177) (xy 82.082034 -63.634989) (xy 82.028077 -63.649095)
			(xy 81.97264 -63.655195) (xy 81.916906 -63.653158) (xy 81.862063 -63.643028) (xy 81.809279 -63.625021)
			(xy 81.759679 -63.59952) (xy 81.714321 -63.567069) (xy 81.674172 -63.52836) (xy 81.640086 -63.484217)
			(xy 81.61279 -63.435582) (xy 81.592867 -63.383491) (xy 81.580741 -63.329054) (xy 81.57667 -63.273432)
			(xy 80.102448 -63.273432) (xy 80.071828 -63.319713) (xy 80.034611 -63.36125) (xy 79.991743 -63.396925)
			(xy 79.944137 -63.425979) (xy 79.892808 -63.447791) (xy 79.838851 -63.461897) (xy 79.783414 -63.467997)
			(xy 79.72768 -63.46596) (xy 79.672837 -63.45583) (xy 79.620053 -63.437823) (xy 79.570453 -63.412322)
			(xy 79.525095 -63.379871) (xy 79.484946 -63.341162) (xy 79.45086 -63.297019) (xy 79.423564 -63.248384)
			(xy 79.403641 -63.196293) (xy 79.391515 -63.141856) (xy 79.387444 -63.086234) (xy 76.13956 -63.086234)
			(xy 76.145097 -63.105088) (xy 76.152855 -63.159044) (xy 76.152855 -63.213556) (xy 76.145097 -63.267512)
			(xy 76.129738 -63.319815) (xy 76.107092 -63.369399) (xy 76.077619 -63.415256) (xy 76.041919 -63.456451)
			(xy 76.00072 -63.492145) (xy 75.95486 -63.521613) (xy 75.905273 -63.544253) (xy 75.852969 -63.559606)
			(xy 75.799012 -63.567358) (xy 75.771756 -63.567818) (xy 75.744386 -63.567339) (xy 75.690207 -63.559527)
			(xy 75.637703 -63.544042) (xy 75.587956 -63.521203) (xy 75.541989 -63.491479) (xy 75.521058 -63.473838)
			(xy 75.520804 -63.473584) (xy 75.513722 -63.467991) (xy 75.496802 -63.461749) (xy 75.487784 -63.461392)
			(xy 75.420728 -63.461392) (xy 75.411713 -63.461764) (xy 75.394796 -63.468001) (xy 75.387708 -63.473584)
			(xy 75.387454 -63.473838) (xy 75.366521 -63.491479) (xy 75.320553 -63.521203) (xy 75.270807 -63.544049)
			(xy 75.218305 -63.559545) (xy 75.164127 -63.567374) (xy 75.109385 -63.567374) (xy 75.055207 -63.559545)
			(xy 75.002705 -63.544049) (xy 74.952959 -63.521203) (xy 74.906991 -63.491479) (xy 74.886058 -63.473838)
			(xy 74.885804 -63.473584) (xy 74.878722 -63.467991) (xy 74.861802 -63.461749) (xy 74.852784 -63.461392)
			(xy 74.785728 -63.461392) (xy 74.776713 -63.461764) (xy 74.759796 -63.468001) (xy 74.752708 -63.473584)
			(xy 74.752708 -63.473838) (xy 74.752454 -63.473838) (xy 74.731518 -63.491472) (xy 74.685545 -63.521183)
			(xy 74.635799 -63.54402) (xy 74.583299 -63.559512) (xy 74.529125 -63.567343) (xy 74.501756 -63.567818)
			(xy 74.474508 -63.567309) (xy 74.420566 -63.559547) (xy 74.368278 -63.544189) (xy 74.318708 -63.521546)
			(xy 74.272864 -63.492079) (xy 74.23168 -63.456389) (xy 74.195994 -63.415201) (xy 74.166533 -63.369354)
			(xy 74.143896 -63.319781) (xy 74.128543 -63.267491) (xy 74.120788 -63.213549) (xy 66.133687 -63.213549)
			(xy 66.119756 -64.58331) (xy 66.119756 -65.100962) (xy 72.132442 -65.100962) (xy 72.136513 -65.04534)
			(xy 72.148639 -64.990903) (xy 72.168562 -64.938812) (xy 72.195858 -64.890177) (xy 72.229944 -64.846034)
			(xy 72.270093 -64.807325) (xy 72.315451 -64.774874) (xy 72.365051 -64.749373) (xy 72.417835 -64.731366)
			(xy 72.472678 -64.721236) (xy 72.528412 -64.719199) (xy 72.583849 -64.725299) (xy 72.637806 -64.739405)
			(xy 72.689135 -64.761217) (xy 72.736741 -64.790271) (xy 72.779609 -64.825946) (xy 72.816826 -64.867483)
			(xy 72.847599 -64.913996) (xy 72.871271 -64.964493) (xy 72.887339 -65.0179) (xy 72.895459 -65.073076)
			(xy 72.895968 -65.100962) (xy 72.895546 -65.124076) (xy 84.107272 -65.124076) (xy 84.111343 -65.068454)
			(xy 84.123469 -65.014017) (xy 84.143392 -64.961926) (xy 84.170688 -64.913291) (xy 84.204774 -64.869148)
			(xy 84.244923 -64.830439) (xy 84.290281 -64.797988) (xy 84.339881 -64.772487) (xy 84.392665 -64.75448)
			(xy 84.447508 -64.74435) (xy 84.503242 -64.742313) (xy 84.558679 -64.748413) (xy 84.612636 -64.762519)
			(xy 84.663965 -64.784331) (xy 84.711571 -64.813385) (xy 84.754439 -64.84906) (xy 84.791656 -64.890597)
			(xy 84.822429 -64.93711) (xy 84.846101 -64.987607) (xy 84.862169 -65.041014) (xy 84.870289 -65.09619)
			(xy 84.870798 -65.124076) (xy 84.870289 -65.151962) (xy 84.862169 -65.207138) (xy 84.846101 -65.260545)
			(xy 84.822429 -65.311042) (xy 84.791656 -65.357555) (xy 84.754439 -65.399092) (xy 84.711571 -65.434767)
			(xy 84.663965 -65.463821) (xy 84.612636 -65.485633) (xy 84.558679 -65.499739) (xy 84.503242 -65.505839)
			(xy 84.447508 -65.503802) (xy 84.392665 -65.493672) (xy 84.339881 -65.475665) (xy 84.290281 -65.450164)
			(xy 84.244923 -65.417713) (xy 84.204774 -65.379004) (xy 84.170688 -65.334861) (xy 84.143392 -65.286226)
			(xy 84.123469 -65.234135) (xy 84.111343 -65.179698) (xy 84.107272 -65.124076) (xy 72.895546 -65.124076)
			(xy 72.895459 -65.128848) (xy 72.887339 -65.184024) (xy 72.871271 -65.237431) (xy 72.847599 -65.287928)
			(xy 72.816826 -65.334441) (xy 72.779609 -65.375978) (xy 72.736741 -65.411653) (xy 72.689135 -65.440707)
			(xy 72.637806 -65.462519) (xy 72.583849 -65.476625) (xy 72.528412 -65.482725) (xy 72.472678 -65.480688)
			(xy 72.417835 -65.470558) (xy 72.365051 -65.452551) (xy 72.315451 -65.42705) (xy 72.270093 -65.394599)
			(xy 72.229944 -65.35589) (xy 72.195858 -65.311747) (xy 72.168562 -65.263112) (xy 72.148639 -65.211021)
			(xy 72.136513 -65.156584) (xy 72.132442 -65.100962) (xy 66.119756 -65.100962) (xy 66.119756 -65.75552)
			(xy 66.346576 -65.75552) (xy 66.350647 -65.699898) (xy 66.362773 -65.645461) (xy 66.382696 -65.59337)
			(xy 66.409992 -65.544735) (xy 66.444078 -65.500592) (xy 66.484227 -65.461883) (xy 66.529585 -65.429432)
			(xy 66.579185 -65.403931) (xy 66.631969 -65.385924) (xy 66.686812 -65.375794) (xy 66.742546 -65.373757)
			(xy 66.797983 -65.379857) (xy 66.85194 -65.393963) (xy 66.903269 -65.415775) (xy 66.950875 -65.444829)
			(xy 66.993743 -65.480504) (xy 67.03096 -65.522041) (xy 67.061733 -65.568554) (xy 67.085405 -65.619051)
			(xy 67.101473 -65.672458) (xy 67.109593 -65.727634) (xy 67.110102 -65.75552) (xy 67.109593 -65.783406)
			(xy 67.101473 -65.838582) (xy 67.085405 -65.891989) (xy 67.061733 -65.942486) (xy 67.03096 -65.988999)
			(xy 66.993743 -66.030536) (xy 66.950875 -66.066211) (xy 66.903269 -66.095265) (xy 66.85194 -66.117077)
			(xy 66.797983 -66.131183) (xy 66.742546 -66.137283) (xy 66.686812 -66.135246) (xy 66.631969 -66.125116)
			(xy 66.579185 -66.107109) (xy 66.529585 -66.081608) (xy 66.484227 -66.049157) (xy 66.444078 -66.010448)
			(xy 66.409992 -65.966305) (xy 66.382696 -65.91767) (xy 66.362773 -65.865579) (xy 66.350647 -65.811142)
			(xy 66.346576 -65.75552) (xy 66.119756 -65.75552) (xy 66.119756 -67.128953) (xy 66.366575 -67.128953)
			(xy 66.366575 -67.074447) (xy 66.374333 -67.020495) (xy 66.389691 -66.968196) (xy 66.412335 -66.918616)
			(xy 66.441806 -66.872763) (xy 66.477502 -66.831571) (xy 66.518698 -66.795879) (xy 66.564554 -66.766414)
			(xy 66.614137 -66.743775) (xy 66.666438 -66.728424) (xy 66.720391 -66.720672) (xy 66.747644 -66.720212)
			(xy 66.775013 -66.720708) (xy 66.829191 -66.728518) (xy 66.881694 -66.744) (xy 66.931441 -66.766835)
			(xy 66.977409 -66.796554) (xy 66.998342 -66.814192) (xy 66.998596 -66.814446) (xy 67.005676 -66.820043)
			(xy 67.022598 -66.826282) (xy 67.031616 -66.826638) (xy 67.098672 -66.826638) (xy 67.107686 -66.826259)
			(xy 67.124603 -66.820026) (xy 67.131692 -66.814446) (xy 67.131692 -66.814192) (xy 67.131946 -66.814192)
			(xy 67.152887 -66.796564) (xy 67.198857 -66.76685) (xy 67.248603 -66.744013) (xy 67.301101 -66.728519)
			(xy 67.355275 -66.720688) (xy 67.382644 -66.720212) (xy 67.409895 -66.720661) (xy 67.46384 -66.728423)
			(xy 67.516133 -66.743783) (xy 67.565707 -66.766427) (xy 67.611554 -66.795896) (xy 67.652741 -66.83159)
			(xy 67.68843 -66.872781) (xy 67.717894 -66.918632) (xy 67.740533 -66.968209) (xy 67.755887 -67.020503)
			(xy 67.763642 -67.074449) (xy 67.763642 -67.128951) (xy 67.755887 -67.182897) (xy 67.740533 -67.235191)
			(xy 67.717894 -67.284768) (xy 67.68843 -67.330619) (xy 67.652741 -67.37181) (xy 67.611554 -67.407504)
			(xy 67.565707 -67.436973) (xy 67.516133 -67.459617) (xy 67.46384 -67.474977) (xy 67.409895 -67.482739)
			(xy 67.382644 -67.483228) (xy 67.355274 -67.482754) (xy 67.301094 -67.474941) (xy 67.248591 -67.459454)
			(xy 67.198844 -67.436614) (xy 67.152877 -67.40689) (xy 67.131946 -67.389248) (xy 67.131692 -67.388994)
			(xy 67.124612 -67.383397) (xy 67.10769 -67.377157) (xy 67.098672 -67.376802) (xy 67.031616 -67.376802)
			(xy 67.0226 -67.377166) (xy 67.005683 -67.383409) (xy 66.998596 -67.388994) (xy 66.998596 -67.389248)
			(xy 66.998342 -67.389248) (xy 66.977398 -67.406873) (xy 66.931429 -67.436589) (xy 66.881685 -67.459428)
			(xy 66.829187 -67.474922) (xy 66.775013 -67.482753) (xy 66.747644 -67.483228) (xy 66.720391 -67.482728)
			(xy 66.666438 -67.474976) (xy 66.614137 -67.459625) (xy 66.564554 -67.436986) (xy 66.518698 -67.407521)
			(xy 66.477502 -67.371829) (xy 66.441806 -67.330637) (xy 66.412335 -67.284784) (xy 66.389691 -67.235204)
			(xy 66.374333 -67.182905) (xy 66.366575 -67.128953) (xy 66.119756 -67.128953) (xy 66.119756 -67.488054)
			(xy 70.77913 -67.488054) (xy 70.783201 -67.432432) (xy 70.795327 -67.377995) (xy 70.81525 -67.325904)
			(xy 70.842546 -67.277269) (xy 70.876632 -67.233126) (xy 70.916781 -67.194417) (xy 70.962139 -67.161966)
			(xy 71.011739 -67.136465) (xy 71.064523 -67.118458) (xy 71.119366 -67.108328) (xy 71.1751 -67.106291)
			(xy 71.230537 -67.112391) (xy 71.284494 -67.126497) (xy 71.335823 -67.148309) (xy 71.383429 -67.177363)
			(xy 71.426297 -67.213038) (xy 71.463514 -67.254575) (xy 71.494287 -67.301088) (xy 71.517959 -67.351585)
			(xy 71.534027 -67.404992) (xy 71.542147 -67.460168) (xy 71.542656 -67.488054) (xy 71.542147 -67.51594)
			(xy 71.538962 -67.537584) (xy 72.071228 -67.537584) (xy 72.075299 -67.481962) (xy 72.087425 -67.427525)
			(xy 72.107348 -67.375434) (xy 72.134644 -67.326799) (xy 72.16873 -67.282656) (xy 72.208879 -67.243947)
			(xy 72.254237 -67.211496) (xy 72.303837 -67.185995) (xy 72.356621 -67.167988) (xy 72.411464 -67.157858)
			(xy 72.467198 -67.155821) (xy 72.522635 -67.161921) (xy 72.576592 -67.176027) (xy 72.627921 -67.197839)
			(xy 72.675527 -67.226893) (xy 72.718395 -67.262568) (xy 72.755612 -67.304105) (xy 72.786385 -67.350618)
			(xy 72.810057 -67.401115) (xy 72.826125 -67.454522) (xy 72.834245 -67.509698) (xy 72.834754 -67.537584)
			(xy 72.834245 -67.56547) (xy 72.8302 -67.592956) (xy 73.345292 -67.592956) (xy 73.349363 -67.537334)
			(xy 73.361489 -67.482897) (xy 73.381412 -67.430806) (xy 73.408708 -67.382171) (xy 73.442794 -67.338028)
			(xy 73.482943 -67.299319) (xy 73.528301 -67.266868) (xy 73.577901 -67.241367) (xy 73.630685 -67.22336)
			(xy 73.685528 -67.21323) (xy 73.741262 -67.211193) (xy 73.796699 -67.217293) (xy 73.850656 -67.231399)
			(xy 73.901985 -67.253211) (xy 73.949591 -67.282265) (xy 73.992459 -67.31794) (xy 74.029676 -67.359477)
			(xy 74.060449 -67.40599) (xy 74.084121 -67.456487) (xy 74.100189 -67.509894) (xy 74.108306 -67.565052)
			(xy 76.446593 -67.565052) (xy 76.446593 -67.510548) (xy 76.45435 -67.4566) (xy 76.469707 -67.404304)
			(xy 76.492349 -67.354727) (xy 76.521818 -67.308877) (xy 76.557511 -67.267687) (xy 76.598704 -67.231997)
			(xy 76.644557 -67.202533) (xy 76.694136 -67.179895) (xy 76.746433 -67.164543) (xy 76.800382 -67.156791)
			(xy 76.827634 -67.15633) (xy 76.855005 -67.156769) (xy 76.909186 -67.164592) (xy 76.96169 -67.180087)
			(xy 77.011436 -67.202935) (xy 77.057401 -67.232666) (xy 77.078332 -67.25031) (xy 77.078586 -67.250564)
			(xy 77.085667 -67.256158) (xy 77.102588 -67.262399) (xy 77.111606 -67.262756) (xy 77.178662 -67.262756)
			(xy 77.187678 -67.26239) (xy 77.204596 -67.25615) (xy 77.211682 -67.250564) (xy 77.211682 -67.25031)
			(xy 77.211936 -67.25031) (xy 77.232883 -67.232689) (xy 77.278851 -67.202974) (xy 77.328595 -67.180135)
			(xy 77.381093 -67.164639) (xy 77.435266 -67.156806) (xy 77.462634 -67.15633) (xy 77.489886 -67.156742)
			(xy 77.543836 -67.164503) (xy 77.596132 -67.179863) (xy 77.64571 -67.202508) (xy 77.69156 -67.231978)
			(xy 77.732751 -67.267674) (xy 77.768442 -67.308867) (xy 77.797908 -67.35472) (xy 77.820549 -67.4043)
			(xy 77.835904 -67.456597) (xy 77.84366 -67.510548) (xy 77.84366 -67.565052) (xy 77.835904 -67.619003)
			(xy 77.820549 -67.6713) (xy 77.797908 -67.72088) (xy 77.768442 -67.766733) (xy 77.732751 -67.807926)
			(xy 77.69156 -67.843622) (xy 77.64571 -67.873092) (xy 77.596132 -67.895737) (xy 77.543836 -67.911097)
			(xy 77.489886 -67.918858) (xy 77.462634 -67.919346) (xy 77.435264 -67.918873) (xy 77.381085 -67.911059)
			(xy 77.328581 -67.895572) (xy 77.278834 -67.872732) (xy 77.232867 -67.843007) (xy 77.211936 -67.825366)
			(xy 77.211682 -67.825112) (xy 77.204604 -67.819513) (xy 77.187681 -67.813273) (xy 77.178662 -67.81292)
			(xy 77.111606 -67.81292) (xy 77.102589 -67.813275) (xy 77.085672 -67.819524) (xy 77.078586 -67.825112)
			(xy 77.078586 -67.825366) (xy 77.078332 -67.825366) (xy 77.057394 -67.842998) (xy 77.011424 -67.872712)
			(xy 76.961678 -67.89555) (xy 76.909178 -67.911043) (xy 76.855003 -67.918872) (xy 76.827634 -67.919346)
			(xy 76.800382 -67.918809) (xy 76.746433 -67.911057) (xy 76.694136 -67.895705) (xy 76.644557 -67.873067)
			(xy 76.598704 -67.843603) (xy 76.557511 -67.807913) (xy 76.521818 -67.766723) (xy 76.492349 -67.720873)
			(xy 76.469707 -67.671296) (xy 76.45435 -67.619) (xy 76.446593 -67.565052) (xy 74.108306 -67.565052)
			(xy 74.108309 -67.56507) (xy 74.108818 -67.592956) (xy 74.108309 -67.620842) (xy 74.100189 -67.676018)
			(xy 74.084121 -67.729425) (xy 74.060449 -67.779922) (xy 74.029676 -67.826435) (xy 73.992459 -67.867972)
			(xy 73.949591 -67.903647) (xy 73.901985 -67.932701) (xy 73.850656 -67.954513) (xy 73.796699 -67.968619)
			(xy 73.741262 -67.974719) (xy 73.685528 -67.972682) (xy 73.630685 -67.962552) (xy 73.577901 -67.944545)
			(xy 73.528301 -67.919044) (xy 73.482943 -67.886593) (xy 73.442794 -67.847884) (xy 73.408708 -67.803741)
			(xy 73.381412 -67.755106) (xy 73.361489 -67.703015) (xy 73.349363 -67.648578) (xy 73.345292 -67.592956)
			(xy 72.8302 -67.592956) (xy 72.826125 -67.620646) (xy 72.810057 -67.674053) (xy 72.786385 -67.72455)
			(xy 72.755612 -67.771063) (xy 72.718395 -67.8126) (xy 72.675527 -67.848275) (xy 72.627921 -67.877329)
			(xy 72.576592 -67.899141) (xy 72.522635 -67.913247) (xy 72.467198 -67.919347) (xy 72.411464 -67.91731)
			(xy 72.356621 -67.90718) (xy 72.303837 -67.889173) (xy 72.254237 -67.863672) (xy 72.208879 -67.831221)
			(xy 72.16873 -67.792512) (xy 72.134644 -67.748369) (xy 72.107348 -67.699734) (xy 72.087425 -67.647643)
			(xy 72.075299 -67.593206) (xy 72.071228 -67.537584) (xy 71.538962 -67.537584) (xy 71.534027 -67.571116)
			(xy 71.517959 -67.624523) (xy 71.494287 -67.67502) (xy 71.463514 -67.721533) (xy 71.426297 -67.76307)
			(xy 71.383429 -67.798745) (xy 71.335823 -67.827799) (xy 71.284494 -67.849611) (xy 71.230537 -67.863717)
			(xy 71.1751 -67.869817) (xy 71.119366 -67.86778) (xy 71.064523 -67.85765) (xy 71.011739 -67.839643)
			(xy 70.962139 -67.814142) (xy 70.916781 -67.781691) (xy 70.876632 -67.742982) (xy 70.842546 -67.698839)
			(xy 70.81525 -67.650204) (xy 70.795327 -67.598113) (xy 70.783201 -67.543676) (xy 70.77913 -67.488054)
			(xy 66.119756 -67.488054) (xy 66.119756 -68.332858) (xy 66.12001 -68.336668) (xy 66.12001 -68.341748)
			(xy 66.120518 -68.367656) (xy 66.120518 -68.368164) (xy 66.118994 -68.419218) (xy 66.110297 -68.586604)
			(xy 68.625212 -68.586604) (xy 68.625677 -68.559234) (xy 68.633495 -68.505054) (xy 68.648984 -68.452551)
			(xy 68.671826 -68.402804) (xy 68.701551 -68.356838) (xy 68.719192 -68.335906) (xy 68.719446 -68.335652)
			(xy 68.725023 -68.328559) (xy 68.731274 -68.311647) (xy 68.731638 -68.302632) (xy 68.731638 -68.235576)
			(xy 68.731284 -68.226559) (xy 68.725034 -68.209642) (xy 68.719446 -68.202556) (xy 68.719192 -68.202556)
			(xy 68.719192 -68.202302) (xy 68.701539 -68.181381) (xy 68.67183 -68.135405) (xy 68.648996 -68.085655)
			(xy 68.633509 -68.033152) (xy 68.625684 -67.978974) (xy 68.625212 -67.951604) (xy 68.625659 -67.92435)
			(xy 68.633416 -67.870398) (xy 68.648773 -67.818098) (xy 68.671416 -67.768517) (xy 68.700886 -67.722663)
			(xy 68.736581 -67.68147) (xy 68.777776 -67.645776) (xy 68.823631 -67.616308) (xy 68.873213 -67.593667)
			(xy 68.925513 -67.578313) (xy 68.979466 -67.570558) (xy 69.00672 -67.570096) (xy 69.033034 -67.570551)
			(xy 69.085163 -67.577789) (xy 69.135806 -67.59211) (xy 69.184005 -67.613245) (xy 69.228848 -67.640793)
			(xy 69.269488 -67.674234) (xy 69.287644 -67.693286) (xy 69.295149 -67.700707) (xy 69.314442 -67.709221)
			(xy 69.324982 -67.709796) (xy 69.399658 -67.709796) (xy 69.410207 -67.709259) (xy 69.429502 -67.70073)
			(xy 69.436996 -67.693286) (xy 69.455158 -67.674237) (xy 69.495786 -67.64078) (xy 69.540626 -67.61322)
			(xy 69.588825 -67.592081) (xy 69.639471 -67.577762) (xy 69.691604 -67.570535) (xy 69.71792 -67.570096)
			(xy 69.745291 -67.570551) (xy 69.79947 -67.578372) (xy 69.851973 -67.593864) (xy 69.90172 -67.616708)
			(xy 69.947686 -67.646434) (xy 69.968618 -67.664076) (xy 69.968872 -67.66433) (xy 69.97596 -67.669914)
			(xy 69.992876 -67.676161) (xy 70.001892 -67.676522) (xy 70.068948 -67.676522) (xy 70.077962 -67.676135)
			(xy 70.094879 -67.669908) (xy 70.101968 -67.66433) (xy 70.101968 -67.664076) (xy 70.102222 -67.664076)
			(xy 70.12317 -67.646456) (xy 70.169139 -67.616742) (xy 70.218882 -67.593903) (xy 70.271379 -67.578407)
			(xy 70.325552 -67.570573) (xy 70.35292 -67.570096) (xy 70.380172 -67.570559) (xy 70.434121 -67.578319)
			(xy 70.486416 -67.593676) (xy 70.535994 -67.61632) (xy 70.581844 -67.645789) (xy 70.623034 -67.681483)
			(xy 70.658725 -67.722675) (xy 70.688191 -67.768527) (xy 70.710832 -67.818106) (xy 70.726187 -67.870403)
			(xy 70.733943 -67.924352) (xy 70.734428 -67.951604) (xy 70.733982 -67.978975) (xy 70.726162 -68.033156)
			(xy 70.710669 -68.08566) (xy 70.687823 -68.135406) (xy 70.658092 -68.181372) (xy 70.640448 -68.202302)
			(xy 70.640194 -68.202556) (xy 70.634619 -68.209651) (xy 70.628366 -68.226561) (xy 70.628002 -68.235576)
			(xy 70.628002 -68.302632) (xy 70.628343 -68.31165) (xy 70.634602 -68.328567) (xy 70.640194 -68.335652)
			(xy 70.640448 -68.335652) (xy 70.640448 -68.335906) (xy 70.658095 -68.356832) (xy 70.687808 -68.402805)
			(xy 70.710643 -68.452554) (xy 70.726132 -68.505057) (xy 70.733956 -68.559234) (xy 70.734428 -68.586604)
			(xy 70.733926 -68.613854) (xy 70.726169 -68.667801) (xy 70.710815 -68.720094) (xy 70.694176 -68.75653)
			(xy 74.170286 -68.75653) (xy 74.170773 -68.729161) (xy 74.178586 -68.674983) (xy 74.194071 -68.62248)
			(xy 74.216908 -68.572733) (xy 74.246627 -68.526765) (xy 74.264266 -68.505832) (xy 74.26452 -68.505578)
			(xy 74.270124 -68.498504) (xy 74.27636 -68.481577) (xy 74.276712 -68.472558) (xy 74.276712 -68.405502)
			(xy 74.276351 -68.396486) (xy 74.270106 -68.379569) (xy 74.26452 -68.372482) (xy 74.264266 -68.372482)
			(xy 74.264266 -68.372228) (xy 74.246621 -68.351301) (xy 74.216911 -68.305326) (xy 74.194077 -68.255577)
			(xy 74.178587 -68.203076) (xy 74.17076 -68.148899) (xy 74.170286 -68.12153) (xy 74.170783 -68.094278)
			(xy 74.178536 -68.040329) (xy 74.193888 -67.988032) (xy 74.216526 -67.938452) (xy 74.245991 -67.892599)
			(xy 74.281681 -67.851406) (xy 74.32287 -67.815712) (xy 74.368721 -67.786244) (xy 74.418298 -67.7636)
			(xy 74.470594 -67.748244) (xy 74.524542 -67.740486) (xy 74.551794 -67.740022) (xy 74.579164 -67.740486)
			(xy 74.633344 -67.748304) (xy 74.685847 -67.763793) (xy 74.735594 -67.786635) (xy 74.781561 -67.81636)
			(xy 74.802492 -67.834002) (xy 74.802746 -67.834256) (xy 74.809839 -67.839833) (xy 74.826751 -67.846084)
			(xy 74.835766 -67.846448) (xy 74.902822 -67.846448) (xy 74.911841 -67.846113) (xy 74.928759 -67.839852)
			(xy 74.935842 -67.834256) (xy 74.935842 -67.834002) (xy 74.936096 -67.834002) (xy 74.957019 -67.816352)
			(xy 75.002994 -67.786641) (xy 75.052744 -67.763808) (xy 75.105247 -67.748319) (xy 75.159424 -67.740494)
			(xy 75.186794 -67.740022) (xy 75.213108 -67.740486) (xy 75.265237 -67.747721) (xy 75.31588 -67.76204)
			(xy 75.364079 -67.783173) (xy 75.408923 -67.81072) (xy 75.449562 -67.84416) (xy 75.467718 -67.863212)
			(xy 75.475229 -67.870625) (xy 75.494517 -67.879143) (xy 75.505056 -67.879722) (xy 75.579732 -67.879722)
			(xy 75.590278 -67.879163) (xy 75.609573 -67.870648) (xy 75.61707 -67.863212) (xy 75.63525 -67.84418)
			(xy 75.675874 -67.810721) (xy 75.720709 -67.783158) (xy 75.768905 -67.762015) (xy 75.819549 -67.747693)
			(xy 75.871679 -67.740463) (xy 75.897994 -67.740022) (xy 75.925248 -67.740461) (xy 75.979201 -67.748218)
			(xy 76.031502 -67.763575) (xy 76.081084 -67.786219) (xy 76.126938 -67.815689) (xy 76.168132 -67.851385)
			(xy 76.203826 -67.892581) (xy 76.233293 -67.938437) (xy 76.255934 -67.988021) (xy 76.271287 -68.040322)
			(xy 76.279041 -68.094276) (xy 76.279502 -68.12153) (xy 76.279053 -68.148901) (xy 76.271231 -68.203081)
			(xy 76.255738 -68.255584) (xy 76.232892 -68.30533) (xy 76.203165 -68.351297) (xy 76.185522 -68.372228)
			(xy 76.185268 -68.372482) (xy 76.179679 -68.379567) (xy 76.173435 -68.396485) (xy 76.173076 -68.405502)
			(xy 76.173076 -68.472558) (xy 76.173458 -68.481572) (xy 76.179689 -68.498489) (xy 76.185268 -68.505578)
			(xy 76.185522 -68.505578) (xy 76.185522 -68.505832) (xy 76.203146 -68.526776) (xy 76.232859 -68.572746)
			(xy 76.255698 -68.62249) (xy 76.271193 -68.674988) (xy 76.279025 -68.729162) (xy 76.279502 -68.75653)
			(xy 76.27905 -68.783782) (xy 76.271289 -68.837732) (xy 76.25593 -68.890027) (xy 76.233285 -68.939605)
			(xy 76.203815 -68.985456) (xy 76.16812 -69.026646) (xy 76.126927 -69.062337) (xy 76.081073 -69.091802)
			(xy 76.031493 -69.114443) (xy 75.979196 -69.129797) (xy 75.925246 -69.137553) (xy 75.897994 -69.138038)
			(xy 75.871679 -69.137594) (xy 75.819549 -69.130357) (xy 75.768905 -69.116035) (xy 75.720705 -69.094898)
			(xy 75.675863 -69.067347) (xy 75.635225 -69.033903) (xy 75.61707 -69.014848) (xy 75.609555 -69.007438)
			(xy 75.59027 -68.998917) (xy 75.579732 -68.998338) (xy 75.505056 -68.998338) (xy 75.494507 -68.998873)
			(xy 75.475211 -69.007403) (xy 75.467718 -69.014848) (xy 75.449556 -69.033897) (xy 75.408927 -69.067353)
			(xy 75.364087 -69.094912) (xy 75.315888 -69.116051) (xy 75.265242 -69.13037) (xy 75.21311 -69.137598)
			(xy 75.186794 -69.138038) (xy 75.159423 -69.137591) (xy 75.105242 -69.129771) (xy 75.052739 -69.114278)
			(xy 75.002992 -69.091432) (xy 74.957026 -69.061702) (xy 74.936096 -69.044058) (xy 74.935842 -69.043804)
			(xy 74.928747 -69.038229) (xy 74.911837 -69.031975) (xy 74.902822 -69.031612) (xy 74.835766 -69.031612)
			(xy 74.826747 -69.03195) (xy 74.80983 -69.038211) (xy 74.802746 -69.043804) (xy 74.802746 -69.044058)
			(xy 74.802492 -69.044058) (xy 74.781568 -69.061708) (xy 74.735594 -69.091419) (xy 74.685844 -69.114254)
			(xy 74.633342 -69.129742) (xy 74.579164 -69.137567) (xy 74.551794 -69.138038) (xy 74.524544 -69.137528)
			(xy 74.470599 -69.129771) (xy 74.418306 -69.114417) (xy 74.368731 -69.091777) (xy 74.322882 -69.062313)
			(xy 74.281693 -69.026624) (xy 74.246001 -68.985437) (xy 74.216534 -68.93959) (xy 74.193891 -68.890016)
			(xy 74.178534 -68.837725) (xy 74.170774 -68.78378) (xy 74.170286 -68.75653) (xy 70.694176 -68.75653)
			(xy 70.688175 -68.76967) (xy 70.65871 -68.815519) (xy 70.62302 -68.856709) (xy 70.581832 -68.8924)
			(xy 70.535984 -68.921867) (xy 70.486409 -68.944509) (xy 70.434116 -68.959866) (xy 70.38017 -68.967625)
			(xy 70.35292 -68.968112) (xy 70.32555 -68.967631) (xy 70.271372 -68.959817) (xy 70.218869 -68.944331)
			(xy 70.169122 -68.921492) (xy 70.123154 -68.891771) (xy 70.102222 -68.874132) (xy 70.101968 -68.873878)
			(xy 70.094868 -68.868311) (xy 70.077961 -68.862053) (xy 70.068948 -68.861686) (xy 70.001892 -68.861686)
			(xy 69.992875 -68.862042) (xy 69.975958 -68.868291) (xy 69.968872 -68.873878) (xy 69.968872 -68.874132)
			(xy 69.968618 -68.874132) (xy 69.947694 -68.891781) (xy 69.901719 -68.92149) (xy 69.851969 -68.944324)
			(xy 69.799467 -68.959813) (xy 69.74529 -68.967639) (xy 69.71792 -68.968112) (xy 69.691607 -68.967627)
			(xy 69.639479 -68.960396) (xy 69.588837 -68.94608) (xy 69.540638 -68.92495) (xy 69.495794 -68.897407)
			(xy 69.455153 -68.863972) (xy 69.436996 -68.844922) (xy 69.429475 -68.83752) (xy 69.410195 -68.828995)
			(xy 69.399658 -68.828412) (xy 69.324982 -68.828412) (xy 69.314435 -68.828968) (xy 69.295139 -68.837484)
			(xy 69.287644 -68.844922) (xy 69.269513 -68.864002) (xy 69.228878 -68.897456) (xy 69.184032 -68.925011)
			(xy 69.135826 -68.946145) (xy 69.085175 -68.960458) (xy 69.033037 -68.967677) (xy 69.00672 -68.968112)
			(xy 68.979468 -68.967626) (xy 68.925518 -68.959872) (xy 68.873221 -68.944519) (xy 68.823641 -68.921879)
			(xy 68.777788 -68.892413) (xy 68.736595 -68.856722) (xy 68.700901 -68.815531) (xy 68.671433 -68.76968)
			(xy 68.64879 -68.720102) (xy 68.633433 -68.667806) (xy 68.625676 -68.613856) (xy 68.625212 -68.586604)
			(xy 66.110297 -68.586604) (xy 65.956029 -71.555864) (xy 71.19442 -71.555864) (xy 71.198491 -71.500242)
			(xy 71.210617 -71.445805) (xy 71.23054 -71.393714) (xy 71.257836 -71.345079) (xy 71.291922 -71.300936)
			(xy 71.332071 -71.262227) (xy 71.377429 -71.229776) (xy 71.427029 -71.204275) (xy 71.479813 -71.186268)
			(xy 71.534656 -71.176138) (xy 71.59039 -71.174101) (xy 71.645827 -71.180201) (xy 71.699784 -71.194307)
			(xy 71.751113 -71.216119) (xy 71.798719 -71.245173) (xy 71.841587 -71.280848) (xy 71.878804 -71.322385)
			(xy 71.909577 -71.368898) (xy 71.933249 -71.419395) (xy 71.949317 -71.472802) (xy 71.957437 -71.527978)
			(xy 71.957946 -71.555864) (xy 71.957437 -71.58375) (xy 71.951598 -71.623428) (xy 72.703434 -71.623428)
			(xy 72.707505 -71.567806) (xy 72.719631 -71.513369) (xy 72.739554 -71.461278) (xy 72.76685 -71.412643)
			(xy 72.800936 -71.3685) (xy 72.841085 -71.329791) (xy 72.886443 -71.29734) (xy 72.936043 -71.271839)
			(xy 72.988827 -71.253832) (xy 73.04367 -71.243702) (xy 73.099404 -71.241665) (xy 73.154841 -71.247765)
			(xy 73.208798 -71.261871) (xy 73.260127 -71.283683) (xy 73.307733 -71.312737) (xy 73.350601 -71.348412)
			(xy 73.387818 -71.389949) (xy 73.418591 -71.436462) (xy 73.442263 -71.486959) (xy 73.458331 -71.540366)
			(xy 73.466451 -71.595542) (xy 73.46696 -71.623428) (xy 73.466451 -71.651314) (xy 73.458331 -71.70649)
			(xy 73.442263 -71.759897) (xy 73.418591 -71.810394) (xy 73.387818 -71.856907) (xy 73.350601 -71.898444)
			(xy 73.307733 -71.934119) (xy 73.260127 -71.963173) (xy 73.208798 -71.984985) (xy 73.154841 -71.999091)
			(xy 73.099404 -72.005191) (xy 73.04367 -72.003154) (xy 72.988827 -71.993024) (xy 72.936043 -71.975017)
			(xy 72.886443 -71.949516) (xy 72.841085 -71.917065) (xy 72.800936 -71.878356) (xy 72.76685 -71.834213)
			(xy 72.739554 -71.785578) (xy 72.719631 -71.733487) (xy 72.707505 -71.67905) (xy 72.703434 -71.623428)
			(xy 71.951598 -71.623428) (xy 71.949317 -71.638926) (xy 71.933249 -71.692333) (xy 71.909577 -71.74283)
			(xy 71.878804 -71.789343) (xy 71.841587 -71.83088) (xy 71.798719 -71.866555) (xy 71.751113 -71.895609)
			(xy 71.699784 -71.917421) (xy 71.645827 -71.931527) (xy 71.59039 -71.937627) (xy 71.534656 -71.93559)
			(xy 71.479813 -71.92546) (xy 71.427029 -71.907453) (xy 71.377429 -71.881952) (xy 71.332071 -71.849501)
			(xy 71.291922 -71.810792) (xy 71.257836 -71.766649) (xy 71.23054 -71.718014) (xy 71.210617 -71.665923)
			(xy 71.198491 -71.611486) (xy 71.19442 -71.555864) (xy 65.956029 -71.555864) (xy 65.662458 -77.206348)
			(xy 82.68411 -77.206348) (xy 82.688181 -77.150726) (xy 82.700307 -77.096289) (xy 82.72023 -77.044198)
			(xy 82.747526 -76.995563) (xy 82.781612 -76.95142) (xy 82.821761 -76.912711) (xy 82.867119 -76.88026)
			(xy 82.916719 -76.854759) (xy 82.969503 -76.836752) (xy 83.024346 -76.826622) (xy 83.08008 -76.824585)
			(xy 83.135517 -76.830685) (xy 83.189474 -76.844791) (xy 83.240803 -76.866603) (xy 83.288409 -76.895657)
			(xy 83.331277 -76.931332) (xy 83.368494 -76.972869) (xy 83.399267 -77.019382) (xy 83.422939 -77.069879)
			(xy 83.439007 -77.123286) (xy 83.447127 -77.178462) (xy 83.447636 -77.206348) (xy 83.447127 -77.234234)
			(xy 83.439007 -77.28941) (xy 83.422939 -77.342817) (xy 83.399267 -77.393314) (xy 83.368494 -77.439827)
			(xy 83.331277 -77.481364) (xy 83.288409 -77.517039) (xy 83.240803 -77.546093) (xy 83.189474 -77.567905)
			(xy 83.135517 -77.582011) (xy 83.08008 -77.588111) (xy 83.024346 -77.586074) (xy 82.969503 -77.575944)
			(xy 82.916719 -77.557937) (xy 82.867119 -77.532436) (xy 82.821761 -77.499985) (xy 82.781612 -77.461276)
			(xy 82.747526 -77.417133) (xy 82.72023 -77.368498) (xy 82.700307 -77.316407) (xy 82.688181 -77.26197)
			(xy 82.68411 -77.206348) (xy 65.662458 -77.206348) (xy 65.630298 -77.825346) (xy 65.630569 -77.832464)
			(xy 65.634559 -77.846132) (xy 65.638172 -77.85227) (xy 65.6463 -77.862176) (xy 65.646554 -77.86243)
			(xy 65.650872 -77.865732) (xy 65.653158 -77.867256) (xy 65.656968 -77.869796) (xy 65.663064 -77.872844)
			(xy 65.66535 -77.873606) (xy 65.692125 -77.884333) (xy 65.742358 -77.912677) (xy 65.787758 -77.948251)
			(xy 65.827293 -77.990247) (xy 65.860064 -78.03771) (xy 65.885327 -78.089561) (xy 65.902506 -78.144621)
			(xy 65.911212 -78.201638) (xy 65.91173 -78.230476) (xy 65.91123 -78.258173) (xy 65.903213 -78.312983)
			(xy 65.887357 -78.366059) (xy 65.863997 -78.416287) (xy 65.833622 -78.46261) (xy 65.796871 -78.504056)
			(xy 65.754515 -78.539756) (xy 65.707444 -78.568958) (xy 65.656646 -78.59105) (xy 65.630044 -78.598776)
			(xy 65.624456 -78.6003) (xy 65.61455 -78.60538) (xy 65.613788 -78.605888) (xy 65.612518 -78.606396)
			(xy 65.61074 -78.607412) (xy 65.601297 -78.614019) (xy 65.588893 -78.633406) (xy 65.586864 -78.64475)
			(xy 65.571624 -78.939644) (xy 65.57391 -78.951328) (xy 65.57645 -78.95717) (xy 65.583816 -78.975204)
			(xy 65.587372 -78.98003) (xy 65.59042 -78.984348) (xy 65.594484 -78.988158) (xy 65.597278 -78.990952)
			(xy 65.615844 -79.009047) (xy 65.64841 -79.049384) (xy 65.675217 -79.093758) (xy 65.69577 -79.141352)
			(xy 65.707091 -79.18196) (xy 79.591662 -79.18196) (xy 79.592148 -79.154709) (xy 79.599904 -79.100761)
			(xy 79.615259 -79.048466) (xy 79.637901 -78.998889) (xy 79.667367 -78.953039) (xy 79.703058 -78.911848)
			(xy 79.744249 -78.876157) (xy 79.790099 -78.846691) (xy 79.839676 -78.824049) (xy 79.891971 -78.808694)
			(xy 79.945919 -78.800938) (xy 80.000421 -78.800938) (xy 80.054369 -78.808694) (xy 80.106664 -78.824049)
			(xy 80.156241 -78.846691) (xy 80.202091 -78.876157) (xy 80.243282 -78.911848) (xy 80.278973 -78.953039)
			(xy 80.308439 -78.998889) (xy 80.331081 -79.048466) (xy 80.346436 -79.100761) (xy 80.354192 -79.154709)
			(xy 80.354678 -79.18196) (xy 80.354093 -79.210842) (xy 80.345378 -79.267945) (xy 80.328157 -79.323083)
			(xy 80.302823 -79.374995) (xy 80.269955 -79.422497) (xy 80.230304 -79.464502) (xy 80.207866 -79.482696)
			(xy 80.19695 -79.491864) (xy 80.180205 -79.514917) (xy 80.17047 -79.541695) (xy 80.168502 -79.570119)
			(xy 80.174454 -79.597983) (xy 80.187863 -79.623123) (xy 80.207689 -79.643587) (xy 80.219804 -79.651098)
			(xy 80.244418 -79.665742) (xy 80.289288 -79.701335) (xy 80.328334 -79.743237) (xy 80.360676 -79.790504)
			(xy 80.385589 -79.842076) (xy 80.402512 -79.896792) (xy 80.411065 -79.953423) (xy 80.411574 -79.98206)
			(xy 80.411088 -80.009311) (xy 80.403332 -80.063259) (xy 80.387977 -80.115554) (xy 80.365335 -80.165131)
			(xy 80.335869 -80.210981) (xy 80.300178 -80.252172) (xy 80.258987 -80.287863) (xy 80.213137 -80.317329)
			(xy 80.16356 -80.339971) (xy 80.111265 -80.355326) (xy 80.057317 -80.363082) (xy 80.002815 -80.363082)
			(xy 79.948867 -80.355326) (xy 79.896572 -80.339971) (xy 79.846995 -80.317329) (xy 79.801145 -80.287863)
			(xy 79.759954 -80.252172) (xy 79.724263 -80.210981) (xy 79.694797 -80.165131) (xy 79.672155 -80.115554)
			(xy 79.6568 -80.063259) (xy 79.649044 -80.009311) (xy 79.648558 -79.98206) (xy 79.649073 -79.953175)
			(xy 79.6578 -79.896068) (xy 79.675034 -79.840929) (xy 79.700381 -79.789016) (xy 79.733262 -79.741517)
			(xy 79.772926 -79.699515) (xy 79.79537 -79.681324) (xy 79.806276 -79.672141) (xy 79.823033 -79.649095)
			(xy 79.832777 -79.622319) (xy 79.834749 -79.593893) (xy 79.828797 -79.566027) (xy 79.815384 -79.540887)
			(xy 79.795551 -79.520428) (xy 79.783432 -79.512922) (xy 79.758835 -79.49825) (xy 79.713963 -79.462663)
			(xy 79.674916 -79.420767) (xy 79.64257 -79.373504) (xy 79.617655 -79.321937) (xy 79.600729 -79.267224)
			(xy 79.592172 -79.210596) (xy 79.591662 -79.18196) (xy 65.707091 -79.18196) (xy 65.709692 -79.19129)
			(xy 65.716727 -79.242653) (xy 65.717166 -79.268574) (xy 65.715642 -79.301848) (xy 65.714372 -79.313532)
			(xy 65.710853 -79.33927) (xy 65.697748 -79.389538) (xy 65.677947 -79.437564) (xy 65.651818 -79.482461)
			(xy 65.619841 -79.523401) (xy 65.582609 -79.559627) (xy 65.561972 -79.575406) (xy 65.56121 -79.576168)
			(xy 65.559686 -79.577184) (xy 65.555876 -79.580232) (xy 65.547935 -79.586996) (xy 65.537824 -79.605218)
			(xy 65.536318 -79.615538) (xy 65.515264 -80.019906) (xy 72.500742 -80.019906) (xy 72.504813 -79.964284)
			(xy 72.516939 -79.909847) (xy 72.536862 -79.857756) (xy 72.564158 -79.809121) (xy 72.598244 -79.764978)
			(xy 72.638393 -79.726269) (xy 72.683751 -79.693818) (xy 72.733351 -79.668317) (xy 72.786135 -79.65031)
			(xy 72.840978 -79.64018) (xy 72.896712 -79.638143) (xy 72.952149 -79.644243) (xy 73.006106 -79.658349)
			(xy 73.057435 -79.680161) (xy 73.105041 -79.709215) (xy 73.147909 -79.74489) (xy 73.185126 -79.786427)
			(xy 73.215899 -79.83294) (xy 73.239571 -79.883437) (xy 73.255639 -79.936844) (xy 73.263759 -79.99202)
			(xy 73.264268 -80.019906) (xy 73.263759 -80.047792) (xy 73.255639 -80.102968) (xy 73.239571 -80.156375)
			(xy 73.215899 -80.206872) (xy 73.185126 -80.253385) (xy 73.147909 -80.294922) (xy 73.105041 -80.330597)
			(xy 73.057435 -80.359651) (xy 73.006106 -80.381463) (xy 72.952149 -80.395569) (xy 72.896712 -80.401669)
			(xy 72.840978 -80.399632) (xy 72.786135 -80.389502) (xy 72.733351 -80.371495) (xy 72.683751 -80.345994)
			(xy 72.638393 -80.313543) (xy 72.598244 -80.274834) (xy 72.564158 -80.230691) (xy 72.536862 -80.182056)
			(xy 72.516939 -80.129965) (xy 72.504813 -80.075528) (xy 72.500742 -80.019906) (xy 65.515264 -80.019906)
			(xy 65.389908 -82.427572) (xy 78.932784 -82.427572) (xy 78.936855 -82.37195) (xy 78.948981 -82.317513)
			(xy 78.968904 -82.265422) (xy 78.9962 -82.216787) (xy 79.030286 -82.172644) (xy 79.070435 -82.133935)
			(xy 79.115793 -82.101484) (xy 79.165393 -82.075983) (xy 79.218177 -82.057976) (xy 79.27302 -82.047846)
			(xy 79.328754 -82.045809) (xy 79.384191 -82.051909) (xy 79.438148 -82.066015) (xy 79.489477 -82.087827)
			(xy 79.537083 -82.116881) (xy 79.579951 -82.152556) (xy 79.617168 -82.194093) (xy 79.647941 -82.240606)
			(xy 79.671613 -82.291103) (xy 79.687681 -82.34451) (xy 79.692578 -82.377788) (xy 80.519014 -82.377788)
			(xy 80.523085 -82.322166) (xy 80.535211 -82.267729) (xy 80.555134 -82.215638) (xy 80.58243 -82.167003)
			(xy 80.616516 -82.12286) (xy 80.656665 -82.084151) (xy 80.702023 -82.0517) (xy 80.751623 -82.026199)
			(xy 80.804407 -82.008192) (xy 80.85925 -81.998062) (xy 80.914984 -81.996025) (xy 80.970421 -82.002125)
			(xy 81.024378 -82.016231) (xy 81.075707 -82.038043) (xy 81.123313 -82.067097) (xy 81.166181 -82.102772)
			(xy 81.203398 -82.144309) (xy 81.234171 -82.190822) (xy 81.257843 -82.241319) (xy 81.273911 -82.294726)
			(xy 81.282031 -82.349902) (xy 81.28254 -82.377788) (xy 81.282031 -82.405674) (xy 81.273911 -82.46085)
			(xy 81.257843 -82.514257) (xy 81.234171 -82.564754) (xy 81.203398 -82.611267) (xy 81.166181 -82.652804)
			(xy 81.123313 -82.688479) (xy 81.075707 -82.717533) (xy 81.024378 -82.739345) (xy 80.970421 -82.753451)
			(xy 80.914984 -82.759551) (xy 80.85925 -82.757514) (xy 80.804407 -82.747384) (xy 80.751623 -82.729377)
			(xy 80.702023 -82.703876) (xy 80.656665 -82.671425) (xy 80.616516 -82.632716) (xy 80.58243 -82.588573)
			(xy 80.555134 -82.539938) (xy 80.535211 -82.487847) (xy 80.523085 -82.43341) (xy 80.519014 -82.377788)
			(xy 79.692578 -82.377788) (xy 79.695801 -82.399686) (xy 79.69631 -82.427572) (xy 79.695801 -82.455458)
			(xy 79.687681 -82.510634) (xy 79.671613 -82.564041) (xy 79.647941 -82.614538) (xy 79.617168 -82.661051)
			(xy 79.579951 -82.702588) (xy 79.537083 -82.738263) (xy 79.489477 -82.767317) (xy 79.438148 -82.789129)
			(xy 79.384191 -82.803235) (xy 79.328754 -82.809335) (xy 79.27302 -82.807298) (xy 79.218177 -82.797168)
			(xy 79.165393 -82.779161) (xy 79.115793 -82.75366) (xy 79.070435 -82.721209) (xy 79.030286 -82.6825)
			(xy 78.9962 -82.638357) (xy 78.968904 -82.589722) (xy 78.948981 -82.537631) (xy 78.936855 -82.483194)
			(xy 78.932784 -82.427572) (xy 65.389908 -82.427572) (xy 65.334642 -83.489038) (xy 65.334642 -83.489546)
			(xy 65.33261 -83.527138) (xy 65.332102 -83.52917) (xy 65.331943 -83.532218) (xy 76.311504 -83.532218)
			(xy 76.315575 -83.476596) (xy 76.327701 -83.422159) (xy 76.347624 -83.370068) (xy 76.37492 -83.321433)
			(xy 76.409006 -83.27729) (xy 76.449155 -83.238581) (xy 76.494513 -83.20613) (xy 76.544113 -83.180629)
			(xy 76.596897 -83.162622) (xy 76.65174 -83.152492) (xy 76.707474 -83.150455) (xy 76.762911 -83.156555)
			(xy 76.816868 -83.170661) (xy 76.868197 -83.192473) (xy 76.915803 -83.221527) (xy 76.958671 -83.257202)
			(xy 76.995888 -83.298739) (xy 77.026661 -83.345252) (xy 77.050333 -83.395749) (xy 77.066401 -83.449156)
			(xy 77.074521 -83.504332) (xy 77.07503 -83.532218) (xy 77.074521 -83.560104) (xy 77.066401 -83.61528)
			(xy 77.050333 -83.668687) (xy 77.026661 -83.719184) (xy 76.995888 -83.765697) (xy 76.958671 -83.807234)
			(xy 76.915803 -83.842909) (xy 76.868197 -83.871963) (xy 76.816868 -83.893775) (xy 76.762911 -83.907881)
			(xy 76.707474 -83.913981) (xy 76.65174 -83.911944) (xy 76.596897 -83.901814) (xy 76.544113 -83.883807)
			(xy 76.494513 -83.858306) (xy 76.449155 -83.825855) (xy 76.409006 -83.787146) (xy 76.37492 -83.743003)
			(xy 76.347624 -83.694368) (xy 76.327701 -83.642277) (xy 76.315575 -83.58784) (xy 76.311504 -83.532218)
			(xy 65.331943 -83.532218) (xy 65.282813 -84.476336) (xy 79.867758 -84.476336) (xy 79.871829 -84.420714)
			(xy 79.883955 -84.366277) (xy 79.903878 -84.314186) (xy 79.931174 -84.265551) (xy 79.96526 -84.221408)
			(xy 80.005409 -84.182699) (xy 80.050767 -84.150248) (xy 80.100367 -84.124747) (xy 80.153151 -84.10674)
			(xy 80.207994 -84.09661) (xy 80.263728 -84.094573) (xy 80.319165 -84.100673) (xy 80.373122 -84.114779)
			(xy 80.424451 -84.136591) (xy 80.472057 -84.165645) (xy 80.514925 -84.20132) (xy 80.552142 -84.242857)
			(xy 80.582915 -84.28937) (xy 80.606587 -84.339867) (xy 80.622655 -84.393274) (xy 80.630775 -84.44845)
			(xy 80.631284 -84.476336) (xy 80.630775 -84.504222) (xy 80.622655 -84.559398) (xy 80.606587 -84.612805)
			(xy 80.582915 -84.663302) (xy 80.552142 -84.709815) (xy 80.514925 -84.751352) (xy 80.472057 -84.787027)
			(xy 80.424451 -84.816081) (xy 80.373122 -84.837893) (xy 80.319165 -84.851999) (xy 80.263728 -84.858099)
			(xy 80.207994 -84.856062) (xy 80.153151 -84.845932) (xy 80.100367 -84.827925) (xy 80.050767 -84.802424)
			(xy 80.005409 -84.769973) (xy 79.96526 -84.731264) (xy 79.931174 -84.687121) (xy 79.903878 -84.638486)
			(xy 79.883955 -84.586395) (xy 79.871829 -84.531958) (xy 79.867758 -84.476336) (xy 65.282813 -84.476336)
			(xy 65.190619 -86.247986) (xy 75.238608 -86.247986) (xy 75.242679 -86.192364) (xy 75.254805 -86.137927)
			(xy 75.274728 -86.085836) (xy 75.302024 -86.037201) (xy 75.33611 -85.993058) (xy 75.376259 -85.954349)
			(xy 75.421617 -85.921898) (xy 75.471217 -85.896397) (xy 75.524001 -85.87839) (xy 75.578844 -85.86826)
			(xy 75.634578 -85.866223) (xy 75.690015 -85.872323) (xy 75.743972 -85.886429) (xy 75.795301 -85.908241)
			(xy 75.842907 -85.937295) (xy 75.885775 -85.97297) (xy 75.922992 -86.014507) (xy 75.953765 -86.06102)
			(xy 75.977437 -86.111517) (xy 75.993505 -86.164924) (xy 76.001625 -86.2201) (xy 76.002134 -86.247986)
			(xy 76.001625 -86.275872) (xy 75.993505 -86.331048) (xy 75.977437 -86.384455) (xy 75.953765 -86.434952)
			(xy 75.922992 -86.481465) (xy 75.885775 -86.523002) (xy 75.842907 -86.558677) (xy 75.795301 -86.587731)
			(xy 75.743972 -86.609543) (xy 75.690015 -86.623649) (xy 75.634578 -86.629749) (xy 75.578844 -86.627712)
			(xy 75.524001 -86.617582) (xy 75.471217 -86.599575) (xy 75.421617 -86.574074) (xy 75.376259 -86.541623)
			(xy 75.33611 -86.502914) (xy 75.302024 -86.458771) (xy 75.274728 -86.410136) (xy 75.254805 -86.358045)
			(xy 75.242679 -86.303608) (xy 75.238608 -86.247986) (xy 65.190619 -86.247986) (xy 65.079881 -88.375998)
			(xy 79.899 -88.375998) (xy 79.903071 -88.320376) (xy 79.915197 -88.265939) (xy 79.93512 -88.213848)
			(xy 79.962416 -88.165213) (xy 79.996502 -88.12107) (xy 80.036651 -88.082361) (xy 80.082009 -88.04991)
			(xy 80.131609 -88.024409) (xy 80.184393 -88.006402) (xy 80.239236 -87.996272) (xy 80.29497 -87.994235)
			(xy 80.350407 -88.000335) (xy 80.404364 -88.014441) (xy 80.455693 -88.036253) (xy 80.503299 -88.065307)
			(xy 80.546167 -88.100982) (xy 80.583384 -88.142519) (xy 80.614157 -88.189032) (xy 80.637829 -88.239529)
			(xy 80.653897 -88.292936) (xy 80.662017 -88.348112) (xy 80.662526 -88.375998) (xy 80.662017 -88.403884)
			(xy 80.653897 -88.45906) (xy 80.637829 -88.512467) (xy 80.614157 -88.562964) (xy 80.583384 -88.609477)
			(xy 80.546167 -88.651014) (xy 80.503299 -88.686689) (xy 80.455693 -88.715743) (xy 80.404364 -88.737555)
			(xy 80.350407 -88.751661) (xy 80.29497 -88.757761) (xy 80.239236 -88.755724) (xy 80.184393 -88.745594)
			(xy 80.131609 -88.727587) (xy 80.082009 -88.702086) (xy 80.036651 -88.669635) (xy 79.996502 -88.630926)
			(xy 79.962416 -88.586783) (xy 79.93512 -88.538148) (xy 79.915197 -88.486057) (xy 79.903071 -88.43162)
			(xy 79.899 -88.375998) (xy 65.079881 -88.375998) (xy 65.049665 -88.956642) (xy 73.632566 -88.956642)
			(xy 73.636637 -88.90102) (xy 73.648763 -88.846583) (xy 73.668686 -88.794492) (xy 73.695982 -88.745857)
			(xy 73.730068 -88.701714) (xy 73.770217 -88.663005) (xy 73.815575 -88.630554) (xy 73.865175 -88.605053)
			(xy 73.917959 -88.587046) (xy 73.972802 -88.576916) (xy 74.028536 -88.574879) (xy 74.083973 -88.580979)
			(xy 74.13793 -88.595085) (xy 74.189259 -88.616897) (xy 74.236865 -88.645951) (xy 74.279733 -88.681626)
			(xy 74.31695 -88.723163) (xy 74.347723 -88.769676) (xy 74.371395 -88.820173) (xy 74.387463 -88.87358)
			(xy 74.395583 -88.928756) (xy 74.396092 -88.956642) (xy 74.395583 -88.984528) (xy 74.387463 -89.039704)
			(xy 74.371395 -89.093111) (xy 74.347723 -89.143608) (xy 74.31695 -89.190121) (xy 74.279733 -89.231658)
			(xy 74.236865 -89.267333) (xy 74.189259 -89.296387) (xy 74.13793 -89.318199) (xy 74.083973 -89.332305)
			(xy 74.028536 -89.338405) (xy 73.972802 -89.336368) (xy 73.917959 -89.326238) (xy 73.865175 -89.308231)
			(xy 73.815575 -89.28273) (xy 73.770217 -89.250279) (xy 73.730068 -89.21157) (xy 73.695982 -89.167427)
			(xy 73.668686 -89.118792) (xy 73.648763 -89.066701) (xy 73.636637 -89.012264) (xy 73.632566 -88.956642)
			(xy 65.049665 -88.956642) (xy 64.872362 -92.363798) (xy 64.723977 -95.214948) (xy 71.639189 -95.214948)
			(xy 71.643144 -95.123111) (xy 71.654979 -95.031954) (xy 71.674606 -94.942151) (xy 71.70188 -94.854369)
			(xy 71.7366 -94.769255) (xy 71.778508 -94.687442) (xy 71.827294 -94.609534) (xy 71.882597 -94.536109)
			(xy 71.944007 -94.467709) (xy 72.011069 -94.404842) (xy 72.083288 -94.347972) (xy 72.160128 -94.297521)
			(xy 72.241021 -94.253862) (xy 72.325367 -94.217319) (xy 72.412543 -94.188162) (xy 72.501902 -94.166608)
			(xy 72.592783 -94.152814) (xy 72.684514 -94.146884) (xy 72.776415 -94.148862) (xy 72.867806 -94.158733)
			(xy 72.95801 -94.176423) (xy 73.046359 -94.201803) (xy 73.132199 -94.234683) (xy 73.214895 -94.274821)
			(xy 73.293835 -94.32192) (xy 73.368433 -94.37563) (xy 73.438139 -94.435554) (xy 73.502434 -94.501248)
			(xy 73.560845 -94.572226) (xy 73.612937 -94.647963) (xy 73.658326 -94.727898) (xy 73.696676 -94.811438)
			(xy 73.727701 -94.897966) (xy 73.751174 -94.986841) (xy 73.76692 -95.077405) (xy 73.774822 -95.168987)
			(xy 73.775316 -95.214948) (xy 73.774822 -95.260909) (xy 73.76692 -95.352491) (xy 73.751174 -95.443055)
			(xy 73.727701 -95.53193) (xy 73.696676 -95.618458) (xy 73.658326 -95.701998) (xy 73.612937 -95.781933)
			(xy 73.560845 -95.85767) (xy 73.502434 -95.928648) (xy 73.442733 -95.989648) (xy 75.563982 -95.989648)
			(xy 75.568053 -95.934026) (xy 75.580179 -95.879589) (xy 75.600102 -95.827498) (xy 75.627398 -95.778863)
			(xy 75.661484 -95.73472) (xy 75.701633 -95.696011) (xy 75.746991 -95.66356) (xy 75.796591 -95.638059)
			(xy 75.849375 -95.620052) (xy 75.904218 -95.609922) (xy 75.959952 -95.607885) (xy 76.015389 -95.613985)
			(xy 76.069346 -95.628091) (xy 76.120675 -95.649903) (xy 76.168281 -95.678957) (xy 76.211149 -95.714632)
			(xy 76.248366 -95.756169) (xy 76.279139 -95.802682) (xy 76.302811 -95.853179) (xy 76.318879 -95.906586)
			(xy 76.326999 -95.961762) (xy 76.327508 -95.989648) (xy 76.326999 -96.017534) (xy 76.318879 -96.07271)
			(xy 76.302811 -96.126117) (xy 76.279139 -96.176614) (xy 76.248366 -96.223127) (xy 76.211149 -96.264664)
			(xy 76.168281 -96.300339) (xy 76.120675 -96.329393) (xy 76.069346 -96.351205) (xy 76.015389 -96.365311)
			(xy 75.959952 -96.371411) (xy 75.904218 -96.369374) (xy 75.849375 -96.359244) (xy 75.796591 -96.341237)
			(xy 75.746991 -96.315736) (xy 75.701633 -96.283285) (xy 75.661484 -96.244576) (xy 75.627398 -96.200433)
			(xy 75.600102 -96.151798) (xy 75.580179 -96.099707) (xy 75.568053 -96.04527) (xy 75.563982 -95.989648)
			(xy 73.442733 -95.989648) (xy 73.438139 -95.994342) (xy 73.368433 -96.054266) (xy 73.293835 -96.107976)
			(xy 73.214895 -96.155075) (xy 73.132199 -96.195213) (xy 73.046359 -96.228093) (xy 72.95801 -96.253473)
			(xy 72.867806 -96.271163) (xy 72.776415 -96.281034) (xy 72.684514 -96.283012) (xy 72.592783 -96.277082)
			(xy 72.501902 -96.263288) (xy 72.412543 -96.241734) (xy 72.325367 -96.212577) (xy 72.241021 -96.176034)
			(xy 72.160128 -96.132375) (xy 72.083288 -96.081924) (xy 72.011069 -96.025054) (xy 71.944007 -95.962187)
			(xy 71.882597 -95.893787) (xy 71.827294 -95.820362) (xy 71.778508 -95.742454) (xy 71.7366 -95.660641)
			(xy 71.70188 -95.575527) (xy 71.674606 -95.487745) (xy 71.654979 -95.397942) (xy 71.643144 -95.306785)
			(xy 71.639189 -95.214948) (xy 64.723977 -95.214948) (xy 64.636228 -96.901) (xy 69.321932 -96.901)
			(xy 69.326003 -96.845378) (xy 69.338129 -96.790941) (xy 69.358052 -96.73885) (xy 69.385348 -96.690215)
			(xy 69.419434 -96.646072) (xy 69.459583 -96.607363) (xy 69.504941 -96.574912) (xy 69.554541 -96.549411)
			(xy 69.607325 -96.531404) (xy 69.662168 -96.521274) (xy 69.717902 -96.519237) (xy 69.773339 -96.525337)
			(xy 69.827296 -96.539443) (xy 69.878625 -96.561255) (xy 69.926231 -96.590309) (xy 69.969099 -96.625984)
			(xy 70.006316 -96.667521) (xy 70.037089 -96.714034) (xy 70.060761 -96.764531) (xy 70.076829 -96.817938)
			(xy 70.084949 -96.873114) (xy 70.085458 -96.901) (xy 70.084949 -96.928886) (xy 70.076829 -96.984062)
			(xy 70.060761 -97.037469) (xy 70.059604 -97.039938) (xy 74.725528 -97.039938) (xy 74.729599 -96.984316)
			(xy 74.741725 -96.929879) (xy 74.761648 -96.877788) (xy 74.788944 -96.829153) (xy 74.82303 -96.78501)
			(xy 74.863179 -96.746301) (xy 74.908537 -96.71385) (xy 74.958137 -96.688349) (xy 75.010921 -96.670342)
			(xy 75.065764 -96.660212) (xy 75.121498 -96.658175) (xy 75.176935 -96.664275) (xy 75.230892 -96.678381)
			(xy 75.282221 -96.700193) (xy 75.329827 -96.729247) (xy 75.372695 -96.764922) (xy 75.409912 -96.806459)
			(xy 75.440685 -96.852972) (xy 75.464357 -96.903469) (xy 75.480425 -96.956876) (xy 75.488545 -97.012052)
			(xy 75.489054 -97.039938) (xy 75.488545 -97.067824) (xy 75.480425 -97.123) (xy 75.464357 -97.176407)
			(xy 75.440685 -97.226904) (xy 75.409912 -97.273417) (xy 75.372695 -97.314954) (xy 75.329827 -97.350629)
			(xy 75.282221 -97.379683) (xy 75.230892 -97.401495) (xy 75.176935 -97.415601) (xy 75.121498 -97.421701)
			(xy 75.065764 -97.419664) (xy 75.010921 -97.409534) (xy 74.958137 -97.391527) (xy 74.908537 -97.366026)
			(xy 74.863179 -97.333575) (xy 74.82303 -97.294866) (xy 74.788944 -97.250723) (xy 74.761648 -97.202088)
			(xy 74.741725 -97.149997) (xy 74.729599 -97.09556) (xy 74.725528 -97.039938) (xy 70.059604 -97.039938)
			(xy 70.037089 -97.087966) (xy 70.006316 -97.134479) (xy 69.969099 -97.176016) (xy 69.926231 -97.211691)
			(xy 69.878625 -97.240745) (xy 69.827296 -97.262557) (xy 69.773339 -97.276663) (xy 69.717902 -97.282763)
			(xy 69.662168 -97.280726) (xy 69.607325 -97.270596) (xy 69.554541 -97.252589) (xy 69.504941 -97.227088)
			(xy 69.459583 -97.194637) (xy 69.419434 -97.155928) (xy 69.385348 -97.111785) (xy 69.358052 -97.06315)
			(xy 69.338129 -97.011059) (xy 69.326003 -96.956622) (xy 69.321932 -96.901) (xy 64.636228 -96.901)
			(xy 64.59776 -97.64014) (xy 73.918062 -97.64014) (xy 73.922133 -97.584518) (xy 73.934259 -97.530081)
			(xy 73.954182 -97.47799) (xy 73.981478 -97.429355) (xy 74.015564 -97.385212) (xy 74.055713 -97.346503)
			(xy 74.101071 -97.314052) (xy 74.150671 -97.288551) (xy 74.203455 -97.270544) (xy 74.258298 -97.260414)
			(xy 74.314032 -97.258377) (xy 74.369469 -97.264477) (xy 74.423426 -97.278583) (xy 74.474755 -97.300395)
			(xy 74.522361 -97.329449) (xy 74.565229 -97.365124) (xy 74.602446 -97.406661) (xy 74.633219 -97.453174)
			(xy 74.656891 -97.503671) (xy 74.672959 -97.557078) (xy 74.681079 -97.612254) (xy 74.681588 -97.64014)
			(xy 74.681079 -97.668026) (xy 74.672959 -97.723202) (xy 74.656891 -97.776609) (xy 74.633219 -97.827106)
			(xy 74.602446 -97.873619) (xy 74.565229 -97.915156) (xy 74.522361 -97.950831) (xy 74.474755 -97.979885)
			(xy 74.423426 -98.001697) (xy 74.369469 -98.015803) (xy 74.314032 -98.021903) (xy 74.258298 -98.019866)
			(xy 74.203455 -98.009736) (xy 74.150671 -97.991729) (xy 74.101071 -97.966228) (xy 74.055713 -97.933777)
			(xy 74.015564 -97.895068) (xy 73.981478 -97.850925) (xy 73.954182 -97.80229) (xy 73.934259 -97.750199)
			(xy 73.922133 -97.695762) (xy 73.918062 -97.64014) (xy 64.59776 -97.64014) (xy 64.570132 -98.171)
			(xy 75.563982 -98.171) (xy 75.568053 -98.115378) (xy 75.580179 -98.060941) (xy 75.600102 -98.00885)
			(xy 75.627398 -97.960215) (xy 75.661484 -97.916072) (xy 75.701633 -97.877363) (xy 75.746991 -97.844912)
			(xy 75.796591 -97.819411) (xy 75.849375 -97.801404) (xy 75.904218 -97.791274) (xy 75.959952 -97.789237)
			(xy 76.015389 -97.795337) (xy 76.069346 -97.809443) (xy 76.120675 -97.831255) (xy 76.168281 -97.860309)
			(xy 76.211149 -97.895984) (xy 76.248366 -97.937521) (xy 76.279139 -97.984034) (xy 76.302811 -98.034531)
			(xy 76.318879 -98.087938) (xy 76.326999 -98.143114) (xy 76.327508 -98.171) (xy 76.326999 -98.198886)
			(xy 76.318879 -98.254062) (xy 76.302811 -98.307469) (xy 76.279139 -98.357966) (xy 76.248366 -98.404479)
			(xy 76.211149 -98.446016) (xy 76.168281 -98.481691) (xy 76.120675 -98.510745) (xy 76.069346 -98.532557)
			(xy 76.015389 -98.546663) (xy 75.959952 -98.552763) (xy 75.904218 -98.550726) (xy 75.849375 -98.540596)
			(xy 75.796591 -98.522589) (xy 75.746991 -98.497088) (xy 75.701633 -98.464637) (xy 75.661484 -98.425928)
			(xy 75.627398 -98.381785) (xy 75.600102 -98.33315) (xy 75.580179 -98.281059) (xy 75.568053 -98.226622)
			(xy 75.563982 -98.171) (xy 64.570132 -98.171) (xy 64.504089 -99.439984) (xy 75.309982 -99.439984)
			(xy 75.314053 -99.384362) (xy 75.326179 -99.329925) (xy 75.346102 -99.277834) (xy 75.373398 -99.229199)
			(xy 75.407484 -99.185056) (xy 75.447633 -99.146347) (xy 75.492991 -99.113896) (xy 75.542591 -99.088395)
			(xy 75.595375 -99.070388) (xy 75.650218 -99.060258) (xy 75.705952 -99.058221) (xy 75.761389 -99.064321)
			(xy 75.815346 -99.078427) (xy 75.866675 -99.100239) (xy 75.914281 -99.129293) (xy 75.957149 -99.164968)
			(xy 75.994366 -99.206505) (xy 76.025139 -99.253018) (xy 76.048811 -99.303515) (xy 76.064879 -99.356922)
			(xy 76.072999 -99.412098) (xy 76.073508 -99.439984) (xy 76.072999 -99.46787) (xy 76.064879 -99.523046)
			(xy 76.048811 -99.576453) (xy 76.025139 -99.62695) (xy 75.994366 -99.673463) (xy 75.957149 -99.715)
			(xy 75.914281 -99.750675) (xy 75.866675 -99.779729) (xy 75.815346 -99.801541) (xy 75.761389 -99.815647)
			(xy 75.705952 -99.821747) (xy 75.650218 -99.81971) (xy 75.595375 -99.80958) (xy 75.542591 -99.791573)
			(xy 75.492991 -99.766072) (xy 75.447633 -99.733621) (xy 75.407484 -99.694912) (xy 75.373398 -99.650769)
			(xy 75.346102 -99.602134) (xy 75.326179 -99.550043) (xy 75.314053 -99.495606) (xy 75.309982 -99.439984)
			(xy 64.504089 -99.439984) (xy 64.456659 -100.351336) (xy 70.122032 -100.351336) (xy 70.126103 -100.295714)
			(xy 70.138229 -100.241277) (xy 70.158152 -100.189186) (xy 70.185448 -100.140551) (xy 70.219534 -100.096408)
			(xy 70.259683 -100.057699) (xy 70.305041 -100.025248) (xy 70.354641 -99.999747) (xy 70.407425 -99.98174)
			(xy 70.462268 -99.97161) (xy 70.518002 -99.969573) (xy 70.573439 -99.975673) (xy 70.627396 -99.989779)
			(xy 70.678725 -100.011591) (xy 70.725163 -100.039932) (xy 73.876914 -100.039932) (xy 73.880985 -99.98431)
			(xy 73.893111 -99.929873) (xy 73.913034 -99.877782) (xy 73.94033 -99.829147) (xy 73.974416 -99.785004)
			(xy 74.014565 -99.746295) (xy 74.059923 -99.713844) (xy 74.109523 -99.688343) (xy 74.162307 -99.670336)
			(xy 74.21715 -99.660206) (xy 74.272884 -99.658169) (xy 74.328321 -99.664269) (xy 74.382278 -99.678375)
			(xy 74.433607 -99.700187) (xy 74.481213 -99.729241) (xy 74.524081 -99.764916) (xy 74.561298 -99.806453)
			(xy 74.592071 -99.852966) (xy 74.615743 -99.903463) (xy 74.631811 -99.95687) (xy 74.639931 -100.012046)
			(xy 74.64044 -100.039932) (xy 74.639931 -100.067818) (xy 74.631811 -100.122994) (xy 74.615743 -100.176401)
			(xy 74.592071 -100.226898) (xy 74.561298 -100.273411) (xy 74.524081 -100.314948) (xy 74.481213 -100.350623)
			(xy 74.433607 -100.379677) (xy 74.382278 -100.401489) (xy 74.328321 -100.415595) (xy 74.272884 -100.421695)
			(xy 74.21715 -100.419658) (xy 74.162307 -100.409528) (xy 74.109523 -100.391521) (xy 74.059923 -100.36602)
			(xy 74.014565 -100.333569) (xy 73.974416 -100.29486) (xy 73.94033 -100.250717) (xy 73.913034 -100.202082)
			(xy 73.893111 -100.149991) (xy 73.880985 -100.095554) (xy 73.876914 -100.039932) (xy 70.725163 -100.039932)
			(xy 70.726331 -100.040645) (xy 70.769199 -100.07632) (xy 70.806416 -100.117857) (xy 70.837189 -100.16437)
			(xy 70.860861 -100.214867) (xy 70.876929 -100.268274) (xy 70.885049 -100.32345) (xy 70.885558 -100.351336)
			(xy 70.885049 -100.379222) (xy 70.876929 -100.434398) (xy 70.860861 -100.487805) (xy 70.837189 -100.538302)
			(xy 70.806416 -100.584815) (xy 70.769199 -100.626352) (xy 70.726331 -100.662027) (xy 70.678725 -100.691081)
			(xy 70.627396 -100.712893) (xy 70.573439 -100.726999) (xy 70.518002 -100.733099) (xy 70.462268 -100.731062)
			(xy 70.407425 -100.720932) (xy 70.354641 -100.702925) (xy 70.305041 -100.677424) (xy 70.259683 -100.644973)
			(xy 70.219534 -100.606264) (xy 70.185448 -100.562121) (xy 70.158152 -100.513486) (xy 70.138229 -100.461395)
			(xy 70.126103 -100.406958) (xy 70.122032 -100.351336) (xy 64.456659 -100.351336) (xy 64.410405 -101.240082)
			(xy 74.293982 -101.240082) (xy 74.298053 -101.18446) (xy 74.310179 -101.130023) (xy 74.330102 -101.077932)
			(xy 74.357398 -101.029297) (xy 74.391484 -100.985154) (xy 74.431633 -100.946445) (xy 74.476991 -100.913994)
			(xy 74.526591 -100.888493) (xy 74.579375 -100.870486) (xy 74.634218 -100.860356) (xy 74.689952 -100.858319)
			(xy 74.745389 -100.864419) (xy 74.799346 -100.878525) (xy 74.850675 -100.900337) (xy 74.898281 -100.929391)
			(xy 74.941149 -100.965066) (xy 74.978366 -101.006603) (xy 75.009139 -101.053116) (xy 75.016889 -101.069648)
			(xy 75.586334 -101.069648) (xy 75.590405 -101.014026) (xy 75.602531 -100.959589) (xy 75.622454 -100.907498)
			(xy 75.64975 -100.858863) (xy 75.683836 -100.81472) (xy 75.723985 -100.776011) (xy 75.769343 -100.74356)
			(xy 75.818943 -100.718059) (xy 75.871727 -100.700052) (xy 75.92657 -100.689922) (xy 75.982304 -100.687885)
			(xy 76.037741 -100.693985) (xy 76.091698 -100.708091) (xy 76.143027 -100.729903) (xy 76.190633 -100.758957)
			(xy 76.233501 -100.794632) (xy 76.270718 -100.836169) (xy 76.301491 -100.882682) (xy 76.325163 -100.933179)
			(xy 76.341231 -100.986586) (xy 76.349351 -101.041762) (xy 76.34986 -101.069648) (xy 76.349351 -101.097534)
			(xy 76.341231 -101.15271) (xy 76.325163 -101.206117) (xy 76.301491 -101.256614) (xy 76.270718 -101.303127)
			(xy 76.233501 -101.344664) (xy 76.190633 -101.380339) (xy 76.143027 -101.409393) (xy 76.091698 -101.431205)
			(xy 76.037741 -101.445311) (xy 75.982304 -101.451411) (xy 75.92657 -101.449374) (xy 75.871727 -101.439244)
			(xy 75.818943 -101.421237) (xy 75.769343 -101.395736) (xy 75.723985 -101.363285) (xy 75.683836 -101.324576)
			(xy 75.64975 -101.280433) (xy 75.622454 -101.231798) (xy 75.602531 -101.179707) (xy 75.590405 -101.12527)
			(xy 75.586334 -101.069648) (xy 75.016889 -101.069648) (xy 75.032811 -101.103613) (xy 75.048879 -101.15702)
			(xy 75.056999 -101.212196) (xy 75.057508 -101.240082) (xy 75.056999 -101.267968) (xy 75.048879 -101.323144)
			(xy 75.032811 -101.376551) (xy 75.009139 -101.427048) (xy 74.978366 -101.473561) (xy 74.941149 -101.515098)
			(xy 74.898281 -101.550773) (xy 74.850675 -101.579827) (xy 74.799346 -101.601639) (xy 74.745389 -101.615745)
			(xy 74.689952 -101.621845) (xy 74.634218 -101.619808) (xy 74.579375 -101.609678) (xy 74.526591 -101.591671)
			(xy 74.476991 -101.56617) (xy 74.431633 -101.533719) (xy 74.391484 -101.49501) (xy 74.357398 -101.450867)
			(xy 74.330102 -101.402232) (xy 74.310179 -101.350141) (xy 74.298053 -101.295704) (xy 74.293982 -101.240082)
			(xy 64.410405 -101.240082) (xy 64.345407 -102.489) (xy 74.801982 -102.489) (xy 74.806053 -102.433378)
			(xy 74.818179 -102.378941) (xy 74.838102 -102.32685) (xy 74.865398 -102.278215) (xy 74.899484 -102.234072)
			(xy 74.939633 -102.195363) (xy 74.984991 -102.162912) (xy 75.034591 -102.137411) (xy 75.087375 -102.119404)
			(xy 75.142218 -102.109274) (xy 75.197952 -102.107237) (xy 75.253389 -102.113337) (xy 75.307346 -102.127443)
			(xy 75.358675 -102.149255) (xy 75.406281 -102.178309) (xy 75.449149 -102.213984) (xy 75.486366 -102.255521)
			(xy 75.517139 -102.302034) (xy 75.540811 -102.352531) (xy 75.556879 -102.405938) (xy 75.564999 -102.461114)
			(xy 75.565508 -102.489) (xy 75.564999 -102.516886) (xy 75.556879 -102.572062) (xy 75.540811 -102.625469)
			(xy 75.517139 -102.675966) (xy 75.486366 -102.722479) (xy 75.449149 -102.764016) (xy 75.406281 -102.799691)
			(xy 75.358675 -102.828745) (xy 75.307346 -102.850557) (xy 75.253389 -102.864663) (xy 75.197952 -102.870763)
			(xy 75.142218 -102.868726) (xy 75.087375 -102.858596) (xy 75.034591 -102.840589) (xy 74.984991 -102.815088)
			(xy 74.939633 -102.782637) (xy 74.899484 -102.743928) (xy 74.865398 -102.699785) (xy 74.838102 -102.65115)
			(xy 74.818179 -102.599059) (xy 74.806053 -102.544622) (xy 74.801982 -102.489) (xy 64.345407 -102.489)
			(xy 64.272702 -103.886) (xy 75.309982 -103.886) (xy 75.314053 -103.830378) (xy 75.326179 -103.775941)
			(xy 75.346102 -103.72385) (xy 75.373398 -103.675215) (xy 75.407484 -103.631072) (xy 75.447633 -103.592363)
			(xy 75.492991 -103.559912) (xy 75.542591 -103.534411) (xy 75.595375 -103.516404) (xy 75.650218 -103.506274)
			(xy 75.705952 -103.504237) (xy 75.761389 -103.510337) (xy 75.815346 -103.524443) (xy 75.866675 -103.546255)
			(xy 75.914281 -103.575309) (xy 75.957149 -103.610984) (xy 75.994366 -103.652521) (xy 76.025139 -103.699034)
			(xy 76.048811 -103.749531) (xy 76.064879 -103.802938) (xy 76.072999 -103.858114) (xy 76.073508 -103.886)
			(xy 76.072999 -103.913886) (xy 76.064879 -103.969062) (xy 76.048811 -104.022469) (xy 76.025139 -104.072966)
			(xy 75.994366 -104.119479) (xy 75.957149 -104.161016) (xy 75.914281 -104.196691) (xy 75.866675 -104.225745)
			(xy 75.815346 -104.247557) (xy 75.761389 -104.261663) (xy 75.705952 -104.267763) (xy 75.650218 -104.265726)
			(xy 75.595375 -104.255596) (xy 75.542591 -104.237589) (xy 75.492991 -104.212088) (xy 75.447633 -104.179637)
			(xy 75.407484 -104.140928) (xy 75.373398 -104.096785) (xy 75.346102 -104.04815) (xy 75.326179 -103.996059)
			(xy 75.314053 -103.941622) (xy 75.309982 -103.886) (xy 64.272702 -103.886) (xy 64.09969 -107.210352)
			(xy 64.762632 -107.210352) (xy 64.766703 -107.15473) (xy 64.778829 -107.100293) (xy 64.798752 -107.048202)
			(xy 64.826048 -106.999567) (xy 64.860134 -106.955424) (xy 64.900283 -106.916715) (xy 64.945641 -106.884264)
			(xy 64.995241 -106.858763) (xy 65.048025 -106.840756) (xy 65.102868 -106.830626) (xy 65.158602 -106.828589)
			(xy 65.214039 -106.834689) (xy 65.267996 -106.848795) (xy 65.319325 -106.870607) (xy 65.366931 -106.899661)
			(xy 65.409799 -106.935336) (xy 65.447016 -106.976873) (xy 65.477789 -107.023386) (xy 65.501461 -107.073883)
			(xy 65.517529 -107.12729) (xy 65.525649 -107.182466) (xy 65.526158 -107.210352) (xy 65.525649 -107.238238)
			(xy 65.517529 -107.293414) (xy 65.501461 -107.346821) (xy 65.477789 -107.397318) (xy 65.447016 -107.443831)
			(xy 65.409799 -107.485368) (xy 65.366931 -107.521043) (xy 65.319325 -107.550097) (xy 65.267996 -107.571909)
			(xy 65.214039 -107.586015) (xy 65.158602 -107.592115) (xy 65.102868 -107.590078) (xy 65.048025 -107.579948)
			(xy 64.995241 -107.561941) (xy 64.945641 -107.53644) (xy 64.900283 -107.503989) (xy 64.860134 -107.46528)
			(xy 64.826048 -107.421137) (xy 64.798752 -107.372502) (xy 64.778829 -107.320411) (xy 64.766703 -107.265974)
			(xy 64.762632 -107.210352) (xy 64.09969 -107.210352) (xy 63.926916 -110.530132) (xy 70.429118 -110.530132)
			(xy 70.433189 -110.47451) (xy 70.445315 -110.420073) (xy 70.465238 -110.367982) (xy 70.492534 -110.319347)
			(xy 70.52662 -110.275204) (xy 70.566769 -110.236495) (xy 70.612127 -110.204044) (xy 70.661727 -110.178543)
			(xy 70.714511 -110.160536) (xy 70.769354 -110.150406) (xy 70.825088 -110.148369) (xy 70.880525 -110.154469)
			(xy 70.934482 -110.168575) (xy 70.985811 -110.190387) (xy 71.033417 -110.219441) (xy 71.076285 -110.255116)
			(xy 71.113502 -110.296653) (xy 71.144275 -110.343166) (xy 71.167947 -110.393663) (xy 71.184015 -110.44707)
			(xy 71.192135 -110.502246) (xy 71.192644 -110.530132) (xy 71.192135 -110.558018) (xy 71.184015 -110.613194)
			(xy 71.167947 -110.666601) (xy 71.144275 -110.717098) (xy 71.113502 -110.763611) (xy 71.076285 -110.805148)
			(xy 71.033417 -110.840823) (xy 70.985811 -110.869877) (xy 70.934482 -110.891689) (xy 70.880525 -110.905795)
			(xy 70.825088 -110.911895) (xy 70.769354 -110.909858) (xy 70.714511 -110.899728) (xy 70.661727 -110.881721)
			(xy 70.612127 -110.85622) (xy 70.566769 -110.823769) (xy 70.52662 -110.78506) (xy 70.492534 -110.740917)
			(xy 70.465238 -110.692282) (xy 70.445315 -110.640191) (xy 70.433189 -110.585754) (xy 70.429118 -110.530132)
			(xy 63.926916 -110.530132) (xy 63.885077 -111.334042) (xy 64.26403 -111.334042) (xy 64.268101 -111.27842)
			(xy 64.280227 -111.223983) (xy 64.30015 -111.171892) (xy 64.327446 -111.123257) (xy 64.361532 -111.079114)
			(xy 64.401681 -111.040405) (xy 64.447039 -111.007954) (xy 64.496639 -110.982453) (xy 64.549423 -110.964446)
			(xy 64.604266 -110.954316) (xy 64.66 -110.952279) (xy 64.715437 -110.958379) (xy 64.769394 -110.972485)
			(xy 64.820723 -110.994297) (xy 64.868329 -111.023351) (xy 64.911197 -111.059026) (xy 64.948414 -111.100563)
			(xy 64.979187 -111.147076) (xy 65.002859 -111.197573) (xy 65.018927 -111.25098) (xy 65.027047 -111.306156)
			(xy 65.027556 -111.334042) (xy 65.027047 -111.361928) (xy 65.018927 -111.417104) (xy 65.002859 -111.470511)
			(xy 64.979187 -111.521008) (xy 64.948414 -111.567521) (xy 64.911197 -111.609058) (xy 64.868329 -111.644733)
			(xy 64.820723 -111.673787) (xy 64.769394 -111.695599) (xy 64.715437 -111.709705) (xy 64.66 -111.715805)
			(xy 64.604266 -111.713768) (xy 64.549423 -111.703638) (xy 64.496639 -111.685631) (xy 64.447039 -111.66013)
			(xy 64.401681 -111.627679) (xy 64.361532 -111.58897) (xy 64.327446 -111.544827) (xy 64.30015 -111.496192)
			(xy 64.280227 -111.444101) (xy 64.268101 -111.389664) (xy 64.26403 -111.334042) (xy 63.885077 -111.334042)
			(xy 63.856444 -111.884206) (xy 70.364348 -111.884206) (xy 70.368419 -111.828584) (xy 70.380545 -111.774147)
			(xy 70.400468 -111.722056) (xy 70.427764 -111.673421) (xy 70.46185 -111.629278) (xy 70.501999 -111.590569)
			(xy 70.547357 -111.558118) (xy 70.596957 -111.532617) (xy 70.649741 -111.51461) (xy 70.704584 -111.50448)
			(xy 70.760318 -111.502443) (xy 70.815755 -111.508543) (xy 70.869712 -111.522649) (xy 70.921041 -111.544461)
			(xy 70.968647 -111.573515) (xy 71.011515 -111.60919) (xy 71.048732 -111.650727) (xy 71.079505 -111.69724)
			(xy 71.103177 -111.747737) (xy 71.119245 -111.801144) (xy 71.127365 -111.85632) (xy 71.127874 -111.884206)
			(xy 71.127365 -111.912092) (xy 71.119245 -111.967268) (xy 71.115196 -111.980726) (xy 73.901554 -111.980726)
			(xy 73.902106 -111.951988) (xy 73.910723 -111.895163) (xy 73.927768 -111.840273) (xy 73.952853 -111.788561)
			(xy 73.985411 -111.741196) (xy 74.004678 -111.719868) (xy 74.011282 -111.71301) (xy 74.018394 -111.694976)
			(xy 74.018394 -111.606076) (xy 74.011282 -111.588042) (xy 74.004678 -111.581184) (xy 73.985435 -111.559834)
			(xy 73.952873 -111.512474) (xy 73.927783 -111.460766) (xy 73.910733 -111.405879) (xy 73.902109 -111.349056)
			(xy 73.902106 -111.291582) (xy 73.910725 -111.234758) (xy 73.927769 -111.17987) (xy 73.952854 -111.128159)
			(xy 73.985411 -111.080796) (xy 74.004678 -111.059468) (xy 74.011282 -111.05261) (xy 74.018394 -111.034576)
			(xy 74.018394 -110.945676) (xy 74.011282 -110.927642) (xy 74.004678 -110.920784) (xy 73.985435 -110.899434)
			(xy 73.952873 -110.852074) (xy 73.927783 -110.800366) (xy 73.910733 -110.745479) (xy 73.902109 -110.688656)
			(xy 73.902106 -110.631182) (xy 73.910725 -110.574358) (xy 73.927769 -110.51947) (xy 73.952854 -110.467759)
			(xy 73.985411 -110.420396) (xy 74.004678 -110.399068) (xy 74.011282 -110.39221) (xy 74.018394 -110.374176)
			(xy 74.018394 -110.285276) (xy 74.011282 -110.267242) (xy 74.004678 -110.260384) (xy 73.985435 -110.239034)
			(xy 73.952873 -110.191674) (xy 73.927783 -110.139966) (xy 73.910733 -110.085079) (xy 73.902109 -110.028256)
			(xy 73.902106 -109.970782) (xy 73.910725 -109.913958) (xy 73.927769 -109.85907) (xy 73.952854 -109.807359)
			(xy 73.985411 -109.759996) (xy 74.004678 -109.738668) (xy 74.011282 -109.73181) (xy 74.018394 -109.713776)
			(xy 74.018394 -109.624876) (xy 74.011282 -109.606842) (xy 74.004678 -109.599984) (xy 73.985426 -109.57864)
			(xy 73.952856 -109.531284) (xy 73.927759 -109.479576) (xy 73.910704 -109.424689) (xy 73.902077 -109.367864)
			(xy 73.901554 -109.339126) (xy 73.902102 -109.311877) (xy 73.909854 -109.257934) (xy 73.925204 -109.205642)
			(xy 73.94784 -109.156068) (xy 73.9773 -109.110219) (xy 74.012984 -109.06903) (xy 74.054168 -109.033338)
			(xy 74.100012 -109.00387) (xy 74.149582 -108.981227) (xy 74.201871 -108.965868) (xy 74.255813 -108.958107)
			(xy 74.283062 -108.957618) (xy 74.309378 -108.958038) (xy 74.361508 -108.965282) (xy 74.412152 -108.97961)
			(xy 74.460351 -109.000751) (xy 74.505193 -109.028306) (xy 74.545831 -109.061753) (xy 74.563986 -109.080808)
			(xy 74.57151 -109.088206) (xy 74.590788 -109.096732) (xy 74.601324 -109.097318) (xy 74.676 -109.097318)
			(xy 74.686551 -109.096797) (xy 74.705845 -109.088256) (xy 74.713338 -109.080808) (xy 74.731484 -109.061743)
			(xy 74.772115 -109.028286) (xy 74.816958 -109.000728) (xy 74.86516 -108.979591) (xy 74.91581 -108.965276)
			(xy 74.967945 -108.958055) (xy 74.994262 -108.957618) (xy 75.021515 -108.958091) (xy 75.075467 -108.965843)
			(xy 75.127766 -108.981196) (xy 75.177348 -109.003836) (xy 75.223203 -109.033302) (xy 75.264396 -109.068995)
			(xy 75.300091 -109.110188) (xy 75.329559 -109.156041) (xy 75.3522 -109.205622) (xy 75.367554 -109.257921)
			(xy 75.375308 -109.311873) (xy 75.37577 -109.339126) (xy 75.375243 -109.367865) (xy 75.366619 -109.424691)
			(xy 75.349568 -109.479581) (xy 75.324478 -109.531293) (xy 75.291915 -109.578656) (xy 75.272646 -109.599984)
			(xy 75.266042 -109.606842) (xy 75.25893 -109.624876) (xy 75.25893 -109.713776) (xy 75.266042 -109.73181)
			(xy 75.272646 -109.738668) (xy 75.291944 -109.759972) (xy 75.324511 -109.807337) (xy 75.349603 -109.859053)
			(xy 75.366653 -109.913947) (xy 75.375273 -109.970778) (xy 75.375271 -110.02826) (xy 75.366644 -110.08509)
			(xy 75.349589 -110.139983) (xy 75.324492 -110.191696) (xy 75.29192 -110.239058) (xy 75.272646 -110.260384)
			(xy 75.266042 -110.267242) (xy 75.25893 -110.285276) (xy 75.25893 -110.374176) (xy 75.266042 -110.39221)
			(xy 75.272646 -110.399068) (xy 75.291944 -110.420372) (xy 75.324511 -110.467737) (xy 75.349603 -110.519453)
			(xy 75.366653 -110.574347) (xy 75.375273 -110.631178) (xy 75.375271 -110.68866) (xy 75.366644 -110.74549)
			(xy 75.349589 -110.800383) (xy 75.324492 -110.852096) (xy 75.29192 -110.899458) (xy 75.272646 -110.920784)
			(xy 75.266042 -110.927642) (xy 75.25893 -110.945676) (xy 75.25893 -111.034576) (xy 75.266042 -111.05261)
			(xy 75.272646 -111.059468) (xy 75.291944 -111.080772) (xy 75.324511 -111.128137) (xy 75.349603 -111.179853)
			(xy 75.366653 -111.234747) (xy 75.375273 -111.291578) (xy 75.375271 -111.34906) (xy 75.366644 -111.40589)
			(xy 75.349589 -111.460783) (xy 75.324492 -111.512496) (xy 75.29192 -111.559858) (xy 75.272646 -111.581184)
			(xy 75.266042 -111.588042) (xy 75.25893 -111.606076) (xy 75.25893 -111.694976) (xy 75.266042 -111.71301)
			(xy 75.272646 -111.719868) (xy 75.291926 -111.741187) (xy 75.324492 -111.788551) (xy 75.349583 -111.840264)
			(xy 75.366631 -111.895157) (xy 75.375251 -111.951986) (xy 75.37577 -111.980726) (xy 75.375369 -112.007981)
			(xy 75.367608 -112.061936) (xy 75.352246 -112.114238) (xy 75.329598 -112.163821) (xy 75.300124 -112.209676)
			(xy 75.264424 -112.250869) (xy 75.223224 -112.286562) (xy 75.177364 -112.316029) (xy 75.127778 -112.338669)
			(xy 75.075474 -112.354021) (xy 75.021517 -112.361774) (xy 74.994262 -112.362234) (xy 74.967948 -112.361781)
			(xy 74.915819 -112.354542) (xy 74.865176 -112.340219) (xy 74.816978 -112.319084) (xy 74.772135 -112.291536)
			(xy 74.731495 -112.258096) (xy 74.713338 -112.239044) (xy 74.705798 -112.231664) (xy 74.686532 -112.223126)
			(xy 74.676 -112.222534) (xy 74.601324 -112.222534) (xy 74.590773 -112.223052) (xy 74.571477 -112.231594)
			(xy 74.563986 -112.239044) (xy 74.545839 -112.258108) (xy 74.505206 -112.291562) (xy 74.460364 -112.319119)
			(xy 74.412162 -112.340256) (xy 74.361513 -112.354572) (xy 74.309378 -112.361796) (xy 74.283062 -112.362234)
			(xy 74.255811 -112.361758) (xy 74.201864 -112.353997) (xy 74.149571 -112.338638) (xy 74.099995 -112.315994)
			(xy 74.054146 -112.286526) (xy 74.012957 -112.250834) (xy 73.977266 -112.209644) (xy 73.9478 -112.163794)
			(xy 73.925158 -112.114218) (xy 73.909801 -112.061924) (xy 73.902042 -112.007977) (xy 73.901554 -111.980726)
			(xy 71.115196 -111.980726) (xy 71.103177 -112.020675) (xy 71.079505 -112.071172) (xy 71.048732 -112.117685)
			(xy 71.011515 -112.159222) (xy 70.968647 -112.194897) (xy 70.921041 -112.223951) (xy 70.869712 -112.245763)
			(xy 70.815755 -112.259869) (xy 70.760318 -112.265969) (xy 70.704584 -112.263932) (xy 70.649741 -112.253802)
			(xy 70.596957 -112.235795) (xy 70.547357 -112.210294) (xy 70.501999 -112.177843) (xy 70.46185 -112.139134)
			(xy 70.427764 -112.094991) (xy 70.400468 -112.046356) (xy 70.380545 -111.994265) (xy 70.368419 -111.939828)
			(xy 70.364348 -111.884206) (xy 63.856444 -111.884206) (xy 63.845948 -112.085882) (xy 63.846039 -112.092373)
			(xy 63.849113 -112.104982) (xy 63.852044 -112.110774) (xy 63.855338 -112.116495) (xy 63.864344 -112.126142)
			(xy 63.869824 -112.129824) (xy 63.94323 -112.175544) (xy 63.945262 -112.17656) (xy 63.951866 -112.18037)
			(xy 63.966852 -112.183926) (xy 63.980314 -112.18291) (xy 63.991236 -112.179862) (xy 64.00038 -112.176306)
			(xy 64.006476 -112.173258) (xy 64.034003 -112.15942) (xy 64.092416 -112.139836) (xy 64.153218 -112.1299)
			(xy 64.184022 -112.129316) (xy 64.188594 -112.129316) (xy 64.216689 -112.130117) (xy 64.272192 -112.138959)
			(xy 64.325797 -112.155849) (xy 64.376345 -112.18042) (xy 64.42274 -112.212142) (xy 64.46398 -112.250327)
			(xy 64.499171 -112.294149) (xy 64.527551 -112.34266) (xy 64.548508 -112.39481) (xy 64.554995 -112.421924)
			(xy 69.455028 -112.421924) (xy 69.459099 -112.366302) (xy 69.471225 -112.311865) (xy 69.491148 -112.259774)
			(xy 69.518444 -112.211139) (xy 69.55253 -112.166996) (xy 69.592679 -112.128287) (xy 69.638037 -112.095836)
			(xy 69.687637 -112.070335) (xy 69.740421 -112.052328) (xy 69.795264 -112.042198) (xy 69.850998 -112.040161)
			(xy 69.906435 -112.046261) (xy 69.960392 -112.060367) (xy 70.011721 -112.082179) (xy 70.059327 -112.111233)
			(xy 70.102195 -112.146908) (xy 70.139412 -112.188445) (xy 70.170185 -112.234958) (xy 70.193857 -112.285455)
			(xy 70.209925 -112.338862) (xy 70.218045 -112.394038) (xy 70.218554 -112.421924) (xy 70.218045 -112.44981)
			(xy 70.209925 -112.504986) (xy 70.193857 -112.558393) (xy 70.170185 -112.60889) (xy 70.139412 -112.655403)
			(xy 70.102195 -112.69694) (xy 70.059327 -112.732615) (xy 70.011721 -112.761669) (xy 69.960392 -112.783481)
			(xy 69.906435 -112.797587) (xy 69.850998 -112.803687) (xy 69.795264 -112.80165) (xy 69.740421 -112.79152)
			(xy 69.687637 -112.773513) (xy 69.638037 -112.748012) (xy 69.592679 -112.715561) (xy 69.55253 -112.676852)
			(xy 69.518444 -112.632709) (xy 69.491148 -112.584074) (xy 69.471225 -112.531983) (xy 69.459099 -112.477546)
			(xy 69.455028 -112.421924) (xy 64.554995 -112.421924) (xy 64.561586 -112.44947) (xy 64.566504 -112.505458)
			(xy 64.563154 -112.561561) (xy 64.551609 -112.616566) (xy 64.532119 -112.669282) (xy 64.505106 -112.718567)
			(xy 64.471154 -112.763356) (xy 64.430998 -112.80268) (xy 64.386553 -112.834928) (xy 66.496946 -112.834928)
			(xy 66.497432 -112.807677) (xy 66.505188 -112.753729) (xy 66.520543 -112.701434) (xy 66.543185 -112.651857)
			(xy 66.572651 -112.606007) (xy 66.608342 -112.564816) (xy 66.649533 -112.529125) (xy 66.695383 -112.499659)
			(xy 66.74496 -112.477017) (xy 66.797255 -112.461662) (xy 66.851203 -112.453906) (xy 66.905705 -112.453906)
			(xy 66.959653 -112.461662) (xy 67.011948 -112.477017) (xy 67.061525 -112.499659) (xy 67.107375 -112.529125)
			(xy 67.148566 -112.564816) (xy 67.184257 -112.606007) (xy 67.213723 -112.651857) (xy 67.236365 -112.701434)
			(xy 67.25172 -112.753729) (xy 67.259476 -112.807677) (xy 67.259962 -112.834928) (xy 67.259592 -112.858546)
			(xy 67.253736 -112.905418) (xy 67.248278 -112.9284) (xy 67.245153 -112.942907) (xy 67.246479 -112.97254)
			(xy 67.252438 -112.989614) (xy 70.44004 -112.989614) (xy 70.444111 -112.933992) (xy 70.456237 -112.879555)
			(xy 70.47616 -112.827464) (xy 70.503456 -112.778829) (xy 70.537542 -112.734686) (xy 70.577691 -112.695977)
			(xy 70.623049 -112.663526) (xy 70.672649 -112.638025) (xy 70.725433 -112.620018) (xy 70.780276 -112.609888)
			(xy 70.83601 -112.607851) (xy 70.891447 -112.613951) (xy 70.945404 -112.628057) (xy 70.996733 -112.649869)
			(xy 71.044339 -112.678923) (xy 71.087207 -112.714598) (xy 71.124424 -112.756135) (xy 71.155197 -112.802648)
			(xy 71.178869 -112.853145) (xy 71.194937 -112.906552) (xy 71.203057 -112.961728) (xy 71.203566 -112.989614)
			(xy 71.203057 -113.0175) (xy 71.194937 -113.072676) (xy 71.178869 -113.126083) (xy 71.155197 -113.17658)
			(xy 71.124424 -113.223093) (xy 71.087207 -113.26463) (xy 71.044339 -113.300305) (xy 70.996733 -113.329359)
			(xy 70.945404 -113.351171) (xy 70.891447 -113.365277) (xy 70.83601 -113.371377) (xy 70.780276 -113.36934)
			(xy 70.725433 -113.35921) (xy 70.672649 -113.341203) (xy 70.623049 -113.315702) (xy 70.577691 -113.283251)
			(xy 70.537542 -113.244542) (xy 70.503456 -113.200399) (xy 70.47616 -113.151764) (xy 70.456237 -113.099673)
			(xy 70.444111 -113.045236) (xy 70.44004 -112.989614) (xy 67.252438 -112.989614) (xy 67.256253 -113.000546)
			(xy 67.273654 -113.024568) (xy 67.297217 -113.042587) (xy 67.32496 -113.053085) (xy 67.339718 -113.054638)
			(xy 67.368241 -113.057167) (xy 67.424115 -113.069687) (xy 67.47749 -113.090418) (xy 67.527167 -113.118895)
			(xy 67.572028 -113.154479) (xy 67.611066 -113.196368) (xy 67.643403 -113.243623) (xy 67.668313 -113.295181)
			(xy 67.685236 -113.349883) (xy 67.693791 -113.4065) (xy 67.694302 -113.43513) (xy 67.694252 -113.437924)
			(xy 69.433946 -113.437924) (xy 69.438017 -113.382302) (xy 69.450143 -113.327865) (xy 69.470066 -113.275774)
			(xy 69.497362 -113.227139) (xy 69.531448 -113.182996) (xy 69.571597 -113.144287) (xy 69.616955 -113.111836)
			(xy 69.666555 -113.086335) (xy 69.719339 -113.068328) (xy 69.774182 -113.058198) (xy 69.829916 -113.056161)
			(xy 69.885353 -113.062261) (xy 69.93931 -113.076367) (xy 69.990639 -113.098179) (xy 70.038245 -113.127233)
			(xy 70.081113 -113.162908) (xy 70.11833 -113.204445) (xy 70.149103 -113.250958) (xy 70.172775 -113.301455)
			(xy 70.188843 -113.354862) (xy 70.196963 -113.410038) (xy 70.197472 -113.437924) (xy 70.196963 -113.46581)
			(xy 70.188843 -113.520986) (xy 70.172775 -113.574393) (xy 70.149103 -113.62489) (xy 70.11833 -113.671403)
			(xy 70.081113 -113.71294) (xy 70.038245 -113.748615) (xy 69.990639 -113.777669) (xy 69.93931 -113.799481)
			(xy 69.885353 -113.813587) (xy 69.829916 -113.819687) (xy 69.774182 -113.81765) (xy 69.719339 -113.80752)
			(xy 69.666555 -113.789513) (xy 69.616955 -113.764012) (xy 69.571597 -113.731561) (xy 69.531448 -113.692852)
			(xy 69.497362 -113.648709) (xy 69.470066 -113.600074) (xy 69.450143 -113.547983) (xy 69.438017 -113.493546)
			(xy 69.433946 -113.437924) (xy 67.694252 -113.437924) (xy 67.693816 -113.462381) (xy 67.68606 -113.516329)
			(xy 67.670705 -113.568624) (xy 67.648063 -113.618201) (xy 67.618597 -113.664051) (xy 67.582906 -113.705242)
			(xy 67.541715 -113.740933) (xy 67.495865 -113.770399) (xy 67.446288 -113.793041) (xy 67.393993 -113.808396)
			(xy 67.340045 -113.816152) (xy 67.285543 -113.816152) (xy 67.231595 -113.808396) (xy 67.1793 -113.793041)
			(xy 67.129723 -113.770399) (xy 67.083873 -113.740933) (xy 67.042682 -113.705242) (xy 67.006991 -113.664051)
			(xy 66.977525 -113.618201) (xy 66.954883 -113.568624) (xy 66.939528 -113.516329) (xy 66.931772 -113.462381)
			(xy 66.931286 -113.43513) (xy 66.93165 -113.411512) (xy 66.93751 -113.364639) (xy 66.94297 -113.341658)
			(xy 66.946079 -113.327146) (xy 66.944768 -113.297511) (xy 66.935001 -113.269501) (xy 66.917602 -113.245475)
			(xy 66.894037 -113.227458) (xy 66.86629 -113.216967) (xy 66.85153 -113.21542) (xy 66.823006 -113.212891)
			(xy 66.767129 -113.200377) (xy 66.713751 -113.179649) (xy 66.664072 -113.151173) (xy 66.619209 -113.11559)
			(xy 66.58017 -113.073699) (xy 66.547833 -113.026443) (xy 66.522924 -112.974883) (xy 66.506005 -112.920178)
			(xy 66.497454 -112.863559) (xy 66.496946 -112.834928) (xy 64.386553 -112.834928) (xy 64.385508 -112.835686)
			(xy 64.335668 -112.861661) (xy 64.282555 -112.880043) (xy 64.227321 -112.890434) (xy 64.199262 -112.892078)
			(xy 64.199008 -112.892078) (xy 64.187832 -112.892586) (xy 64.18453 -112.892586) (xy 64.155441 -112.892013)
			(xy 64.097942 -112.88314) (xy 64.042452 -112.865653) (xy 63.990253 -112.839959) (xy 63.96609 -112.823752)
			(xy 63.965582 -112.823498) (xy 63.962534 -112.821466) (xy 63.95593 -112.818164) (xy 63.949935 -112.815529)
			(xy 63.937074 -112.81309) (xy 63.93053 -112.813338) (xy 63.928498 -112.813592) (xy 63.917576 -112.815878)
			(xy 63.91275 -112.81791) (xy 63.912496 -112.81791) (xy 63.892938 -112.827308) (xy 63.89243 -112.827308)
			(xy 63.823596 -112.86109) (xy 63.823088 -112.861852) (xy 63.82258 -112.86236) (xy 63.815214 -112.870996)
			(xy 63.809118 -112.88014) (xy 63.806832 -112.884966) (xy 63.805054 -112.892586) (xy 63.8048 -112.893856)
			(xy 63.804038 -112.899444) (xy 63.78558 -113.251742) (xy 64.306194 -113.251742) (xy 64.310265 -113.19612)
			(xy 64.322391 -113.141683) (xy 64.342314 -113.089592) (xy 64.36961 -113.040957) (xy 64.403696 -112.996814)
			(xy 64.443845 -112.958105) (xy 64.489203 -112.925654) (xy 64.538803 -112.900153) (xy 64.591587 -112.882146)
			(xy 64.64643 -112.872016) (xy 64.702164 -112.869979) (xy 64.757601 -112.876079) (xy 64.811558 -112.890185)
			(xy 64.862887 -112.911997) (xy 64.910493 -112.941051) (xy 64.953361 -112.976726) (xy 64.990578 -113.018263)
			(xy 65.021351 -113.064776) (xy 65.045023 -113.115273) (xy 65.061091 -113.16868) (xy 65.069211 -113.223856)
			(xy 65.06972 -113.251742) (xy 65.069211 -113.279628) (xy 65.061091 -113.334804) (xy 65.045023 -113.388211)
			(xy 65.021351 -113.438708) (xy 64.990578 -113.485221) (xy 64.953361 -113.526758) (xy 64.910493 -113.562433)
			(xy 64.862887 -113.591487) (xy 64.811558 -113.613299) (xy 64.757601 -113.627405) (xy 64.702164 -113.633505)
			(xy 64.64643 -113.631468) (xy 64.591587 -113.621338) (xy 64.538803 -113.603331) (xy 64.489203 -113.57783)
			(xy 64.443845 -113.545379) (xy 64.403696 -113.50667) (xy 64.36961 -113.462527) (xy 64.342314 -113.413892)
			(xy 64.322391 -113.361801) (xy 64.310265 -113.307364) (xy 64.306194 -113.251742) (xy 63.78558 -113.251742)
			(xy 63.750952 -113.91265) (xy 63.750715 -113.917222) (xy 70.793862 -113.917222) (xy 70.797933 -113.8616)
			(xy 70.810059 -113.807163) (xy 70.829982 -113.755072) (xy 70.857278 -113.706437) (xy 70.891364 -113.662294)
			(xy 70.931513 -113.623585) (xy 70.976871 -113.591134) (xy 71.026471 -113.565633) (xy 71.079255 -113.547626)
			(xy 71.134098 -113.537496) (xy 71.189832 -113.535459) (xy 71.245269 -113.541559) (xy 71.299226 -113.555665)
			(xy 71.350555 -113.577477) (xy 71.398161 -113.606531) (xy 71.441029 -113.642206) (xy 71.478246 -113.683743)
			(xy 71.509019 -113.730256) (xy 71.532691 -113.780753) (xy 71.548759 -113.83416) (xy 71.556879 -113.889336)
			(xy 71.557388 -113.917222) (xy 71.556879 -113.945108) (xy 71.548759 -114.000284) (xy 71.532691 -114.053691)
			(xy 71.509019 -114.104188) (xy 71.478246 -114.150701) (xy 71.441029 -114.192238) (xy 71.398161 -114.227913)
			(xy 71.350555 -114.256967) (xy 71.299226 -114.278779) (xy 71.245269 -114.292885) (xy 71.189832 -114.298985)
			(xy 71.134098 -114.296948) (xy 71.079255 -114.286818) (xy 71.026471 -114.268811) (xy 70.976871 -114.24331)
			(xy 70.931513 -114.210859) (xy 70.891364 -114.17215) (xy 70.857278 -114.128007) (xy 70.829982 -114.079372)
			(xy 70.810059 -114.027281) (xy 70.797933 -113.972844) (xy 70.793862 -113.917222) (xy 63.750715 -113.917222)
			(xy 63.738506 -114.152426) (xy 63.716148 -114.581432) (xy 66.299586 -114.581432) (xy 66.303657 -114.52581)
			(xy 66.315783 -114.471373) (xy 66.335706 -114.419282) (xy 66.363002 -114.370647) (xy 66.397088 -114.326504)
			(xy 66.437237 -114.287795) (xy 66.482595 -114.255344) (xy 66.532195 -114.229843) (xy 66.584979 -114.211836)
			(xy 66.639822 -114.201706) (xy 66.695556 -114.199669) (xy 66.750993 -114.205769) (xy 66.80495 -114.219875)
			(xy 66.856279 -114.241687) (xy 66.903885 -114.270741) (xy 66.946753 -114.306416) (xy 66.98397 -114.347953)
			(xy 67.014743 -114.394466) (xy 67.038415 -114.444963) (xy 67.054483 -114.49837) (xy 67.062603 -114.553546)
			(xy 67.063112 -114.581432) (xy 67.062603 -114.609318) (xy 67.054483 -114.664494) (xy 67.038415 -114.717901)
			(xy 67.014743 -114.768398) (xy 66.98397 -114.814911) (xy 66.946753 -114.856448) (xy 66.903885 -114.892123)
			(xy 66.856279 -114.921177) (xy 66.80495 -114.942989) (xy 66.750993 -114.957095) (xy 66.695556 -114.963195)
			(xy 66.639822 -114.961158) (xy 66.584979 -114.951028) (xy 66.532195 -114.933021) (xy 66.482595 -114.90752)
			(xy 66.437237 -114.875069) (xy 66.397088 -114.83636) (xy 66.363002 -114.792217) (xy 66.335706 -114.743582)
			(xy 66.315783 -114.691491) (xy 66.303657 -114.637054) (xy 66.299586 -114.581432) (xy 63.716148 -114.581432)
			(xy 63.695326 -114.980974) (xy 63.679451 -115.285774) (xy 66.930776 -115.285774) (xy 66.934847 -115.230152)
			(xy 66.946973 -115.175715) (xy 66.966896 -115.123624) (xy 66.994192 -115.074989) (xy 67.028278 -115.030846)
			(xy 67.068427 -114.992137) (xy 67.113785 -114.959686) (xy 67.163385 -114.934185) (xy 67.216169 -114.916178)
			(xy 67.271012 -114.906048) (xy 67.326746 -114.904011) (xy 67.382183 -114.910111) (xy 67.43614 -114.924217)
			(xy 67.487469 -114.946029) (xy 67.535075 -114.975083) (xy 67.577943 -115.010758) (xy 67.61516 -115.052295)
			(xy 67.645933 -115.098808) (xy 67.669605 -115.149305) (xy 67.685673 -115.202712) (xy 67.693793 -115.257888)
			(xy 67.694302 -115.285774) (xy 67.693793 -115.31366) (xy 67.686832 -115.360958) (xy 74.11847 -115.360958)
			(xy 74.118953 -115.333588) (xy 74.126764 -115.279409) (xy 74.142248 -115.226906) (xy 74.165087 -115.177158)
			(xy 74.194809 -115.131191) (xy 74.21245 -115.11026) (xy 74.212704 -115.110006) (xy 74.218295 -115.102922)
			(xy 74.224539 -115.086003) (xy 74.224896 -115.076986) (xy 74.224896 -115.00993) (xy 74.224526 -115.000914)
			(xy 74.218288 -114.983997) (xy 74.212704 -114.97691) (xy 74.21245 -114.97691) (xy 74.21245 -114.976656)
			(xy 74.194831 -114.955707) (xy 74.165115 -114.90974) (xy 74.142274 -114.859997) (xy 74.126778 -114.807499)
			(xy 74.118946 -114.753326) (xy 74.11847 -114.725958) (xy 74.118939 -114.698707) (xy 74.1267 -114.64476)
			(xy 74.14206 -114.592466) (xy 74.164704 -114.54289) (xy 74.194173 -114.497041) (xy 74.229866 -114.455852)
			(xy 74.271057 -114.420161) (xy 74.316907 -114.390694) (xy 74.366485 -114.368053) (xy 74.418779 -114.352696)
			(xy 74.472727 -114.344937) (xy 74.499978 -114.34445) (xy 74.527348 -114.344917) (xy 74.581528 -114.352733)
			(xy 74.634031 -114.368221) (xy 74.683778 -114.391063) (xy 74.729745 -114.420788) (xy 74.750676 -114.43843)
			(xy 74.75093 -114.438684) (xy 74.758034 -114.444246) (xy 74.774937 -114.450508) (xy 74.78395 -114.450876)
			(xy 74.851006 -114.450876) (xy 74.860024 -114.450527) (xy 74.876941 -114.444275) (xy 74.884026 -114.438684)
			(xy 74.884026 -114.43843) (xy 74.88428 -114.43843) (xy 74.905213 -114.420791) (xy 74.951185 -114.391079)
			(xy 75.000932 -114.368242) (xy 75.053433 -114.352751) (xy 75.107609 -114.344923) (xy 75.134978 -114.34445)
			(xy 75.162227 -114.344999) (xy 75.21617 -114.352751) (xy 75.268461 -114.368101) (xy 75.318035 -114.390737)
			(xy 75.363884 -114.420197) (xy 75.405073 -114.455882) (xy 75.440765 -114.497065) (xy 75.470233 -114.542909)
			(xy 75.492876 -114.592479) (xy 75.508235 -114.644767) (xy 75.515997 -114.698709) (xy 75.516486 -114.725958)
			(xy 75.515999 -114.753328) (xy 75.508187 -114.807506) (xy 75.492703 -114.860009) (xy 75.469866 -114.909756)
			(xy 75.440145 -114.955724) (xy 75.422506 -114.976656) (xy 75.422252 -114.97691) (xy 75.416649 -114.983985)
			(xy 75.410413 -115.000911) (xy 75.41006 -115.00993) (xy 75.41006 -115.076986) (xy 75.410411 -115.086004)
			(xy 75.416661 -115.102921) (xy 75.422252 -115.110006) (xy 75.422506 -115.110006) (xy 75.422506 -115.11026)
			(xy 75.440141 -115.131196) (xy 75.469853 -115.177167) (xy 75.49269 -115.226914) (xy 75.508182 -115.279414)
			(xy 75.516011 -115.333589) (xy 75.516486 -115.360958) (xy 75.516006 -115.388211) (xy 75.508254 -115.442162)
			(xy 75.492902 -115.494461) (xy 75.470263 -115.544043) (xy 75.440797 -115.589897) (xy 75.405105 -115.631091)
			(xy 75.363913 -115.666785) (xy 75.31806 -115.696253) (xy 75.26848 -115.718895) (xy 75.216182 -115.734249)
			(xy 75.162231 -115.742004) (xy 75.134978 -115.742466) (xy 75.107607 -115.742021) (xy 75.053427 -115.734199)
			(xy 75.000923 -115.718706) (xy 74.951176 -115.695859) (xy 74.905211 -115.66613) (xy 74.88428 -115.648486)
			(xy 74.884026 -115.648232) (xy 74.876942 -115.642642) (xy 74.860023 -115.636399) (xy 74.851006 -115.63604)
			(xy 74.78395 -115.63604) (xy 74.774934 -115.636412) (xy 74.758017 -115.642648) (xy 74.75093 -115.648232)
			(xy 74.75093 -115.648486) (xy 74.750676 -115.648486) (xy 74.729724 -115.666101) (xy 74.683757 -115.695817)
			(xy 74.634015 -115.718658) (xy 74.581518 -115.734154) (xy 74.527346 -115.741989) (xy 74.499978 -115.742466)
			(xy 74.472723 -115.742065) (xy 74.418767 -115.734304) (xy 74.366466 -115.718943) (xy 74.316883 -115.696295)
			(xy 74.271027 -115.666821) (xy 74.229834 -115.631121) (xy 74.194141 -115.589921) (xy 74.164674 -115.544061)
			(xy 74.142034 -115.494474) (xy 74.126682 -115.44217) (xy 74.11893 -115.388213) (xy 74.11847 -115.360958)
			(xy 67.686832 -115.360958) (xy 67.685673 -115.368836) (xy 67.669605 -115.422243) (xy 67.645933 -115.47274)
			(xy 67.61516 -115.519253) (xy 67.577943 -115.56079) (xy 67.535075 -115.596465) (xy 67.487469 -115.625519)
			(xy 67.43614 -115.647331) (xy 67.382183 -115.661437) (xy 67.326746 -115.667537) (xy 67.271012 -115.6655)
			(xy 67.216169 -115.65537) (xy 67.163385 -115.637363) (xy 67.113785 -115.611862) (xy 67.068427 -115.579411)
			(xy 67.028278 -115.540702) (xy 66.994192 -115.496559) (xy 66.966896 -115.447924) (xy 66.946973 -115.395833)
			(xy 66.934847 -115.341396) (xy 66.930776 -115.285774) (xy 63.679451 -115.285774) (xy 63.666116 -115.541806)
			(xy 63.672212 -115.544346) (xy 63.67272 -115.548918) (xy 63.703708 -115.559332) (xy 63.703962 -115.559332)
			(xy 63.7291 -115.568058) (xy 63.776873 -115.591495) (xy 63.820929 -115.621337) (xy 63.860416 -115.657007)
			(xy 63.894567 -115.697813) (xy 63.922722 -115.742966) (xy 63.944336 -115.79159) (xy 63.958989 -115.842745)
			(xy 63.966399 -115.895438) (xy 63.966852 -115.922044) (xy 63.966352 -115.949876) (xy 63.958273 -116.004951)
			(xy 63.94228 -116.058269) (xy 63.918711 -116.108697) (xy 63.888066 -116.155167) (xy 63.850996 -116.196692)
			(xy 63.829946 -116.214906) (xy 63.822072 -116.221256) (xy 63.821818 -116.22151) (xy 63.818516 -116.224304)
			(xy 63.816992 -116.22532) (xy 63.815722 -116.226336) (xy 63.806578 -116.232686) (xy 63.805562 -116.233194)
			(xy 63.773558 -116.253768) (xy 63.757582 -116.262651) (xy 63.724252 -116.277668) (xy 63.70701 -116.28374)
			(xy 63.706502 -116.28374) (xy 63.699644 -116.286026) (xy 63.6651 -116.29517) (xy 63.664592 -116.29517)
			(xy 63.664338 -116.295424) (xy 63.656301 -116.297438) (xy 63.642055 -116.305878) (xy 63.636398 -116.311934)
			(xy 63.631064 -116.318284) (xy 63.628016 -116.32565) (xy 63.626659 -116.329139) (xy 63.624869 -116.336407)
			(xy 63.62446 -116.340128) (xy 63.618885 -116.44757) (xy 66.157092 -116.44757) (xy 66.161163 -116.391948)
			(xy 66.173289 -116.337511) (xy 66.193212 -116.28542) (xy 66.220508 -116.236785) (xy 66.254594 -116.192642)
			(xy 66.294743 -116.153933) (xy 66.340101 -116.121482) (xy 66.389701 -116.095981) (xy 66.442485 -116.077974)
			(xy 66.497328 -116.067844) (xy 66.553062 -116.065807) (xy 66.608499 -116.071907) (xy 66.662456 -116.086013)
			(xy 66.713785 -116.107825) (xy 66.761391 -116.136879) (xy 66.804259 -116.172554) (xy 66.841476 -116.214091)
			(xy 66.872249 -116.260604) (xy 66.895921 -116.311101) (xy 66.911989 -116.364508) (xy 66.920109 -116.419684)
			(xy 66.920618 -116.44757) (xy 66.920109 -116.475456) (xy 66.919839 -116.477288) (xy 71.304402 -116.477288)
			(xy 71.308473 -116.421666) (xy 71.320599 -116.367229) (xy 71.340522 -116.315138) (xy 71.367818 -116.266503)
			(xy 71.401904 -116.22236) (xy 71.442053 -116.183651) (xy 71.487411 -116.1512) (xy 71.537011 -116.125699)
			(xy 71.589795 -116.107692) (xy 71.644638 -116.097562) (xy 71.700372 -116.095525) (xy 71.755809 -116.101625)
			(xy 71.809766 -116.115731) (xy 71.861095 -116.137543) (xy 71.908701 -116.166597) (xy 71.951569 -116.202272)
			(xy 71.988786 -116.243809) (xy 72.019559 -116.290322) (xy 72.043231 -116.340819) (xy 72.059299 -116.394226)
			(xy 72.067419 -116.449402) (xy 72.067928 -116.477288) (xy 72.067419 -116.505174) (xy 72.059299 -116.56035)
			(xy 72.043231 -116.613757) (xy 72.019559 -116.664254) (xy 71.988786 -116.710767) (xy 71.951569 -116.752304)
			(xy 71.908701 -116.787979) (xy 71.861095 -116.817033) (xy 71.809766 -116.838845) (xy 71.755809 -116.852951)
			(xy 71.700372 -116.859051) (xy 71.644638 -116.857014) (xy 71.589795 -116.846884) (xy 71.537011 -116.828877)
			(xy 71.487411 -116.803376) (xy 71.442053 -116.770925) (xy 71.401904 -116.732216) (xy 71.367818 -116.688073)
			(xy 71.340522 -116.639438) (xy 71.320599 -116.587347) (xy 71.308473 -116.53291) (xy 71.304402 -116.477288)
			(xy 66.919839 -116.477288) (xy 66.911989 -116.530632) (xy 66.895921 -116.584039) (xy 66.872249 -116.634536)
			(xy 66.841476 -116.681049) (xy 66.804259 -116.722586) (xy 66.761391 -116.758261) (xy 66.713785 -116.787315)
			(xy 66.662456 -116.809127) (xy 66.608499 -116.823233) (xy 66.553062 -116.829333) (xy 66.497328 -116.827296)
			(xy 66.442485 -116.817166) (xy 66.389701 -116.799159) (xy 66.340101 -116.773658) (xy 66.294743 -116.741207)
			(xy 66.254594 -116.702498) (xy 66.220508 -116.658355) (xy 66.193212 -116.60972) (xy 66.173289 -116.557629)
			(xy 66.161163 -116.503192) (xy 66.157092 -116.44757) (xy 63.618885 -116.44757) (xy 63.552667 -117.723666)
			(xy 69.689724 -117.723666) (xy 69.693795 -117.668044) (xy 69.705921 -117.613607) (xy 69.725844 -117.561516)
			(xy 69.75314 -117.512881) (xy 69.787226 -117.468738) (xy 69.827375 -117.430029) (xy 69.872733 -117.397578)
			(xy 69.922333 -117.372077) (xy 69.975117 -117.35407) (xy 70.02996 -117.34394) (xy 70.085694 -117.341903)
			(xy 70.141131 -117.348003) (xy 70.195088 -117.362109) (xy 70.246417 -117.383921) (xy 70.294023 -117.412975)
			(xy 70.336891 -117.44865) (xy 70.374108 -117.490187) (xy 70.404881 -117.5367) (xy 70.428553 -117.587197)
			(xy 70.444621 -117.640604) (xy 70.452741 -117.69578) (xy 70.45325 -117.723666) (xy 70.452741 -117.751552)
			(xy 70.451686 -117.758718) (xy 74.474832 -117.758718) (xy 74.474832 -116.895118) (xy 74.475322 -116.865134)
			(xy 74.48315 -116.805678) (xy 74.498671 -116.747753) (xy 74.52162 -116.692349) (xy 74.551604 -116.640415)
			(xy 74.58811 -116.592839) (xy 74.630515 -116.550434) (xy 74.678091 -116.513928) (xy 74.730025 -116.483944)
			(xy 74.785429 -116.460995) (xy 74.843354 -116.445474) (xy 74.90281 -116.437646) (xy 74.962778 -116.437646)
			(xy 75.022234 -116.445474) (xy 75.080159 -116.460995) (xy 75.135563 -116.483944) (xy 75.187497 -116.513928)
			(xy 75.235073 -116.550434) (xy 75.277478 -116.592839) (xy 75.313984 -116.640415) (xy 75.343968 -116.692349)
			(xy 75.366917 -116.747753) (xy 75.382438 -116.805678) (xy 75.390266 -116.865134) (xy 75.390756 -116.895118)
			(xy 75.390756 -117.758718) (xy 75.390266 -117.788702) (xy 75.382438 -117.848158) (xy 75.366917 -117.906083)
			(xy 75.343968 -117.961487) (xy 75.313984 -118.013421) (xy 75.277478 -118.060997) (xy 75.235073 -118.103402)
			(xy 75.187497 -118.139908) (xy 75.135563 -118.169892) (xy 75.080159 -118.192841) (xy 75.022234 -118.208362)
			(xy 74.962778 -118.21619) (xy 74.90281 -118.21619) (xy 74.843354 -118.208362) (xy 74.785429 -118.192841)
			(xy 74.730025 -118.169892) (xy 74.678091 -118.139908) (xy 74.630515 -118.103402) (xy 74.58811 -118.060997)
			(xy 74.551604 -118.013421) (xy 74.52162 -117.961487) (xy 74.498671 -117.906083) (xy 74.48315 -117.848158)
			(xy 74.475322 -117.788702) (xy 74.474832 -117.758718) (xy 70.451686 -117.758718) (xy 70.444621 -117.806728)
			(xy 70.428553 -117.860135) (xy 70.404881 -117.910632) (xy 70.374108 -117.957145) (xy 70.336891 -117.998682)
			(xy 70.294023 -118.034357) (xy 70.246417 -118.063411) (xy 70.195088 -118.085223) (xy 70.141131 -118.099329)
			(xy 70.085694 -118.105429) (xy 70.02996 -118.103392) (xy 69.975117 -118.093262) (xy 69.922333 -118.075255)
			(xy 69.872733 -118.049754) (xy 69.827375 -118.017303) (xy 69.787226 -117.978594) (xy 69.75314 -117.934451)
			(xy 69.725844 -117.885816) (xy 69.705921 -117.833725) (xy 69.693795 -117.779288) (xy 69.689724 -117.723666)
			(xy 63.552667 -117.723666) (xy 63.537338 -118.019068) (xy 63.536576 -118.030752) (xy 63.551054 -118.06555)
			(xy 63.557404 -118.072154) (xy 63.567239 -118.082964) (xy 63.585421 -118.105849) (xy 63.593726 -118.117874)
			(xy 63.595504 -118.120922) (xy 63.614554 -118.152672) (xy 63.614554 -118.152926) (xy 63.627508 -118.179342)
			(xy 63.629032 -118.183152) (xy 63.629286 -118.183406) (xy 63.630048 -118.185438) (xy 63.631572 -118.18874)
			(xy 63.641732 -118.198646) (xy 63.64859 -118.20652) (xy 63.650368 -118.209314) (xy 63.654468 -118.215769)
			(xy 63.65898 -118.230373) (xy 63.659258 -118.238016) (xy 63.659258 -118.332504) (xy 63.658756 -118.360014)
			(xy 63.650819 -118.414459) (xy 63.635151 -118.467201) (xy 63.612078 -118.51715) (xy 63.582076 -118.563272)
			(xy 63.545768 -118.604611) (xy 63.525146 -118.622826) (xy 63.523622 -118.624096) (xy 63.523368 -118.62435)
			(xy 63.522352 -118.625112) (xy 63.518542 -118.628414) (xy 63.513716 -118.632478) (xy 63.509144 -118.641368)
			(xy 63.507164 -118.645579) (xy 63.504602 -118.654526) (xy 63.504064 -118.659148) (xy 63.497206 -118.788942)
			(xy 63.490094 -118.925594) (xy 63.481712 -119.086376) (xy 63.456695 -119.567198) (xy 66.599308 -119.567198)
			(xy 66.599308 -118.703598) (xy 66.599798 -118.673614) (xy 66.607626 -118.614158) (xy 66.623147 -118.556233)
			(xy 66.646096 -118.500829) (xy 66.67608 -118.448895) (xy 66.712586 -118.401319) (xy 66.754991 -118.358914)
			(xy 66.802567 -118.322408) (xy 66.854501 -118.292424) (xy 66.909905 -118.269475) (xy 66.96783 -118.253954)
			(xy 67.027286 -118.246126) (xy 67.087254 -118.246126) (xy 67.14671 -118.253954) (xy 67.204635 -118.269475)
			(xy 67.260039 -118.292424) (xy 67.311973 -118.322408) (xy 67.359549 -118.358914) (xy 67.401954 -118.401319)
			(xy 67.43846 -118.448895) (xy 67.468444 -118.500829) (xy 67.491393 -118.556233) (xy 67.506914 -118.614158)
			(xy 67.514742 -118.673614) (xy 67.515232 -118.703598) (xy 67.515232 -118.711218) (xy 69.809358 -118.711218)
			(xy 69.813429 -118.655596) (xy 69.825555 -118.601159) (xy 69.845478 -118.549068) (xy 69.872774 -118.500433)
			(xy 69.90686 -118.45629) (xy 69.947009 -118.417581) (xy 69.992367 -118.38513) (xy 70.041967 -118.359629)
			(xy 70.094751 -118.341622) (xy 70.149594 -118.331492) (xy 70.205328 -118.329455) (xy 70.260765 -118.335555)
			(xy 70.314722 -118.349661) (xy 70.366051 -118.371473) (xy 70.413657 -118.400527) (xy 70.456525 -118.436202)
			(xy 70.493742 -118.477739) (xy 70.524515 -118.524252) (xy 70.548187 -118.574749) (xy 70.564255 -118.628156)
			(xy 70.572375 -118.683332) (xy 70.572884 -118.711218) (xy 70.572375 -118.739104) (xy 70.564255 -118.79428)
			(xy 70.548187 -118.847687) (xy 70.524515 -118.898184) (xy 70.493742 -118.944697) (xy 70.456525 -118.986234)
			(xy 70.413657 -119.021909) (xy 70.366051 -119.050963) (xy 70.314722 -119.072775) (xy 70.260765 -119.086881)
			(xy 70.205328 -119.092981) (xy 70.149594 -119.090944) (xy 70.094751 -119.080814) (xy 70.041967 -119.062807)
			(xy 69.992367 -119.037306) (xy 69.947009 -119.004855) (xy 69.90686 -118.966146) (xy 69.872774 -118.922003)
			(xy 69.845478 -118.873368) (xy 69.825555 -118.821277) (xy 69.813429 -118.76684) (xy 69.809358 -118.711218)
			(xy 67.515232 -118.711218) (xy 67.515232 -119.567198) (xy 67.514742 -119.597182) (xy 67.506914 -119.656638)
			(xy 67.491393 -119.714563) (xy 67.468444 -119.769967) (xy 67.43846 -119.821901) (xy 67.401954 -119.869477)
			(xy 67.359549 -119.911882) (xy 67.311973 -119.948388) (xy 67.260039 -119.978372) (xy 67.204635 -120.001321)
			(xy 67.14671 -120.016842) (xy 67.087254 -120.02467) (xy 67.027286 -120.02467) (xy 66.96783 -120.016842)
			(xy 66.909905 -120.001321) (xy 66.854501 -119.978372) (xy 66.802567 -119.948388) (xy 66.754991 -119.911882)
			(xy 66.712586 -119.869477) (xy 66.67608 -119.821901) (xy 66.646096 -119.769967) (xy 66.623147 -119.714563)
			(xy 66.607626 -119.656638) (xy 66.599798 -119.597182) (xy 66.599308 -119.567198) (xy 63.456695 -119.567198)
			(xy 63.363856 -121.351548) (xy 63.363036 -121.367296) (xy 64.745108 -121.367296) (xy 64.745108 -120.503696)
			(xy 64.745598 -120.473712) (xy 64.753426 -120.414256) (xy 64.768947 -120.356331) (xy 64.791896 -120.300927)
			(xy 64.82188 -120.248993) (xy 64.858386 -120.201417) (xy 64.900791 -120.159012) (xy 64.948367 -120.122506)
			(xy 65.000301 -120.092522) (xy 65.055705 -120.069573) (xy 65.11363 -120.054052) (xy 65.173086 -120.046224)
			(xy 65.233054 -120.046224) (xy 65.29251 -120.054052) (xy 65.350435 -120.069573) (xy 65.405839 -120.092522)
			(xy 65.457773 -120.122506) (xy 65.505349 -120.159012) (xy 65.547754 -120.201417) (xy 65.58426 -120.248993)
			(xy 65.614244 -120.300927) (xy 65.637193 -120.356331) (xy 65.652714 -120.414256) (xy 65.660542 -120.473712)
			(xy 65.661032 -120.503696) (xy 65.661032 -121.367296) (xy 65.660542 -121.39728) (xy 65.652714 -121.456736)
			(xy 65.637193 -121.514661) (xy 65.614244 -121.570065) (xy 65.58426 -121.621999) (xy 65.547754 -121.669575)
			(xy 65.505349 -121.71198) (xy 65.457773 -121.748486) (xy 65.405839 -121.77847) (xy 65.350435 -121.801419)
			(xy 65.29251 -121.81694) (xy 65.233054 -121.824768) (xy 65.173086 -121.824768) (xy 65.11363 -121.81694)
			(xy 65.055705 -121.801419) (xy 65.000301 -121.77847) (xy 64.948367 -121.748486) (xy 64.900791 -121.71198)
			(xy 64.858386 -121.669575) (xy 64.82188 -121.621999) (xy 64.791896 -121.570065) (xy 64.768947 -121.514661)
			(xy 64.753426 -121.456736) (xy 64.745598 -121.39728) (xy 64.745108 -121.367296) (xy 63.363036 -121.367296)
			(xy 63.297816 -122.61977) (xy 63.269229 -123.16714) (xy 66.599308 -123.16714) (xy 66.599308 -122.30354)
			(xy 66.599798 -122.273556) (xy 66.607626 -122.2141) (xy 66.623147 -122.156175) (xy 66.646096 -122.100771)
			(xy 66.67608 -122.048837) (xy 66.712586 -122.001261) (xy 66.754991 -121.958856) (xy 66.802567 -121.92235)
			(xy 66.854501 -121.892366) (xy 66.909905 -121.869417) (xy 66.96783 -121.853896) (xy 67.027286 -121.846068)
			(xy 67.087254 -121.846068) (xy 67.14671 -121.853896) (xy 67.204635 -121.869417) (xy 67.260039 -121.892366)
			(xy 67.311973 -121.92235) (xy 67.359549 -121.958856) (xy 67.401954 -122.001261) (xy 67.43846 -122.048837)
			(xy 67.468444 -122.100771) (xy 67.491393 -122.156175) (xy 67.506914 -122.2141) (xy 67.514742 -122.273556)
			(xy 67.515232 -122.30354) (xy 67.515232 -123.16714) (xy 67.514742 -123.197124) (xy 67.506914 -123.25658)
			(xy 67.491393 -123.314505) (xy 67.468444 -123.369909) (xy 67.43846 -123.421843) (xy 67.401954 -123.469419)
			(xy 67.359549 -123.511824) (xy 67.311973 -123.54833) (xy 67.260039 -123.578314) (xy 67.204635 -123.601263)
			(xy 67.14671 -123.616784) (xy 67.087254 -123.624612) (xy 67.027286 -123.624612) (xy 66.96783 -123.616784)
			(xy 66.909905 -123.601263) (xy 66.854501 -123.578314) (xy 66.802567 -123.54833) (xy 66.754991 -123.511824)
			(xy 66.712586 -123.469419) (xy 66.67608 -123.421843) (xy 66.646096 -123.369909) (xy 66.623147 -123.314505)
			(xy 66.607626 -123.25658) (xy 66.599798 -123.197124) (xy 66.599308 -123.16714) (xy 63.269229 -123.16714)
			(xy 63.258192 -123.378468) (xy 63.175498 -124.967238) (xy 64.745108 -124.967238) (xy 64.745108 -124.103638)
			(xy 64.745598 -124.073654) (xy 64.753426 -124.014198) (xy 64.768947 -123.956273) (xy 64.791896 -123.900869)
			(xy 64.82188 -123.848935) (xy 64.858386 -123.801359) (xy 64.900791 -123.758954) (xy 64.948367 -123.722448)
			(xy 65.000301 -123.692464) (xy 65.055705 -123.669515) (xy 65.11363 -123.653994) (xy 65.173086 -123.646166)
			(xy 65.233054 -123.646166) (xy 65.29251 -123.653994) (xy 65.350435 -123.669515) (xy 65.405839 -123.692464)
			(xy 65.457773 -123.722448) (xy 65.505349 -123.758954) (xy 65.547754 -123.801359) (xy 65.58426 -123.848935)
			(xy 65.614244 -123.900869) (xy 65.637193 -123.956273) (xy 65.652714 -124.014198) (xy 65.660542 -124.073654)
			(xy 65.661032 -124.103638) (xy 65.661032 -124.967238) (xy 65.660542 -124.997222) (xy 65.652714 -125.056678)
			(xy 65.637193 -125.114603) (xy 65.614244 -125.170007) (xy 65.58426 -125.221941) (xy 65.547754 -125.269517)
			(xy 65.505349 -125.311922) (xy 65.457773 -125.348428) (xy 65.405839 -125.378412) (xy 65.350435 -125.401361)
			(xy 65.29251 -125.416882) (xy 65.233054 -125.42471) (xy 65.173086 -125.42471) (xy 65.11363 -125.416882)
			(xy 65.055705 -125.401361) (xy 65.000301 -125.378412) (xy 64.948367 -125.348428) (xy 64.900791 -125.311922)
			(xy 64.858386 -125.269517) (xy 64.82188 -125.221941) (xy 64.791896 -125.170007) (xy 64.768947 -125.114603)
			(xy 64.753426 -125.056678) (xy 64.745598 -124.997222) (xy 64.745108 -124.967238) (xy 63.175498 -124.967238)
			(xy 62.873092 -130.777234) (xy 66.599308 -130.777234) (xy 66.599308 -129.913634) (xy 66.599798 -129.88365)
			(xy 66.607626 -129.824194) (xy 66.623147 -129.766269) (xy 66.646096 -129.710865) (xy 66.67608 -129.658931)
			(xy 66.712586 -129.611355) (xy 66.754991 -129.56895) (xy 66.802567 -129.532444) (xy 66.854501 -129.50246)
			(xy 66.909905 -129.479511) (xy 66.96783 -129.46399) (xy 67.027286 -129.456162) (xy 67.087254 -129.456162)
			(xy 67.14671 -129.46399) (xy 67.204635 -129.479511) (xy 67.260039 -129.50246) (xy 67.311973 -129.532444)
			(xy 67.359549 -129.56895) (xy 67.401954 -129.611355) (xy 67.43846 -129.658931) (xy 67.468444 -129.710865)
			(xy 67.491393 -129.766269) (xy 67.506914 -129.824194) (xy 67.514742 -129.88365) (xy 67.515232 -129.913634)
			(xy 67.515232 -130.777234) (xy 67.514742 -130.807218) (xy 67.506914 -130.866674) (xy 67.491393 -130.924599)
			(xy 67.468444 -130.980003) (xy 67.43846 -131.031937) (xy 67.401954 -131.079513) (xy 67.359549 -131.121918)
			(xy 67.311973 -131.158424) (xy 67.260039 -131.188408) (xy 67.204635 -131.211357) (xy 67.14671 -131.226878)
			(xy 67.087254 -131.234706) (xy 67.027286 -131.234706) (xy 66.96783 -131.226878) (xy 66.909905 -131.211357)
			(xy 66.854501 -131.188408) (xy 66.802567 -131.158424) (xy 66.754991 -131.121918) (xy 66.712586 -131.079513)
			(xy 66.67608 -131.031937) (xy 66.646096 -130.980003) (xy 66.623147 -130.924599) (xy 66.607626 -130.866674)
			(xy 66.599798 -130.807218) (xy 66.599308 -130.777234) (xy 62.873092 -130.777234) (xy 62.779398 -132.577332)
			(xy 64.745108 -132.577332) (xy 64.745108 -131.713732) (xy 64.745598 -131.683748) (xy 64.753426 -131.624292)
			(xy 64.768947 -131.566367) (xy 64.791896 -131.510963) (xy 64.82188 -131.459029) (xy 64.858386 -131.411453)
			(xy 64.900791 -131.369048) (xy 64.948367 -131.332542) (xy 65.000301 -131.302558) (xy 65.055705 -131.279609)
			(xy 65.11363 -131.264088) (xy 65.173086 -131.25626) (xy 65.233054 -131.25626) (xy 65.29251 -131.264088)
			(xy 65.350435 -131.279609) (xy 65.405839 -131.302558) (xy 65.457773 -131.332542) (xy 65.505349 -131.369048)
			(xy 65.547754 -131.411453) (xy 65.58426 -131.459029) (xy 65.614244 -131.510963) (xy 65.637193 -131.566367)
			(xy 65.652714 -131.624292) (xy 65.660542 -131.683748) (xy 65.661032 -131.713732) (xy 65.661032 -132.577332)
			(xy 65.660542 -132.607316) (xy 65.652714 -132.666772) (xy 65.637193 -132.724697) (xy 65.614244 -132.780101)
			(xy 65.58426 -132.832035) (xy 65.547754 -132.879611) (xy 65.505349 -132.922016) (xy 65.457773 -132.958522)
			(xy 65.405839 -132.988506) (xy 65.350435 -133.011455) (xy 65.29251 -133.026976) (xy 65.233054 -133.034804)
			(xy 65.173086 -133.034804) (xy 65.11363 -133.026976) (xy 65.055705 -133.011455) (xy 65.000301 -132.988506)
			(xy 64.948367 -132.958522) (xy 64.900791 -132.922016) (xy 64.858386 -132.879611) (xy 64.82188 -132.832035)
			(xy 64.791896 -132.780101) (xy 64.768947 -132.724697) (xy 64.753426 -132.666772) (xy 64.745598 -132.607316)
			(xy 64.745108 -132.577332) (xy 62.779398 -132.577332) (xy 62.685718 -134.377176) (xy 66.599308 -134.377176)
			(xy 66.599308 -133.513576) (xy 66.599798 -133.483592) (xy 66.607626 -133.424136) (xy 66.623147 -133.366211)
			(xy 66.646096 -133.310807) (xy 66.67608 -133.258873) (xy 66.712586 -133.211297) (xy 66.754991 -133.168892)
			(xy 66.802567 -133.132386) (xy 66.854501 -133.102402) (xy 66.909905 -133.079453) (xy 66.96783 -133.063932)
			(xy 67.027286 -133.056104) (xy 67.087254 -133.056104) (xy 67.14671 -133.063932) (xy 67.204635 -133.079453)
			(xy 67.260039 -133.102402) (xy 67.311973 -133.132386) (xy 67.359549 -133.168892) (xy 67.401954 -133.211297)
			(xy 67.43846 -133.258873) (xy 67.468444 -133.310807) (xy 67.491393 -133.366211) (xy 67.506914 -133.424136)
			(xy 67.514742 -133.483592) (xy 67.515232 -133.513576) (xy 67.515232 -134.377176) (xy 67.514742 -134.40716)
			(xy 67.506914 -134.466616) (xy 67.491393 -134.524541) (xy 67.468444 -134.579945) (xy 67.43846 -134.631879)
			(xy 67.401954 -134.679455) (xy 67.359549 -134.72186) (xy 67.311973 -134.758366) (xy 67.260039 -134.78835)
			(xy 67.204635 -134.811299) (xy 67.14671 -134.82682) (xy 67.087254 -134.834648) (xy 67.027286 -134.834648)
			(xy 66.96783 -134.82682) (xy 66.909905 -134.811299) (xy 66.854501 -134.78835) (xy 66.802567 -134.758366)
			(xy 66.754991 -134.72186) (xy 66.712586 -134.679455) (xy 66.67608 -134.631879) (xy 66.646096 -134.579945)
			(xy 66.623147 -134.524541) (xy 66.607626 -134.466616) (xy 66.599798 -134.40716) (xy 66.599308 -134.377176)
			(xy 62.685718 -134.377176) (xy 62.592024 -136.177274) (xy 64.745108 -136.177274) (xy 64.745108 -135.313674)
			(xy 64.745598 -135.28369) (xy 64.753426 -135.224234) (xy 64.768947 -135.166309) (xy 64.791896 -135.110905)
			(xy 64.82188 -135.058971) (xy 64.858386 -135.011395) (xy 64.900791 -134.96899) (xy 64.948367 -134.932484)
			(xy 65.000301 -134.9025) (xy 65.055705 -134.879551) (xy 65.11363 -134.86403) (xy 65.173086 -134.856202)
			(xy 65.233054 -134.856202) (xy 65.29251 -134.86403) (xy 65.350435 -134.879551) (xy 65.405839 -134.9025)
			(xy 65.457773 -134.932484) (xy 65.505349 -134.96899) (xy 65.547754 -135.011395) (xy 65.58426 -135.058971)
			(xy 65.614244 -135.110905) (xy 65.637193 -135.166309) (xy 65.652714 -135.224234) (xy 65.660542 -135.28369)
			(xy 65.661032 -135.313674) (xy 65.661032 -136.177274) (xy 65.660542 -136.207258) (xy 65.652714 -136.266714)
			(xy 65.637193 -136.324639) (xy 65.614244 -136.380043) (xy 65.58426 -136.431977) (xy 65.547754 -136.479553)
			(xy 65.505349 -136.521958) (xy 65.457773 -136.558464) (xy 65.405839 -136.588448) (xy 65.350435 -136.611397)
			(xy 65.29251 -136.626918) (xy 65.233054 -136.634746) (xy 65.173086 -136.634746) (xy 65.11363 -136.626918)
			(xy 65.055705 -136.611397) (xy 65.000301 -136.588448) (xy 64.948367 -136.558464) (xy 64.900791 -136.521958)
			(xy 64.858386 -136.479553) (xy 64.82188 -136.431977) (xy 64.791896 -136.380043) (xy 64.768947 -136.324639)
			(xy 64.753426 -136.266714) (xy 64.745598 -136.207258) (xy 64.745108 -136.177274) (xy 62.592024 -136.177274)
			(xy 62.591442 -136.18845) (xy 62.560962 -136.776968) (xy 62.537594 -137.225786) (xy 62.525148 -137.465562)
			(xy 62.524386 -137.48004) (xy 62.524132 -137.483088) (xy 62.524132 -137.489946) (xy 62.524589 -137.495034)
			(xy 62.527279 -137.504887) (xy 62.529466 -137.509504) (xy 62.538102 -137.526268) (xy 62.539975 -137.529664)
			(xy 62.544564 -137.535913) (xy 62.547246 -137.538714) (xy 62.55258 -137.544048) (xy 62.575054 -137.561757)
			(xy 62.614949 -137.602771) (xy 62.648282 -137.649275) (xy 62.674307 -137.700231) (xy 62.692442 -137.754497)
			(xy 62.702283 -137.810861) (xy 62.703456 -137.83945) (xy 62.703456 -137.84834) (xy 62.702997 -137.877017)
			(xy 62.694529 -137.933739) (xy 62.677669 -137.988556) (xy 62.652797 -138.040233) (xy 62.620472 -138.087607)
			(xy 62.581423 -138.129611) (xy 62.536529 -138.1653) (xy 62.51194 -138.180064) (xy 62.511432 -138.180318)
			(xy 62.50559 -138.183874) (xy 62.49797 -138.190986) (xy 62.495684 -138.194288) (xy 62.492636 -138.199368)
			(xy 62.490068 -138.204104) (xy 62.486735 -138.214347) (xy 62.486032 -138.219688) (xy 62.481206 -138.310112)
			(xy 62.477142 -138.38682) (xy 62.472316 -138.478768) (xy 62.472316 -138.481054) (xy 62.472529 -138.487865)
			(xy 62.476127 -138.501001) (xy 62.479428 -138.506962) (xy 62.483492 -138.51382) (xy 62.493398 -138.523218)
			(xy 62.499748 -138.526774) (xy 62.500256 -138.527028) (xy 62.526194 -138.541351) (xy 62.573692 -138.576767)
			(xy 62.615154 -138.619091) (xy 62.649585 -138.667309) (xy 62.67616 -138.720264) (xy 62.694242 -138.776686)
			(xy 62.703396 -138.835224) (xy 62.703964 -138.864848) (xy 62.703466 -138.89288) (xy 62.695255 -138.94834)
			(xy 62.679017 -139.002001) (xy 62.655101 -139.052708) (xy 62.624023 -139.09937) (xy 62.586451 -139.140982)
			(xy 62.543195 -139.176648) (xy 62.495185 -139.205601) (xy 62.469522 -139.216892) (xy 62.469014 -139.217146)
			(xy 62.462664 -139.21994) (xy 62.449964 -139.229846) (xy 62.442521 -139.236472) (xy 62.433106 -139.254019)
			(xy 62.431676 -139.263882) (xy 62.211732 -143.48714) (xy 66.599308 -143.48714) (xy 66.599308 -142.62354)
			(xy 66.599798 -142.593556) (xy 66.607626 -142.5341) (xy 66.623147 -142.476175) (xy 66.646096 -142.420771)
			(xy 66.67608 -142.368837) (xy 66.712586 -142.321261) (xy 66.754991 -142.278856) (xy 66.802567 -142.24235)
			(xy 66.854501 -142.212366) (xy 66.909905 -142.189417) (xy 66.96783 -142.173896) (xy 67.027286 -142.166068)
			(xy 67.087254 -142.166068) (xy 67.14671 -142.173896) (xy 67.204635 -142.189417) (xy 67.260039 -142.212366)
			(xy 67.311973 -142.24235) (xy 67.359549 -142.278856) (xy 67.401954 -142.321261) (xy 67.43846 -142.368837)
			(xy 67.468444 -142.420771) (xy 67.491393 -142.476175) (xy 67.506914 -142.5341) (xy 67.514742 -142.593556)
			(xy 67.515232 -142.62354) (xy 67.515232 -143.48714) (xy 67.514742 -143.517124) (xy 67.506914 -143.57658)
			(xy 67.491393 -143.634505) (xy 67.468444 -143.689909) (xy 67.43846 -143.741843) (xy 67.401954 -143.789419)
			(xy 67.359549 -143.831824) (xy 67.311973 -143.86833) (xy 67.260039 -143.898314) (xy 67.204635 -143.921263)
			(xy 67.14671 -143.936784) (xy 67.087254 -143.944612) (xy 67.027286 -143.944612) (xy 66.96783 -143.936784)
			(xy 66.909905 -143.921263) (xy 66.854501 -143.898314) (xy 66.802567 -143.86833) (xy 66.754991 -143.831824)
			(xy 66.712586 -143.789419) (xy 66.67608 -143.741843) (xy 66.646096 -143.689909) (xy 66.623147 -143.634505)
			(xy 66.607626 -143.57658) (xy 66.599798 -143.517124) (xy 66.599308 -143.48714) (xy 62.211732 -143.48714)
			(xy 62.165738 -144.370298) (xy 62.117998 -145.287238) (xy 64.745108 -145.287238) (xy 64.745108 -144.423638)
			(xy 64.745598 -144.393654) (xy 64.753426 -144.334198) (xy 64.768947 -144.276273) (xy 64.791896 -144.220869)
			(xy 64.82188 -144.168935) (xy 64.858386 -144.121359) (xy 64.900791 -144.078954) (xy 64.948367 -144.042448)
			(xy 65.000301 -144.012464) (xy 65.055705 -143.989515) (xy 65.11363 -143.973994) (xy 65.173086 -143.966166)
			(xy 65.233054 -143.966166) (xy 65.29251 -143.973994) (xy 65.350435 -143.989515) (xy 65.405839 -144.012464)
			(xy 65.457773 -144.042448) (xy 65.505349 -144.078954) (xy 65.547754 -144.121359) (xy 65.58426 -144.168935)
			(xy 65.614244 -144.220869) (xy 65.637193 -144.276273) (xy 65.652714 -144.334198) (xy 65.660542 -144.393654)
			(xy 65.661032 -144.423638) (xy 65.661032 -145.287238) (xy 65.660542 -145.317222) (xy 65.652714 -145.376678)
			(xy 65.637193 -145.434603) (xy 65.614244 -145.490007) (xy 65.58426 -145.541941) (xy 65.547754 -145.589517)
			(xy 65.505349 -145.631922) (xy 65.457773 -145.668428) (xy 65.405839 -145.698412) (xy 65.350435 -145.721361)
			(xy 65.29251 -145.736882) (xy 65.233054 -145.74471) (xy 65.173086 -145.74471) (xy 65.11363 -145.736882)
			(xy 65.055705 -145.721361) (xy 65.000301 -145.698412) (xy 64.948367 -145.668428) (xy 64.900791 -145.631922)
			(xy 64.858386 -145.589517) (xy 64.82188 -145.541941) (xy 64.791896 -145.490007) (xy 64.768947 -145.434603)
			(xy 64.753426 -145.376678) (xy 64.745598 -145.317222) (xy 64.745108 -145.287238) (xy 62.117998 -145.287238)
			(xy 62.024276 -147.087336) (xy 66.599308 -147.087336) (xy 66.599308 -146.223736) (xy 66.599798 -146.193752)
			(xy 66.607626 -146.134296) (xy 66.623147 -146.076371) (xy 66.646096 -146.020967) (xy 66.67608 -145.969033)
			(xy 66.712586 -145.921457) (xy 66.754991 -145.879052) (xy 66.802567 -145.842546) (xy 66.854501 -145.812562)
			(xy 66.909905 -145.789613) (xy 66.96783 -145.774092) (xy 67.027286 -145.766264) (xy 67.087254 -145.766264)
			(xy 67.14671 -145.774092) (xy 67.204635 -145.789613) (xy 67.260039 -145.812562) (xy 67.311973 -145.842546)
			(xy 67.359549 -145.879052) (xy 67.401954 -145.921457) (xy 67.43846 -145.969033) (xy 67.468444 -146.020967)
			(xy 67.491393 -146.076371) (xy 67.506914 -146.134296) (xy 67.514742 -146.193752) (xy 67.515232 -146.223736)
			(xy 67.515232 -147.087336) (xy 67.514742 -147.11732) (xy 67.506914 -147.176776) (xy 67.491393 -147.234701)
			(xy 67.468444 -147.290105) (xy 67.43846 -147.342039) (xy 67.401954 -147.389615) (xy 67.359549 -147.43202)
			(xy 67.311973 -147.468526) (xy 67.260039 -147.49851) (xy 67.204635 -147.521459) (xy 67.14671 -147.53698)
			(xy 67.087254 -147.544808) (xy 67.027286 -147.544808) (xy 66.96783 -147.53698) (xy 66.909905 -147.521459)
			(xy 66.854501 -147.49851) (xy 66.802567 -147.468526) (xy 66.754991 -147.43202) (xy 66.712586 -147.389615)
			(xy 66.67608 -147.342039) (xy 66.646096 -147.290105) (xy 66.623147 -147.234701) (xy 66.607626 -147.176776)
			(xy 66.599798 -147.11732) (xy 66.599308 -147.087336) (xy 62.024276 -147.087336) (xy 62.003686 -147.482814)
			(xy 61.993018 -147.688554) (xy 61.930641 -148.887434) (xy 64.745108 -148.887434) (xy 64.745108 -148.023834)
			(xy 64.745598 -147.99385) (xy 64.753426 -147.934394) (xy 64.768947 -147.876469) (xy 64.791896 -147.821065)
			(xy 64.82188 -147.769131) (xy 64.858386 -147.721555) (xy 64.900791 -147.67915) (xy 64.948367 -147.642644)
			(xy 65.000301 -147.61266) (xy 65.055705 -147.589711) (xy 65.11363 -147.57419) (xy 65.173086 -147.566362)
			(xy 65.233054 -147.566362) (xy 65.29251 -147.57419) (xy 65.350435 -147.589711) (xy 65.405839 -147.61266)
			(xy 65.457773 -147.642644) (xy 65.505349 -147.67915) (xy 65.547754 -147.721555) (xy 65.58426 -147.769131)
			(xy 65.614244 -147.821065) (xy 65.637193 -147.876469) (xy 65.652714 -147.934394) (xy 65.660542 -147.99385)
			(xy 65.661032 -148.023834) (xy 65.661032 -148.887434) (xy 65.660542 -148.917418) (xy 65.652714 -148.976874)
			(xy 65.637193 -149.034799) (xy 65.614244 -149.090203) (xy 65.58426 -149.142137) (xy 65.547754 -149.189713)
			(xy 65.505349 -149.232118) (xy 65.457773 -149.268624) (xy 65.405839 -149.298608) (xy 65.350435 -149.321557)
			(xy 65.29251 -149.337078) (xy 65.233054 -149.344906) (xy 65.173086 -149.344906) (xy 65.11363 -149.337078)
			(xy 65.055705 -149.321557) (xy 65.000301 -149.298608) (xy 64.948367 -149.268624) (xy 64.900791 -149.232118)
			(xy 64.858386 -149.189713) (xy 64.82188 -149.142137) (xy 64.791896 -149.090203) (xy 64.768947 -149.034799)
			(xy 64.753426 -148.976874) (xy 64.745598 -148.917418) (xy 64.745108 -148.887434) (xy 61.930641 -148.887434)
			(xy 61.836996 -150.687278) (xy 66.599308 -150.687278) (xy 66.599308 -149.823678) (xy 66.599798 -149.793694)
			(xy 66.607626 -149.734238) (xy 66.623147 -149.676313) (xy 66.646096 -149.620909) (xy 66.67608 -149.568975)
			(xy 66.712586 -149.521399) (xy 66.754991 -149.478994) (xy 66.802567 -149.442488) (xy 66.854501 -149.412504)
			(xy 66.909905 -149.389555) (xy 66.96783 -149.374034) (xy 67.027286 -149.366206) (xy 67.087254 -149.366206)
			(xy 67.14671 -149.374034) (xy 67.204635 -149.389555) (xy 67.260039 -149.412504) (xy 67.311973 -149.442488)
			(xy 67.359549 -149.478994) (xy 67.401954 -149.521399) (xy 67.43846 -149.568975) (xy 67.468444 -149.620909)
			(xy 67.491393 -149.676313) (xy 67.506914 -149.734238) (xy 67.514742 -149.793694) (xy 67.515232 -149.823678)
			(xy 67.515232 -150.687278) (xy 67.514742 -150.717262) (xy 67.506914 -150.776718) (xy 67.491393 -150.834643)
			(xy 67.468444 -150.890047) (xy 67.43846 -150.941981) (xy 67.401954 -150.989557) (xy 67.359549 -151.031962)
			(xy 67.311973 -151.068468) (xy 67.260039 -151.098452) (xy 67.204635 -151.121401) (xy 67.14671 -151.136922)
			(xy 67.087254 -151.14475) (xy 67.027286 -151.14475) (xy 66.96783 -151.136922) (xy 66.909905 -151.121401)
			(xy 66.854501 -151.098452) (xy 66.802567 -151.068468) (xy 66.754991 -151.031962) (xy 66.712586 -150.989557)
			(xy 66.67608 -150.941981) (xy 66.646096 -150.890047) (xy 66.623147 -150.834643) (xy 66.607626 -150.776718)
			(xy 66.599798 -150.717262) (xy 66.599308 -150.687278) (xy 61.836996 -150.687278) (xy 61.786262 -151.662384)
			(xy 61.743339 -152.487376) (xy 64.745108 -152.487376) (xy 64.745108 -151.623776) (xy 64.745598 -151.593792)
			(xy 64.753426 -151.534336) (xy 64.768947 -151.476411) (xy 64.791896 -151.421007) (xy 64.82188 -151.369073)
			(xy 64.858386 -151.321497) (xy 64.900791 -151.279092) (xy 64.948367 -151.242586) (xy 65.000301 -151.212602)
			(xy 65.055705 -151.189653) (xy 65.11363 -151.174132) (xy 65.173086 -151.166304) (xy 65.233054 -151.166304)
			(xy 65.29251 -151.174132) (xy 65.350435 -151.189653) (xy 65.405839 -151.212602) (xy 65.457773 -151.242586)
			(xy 65.505349 -151.279092) (xy 65.547754 -151.321497) (xy 65.58426 -151.369073) (xy 65.614244 -151.421007)
			(xy 65.637193 -151.476411) (xy 65.652714 -151.534336) (xy 65.660542 -151.593792) (xy 65.661032 -151.623776)
			(xy 65.661032 -152.487376) (xy 65.660542 -152.51736) (xy 65.652714 -152.576816) (xy 65.637193 -152.634741)
			(xy 65.614244 -152.690145) (xy 65.58426 -152.742079) (xy 65.547754 -152.789655) (xy 65.505349 -152.83206)
			(xy 65.457773 -152.868566) (xy 65.405839 -152.89855) (xy 65.350435 -152.921499) (xy 65.29251 -152.93702)
			(xy 65.233054 -152.944848) (xy 65.173086 -152.944848) (xy 65.11363 -152.93702) (xy 65.055705 -152.921499)
			(xy 65.000301 -152.89855) (xy 64.948367 -152.868566) (xy 64.900791 -152.83206) (xy 64.858386 -152.789655)
			(xy 64.82188 -152.742079) (xy 64.791896 -152.690145) (xy 64.768947 -152.634741) (xy 64.753426 -152.576816)
			(xy 64.745598 -152.51736) (xy 64.745108 -152.487376) (xy 61.743339 -152.487376) (xy 61.712349 -153.083006)
			(xy 62.492126 -153.083006) (xy 62.496197 -153.027384) (xy 62.508323 -152.972947) (xy 62.528246 -152.920856)
			(xy 62.555542 -152.872221) (xy 62.589628 -152.828078) (xy 62.629777 -152.789369) (xy 62.675135 -152.756918)
			(xy 62.724735 -152.731417) (xy 62.777519 -152.71341) (xy 62.832362 -152.70328) (xy 62.888096 -152.701243)
			(xy 62.943533 -152.707343) (xy 62.99749 -152.721449) (xy 63.048819 -152.743261) (xy 63.096425 -152.772315)
			(xy 63.139293 -152.80799) (xy 63.17651 -152.849527) (xy 63.207283 -152.89604) (xy 63.230955 -152.946537)
			(xy 63.247023 -152.999944) (xy 63.255143 -153.05512) (xy 63.255652 -153.083006) (xy 63.255143 -153.110892)
			(xy 63.247023 -153.166068) (xy 63.230955 -153.219475) (xy 63.207283 -153.269972) (xy 63.17651 -153.316485)
			(xy 63.139293 -153.358022) (xy 63.096425 -153.393697) (xy 63.048819 -153.422751) (xy 62.99749 -153.444563)
			(xy 62.943533 -153.458669) (xy 62.888096 -153.464769) (xy 62.832362 -153.462732) (xy 62.777519 -153.452602)
			(xy 62.724735 -153.434595) (xy 62.675135 -153.409094) (xy 62.629777 -153.376643) (xy 62.589628 -153.337934)
			(xy 62.555542 -153.293791) (xy 62.528246 -153.245156) (xy 62.508323 -153.193065) (xy 62.496197 -153.138628)
			(xy 62.492126 -153.083006) (xy 61.712349 -153.083006) (xy 61.649695 -154.28722) (xy 66.599308 -154.28722)
			(xy 66.599308 -153.42362) (xy 66.599798 -153.393636) (xy 66.607626 -153.33418) (xy 66.623147 -153.276255)
			(xy 66.646096 -153.220851) (xy 66.67608 -153.168917) (xy 66.712586 -153.121341) (xy 66.754991 -153.078936)
			(xy 66.802567 -153.04243) (xy 66.854501 -153.012446) (xy 66.909905 -152.989497) (xy 66.96783 -152.973976)
			(xy 67.027286 -152.966148) (xy 67.087254 -152.966148) (xy 67.14671 -152.973976) (xy 67.204635 -152.989497)
			(xy 67.260039 -153.012446) (xy 67.311973 -153.04243) (xy 67.359549 -153.078936) (xy 67.401954 -153.121341)
			(xy 67.43846 -153.168917) (xy 67.468444 -153.220851) (xy 67.491393 -153.276255) (xy 67.506914 -153.33418)
			(xy 67.514742 -153.393636) (xy 67.515232 -153.42362) (xy 67.515232 -154.28722) (xy 67.514742 -154.317204)
			(xy 67.506914 -154.37666) (xy 67.491393 -154.434585) (xy 67.468444 -154.489989) (xy 67.43846 -154.541923)
			(xy 67.401954 -154.589499) (xy 67.359549 -154.631904) (xy 67.311973 -154.66841) (xy 67.260039 -154.698394)
			(xy 67.204635 -154.721343) (xy 67.14671 -154.736864) (xy 67.087254 -154.744692) (xy 67.027286 -154.744692)
			(xy 66.96783 -154.736864) (xy 66.909905 -154.721343) (xy 66.854501 -154.698394) (xy 66.802567 -154.66841)
			(xy 66.754991 -154.631904) (xy 66.712586 -154.589499) (xy 66.67608 -154.541923) (xy 66.646096 -154.489989)
			(xy 66.623147 -154.434585) (xy 66.607626 -154.37666) (xy 66.599798 -154.317204) (xy 66.599308 -154.28722)
			(xy 61.649695 -154.28722) (xy 61.597032 -155.29941) (xy 61.590682 -155.421584) (xy 61.5569 -156.070046)
			(xy 61.5569 -156.073602) (xy 61.557159 -156.081247) (xy 61.559039 -156.087318) (xy 64.745108 -156.087318)
			(xy 64.745108 -155.223718) (xy 64.745598 -155.193734) (xy 64.753426 -155.134278) (xy 64.768947 -155.076353)
			(xy 64.791896 -155.020949) (xy 64.82188 -154.969015) (xy 64.858386 -154.921439) (xy 64.900791 -154.879034)
			(xy 64.948367 -154.842528) (xy 65.000301 -154.812544) (xy 65.055705 -154.789595) (xy 65.11363 -154.774074)
			(xy 65.173086 -154.766246) (xy 65.233054 -154.766246) (xy 65.29251 -154.774074) (xy 65.350435 -154.789595)
			(xy 65.405839 -154.812544) (xy 65.457773 -154.842528) (xy 65.505349 -154.879034) (xy 65.547754 -154.921439)
			(xy 65.58426 -154.969015) (xy 65.614244 -155.020949) (xy 65.637193 -155.076353) (xy 65.652714 -155.134278)
			(xy 65.660542 -155.193734) (xy 65.661032 -155.223718) (xy 65.661032 -156.087318) (xy 65.660542 -156.117302)
			(xy 65.652714 -156.176758) (xy 65.637193 -156.234683) (xy 65.614244 -156.290087) (xy 65.58426 -156.342021)
			(xy 65.547754 -156.389597) (xy 65.505349 -156.432002) (xy 65.457773 -156.468508) (xy 65.405839 -156.498492)
			(xy 65.350435 -156.521441) (xy 65.29251 -156.536962) (xy 65.233054 -156.54479) (xy 65.173086 -156.54479)
			(xy 65.11363 -156.536962) (xy 65.055705 -156.521441) (xy 65.000301 -156.498492) (xy 64.948367 -156.468508)
			(xy 64.900791 -156.432002) (xy 64.858386 -156.389597) (xy 64.82188 -156.342021) (xy 64.791896 -156.290087)
			(xy 64.768947 -156.234683) (xy 64.753426 -156.176758) (xy 64.745598 -156.117302) (xy 64.745108 -156.087318)
			(xy 61.559039 -156.087318) (xy 61.561681 -156.095852) (xy 61.56579 -156.102304) (xy 61.570362 -156.108908)
			(xy 61.582046 -156.117798) (xy 61.590174 -156.120846) (xy 61.617366 -156.131312) (xy 61.668465 -156.159304)
			(xy 61.714713 -156.19474) (xy 61.755035 -156.236797) (xy 61.788493 -156.284496) (xy 61.814309 -156.336728)
			(xy 61.831882 -156.392278) (xy 61.840804 -156.449855) (xy 61.84138 -156.478986) (xy 61.841126 -156.492194)
			(xy 61.840663 -156.503224) (xy 61.838629 -156.525208) (xy 61.837062 -156.536136) (xy 61.837062 -156.536644)
			(xy 61.83503 -156.548074) (xy 61.83503 -156.548582) (xy 61.834522 -156.551122) (xy 61.834268 -156.553916)
			(xy 61.833506 -156.55671) (xy 61.833252 -156.557218) (xy 61.833252 -156.55798) (xy 61.832998 -156.558488)
			(xy 61.831982 -156.563568) (xy 61.831474 -156.571696) (xy 61.831673 -156.577148) (xy 61.834112 -156.58778)
			(xy 61.8363 -156.592778) (xy 61.839602 -156.599128) (xy 61.871352 -156.65323) (xy 61.871606 -156.653484)
			(xy 61.87694 -156.662628) (xy 61.884306 -156.66974) (xy 61.887599 -156.672355) (xy 61.894877 -156.676566)
			(xy 61.898784 -156.678122) (xy 61.900308 -156.678884) (xy 61.903864 -156.6799) (xy 61.930603 -156.688568)
			(xy 61.981388 -156.712656) (xy 62.028093 -156.743931) (xy 62.069707 -156.781715) (xy 62.105331 -156.825193)
			(xy 62.134195 -156.873424) (xy 62.155676 -156.925367) (xy 62.169307 -156.979897) (xy 62.172596 -157.007814)
			(xy 62.174374 -157.043374) (xy 62.174374 -157.045152) (xy 62.426594 -157.045152) (xy 62.430665 -156.98953)
			(xy 62.442791 -156.935093) (xy 62.462714 -156.883002) (xy 62.49001 -156.834367) (xy 62.524096 -156.790224)
			(xy 62.564245 -156.751515) (xy 62.609603 -156.719064) (xy 62.659203 -156.693563) (xy 62.711987 -156.675556)
			(xy 62.76683 -156.665426) (xy 62.822564 -156.663389) (xy 62.878001 -156.669489) (xy 62.931958 -156.683595)
			(xy 62.983287 -156.705407) (xy 63.030893 -156.734461) (xy 63.073761 -156.770136) (xy 63.110978 -156.811673)
			(xy 63.141751 -156.858186) (xy 63.165423 -156.908683) (xy 63.181491 -156.96209) (xy 63.189611 -157.017266)
			(xy 63.19012 -157.045152) (xy 63.189611 -157.073038) (xy 63.181491 -157.128214) (xy 63.165423 -157.181621)
			(xy 63.141751 -157.232118) (xy 63.110978 -157.278631) (xy 63.073761 -157.320168) (xy 63.030893 -157.355843)
			(xy 62.983287 -157.384897) (xy 62.931958 -157.406709) (xy 62.878001 -157.420815) (xy 62.822564 -157.426915)
			(xy 62.76683 -157.424878) (xy 62.711987 -157.414748) (xy 62.659203 -157.396741) (xy 62.609603 -157.37124)
			(xy 62.564245 -157.338789) (xy 62.524096 -157.30008) (xy 62.49001 -157.255937) (xy 62.462714 -157.207302)
			(xy 62.442791 -157.155211) (xy 62.430665 -157.100774) (xy 62.426594 -157.045152) (xy 62.174374 -157.045152)
			(xy 62.173914 -157.072426) (xy 62.166157 -157.126418) (xy 62.150795 -157.178757) (xy 62.128141 -157.228377)
			(xy 62.098654 -157.274268) (xy 62.062937 -157.315495) (xy 62.021716 -157.351218) (xy 61.97583 -157.380712)
			(xy 61.926214 -157.403374) (xy 61.873877 -157.418745) (xy 61.819885 -157.42651) (xy 61.792612 -157.426914)
			(xy 61.792358 -157.426914) (xy 61.764733 -157.426448) (xy 61.710056 -157.418522) (xy 61.657097 -157.402784)
			(xy 61.63183 -157.391608) (xy 61.631322 -157.391354) (xy 61.625734 -157.388814) (xy 61.615574 -157.386782)
			(xy 61.61532 -157.386782) (xy 61.606354 -157.385518) (xy 61.588531 -157.388651) (xy 61.580522 -157.392878)
			(xy 61.580268 -157.392878) (xy 61.535056 -157.419294) (xy 61.508386 -157.435042) (xy 61.507116 -157.435804)
			(xy 61.500539 -157.440349) (xy 61.490335 -157.452644) (xy 61.48705 -157.459934) (xy 61.484002 -157.467808)
			(xy 61.38037 -159.460692) (xy 61.383672 -159.47009) (xy 61.38849 -159.484414) (xy 61.396118 -159.513658)
			(xy 61.398912 -159.52851) (xy 61.399928 -159.534352) (xy 61.402722 -159.5501) (xy 61.402976 -159.551878)
			(xy 61.40323 -159.554164) (xy 61.404246 -159.569404) (xy 61.4045 -159.571436) (xy 61.404754 -159.576516)
			(xy 61.404754 -159.595566) (xy 61.40426 -159.623336) (xy 61.396208 -159.67829) (xy 61.380255 -159.731491)
			(xy 61.36894 -159.756856) (xy 61.364622 -159.766) (xy 61.342985 -160.1851) (xy 69.888875 -160.1851)
			(xy 69.892831 -160.093241) (xy 69.904668 -160.002062) (xy 69.9243 -159.912238) (xy 69.951581 -159.824435)
			(xy 69.986309 -159.739302) (xy 70.028227 -159.657469) (xy 70.077025 -159.579542) (xy 70.13234 -159.506099)
			(xy 70.193765 -159.437683) (xy 70.260844 -159.374801) (xy 70.333079 -159.317918) (xy 70.409938 -159.267455)
			(xy 70.49085 -159.223786) (xy 70.575216 -159.187234) (xy 70.662412 -159.15807) (xy 70.751793 -159.13651)
			(xy 70.842696 -159.122714) (xy 70.934449 -159.116782) (xy 71.026371 -159.118761) (xy 71.117784 -159.128634)
			(xy 71.208009 -159.146329) (xy 71.29638 -159.171714) (xy 71.38224 -159.204602) (xy 71.464956 -159.24475)
			(xy 71.543914 -159.291859) (xy 71.618531 -159.345582) (xy 71.688252 -159.40552) (xy 71.752563 -159.47123)
			(xy 71.810988 -159.542226) (xy 71.863093 -159.61798) (xy 71.908492 -159.697934) (xy 71.946851 -159.781494)
			(xy 71.977884 -159.868043) (xy 72.001362 -159.956939) (xy 72.017112 -160.047524) (xy 72.025016 -160.139128)
			(xy 72.02551 -160.1851) (xy 72.025016 -160.231072) (xy 72.017112 -160.322676) (xy 72.001362 -160.413261)
			(xy 71.977884 -160.502157) (xy 71.946851 -160.588706) (xy 71.908492 -160.672266) (xy 71.863093 -160.75222)
			(xy 71.810988 -160.827974) (xy 71.752563 -160.89897) (xy 71.688252 -160.96468) (xy 71.618531 -161.024618)
			(xy 71.543914 -161.078341) (xy 71.464956 -161.12545) (xy 71.38224 -161.165598) (xy 71.29638 -161.198486)
			(xy 71.208009 -161.223871) (xy 71.117784 -161.241566) (xy 71.026371 -161.251439) (xy 70.934449 -161.253418)
			(xy 70.842696 -161.247486) (xy 70.751793 -161.23369) (xy 70.662412 -161.21213) (xy 70.575216 -161.182966)
			(xy 70.49085 -161.146414) (xy 70.409938 -161.102745) (xy 70.333079 -161.052282) (xy 70.260844 -160.995399)
			(xy 70.193765 -160.932517) (xy 70.13234 -160.864101) (xy 70.077025 -160.790658) (xy 70.028227 -160.712731)
			(xy 69.986309 -160.630898) (xy 69.951581 -160.545765) (xy 69.9243 -160.457962) (xy 69.904668 -160.368138)
			(xy 69.892831 -160.276959) (xy 69.888875 -160.1851) (xy 61.342985 -160.1851) (xy 61.268055 -161.636456)
			(xy 63.800734 -161.636456) (xy 63.804805 -161.580834) (xy 63.816931 -161.526397) (xy 63.836854 -161.474306)
			(xy 63.86415 -161.425671) (xy 63.898236 -161.381528) (xy 63.938385 -161.342819) (xy 63.983743 -161.310368)
			(xy 64.033343 -161.284867) (xy 64.086127 -161.26686) (xy 64.14097 -161.25673) (xy 64.196704 -161.254693)
			(xy 64.252141 -161.260793) (xy 64.306098 -161.274899) (xy 64.357427 -161.296711) (xy 64.405033 -161.325765)
			(xy 64.447901 -161.36144) (xy 64.485118 -161.402977) (xy 64.515891 -161.44949) (xy 64.539563 -161.499987)
			(xy 64.555631 -161.553394) (xy 64.563751 -161.60857) (xy 64.56426 -161.636456) (xy 64.563751 -161.664342)
			(xy 64.555631 -161.719518) (xy 64.539563 -161.772925) (xy 64.515891 -161.823422) (xy 64.485118 -161.869935)
			(xy 64.447901 -161.911472) (xy 64.405033 -161.947147) (xy 64.357427 -161.976201) (xy 64.306098 -161.998013)
			(xy 64.252141 -162.012119) (xy 64.196704 -162.018219) (xy 64.14097 -162.016182) (xy 64.086127 -162.006052)
			(xy 64.033343 -161.988045) (xy 63.983743 -161.962544) (xy 63.938385 -161.930093) (xy 63.898236 -161.891384)
			(xy 63.86415 -161.847241) (xy 63.836854 -161.798606) (xy 63.816931 -161.746515) (xy 63.804805 -161.692078)
			(xy 63.800734 -161.636456) (xy 61.268055 -161.636456) (xy 61.266324 -161.669984) (xy 61.266324 -161.67227)
			(xy 61.266571 -161.679014) (xy 61.270183 -161.692011) (xy 61.273436 -161.697924) (xy 61.276992 -161.703766)
			(xy 61.292232 -161.722308) (xy 61.293502 -161.723578) (xy 61.299598 -161.731198) (xy 61.315092 -161.739326)
			(xy 61.32195 -161.74212) (xy 61.32576 -161.743136) (xy 61.353751 -161.750527) (xy 61.407267 -161.772601)
			(xy 61.456839 -161.802499) (xy 61.50133 -161.839537) (xy 61.539721 -161.882866) (xy 61.571133 -161.931494)
			(xy 61.594845 -161.984305) (xy 61.610314 -162.04009) (xy 61.614304 -162.068764) (xy 61.614304 -162.069018)
			(xy 61.614812 -162.07359) (xy 61.61532 -162.077908) (xy 61.61659 -162.088068) (xy 61.616844 -162.0901)
			(xy 61.616844 -162.092386) (xy 61.616844 -162.094164) (xy 61.616844 -162.12185) (xy 61.61579 -162.148941)
			(xy 61.606976 -162.202435) (xy 61.590681 -162.254144) (xy 61.567234 -162.303026) (xy 61.537107 -162.3481)
			(xy 61.500905 -162.388458) (xy 61.459358 -162.423287) (xy 61.413301 -162.451888) (xy 61.36366 -162.473685)
			(xy 61.311435 -162.488239) (xy 61.284612 -162.492182) (xy 61.284104 -162.492182) (xy 61.275468 -162.493452)
			(xy 61.26861 -162.496754) (xy 61.264778 -162.498714) (xy 61.257756 -162.503691) (xy 61.25464 -162.50666)
			(xy 61.246766 -162.514534) (xy 61.246258 -162.515042) (xy 61.231018 -162.53079) (xy 61.228044 -162.534638)
			(xy 61.223442 -162.543204) (xy 61.221874 -162.547808) (xy 61.221366 -162.549586) (xy 61.219588 -162.55873)
			(xy 61.208158 -162.778694) (xy 61.197236 -162.98545) (xy 61.197236 -162.988498) (xy 61.197582 -162.99719)
			(xy 61.203425 -163.01356) (xy 61.208666 -163.020502) (xy 61.210698 -163.023042) (xy 61.217048 -163.030408)
			(xy 61.22289 -163.034218) (xy 61.244882 -163.049646) (xy 61.284723 -163.085681) (xy 61.319123 -163.126941)
			(xy 61.347405 -163.172613) (xy 61.369012 -163.221796) (xy 61.383516 -163.273521) (xy 61.390632 -163.326767)
			(xy 61.39022 -163.380485) (xy 61.382288 -163.433616) (xy 61.366992 -163.485112) (xy 61.344635 -163.533958)
			(xy 61.315655 -163.579191) (xy 61.280626 -163.619919) (xy 61.260736 -163.637976) (xy 61.231018 -163.661598)
			(xy 61.220264 -163.669121) (xy 61.197892 -163.682849) (xy 61.186314 -163.68903) (xy 61.185552 -163.689538)
			(xy 61.17971 -163.693094) (xy 61.171388 -163.699546) (xy 61.160479 -163.717528) (xy 61.158628 -163.727892)
			(xy 61.09462 -164.95268) (xy 61.092842 -164.986462) (xy 61.028072 -166.231062) (xy 61.003368 -166.705534)
			(xy 61.11189 -166.705534) (xy 61.115961 -166.649912) (xy 61.128087 -166.595475) (xy 61.14801 -166.543384)
			(xy 61.175306 -166.494749) (xy 61.209392 -166.450606) (xy 61.249541 -166.411897) (xy 61.294899 -166.379446)
			(xy 61.344499 -166.353945) (xy 61.397283 -166.335938) (xy 61.452126 -166.325808) (xy 61.50786 -166.323771)
			(xy 61.563297 -166.329871) (xy 61.617254 -166.343977) (xy 61.668583 -166.365789) (xy 61.716189 -166.394843)
			(xy 61.759057 -166.430518) (xy 61.796274 -166.472055) (xy 61.827047 -166.518568) (xy 61.850719 -166.569065)
			(xy 61.866787 -166.622472) (xy 61.874907 -166.677648) (xy 61.875416 -166.705534) (xy 62.12789 -166.705534)
			(xy 62.131961 -166.649912) (xy 62.144087 -166.595475) (xy 62.16401 -166.543384) (xy 62.191306 -166.494749)
			(xy 62.225392 -166.450606) (xy 62.265541 -166.411897) (xy 62.310899 -166.379446) (xy 62.360499 -166.353945)
			(xy 62.413283 -166.335938) (xy 62.468126 -166.325808) (xy 62.52386 -166.323771) (xy 62.579297 -166.329871)
			(xy 62.633254 -166.343977) (xy 62.684583 -166.365789) (xy 62.732189 -166.394843) (xy 62.775057 -166.430518)
			(xy 62.812274 -166.472055) (xy 62.843047 -166.518568) (xy 62.866719 -166.569065) (xy 62.882787 -166.622472)
			(xy 62.890907 -166.677648) (xy 62.891416 -166.705534) (xy 63.14389 -166.705534) (xy 63.147961 -166.649912)
			(xy 63.160087 -166.595475) (xy 63.18001 -166.543384) (xy 63.207306 -166.494749) (xy 63.241392 -166.450606)
			(xy 63.281541 -166.411897) (xy 63.326899 -166.379446) (xy 63.376499 -166.353945) (xy 63.429283 -166.335938)
			(xy 63.484126 -166.325808) (xy 63.53986 -166.323771) (xy 63.595297 -166.329871) (xy 63.649254 -166.343977)
			(xy 63.700583 -166.365789) (xy 63.748189 -166.394843) (xy 63.791057 -166.430518) (xy 63.828274 -166.472055)
			(xy 63.859047 -166.518568) (xy 63.882719 -166.569065) (xy 63.898787 -166.622472) (xy 63.906907 -166.677648)
			(xy 63.907416 -166.705534) (xy 63.906907 -166.73342) (xy 63.898787 -166.788596) (xy 63.882719 -166.842003)
			(xy 63.859047 -166.8925) (xy 63.828274 -166.939013) (xy 63.791057 -166.98055) (xy 63.748189 -167.016225)
			(xy 63.700583 -167.045279) (xy 63.649254 -167.067091) (xy 63.595297 -167.081197) (xy 63.53986 -167.087297)
			(xy 63.484126 -167.08526) (xy 63.429283 -167.07513) (xy 63.376499 -167.057123) (xy 63.326899 -167.031622)
			(xy 63.281541 -166.999171) (xy 63.241392 -166.960462) (xy 63.207306 -166.916319) (xy 63.18001 -166.867684)
			(xy 63.160087 -166.815593) (xy 63.147961 -166.761156) (xy 63.14389 -166.705534) (xy 62.891416 -166.705534)
			(xy 62.890907 -166.73342) (xy 62.882787 -166.788596) (xy 62.866719 -166.842003) (xy 62.843047 -166.8925)
			(xy 62.812274 -166.939013) (xy 62.775057 -166.98055) (xy 62.732189 -167.016225) (xy 62.684583 -167.045279)
			(xy 62.633254 -167.067091) (xy 62.579297 -167.081197) (xy 62.52386 -167.087297) (xy 62.468126 -167.08526)
			(xy 62.413283 -167.07513) (xy 62.360499 -167.057123) (xy 62.310899 -167.031622) (xy 62.265541 -166.999171)
			(xy 62.225392 -166.960462) (xy 62.191306 -166.916319) (xy 62.16401 -166.867684) (xy 62.144087 -166.815593)
			(xy 62.131961 -166.761156) (xy 62.12789 -166.705534) (xy 61.875416 -166.705534) (xy 61.874907 -166.73342)
			(xy 61.866787 -166.788596) (xy 61.850719 -166.842003) (xy 61.827047 -166.8925) (xy 61.796274 -166.939013)
			(xy 61.759057 -166.98055) (xy 61.716189 -167.016225) (xy 61.668583 -167.045279) (xy 61.617254 -167.067091)
			(xy 61.563297 -167.081197) (xy 61.50786 -167.087297) (xy 61.452126 -167.08526) (xy 61.397283 -167.07513)
			(xy 61.344499 -167.057123) (xy 61.294899 -167.031622) (xy 61.249541 -166.999171) (xy 61.209392 -166.960462)
			(xy 61.175306 -166.916319) (xy 61.14801 -166.867684) (xy 61.128087 -166.815593) (xy 61.115961 -166.761156)
			(xy 61.11189 -166.705534) (xy 61.003368 -166.705534) (xy 60.989972 -166.962836) (xy 60.925456 -168.201086)
			(xy 60.922154 -168.266618) (xy 60.894468 -168.797478) (xy 60.875926 -169.15257) (xy 60.875672 -169.157904)
			(xy 60.87364 -169.194988) (xy 60.868814 -169.28592) (xy 60.851034 -169.632884) (xy 60.85078 -169.635424)
			(xy 60.85078 -169.635678) (xy 60.850018 -169.651934) (xy 60.850018 -169.652442) (xy 60.800996 -170.589956)
			(xy 60.791598 -170.77309) (xy 60.787026 -170.860212) (xy 60.783216 -170.933364) (xy 60.710568 -172.329348)
			(xy 61.847982 -172.329348) (xy 61.852053 -172.273726) (xy 61.864179 -172.219289) (xy 61.884102 -172.167198)
			(xy 61.911398 -172.118563) (xy 61.945484 -172.07442) (xy 61.985633 -172.035711) (xy 62.030991 -172.00326)
			(xy 62.080591 -171.977759) (xy 62.133375 -171.959752) (xy 62.188218 -171.949622) (xy 62.243952 -171.947585)
			(xy 62.299389 -171.953685) (xy 62.353346 -171.967791) (xy 62.404675 -171.989603) (xy 62.452281 -172.018657)
			(xy 62.495149 -172.054332) (xy 62.532366 -172.095869) (xy 62.563139 -172.142382) (xy 62.586811 -172.192879)
			(xy 62.602879 -172.246286) (xy 62.610999 -172.301462) (xy 62.611508 -172.329348) (xy 62.611244 -172.343826)
			(xy 62.785242 -172.343826) (xy 62.789313 -172.288204) (xy 62.801439 -172.233767) (xy 62.821362 -172.181676)
			(xy 62.848658 -172.133041) (xy 62.882744 -172.088898) (xy 62.922893 -172.050189) (xy 62.968251 -172.017738)
			(xy 63.017851 -171.992237) (xy 63.070635 -171.97423) (xy 63.125478 -171.9641) (xy 63.181212 -171.962063)
			(xy 63.236649 -171.968163) (xy 63.290606 -171.982269) (xy 63.341935 -172.004081) (xy 63.389541 -172.033135)
			(xy 63.432409 -172.06881) (xy 63.469626 -172.110347) (xy 63.500399 -172.15686) (xy 63.524071 -172.207357)
			(xy 63.540139 -172.260764) (xy 63.548259 -172.31594) (xy 63.548768 -172.343826) (xy 63.548259 -172.371712)
			(xy 63.540139 -172.426888) (xy 63.524071 -172.480295) (xy 63.500399 -172.530792) (xy 63.469626 -172.577305)
			(xy 63.432409 -172.618842) (xy 63.389541 -172.654517) (xy 63.341935 -172.683571) (xy 63.290606 -172.705383)
			(xy 63.236649 -172.719489) (xy 63.181212 -172.725589) (xy 63.125478 -172.723552) (xy 63.070635 -172.713422)
			(xy 63.017851 -172.695415) (xy 62.968251 -172.669914) (xy 62.922893 -172.637463) (xy 62.882744 -172.598754)
			(xy 62.848658 -172.554611) (xy 62.821362 -172.505976) (xy 62.801439 -172.453885) (xy 62.789313 -172.399448)
			(xy 62.785242 -172.343826) (xy 62.611244 -172.343826) (xy 62.610999 -172.357234) (xy 62.602879 -172.41241)
			(xy 62.586811 -172.465817) (xy 62.563139 -172.516314) (xy 62.532366 -172.562827) (xy 62.495149 -172.604364)
			(xy 62.452281 -172.640039) (xy 62.404675 -172.669093) (xy 62.353346 -172.690905) (xy 62.299389 -172.705011)
			(xy 62.243952 -172.711111) (xy 62.188218 -172.709074) (xy 62.133375 -172.698944) (xy 62.080591 -172.680937)
			(xy 62.030991 -172.655436) (xy 61.985633 -172.622985) (xy 61.945484 -172.584276) (xy 61.911398 -172.540133)
			(xy 61.884102 -172.491498) (xy 61.864179 -172.439407) (xy 61.852053 -172.38497) (xy 61.847982 -172.329348)
			(xy 60.710568 -172.329348) (xy 60.676028 -172.99305) (xy 60.584588 -174.750222) (xy 60.543326 -175.542956)
			(xy 62.632842 -175.542956) (xy 62.636913 -175.487334) (xy 62.649039 -175.432897) (xy 62.668962 -175.380806)
			(xy 62.696258 -175.332171) (xy 62.730344 -175.288028) (xy 62.770493 -175.249319) (xy 62.815851 -175.216868)
			(xy 62.865451 -175.191367) (xy 62.918235 -175.17336) (xy 62.973078 -175.16323) (xy 63.028812 -175.161193)
			(xy 63.084249 -175.167293) (xy 63.138206 -175.181399) (xy 63.189535 -175.203211) (xy 63.237141 -175.232265)
			(xy 63.280009 -175.26794) (xy 63.317226 -175.309477) (xy 63.347999 -175.35599) (xy 63.371671 -175.406487)
			(xy 63.387739 -175.459894) (xy 63.395859 -175.51507) (xy 63.396368 -175.542956) (xy 63.395859 -175.570842)
			(xy 63.387739 -175.626018) (xy 63.371671 -175.679425) (xy 63.347999 -175.729922) (xy 63.317226 -175.776435)
			(xy 63.280009 -175.817972) (xy 63.237141 -175.853647) (xy 63.189535 -175.882701) (xy 63.138206 -175.904513)
			(xy 63.084249 -175.918619) (xy 63.028812 -175.924719) (xy 62.973078 -175.922682) (xy 62.918235 -175.912552)
			(xy 62.865451 -175.894545) (xy 62.815851 -175.869044) (xy 62.770493 -175.836593) (xy 62.730344 -175.797884)
			(xy 62.696258 -175.753741) (xy 62.668962 -175.705106) (xy 62.649039 -175.653015) (xy 62.636913 -175.598578)
			(xy 62.632842 -175.542956) (xy 60.543326 -175.542956) (xy 60.466685 -177.015394) (xy 61.6618 -177.015394)
			(xy 61.665871 -176.959772) (xy 61.677997 -176.905335) (xy 61.69792 -176.853244) (xy 61.725216 -176.804609)
			(xy 61.759302 -176.760466) (xy 61.799451 -176.721757) (xy 61.844809 -176.689306) (xy 61.894409 -176.663805)
			(xy 61.947193 -176.645798) (xy 62.002036 -176.635668) (xy 62.05777 -176.633631) (xy 62.113207 -176.639731)
			(xy 62.167164 -176.653837) (xy 62.218493 -176.675649) (xy 62.266099 -176.704703) (xy 62.308967 -176.740378)
			(xy 62.346184 -176.781915) (xy 62.376957 -176.828428) (xy 62.400629 -176.878925) (xy 62.416697 -176.932332)
			(xy 62.424817 -176.987508) (xy 62.425326 -177.015394) (xy 62.424817 -177.04328) (xy 62.416697 -177.098456)
			(xy 62.400629 -177.151863) (xy 62.376957 -177.20236) (xy 62.346184 -177.248873) (xy 62.308967 -177.29041)
			(xy 62.266099 -177.326085) (xy 62.221647 -177.353214) (xy 64.295018 -177.353214) (xy 64.299089 -177.297592)
			(xy 64.311215 -177.243155) (xy 64.331138 -177.191064) (xy 64.358434 -177.142429) (xy 64.39252 -177.098286)
			(xy 64.432669 -177.059577) (xy 64.478027 -177.027126) (xy 64.527627 -177.001625) (xy 64.580411 -176.983618)
			(xy 64.635254 -176.973488) (xy 64.690988 -176.971451) (xy 64.746425 -176.977551) (xy 64.800382 -176.991657)
			(xy 64.851711 -177.013469) (xy 64.899317 -177.042523) (xy 64.942185 -177.078198) (xy 64.979402 -177.119735)
			(xy 65.010175 -177.166248) (xy 65.033847 -177.216745) (xy 65.049915 -177.270152) (xy 65.058035 -177.325328)
			(xy 65.058544 -177.353214) (xy 65.058035 -177.3811) (xy 65.049915 -177.436276) (xy 65.033847 -177.489683)
			(xy 65.010175 -177.54018) (xy 64.979402 -177.586693) (xy 64.942185 -177.62823) (xy 64.899317 -177.663905)
			(xy 64.851711 -177.692959) (xy 64.800382 -177.714771) (xy 64.746425 -177.728877) (xy 64.690988 -177.734977)
			(xy 64.635254 -177.73294) (xy 64.580411 -177.72281) (xy 64.527627 -177.704803) (xy 64.478027 -177.679302)
			(xy 64.432669 -177.646851) (xy 64.39252 -177.608142) (xy 64.358434 -177.563999) (xy 64.331138 -177.515364)
			(xy 64.311215 -177.463273) (xy 64.299089 -177.408836) (xy 64.295018 -177.353214) (xy 62.221647 -177.353214)
			(xy 62.218493 -177.355139) (xy 62.167164 -177.376951) (xy 62.113207 -177.391057) (xy 62.05777 -177.397157)
			(xy 62.002036 -177.39512) (xy 61.947193 -177.38499) (xy 61.894409 -177.366983) (xy 61.844809 -177.341482)
			(xy 61.799451 -177.309031) (xy 61.759302 -177.270322) (xy 61.725216 -177.226179) (xy 61.69792 -177.177544)
			(xy 61.677997 -177.125453) (xy 61.665871 -177.071016) (xy 61.6618 -177.015394) (xy 60.466685 -177.015394)
			(xy 60.314078 -179.947316) (xy 59.732926 -191.113664) (xy 59.732926 -191.118998) (xy 59.73358 -191.128884)
			(xy 59.741405 -191.147064) (xy 59.748166 -191.154304) (xy 59.78017 -191.184276) (xy 59.802014 -191.204596)
			(xy 59.804554 -191.206628) (xy 59.805062 -191.207136) (xy 59.807856 -191.209676) (xy 59.814837 -191.215006)
			(xy 59.831339 -191.22098) (xy 59.840114 -191.22136) (xy 59.846718 -191.22136) (xy 59.849258 -191.221106)
			(xy 59.859892 -191.220012) (xy 59.88124 -191.218867) (xy 59.89193 -191.21882) (xy 59.892692 -191.21882)
			(xy 59.91985 -191.219442) (xy 59.97358 -191.227428) (xy 60.025635 -191.242955) (xy 60.07496 -191.265709)
			(xy 60.120559 -191.29523) (xy 60.161509 -191.330921) (xy 60.196983 -191.37206) (xy 60.226262 -191.417814)
			(xy 60.248754 -191.46726) (xy 60.264006 -191.519395) (xy 60.271707 -191.573168) (xy 60.272168 -191.600328)
			(xy 60.271691 -191.62743) (xy 60.264017 -191.681087) (xy 60.248826 -191.733118) (xy 60.226425 -191.782476)
			(xy 60.197265 -191.828167) (xy 60.161932 -191.869271) (xy 60.121138 -191.904962) (xy 60.075703 -191.93452)
			(xy 60.026543 -191.957352) (xy 59.974647 -191.972996) (xy 59.921059 -191.981139) (xy 59.893962 -191.981836)
			(xy 59.889898 -191.981836) (xy 59.869088 -191.981532) (xy 59.827719 -191.976954) (xy 59.807348 -191.972692)
			(xy 59.79668 -191.970406) (xy 59.779154 -191.973962) (xy 59.769502 -191.97828) (xy 59.707272 -192.025524)
			(xy 59.701938 -192.030096) (xy 59.694826 -192.037208) (xy 59.690845 -192.042743) (xy 59.685682 -192.055358)
			(xy 59.684666 -192.0621) (xy 59.646566 -192.775078) (xy 59.582558 -194.003422) (xy 59.138058 -202.540616)
			(xy 58.944571 -206.258668) (xy 62.738506 -206.258668) (xy 62.742577 -206.203046) (xy 62.754703 -206.148609)
			(xy 62.774626 -206.096518) (xy 62.801922 -206.047883) (xy 62.836008 -206.00374) (xy 62.876157 -205.965031)
			(xy 62.921515 -205.93258) (xy 62.971115 -205.907079) (xy 63.023899 -205.889072) (xy 63.078742 -205.878942)
			(xy 63.134476 -205.876905) (xy 63.189913 -205.883005) (xy 63.24387 -205.897111) (xy 63.295199 -205.918923)
			(xy 63.342805 -205.947977) (xy 63.385673 -205.983652) (xy 63.42289 -206.025189) (xy 63.453663 -206.071702)
			(xy 63.477335 -206.122199) (xy 63.493403 -206.175606) (xy 63.501523 -206.230782) (xy 63.502032 -206.258668)
			(xy 63.501523 -206.286554) (xy 63.493403 -206.34173) (xy 63.477335 -206.395137) (xy 63.453663 -206.445634)
			(xy 63.42289 -206.492147) (xy 63.385673 -206.533684) (xy 63.342805 -206.569359) (xy 63.295199 -206.598413)
			(xy 63.24387 -206.620225) (xy 63.189913 -206.634331) (xy 63.134476 -206.640431) (xy 63.078742 -206.638394)
			(xy 63.023899 -206.628264) (xy 62.971115 -206.610257) (xy 62.921515 -206.584756) (xy 62.876157 -206.552305)
			(xy 62.836008 -206.513596) (xy 62.801922 -206.469453) (xy 62.774626 -206.420818) (xy 62.754703 -206.368727)
			(xy 62.742577 -206.31429) (xy 62.738506 -206.258668) (xy 58.944571 -206.258668) (xy 58.901956 -207.077564)
			(xy 59.966096 -207.077564) (xy 59.970167 -207.021942) (xy 59.982293 -206.967505) (xy 60.002216 -206.915414)
			(xy 60.029512 -206.866779) (xy 60.063598 -206.822636) (xy 60.103747 -206.783927) (xy 60.149105 -206.751476)
			(xy 60.198705 -206.725975) (xy 60.251489 -206.707968) (xy 60.306332 -206.697838) (xy 60.362066 -206.695801)
			(xy 60.417503 -206.701901) (xy 60.47146 -206.716007) (xy 60.522789 -206.737819) (xy 60.570395 -206.766873)
			(xy 60.613263 -206.802548) (xy 60.65048 -206.844085) (xy 60.681253 -206.890598) (xy 60.704925 -206.941095)
			(xy 60.713505 -206.969614) (xy 60.883798 -206.969614) (xy 60.887869 -206.913992) (xy 60.899995 -206.859555)
			(xy 60.919918 -206.807464) (xy 60.947214 -206.758829) (xy 60.9813 -206.714686) (xy 61.021449 -206.675977)
			(xy 61.066807 -206.643526) (xy 61.116407 -206.618025) (xy 61.169191 -206.600018) (xy 61.224034 -206.589888)
			(xy 61.279768 -206.587851) (xy 61.335205 -206.593951) (xy 61.389162 -206.608057) (xy 61.440491 -206.629869)
			(xy 61.488097 -206.658923) (xy 61.530965 -206.694598) (xy 61.568182 -206.736135) (xy 61.598955 -206.782648)
			(xy 61.622627 -206.833145) (xy 61.638695 -206.886552) (xy 61.646815 -206.941728) (xy 61.647324 -206.969614)
			(xy 61.646815 -206.9975) (xy 61.638695 -207.052676) (xy 61.622627 -207.106083) (xy 61.598955 -207.15658)
			(xy 61.568182 -207.203093) (xy 61.530965 -207.24463) (xy 61.488097 -207.280305) (xy 61.440491 -207.309359)
			(xy 61.389162 -207.331171) (xy 61.335205 -207.345277) (xy 61.279768 -207.351377) (xy 61.224034 -207.34934)
			(xy 61.169191 -207.33921) (xy 61.116407 -207.321203) (xy 61.066807 -207.295702) (xy 61.021449 -207.263251)
			(xy 60.9813 -207.224542) (xy 60.947214 -207.180399) (xy 60.919918 -207.131764) (xy 60.899995 -207.079673)
			(xy 60.887869 -207.025236) (xy 60.883798 -206.969614) (xy 60.713505 -206.969614) (xy 60.720993 -206.994502)
			(xy 60.729113 -207.049678) (xy 60.729622 -207.077564) (xy 60.729113 -207.10545) (xy 60.720993 -207.160626)
			(xy 60.704925 -207.214033) (xy 60.681253 -207.26453) (xy 60.65048 -207.311043) (xy 60.613263 -207.35258)
			(xy 60.570395 -207.388255) (xy 60.522789 -207.417309) (xy 60.47146 -207.439121) (xy 60.417503 -207.453227)
			(xy 60.362066 -207.459327) (xy 60.306332 -207.45729) (xy 60.251489 -207.44716) (xy 60.198705 -207.429153)
			(xy 60.149105 -207.403652) (xy 60.103747 -207.371201) (xy 60.063598 -207.332492) (xy 60.029512 -207.288349)
			(xy 60.002216 -207.239714) (xy 59.982293 -207.187623) (xy 59.970167 -207.133186) (xy 59.966096 -207.077564)
			(xy 58.901956 -207.077564) (xy 58.8526 -208.026) (xy 62.180976 -208.026) (xy 62.185047 -207.970378)
			(xy 62.197173 -207.915941) (xy 62.217096 -207.86385) (xy 62.244392 -207.815215) (xy 62.278478 -207.771072)
			(xy 62.318627 -207.732363) (xy 62.363985 -207.699912) (xy 62.413585 -207.674411) (xy 62.466369 -207.656404)
			(xy 62.521212 -207.646274) (xy 62.576946 -207.644237) (xy 62.632383 -207.650337) (xy 62.68634 -207.664443)
			(xy 62.737669 -207.686255) (xy 62.785275 -207.715309) (xy 62.828143 -207.750984) (xy 62.86536 -207.792521)
			(xy 62.896133 -207.839034) (xy 62.919805 -207.889531) (xy 62.935873 -207.942938) (xy 62.943993 -207.998114)
			(xy 62.944502 -208.026) (xy 62.943993 -208.053886) (xy 62.935873 -208.109062) (xy 62.919805 -208.162469)
			(xy 62.896133 -208.212966) (xy 62.86536 -208.259479) (xy 62.828143 -208.301016) (xy 62.785275 -208.336691)
			(xy 62.737669 -208.365745) (xy 62.68634 -208.387557) (xy 62.632383 -208.401663) (xy 62.576946 -208.407763)
			(xy 62.521212 -208.405726) (xy 62.466369 -208.395596) (xy 62.413585 -208.377589) (xy 62.363985 -208.352088)
			(xy 62.318627 -208.319637) (xy 62.278478 -208.280928) (xy 62.244392 -208.236785) (xy 62.217096 -208.18815)
			(xy 62.197173 -208.136059) (xy 62.185047 -208.081622) (xy 62.180976 -208.026) (xy 58.8526 -208.026)
			(xy 58.78647 -209.296762) (xy 62.751206 -209.296762) (xy 62.755277 -209.24114) (xy 62.767403 -209.186703)
			(xy 62.787326 -209.134612) (xy 62.814622 -209.085977) (xy 62.848708 -209.041834) (xy 62.888857 -209.003125)
			(xy 62.934215 -208.970674) (xy 62.983815 -208.945173) (xy 63.036599 -208.927166) (xy 63.091442 -208.917036)
			(xy 63.147176 -208.914999) (xy 63.202613 -208.921099) (xy 63.25657 -208.935205) (xy 63.307899 -208.957017)
			(xy 63.355505 -208.986071) (xy 63.398373 -209.021746) (xy 63.43559 -209.063283) (xy 63.466363 -209.109796)
			(xy 63.490035 -209.160293) (xy 63.506103 -209.2137) (xy 63.514223 -209.268876) (xy 63.514732 -209.296762)
			(xy 63.514223 -209.324648) (xy 63.506103 -209.379824) (xy 63.490035 -209.433231) (xy 63.466363 -209.483728)
			(xy 63.43559 -209.530241) (xy 63.398373 -209.571778) (xy 63.355505 -209.607453) (xy 63.307899 -209.636507)
			(xy 63.25657 -209.658319) (xy 63.202613 -209.672425) (xy 63.147176 -209.678525) (xy 63.091442 -209.676488)
			(xy 63.036599 -209.666358) (xy 62.983815 -209.648351) (xy 62.934215 -209.62285) (xy 62.888857 -209.590399)
			(xy 62.848708 -209.55169) (xy 62.814622 -209.507547) (xy 62.787326 -209.458912) (xy 62.767403 -209.406821)
			(xy 62.755277 -209.352384) (xy 62.751206 -209.296762) (xy 58.78647 -209.296762) (xy 58.615995 -212.5726)
			(xy 60.171582 -212.5726) (xy 60.175653 -212.516978) (xy 60.187779 -212.462541) (xy 60.207702 -212.41045)
			(xy 60.234998 -212.361815) (xy 60.269084 -212.317672) (xy 60.309233 -212.278963) (xy 60.354591 -212.246512)
			(xy 60.404191 -212.221011) (xy 60.456975 -212.203004) (xy 60.511818 -212.192874) (xy 60.567552 -212.190837)
			(xy 60.622989 -212.196937) (xy 60.676946 -212.211043) (xy 60.728275 -212.232855) (xy 60.775881 -212.261909)
			(xy 60.818749 -212.297584) (xy 60.855966 -212.339121) (xy 60.886739 -212.385634) (xy 60.910411 -212.436131)
			(xy 60.926479 -212.489538) (xy 60.934599 -212.544714) (xy 60.935108 -212.5726) (xy 60.934599 -212.600486)
			(xy 60.926479 -212.655662) (xy 60.910411 -212.709069) (xy 60.886739 -212.759566) (xy 60.855966 -212.806079)
			(xy 60.818749 -212.847616) (xy 60.775881 -212.883291) (xy 60.728275 -212.912345) (xy 60.676946 -212.934157)
			(xy 60.622989 -212.948263) (xy 60.567552 -212.954363) (xy 60.511818 -212.952326) (xy 60.456975 -212.942196)
			(xy 60.404191 -212.924189) (xy 60.354591 -212.898688) (xy 60.309233 -212.866237) (xy 60.269084 -212.827528)
			(xy 60.234998 -212.783385) (xy 60.207702 -212.73475) (xy 60.187779 -212.682659) (xy 60.175653 -212.628222)
			(xy 60.171582 -212.5726) (xy 58.615995 -212.5726) (xy 58.593736 -213.000336) (xy 58.413142 -216.47023)
			(xy 58.412881 -216.483991) (xy 58.418838 -216.510851) (xy 58.431745 -216.535147) (xy 58.450668 -216.555119)
			(xy 58.474233 -216.569317) (xy 58.500733 -216.576713) (xy 58.514488 -216.577164) (xy 63.238634 -216.577164)
			(xy 63.238888 -216.577164) (xy 63.249115 -216.576647) (xy 63.267909 -216.568565) (xy 63.282066 -216.553796)
			(xy 63.286132 -216.544398) (xy 63.286894 -216.542366) (xy 63.288418 -216.536016) (xy 63.500254 -215.320626)
			(xy 63.912496 -212.952584) (xy 63.913634 -212.944173) (xy 63.91092 -212.927427) (xy 63.907162 -212.919818)
			(xy 63.903352 -212.912706) (xy 63.890906 -212.901276) (xy 63.882524 -212.89772) (xy 63.85722 -212.886258)
			(xy 63.809943 -212.857095) (xy 63.76739 -212.821389) (xy 63.730459 -212.779895) (xy 63.699931 -212.733488)
			(xy 63.676448 -212.683147) (xy 63.660507 -212.629934) (xy 63.652445 -212.574974) (xy 63.651892 -212.5472)
			(xy 63.652418 -212.518406) (xy 63.661075 -212.461472) (xy 63.678194 -212.406487) (xy 63.703384 -212.354701)
			(xy 63.736074 -212.30729) (xy 63.775519 -212.265332) (xy 63.820824 -212.229782) (xy 63.870959 -212.201446)
			(xy 63.924784 -212.18097) (xy 63.981075 -212.168818) (xy 64.009778 -212.166454) (xy 64.011302 -212.166454)
			(xy 64.022341 -212.164885) (xy 64.041598 -212.153695) (xy 64.054333 -212.135423) (xy 64.056768 -212.124544)
			(xy 64.14389 -211.625688) (xy 64.165226 -211.502752) (xy 64.166088 -211.496968) (xy 64.165443 -211.485294)
			(xy 64.163956 -211.479638) (xy 64.161416 -211.47151) (xy 64.153796 -211.465922) (xy 64.115442 -211.459318)
			(xy 64.1096 -211.459572) (xy 64.097662 -211.46008) (xy 64.085216 -211.46008) (xy 64.057979 -211.459574)
			(xy 64.004063 -211.451785) (xy 63.951804 -211.436405) (xy 63.902265 -211.413747) (xy 63.856452 -211.384273)
			(xy 63.815298 -211.348581) (xy 63.77964 -211.307398) (xy 63.750203 -211.261561) (xy 63.727586 -211.212003)
			(xy 63.712249 -211.159731) (xy 63.704503 -211.10581) (xy 63.703962 -211.078572) (xy 63.70445 -211.051321)
			(xy 63.712209 -210.997375) (xy 63.727566 -210.945082) (xy 63.750209 -210.895506) (xy 63.779675 -210.849657)
			(xy 63.815366 -210.808468) (xy 63.856556 -210.772777) (xy 63.902405 -210.74331) (xy 63.95198 -210.720667)
			(xy 64.004273 -210.70531) (xy 64.058219 -210.69755) (xy 64.08547 -210.697064) (xy 64.086232 -210.697064)
			(xy 64.112415 -210.697475) (xy 64.164291 -210.704609) (xy 64.18961 -210.711288) (xy 64.199596 -210.713602)
			(xy 64.219906 -210.710976) (xy 64.22898 -210.706208) (xy 64.262 -210.68538) (xy 64.294004 -210.665314)
			(xy 64.302706 -210.659151) (xy 64.314515 -210.641426) (xy 64.316864 -210.631024) (xy 64.404494 -210.128866)
			(xy 64.501268 -209.573114) (xy 64.501902 -209.569079) (xy 64.502029 -209.560911) (xy 64.501522 -209.556858)
			(xy 64.500506 -209.55) (xy 64.497204 -209.542888) (xy 64.486079 -209.517648) (xy 64.470378 -209.464773)
			(xy 64.462423 -209.410192) (xy 64.461898 -209.382614) (xy 64.461898 -209.38236) (xy 64.462462 -209.352631)
			(xy 64.47168 -209.293892) (xy 64.489901 -209.237295) (xy 64.516683 -209.184211) (xy 64.551379 -209.135927)
			(xy 64.57188 -209.11439) (xy 64.572642 -209.113628) (xy 64.577119 -209.108592) (xy 64.583551 -209.096756)
			(xy 64.585342 -209.09026) (xy 64.646556 -208.738724) (xy 64.647128 -208.729248) (xy 64.642053 -208.710969)
			(xy 64.63665 -208.703164) (xy 64.634364 -208.70037) (xy 64.582548 -208.640934) (xy 64.574685 -208.632785)
			(xy 64.553988 -208.623669) (xy 64.54267 -208.623408) (xy 64.53251 -208.623662) (xy 64.530478 -208.623662)
			(xy 64.505317 -208.623253) (xy 64.455433 -208.616633) (xy 64.406849 -208.603523) (xy 64.360405 -208.584149)
			(xy 64.338454 -208.571846) (xy 64.332612 -208.568798) (xy 64.321798 -208.564162) (xy 64.300702 -208.553738)
			(xy 64.290448 -208.54797) (xy 64.266091 -208.53341) (xy 64.221578 -208.498217) (xy 64.201802 -208.477866)
			(xy 64.194188 -208.46967) (xy 64.179828 -208.452513) (xy 64.1731 -208.443576) (xy 64.170814 -208.440274)
			(xy 64.166975 -208.436191) (xy 64.157879 -208.429645) (xy 64.15278 -208.42732) (xy 64.147401 -208.42512)
			(xy 64.135986 -208.422951) (xy 64.130174 -208.423002) (xy 64.045338 -208.427066) (xy 64.038968 -208.427536)
			(xy 64.026758 -208.43127) (xy 64.021208 -208.434432) (xy 64.016636 -208.437226) (xy 64.008254 -208.445354)
			(xy 64.004698 -208.45145) (xy 63.989787 -208.475212) (xy 63.954096 -208.518491) (xy 63.912458 -208.556083)
			(xy 63.865768 -208.587179) (xy 63.815032 -208.61111) (xy 63.76134 -208.627361) (xy 63.705848 -208.635582)
			(xy 63.6778 -208.636108) (xy 63.650549 -208.635622) (xy 63.596601 -208.627866) (xy 63.544306 -208.612511)
			(xy 63.494729 -208.589869) (xy 63.448879 -208.560403) (xy 63.407688 -208.524712) (xy 63.371997 -208.483521)
			(xy 63.342531 -208.437671) (xy 63.319889 -208.388094) (xy 63.304534 -208.335799) (xy 63.296778 -208.281851)
			(xy 63.296778 -208.227349) (xy 63.304534 -208.173401) (xy 63.319889 -208.121106) (xy 63.342531 -208.071529)
			(xy 63.371997 -208.025679) (xy 63.407688 -207.984488) (xy 63.448879 -207.948797) (xy 63.494729 -207.919331)
			(xy 63.544306 -207.896689) (xy 63.596601 -207.881334) (xy 63.650549 -207.873578) (xy 63.6778 -207.873092)
			(xy 63.6778 -207.872838) (xy 63.707526 -207.873429) (xy 63.766253 -207.882691) (xy 63.822834 -207.900946)
			(xy 63.875902 -207.927751) (xy 63.924172 -207.962459) (xy 63.966478 -208.004231) (xy 63.984632 -208.027778)
			(xy 63.986918 -208.03108) (xy 63.990716 -208.035125) (xy 63.999687 -208.041651) (xy 64.004698 -208.044034)
			(xy 64.010137 -208.046261) (xy 64.021682 -208.048445) (xy 64.027558 -208.048352) (xy 64.111886 -208.044288)
			(xy 64.118322 -208.043845) (xy 64.130668 -208.040121) (xy 64.13627 -208.036922) (xy 64.14643 -208.030572)
			(xy 64.151002 -208.023206) (xy 64.165828 -207.999061) (xy 64.201489 -207.955034) (xy 64.243267 -207.916761)
			(xy 64.290242 -207.885084) (xy 64.341383 -207.860697) (xy 64.395567 -207.844137) (xy 64.451603 -207.835768)
			(xy 64.479932 -207.835246) (xy 64.480186 -207.835246) (xy 64.505493 -207.835639) (xy 64.555667 -207.842296)
			(xy 64.604518 -207.855535) (xy 64.651188 -207.875124) (xy 64.673226 -207.88757) (xy 64.679068 -207.890618)
			(xy 64.689888 -207.895312) (xy 64.710984 -207.905862) (xy 64.721232 -207.9117) (xy 64.729106 -207.916272)
			(xy 64.764158 -207.922368) (xy 64.765682 -207.92186) (xy 64.77635 -207.917796) (xy 64.784732 -207.907382)
			(xy 64.788672 -207.902279) (xy 64.794072 -207.890577) (xy 64.7954 -207.884268) (xy 64.808862 -207.80756)
			(xy 64.997838 -206.722218) (xy 64.998482 -206.711042) (xy 64.991271 -206.689875) (xy 64.975782 -206.673748)
			(xy 64.96558 -206.669132) (xy 64.965326 -206.669132) (xy 64.941183 -206.659473) (xy 64.895545 -206.634549)
			(xy 64.853713 -206.603661) (xy 64.816462 -206.567379) (xy 64.784481 -206.526376) (xy 64.758363 -206.481411)
			(xy 64.738592 -206.433316) (xy 64.725532 -206.382983) (xy 64.721994 -206.35722) (xy 64.720978 -206.348584)
			(xy 64.719454 -206.312516) (xy 64.719932 -206.285355) (xy 64.727634 -206.231583) (xy 64.742885 -206.179446)
			(xy 64.765376 -206.13) (xy 64.794653 -206.084243) (xy 64.830124 -206.043101) (xy 64.871071 -206.007406)
			(xy 64.916667 -205.977879) (xy 64.96599 -205.955118) (xy 65.018042 -205.939582) (xy 65.071772 -205.931586)
			(xy 65.09893 -205.931008) (xy 65.099692 -205.931008) (xy 65.112392 -205.930754) (xy 65.139824 -205.907132)
			(xy 73.997566 -155.04541) (xy 73.996042 -155.04287) (xy 73.979024 -155.025852) (xy 73.958378 -155.004472)
			(xy 73.923284 -154.956506) (xy 73.909174 -154.930348) (xy 73.895754 -154.903101) (xy 73.876752 -154.845416)
			(xy 73.867099 -154.785454) (xy 73.866502 -154.755088) (xy 73.866973 -154.728032) (xy 73.874611 -154.674461)
			(xy 73.889733 -154.622505) (xy 73.912035 -154.573202) (xy 73.941072 -154.52754) (xy 73.976262 -154.486433)
			(xy 74.016901 -154.450703) (xy 74.062175 -154.421066) (xy 74.086466 -154.40914) (xy 74.10323 -154.401266)
			(xy 74.110596 -154.39644) (xy 74.11339 -154.3812) (xy 74.11339 -154.380692) (xy 74.141076 -154.220926)
			(xy 74.14133 -154.220418) (xy 74.141584 -154.21864) (xy 74.141838 -154.217624) (xy 74.78141 -149.24532)
			(xy 75.342242 -144.885664) (xy 75.420982 -144.274032) (xy 75.42149 -144.267936) (xy 75.433428 -143.00962)
			(xy 75.437746 -142.56004) (xy 75.442064 -142.099792) (xy 75.498452 -136.127744) (xy 75.619102 -123.342146)
			(xy 75.618848 -123.327922) (xy 75.618848 -123.326398) (xy 75.619102 -123.319032) (xy 75.619102 -123.318524)
			(xy 75.679554 -116.901976) (xy 75.680645 -116.852636) (xy 75.691459 -116.754534) (xy 75.701144 -116.706142)
			(xy 75.701144 -116.705888) (xy 76.021946 -115.101878) (xy 76.104242 -114.69116) (xy 77.691488 -106.757724)
			(xy 77.691488 -106.75747) (xy 77.691742 -106.756708) (xy 77.692504 -106.753406) (xy 77.692758 -106.75239)
			(xy 77.693774 -106.74858) (xy 77.694028 -106.746802) (xy 77.695806 -106.73461) (xy 77.692758 -106.723942)
			(xy 77.690815 -106.717752) (xy 77.684259 -106.70656) (xy 77.679804 -106.701844) (xy 77.673454 -106.695494)
			(xy 77.670152 -106.693208) (xy 77.646323 -106.675091) (xy 77.604076 -106.632685) (xy 77.568964 -106.584208)
			(xy 77.541847 -106.530845) (xy 77.523388 -106.473904) (xy 77.514039 -106.414781) (xy 77.513434 -106.384852)
			(xy 77.513954 -106.356505) (xy 77.522341 -106.300434) (xy 77.538924 -106.246219) (xy 77.563339 -106.195051)
			(xy 77.595048 -106.148054) (xy 77.633356 -106.10626) (xy 77.677421 -106.070587) (xy 77.726275 -106.04182)
			(xy 77.778844 -106.020589) (xy 77.806296 -106.013504) (xy 77.808582 -106.012996) (xy 77.818234 -106.010729)
			(xy 77.834875 -105.999985) (xy 77.846171 -105.983715) (xy 77.848714 -105.974134) (xy 77.848968 -105.973118)
			(xy 77.86624 -105.88752) (xy 77.895704 -105.739184) (xy 77.981556 -105.311194) (xy 78.189582 -104.27081)
			(xy 78.190598 -104.261412) (xy 78.190598 -104.24668) (xy 78.19009 -104.244394) (xy 78.18882 -104.239314)
			(xy 78.186788 -104.232964) (xy 78.179162 -104.206491) (xy 78.170747 -104.152046) (xy 78.170024 -104.124506)
			(xy 78.170024 -104.120696) (xy 78.170481 -104.093571) (xy 78.178126 -104.039864) (xy 78.193305 -103.987782)
			(xy 78.215711 -103.938376) (xy 78.244892 -103.892645) (xy 78.262226 -103.871776) (xy 78.262734 -103.871268)
			(xy 78.265782 -103.867458) (xy 78.268288 -103.863772) (xy 78.272128 -103.855727) (xy 78.273402 -103.851456)
			(xy 78.27645 -103.837232) (xy 78.27645 -103.836724) (xy 78.35011 -103.466138) (xy 78.351233 -103.457048)
			(xy 78.347708 -103.439089) (xy 78.343252 -103.431086) (xy 78.336648 -103.422196) (xy 78.32979 -103.415338)
			(xy 78.326488 -103.413052) (xy 78.302681 -103.394922) (xy 78.26048 -103.3525) (xy 78.225412 -103.304015)
			(xy 78.198336 -103.250654) (xy 78.179914 -103.193723) (xy 78.170597 -103.134615) (xy 78.170024 -103.104696)
			(xy 78.17052 -103.076555) (xy 78.178773 -103.020883) (xy 78.195114 -102.967027) (xy 78.219189 -102.916155)
			(xy 78.250475 -102.869371) (xy 78.288294 -102.827691) (xy 78.331825 -102.792018) (xy 78.380124 -102.763126)
			(xy 78.432143 -102.741642) (xy 78.45933 -102.734364) (xy 78.464918 -102.733094) (xy 78.466696 -102.732586)
			(xy 78.4733 -102.731316) (xy 78.486 -102.724458) (xy 78.491334 -102.719124) (xy 78.494946 -102.715355)
			(xy 78.500706 -102.70665) (xy 78.502764 -102.701852) (xy 78.505304 -102.692962) (xy 78.584044 -102.300024)
			(xy 78.593696 -102.251256) (xy 78.731364 -101.562662) (xy 78.731364 -101.555296) (xy 78.730983 -101.546195)
			(xy 78.724589 -101.529152) (xy 78.718918 -101.522022) (xy 78.670912 -101.472492) (xy 78.658466 -101.459538)
			(xy 78.651144 -101.453158) (xy 78.633117 -101.445979) (xy 78.623414 -101.445568) (xy 78.615794 -101.445568)
			(xy 78.61173 -101.44633) (xy 78.596782 -101.448577) (xy 78.566647 -101.45099) (xy 78.551532 -101.451156)
			(xy 78.524274 -101.450695) (xy 78.470313 -101.442941) (xy 78.418005 -101.427586) (xy 78.368414 -101.404942)
			(xy 78.322551 -101.375471) (xy 78.28135 -101.339773) (xy 78.245648 -101.298574) (xy 78.216173 -101.252714)
			(xy 78.193525 -101.203125) (xy 78.178166 -101.150818) (xy 78.170407 -101.096858) (xy 78.170407 -101.042342)
			(xy 78.178166 -100.988382) (xy 78.193525 -100.936075) (xy 78.216173 -100.886486) (xy 78.245648 -100.840626)
			(xy 78.28135 -100.799427) (xy 78.322551 -100.763729) (xy 78.368414 -100.734258) (xy 78.418005 -100.711614)
			(xy 78.470313 -100.696259) (xy 78.524274 -100.688505) (xy 78.551532 -100.68814) (xy 78.577919 -100.688583)
			(xy 78.63019 -100.695857) (xy 78.680957 -100.710273) (xy 78.729249 -100.731557) (xy 78.751938 -100.745036)
			(xy 78.75905 -100.750624) (xy 78.78064 -100.755704) (xy 78.792832 -100.753164) (xy 78.802992 -100.749862)
			(xy 78.877922 -100.716842) (xy 78.882126 -100.714867) (xy 78.88979 -100.709623) (xy 78.893162 -100.706428)
			(xy 78.89494 -100.70465) (xy 78.895702 -100.703634) (xy 78.900219 -100.698361) (xy 78.906532 -100.686002)
			(xy 78.908148 -100.67925) (xy 79.248 -98.982022) (xy 80.252062 -93.965268) (xy 80.849216 -90.979244)
			(xy 80.849314 -90.968065) (xy 80.841084 -90.947307) (xy 80.824837 -90.93199) (xy 80.814418 -90.927936)
			(xy 80.8101 -90.92692) (xy 80.784093 -90.920219) (xy 80.734134 -90.900511) (xy 80.687428 -90.873999)
			(xy 80.644897 -90.841206) (xy 80.60738 -90.802777) (xy 80.591152 -90.781378) (xy 80.586217 -90.776145)
			(xy 80.574102 -90.768403) (xy 80.567276 -90.766138) (xy 80.560164 -90.764614) (xy 80.54467 -90.762328)
			(xy 80.539336 -90.761566) (xy 80.490822 -90.76436) (xy 80.487774 -90.764614) (xy 80.487266 -90.764868)
			(xy 80.483456 -90.765122) (xy 80.482694 -90.765376) (xy 80.478884 -90.76563) (xy 80.477106 -90.76563)
			(xy 80.473296 -90.765884) (xy 80.471518 -90.766138) (xy 80.456786 -90.767408) (xy 80.452214 -90.767662)
			(xy 80.447388 -90.76817) (xy 80.436974 -90.775282) (xy 80.43209 -90.77877) (xy 80.423994 -90.787624)
			(xy 80.420972 -90.792808) (xy 80.420464 -90.793824) (xy 80.419702 -90.795094) (xy 80.419448 -90.795602)
			(xy 80.41767 -90.79865) (xy 80.410633 -90.810363) (xy 80.395126 -90.832865) (xy 80.386682 -90.843608)
			(xy 80.368451 -90.865514) (xy 80.326596 -90.904194) (xy 80.279454 -90.936219) (xy 80.228073 -90.960876)
			(xy 80.173596 -90.977616) (xy 80.117236 -90.986069) (xy 80.08874 -90.98661) (xy 80.064092 -90.98622)
			(xy 80.015206 -90.979868) (xy 79.967545 -90.967276) (xy 79.9219 -90.948655) (xy 79.900272 -90.936826)
			(xy 79.879826 -90.924841) (xy 79.84179 -90.896567) (xy 79.807549 -90.8638) (xy 79.792322 -90.84564)
			(xy 79.791814 -90.844878) (xy 79.790036 -90.842846) (xy 79.78648 -90.83929) (xy 79.779069 -90.83261)
			(xy 79.760633 -90.825037) (xy 79.750666 -90.824558) (xy 79.742792 -90.824558) (xy 79.731773 -90.825099)
			(xy 79.711755 -90.834315) (xy 79.704184 -90.842338) (xy 79.70139 -90.845894) (xy 79.700882 -90.846656)
			(xy 79.699612 -90.848688) (xy 79.682247 -90.87511) (xy 79.641136 -90.923146) (xy 79.593564 -90.964794)
			(xy 79.540514 -90.999192) (xy 79.483081 -91.025631) (xy 79.422451 -91.043564) (xy 79.359877 -91.052622)
			(xy 79.328264 -91.053158) (xy 79.298762 -91.052677) (xy 79.240289 -91.044768) (xy 79.183403 -91.029097)
			(xy 79.129129 -91.005947) (xy 79.078446 -90.975735) (xy 79.032266 -90.939006) (xy 78.991423 -90.896421)
			(xy 78.956653 -90.848749) (xy 78.942184 -90.823034) (xy 78.938628 -90.81643) (xy 78.934818 -90.809318)
			(xy 78.921864 -90.796364) (xy 78.911958 -90.788744) (xy 78.905354 -90.785442) (xy 78.900364 -90.783544)
			(xy 78.889865 -90.781621) (xy 78.884526 -90.781632) (xy 78.876906 -90.781886) (xy 78.862428 -90.782394)
			(xy 78.85587 -90.78306) (xy 78.843394 -90.787304) (xy 78.83779 -90.790776) (xy 78.831948 -90.794586)
			(xy 78.823312 -90.804492) (xy 78.82001 -90.81135) (xy 78.807949 -90.835495) (xy 78.778063 -90.880438)
			(xy 78.742175 -90.92075) (xy 78.700994 -90.955637) (xy 78.655331 -90.98441) (xy 78.606087 -91.006502)
			(xy 78.554234 -91.021477) (xy 78.500794 -91.029039) (xy 78.473808 -91.029536) (xy 78.446424 -91.029071)
			(xy 78.392214 -91.021278) (xy 78.339664 -91.005849) (xy 78.289846 -90.983098) (xy 78.243772 -90.953489)
			(xy 78.202381 -90.917625) (xy 78.166515 -90.876234) (xy 78.136905 -90.830161) (xy 78.114154 -90.780343)
			(xy 78.098724 -90.727794) (xy 78.09093 -90.673584) (xy 78.09093 -90.618816) (xy 78.098724 -90.564606)
			(xy 78.114154 -90.512057) (xy 78.136905 -90.462239) (xy 78.166515 -90.416166) (xy 78.202381 -90.374775)
			(xy 78.243772 -90.338911) (xy 78.289846 -90.309302) (xy 78.339665 -90.286551) (xy 78.392214 -90.271122)
			(xy 78.446424 -90.263329) (xy 78.473808 -90.262964) (xy 78.502141 -90.263475) (xy 78.558189 -90.271823)
			(xy 78.612396 -90.288334) (xy 78.663579 -90.31265) (xy 78.710623 -90.34424) (xy 78.752501 -90.382414)
			(xy 78.7883 -90.426339) (xy 78.803246 -90.450416) (xy 78.806548 -90.456004) (xy 78.817216 -90.466672)
			(xy 78.824523 -90.473275) (xy 78.842688 -90.480836) (xy 78.852522 -90.481404) (xy 78.865984 -90.480896)
			(xy 78.876398 -90.480388) (xy 78.876906 -90.480388) (xy 78.880462 -90.480134) (xy 78.889754 -90.478408)
			(xy 78.906283 -90.469276) (xy 78.91272 -90.462354) (xy 78.918308 -90.455496) (xy 78.921356 -90.448384)
			(xy 78.92161 -90.447876) (xy 78.932919 -90.421276) (xy 78.961527 -90.37105) (xy 78.996481 -90.325015)
			(xy 79.037176 -90.283968) (xy 79.082909 -90.24862) (xy 79.132887 -90.219582) (xy 79.186245 -90.197358)
			(xy 79.242059 -90.182332) (xy 79.299363 -90.174764) (xy 79.328264 -90.174318) (xy 79.358006 -90.174813)
			(xy 79.416946 -90.182834) (xy 79.474269 -90.198722) (xy 79.52893 -90.222185) (xy 79.579932 -90.252798)
			(xy 79.626345 -90.290002) (xy 79.667325 -90.333118) (xy 79.685134 -90.356944) (xy 79.685388 -90.357452)
			(xy 79.688436 -90.361516) (xy 79.68869 -90.36177) (xy 79.689198 -90.362532) (xy 79.690722 -90.364564)
			(xy 79.693784 -90.36804) (xy 79.70094 -90.373922) (xy 79.704946 -90.376248) (xy 79.723488 -90.386154)
			(xy 79.731355 -90.38975) (xy 79.748498 -90.391972) (xy 79.757016 -90.390472) (xy 79.765398 -90.388694)
			(xy 79.780384 -90.379296) (xy 79.786226 -90.371676) (xy 79.805022 -90.349324) (xy 79.805784 -90.348562)
			(xy 79.82396 -90.329177) (xy 79.864751 -90.29512) (xy 79.909871 -90.267049) (xy 79.958448 -90.245509)
			(xy 80.009544 -90.230915) (xy 80.06217 -90.22355) (xy 80.08874 -90.223086) (xy 80.11816 -90.223624)
			(xy 80.176306 -90.232637) (xy 80.232382 -90.250459) (xy 80.285062 -90.276668) (xy 80.3331 -90.310645)
			(xy 80.375361 -90.351586) (xy 80.39354 -90.374724) (xy 80.395064 -90.376756) (xy 80.397096 -90.379296)
			(xy 80.407764 -90.388186) (xy 80.415892 -90.395044) (xy 80.420972 -90.397584) (xy 80.433672 -90.39987)
			(xy 80.497172 -90.39606) (xy 80.497426 -90.39606) (xy 80.500728 -90.395806) (xy 80.526382 -90.393774)
			(xy 80.532585 -90.393098) (xy 80.544409 -90.389125) (xy 80.54975 -90.3859) (xy 80.55483 -90.382598)
			(xy 80.562958 -90.373962) (xy 80.56626 -90.36812) (xy 80.582262 -90.342212) (xy 80.598264 -90.320114)
			(xy 80.60182 -90.315542) (xy 80.602836 -90.314272) (xy 80.60817 -90.30208) (xy 80.609186 -90.291412)
			(xy 80.609314 -90.286502) (xy 80.607901 -90.276783) (xy 80.606392 -90.272108) (xy 80.596486 -90.245692)
			(xy 80.596486 -90.245184) (xy 80.574896 -90.188796) (xy 80.573626 -90.185748) (xy 80.571075 -90.180582)
			(xy 80.56402 -90.171476) (xy 80.559656 -90.167714) (xy 80.55483 -90.16365) (xy 80.543146 -90.158316)
			(xy 80.536288 -90.157046) (xy 80.510133 -90.151959) (xy 80.45946 -90.135488) (xy 80.411571 -90.112126)
			(xy 80.367399 -90.082329) (xy 80.327802 -90.046676) (xy 80.293551 -90.00586) (xy 80.265313 -89.960675)
			(xy 80.243636 -89.912001) (xy 80.228942 -89.860784) (xy 80.221517 -89.808021) (xy 80.221074 -89.78138)
			(xy 80.221561 -89.754129) (xy 80.22932 -89.700183) (xy 80.244677 -89.647889) (xy 80.267319 -89.598313)
			(xy 80.296785 -89.552464) (xy 80.332476 -89.511275) (xy 80.373666 -89.475584) (xy 80.419515 -89.446118)
			(xy 80.469091 -89.423476) (xy 80.521385 -89.408119) (xy 80.575331 -89.400361) (xy 80.602582 -89.399872)
			(xy 80.631428 -89.400407) (xy 80.688462 -89.409101) (xy 80.743538 -89.426278) (xy 80.795401 -89.451548)
			(xy 80.842872 -89.484335) (xy 80.884868 -89.523892) (xy 80.920433 -89.569318) (xy 80.935068 -89.594182)
			(xy 80.937354 -89.598246) (xy 80.942942 -89.608152) (xy 80.946354 -89.613136) (xy 80.955081 -89.621479)
			(xy 80.960214 -89.624662) (xy 80.96706 -89.628303) (xy 80.982188 -89.631662) (xy 80.989932 -89.631266)
			(xy 81.0006 -89.63025) (xy 81.033112 -89.625678) (xy 81.043272 -89.624154) (xy 81.054448 -89.61755)
			(xy 81.059532 -89.61429) (xy 81.068141 -89.605827) (xy 81.071466 -89.600786) (xy 81.075276 -89.59469)
			(xy 81.07553 -89.594436) (xy 81.093818 -89.566496) (xy 81.094326 -89.565734) (xy 81.094326 -89.56548)
			(xy 81.110836 -89.544652) (xy 81.11109 -89.544398) (xy 81.111598 -89.543636) (xy 81.135728 -89.515188)
			(xy 81.138014 -89.51087) (xy 81.146142 -89.494614) (xy 81.147158 -89.492074) (xy 81.22412 -89.107772)
			(xy 81.286858 -88.794082) (xy 81.29905 -88.73363) (xy 81.29905 -88.733122) (xy 81.31302 -88.66124)
			(xy 81.313528 -88.654382) (xy 81.313528 -88.626188) (xy 81.313265 -88.6193) (xy 81.309536 -88.606036)
			(xy 81.306162 -88.600026) (xy 81.292509 -88.576877) (xy 81.270975 -88.527636) (xy 81.256376 -88.475914)
			(xy 81.248986 -88.422681) (xy 81.248504 -88.39581) (xy 81.248954 -88.368848) (xy 81.256353 -88.315435)
			(xy 81.271012 -88.263543) (xy 81.292655 -88.214154) (xy 81.320871 -88.168203) (xy 81.355127 -88.126558)
			(xy 81.394774 -88.09001) (xy 81.416652 -88.074246) (xy 81.429098 -88.06561) (xy 81.434432 -88.057736)
			(xy 81.450942 -87.975186) (xy 81.576418 -87.34806) (xy 82.288888 -83.788758) (xy 86.393528 -63.098172)
			(xy 86.394634 -63.088703) (xy 86.390517 -63.070104) (xy 86.379846 -63.054324) (xy 86.372192 -63.048642)
			(xy 86.345522 -63.031116) (xy 86.336886 -63.025782) (xy 86.334854 -63.024512) (xy 86.332822 -63.022988)
			(xy 86.331298 -63.021972) (xy 86.327947 -63.020054) (xy 86.320806 -63.017118) (xy 86.317074 -63.01613)
			(xy 86.304882 -63.014606) (xy 86.289134 -63.014606) (xy 86.279736 -63.015622) (xy 86.266274 -63.018924)
			(xy 86.261194 -63.022226) (xy 86.258654 -63.024004) (xy 86.235086 -63.039084) (xy 86.184466 -63.062921)
			(xy 86.130906 -63.079101) (xy 86.075556 -63.087277) (xy 86.04758 -63.087758) (xy 86.047072 -63.087758)
			(xy 86.032594 -63.087504) (xy 86.018878 -63.086488) (xy 85.99042 -63.083875) (xy 85.934695 -63.07121)
			(xy 85.881482 -63.050376) (xy 85.831971 -63.021838) (xy 85.787271 -62.986235) (xy 85.74838 -62.944363)
			(xy 85.71617 -62.89716) (xy 85.69136 -62.84568) (xy 85.674505 -62.791076) (xy 85.665982 -62.734569)
			(xy 85.665564 -62.705996) (xy 85.66605 -62.678744) (xy 85.673807 -62.624795) (xy 85.689162 -62.5725)
			(xy 85.711803 -62.522921) (xy 85.741269 -62.477069) (xy 85.77696 -62.435877) (xy 85.81815 -62.400183)
			(xy 85.864 -62.370715) (xy 85.913577 -62.34807) (xy 85.965872 -62.332712) (xy 86.01982 -62.324952)
			(xy 86.047072 -62.324488) (xy 86.048088 -62.324488) (xy 86.070721 -62.324825) (xy 86.11567 -62.330174)
			(xy 86.13775 -62.335156) (xy 86.141814 -62.336172) (xy 86.148926 -62.336934) (xy 86.160541 -62.337339)
			(xy 86.18221 -62.328996) (xy 86.190582 -62.320932) (xy 86.191852 -62.319408) (xy 86.251288 -62.250066)
			(xy 86.255476 -62.24471) (xy 86.261129 -62.23235) (xy 86.262464 -62.225682) (xy 86.26348 -62.21984)
			(xy 86.261956 -62.205616) (xy 86.261702 -62.204854) (xy 86.258908 -62.198504) (xy 86.24958 -62.17512)
			(xy 86.236456 -62.126517) (xy 86.229834 -62.07661) (xy 86.229444 -62.051438) (xy 86.229927 -62.024184)
			(xy 86.237679 -61.970229) (xy 86.25303 -61.917927) (xy 86.275669 -61.868342) (xy 86.305133 -61.822484)
			(xy 86.340824 -61.781285) (xy 86.382015 -61.745585) (xy 86.427867 -61.71611) (xy 86.477447 -61.69346)
			(xy 86.529745 -61.678097) (xy 86.583698 -61.670333) (xy 86.610952 -61.66993) (xy 86.632542 -61.670438)
			(xy 86.633812 -61.670438) (xy 86.645358 -61.670232) (xy 86.666408 -61.660795) (xy 86.681246 -61.64313)
			(xy 86.684612 -61.632084) (xy 86.731856 -61.393578) (xy 86.810596 -60.996576) (xy 86.811612 -60.987432)
			(xy 86.816438 -60.68187) (xy 86.81593 -60.678314) (xy 86.81472 -60.667178) (xy 86.813446 -60.644811)
			(xy 86.81339 -60.63361) (xy 86.81339 -60.63234) (xy 86.813518 -60.618383) (xy 86.815554 -60.590542)
			(xy 86.817454 -60.576714) (xy 86.817962 -60.573412) (xy 86.848442 -58.624978) (xy 86.845902 -58.613802)
			(xy 86.843616 -58.608722) (xy 86.832668 -58.583662) (xy 86.817254 -58.531194) (xy 86.809494 -58.477061)
			(xy 86.809072 -58.449718) (xy 86.809326 -58.436002) (xy 86.810342 -58.421016) (xy 86.812565 -58.396676)
			(xy 86.822469 -58.348812) (xy 86.838419 -58.30261) (xy 86.84895 -58.280554) (xy 86.85149 -58.27522)
			(xy 86.85403 -58.264552) (xy 86.938358 -52.860448) (xy 86.989666 -49.568862) (xy 86.989412 -49.565052)
			(xy 86.989158 -49.563274) (xy 85.662008 -39.7383) (xy 85.658227 -39.708655) (xy 85.653778 -39.649052)
			(xy 85.653118 -39.619174) (xy 85.652864 -39.605712) (xy 85.652356 -39.569898) (xy 85.651594 -39.523162)
			(xy 85.651086 -39.516558) (xy 85.565742 -38.931342) (xy 85.560877 -38.895855) (xy 85.555664 -38.824411)
			(xy 85.555328 -38.788594) (xy 85.555328 -38.497764) (xy 85.55355 -38.48481) (xy 85.552788 -38.481762)
			(xy 85.542439 -38.441757) (xy 85.527604 -38.36046) (xy 85.519538 -38.278215) (xy 85.518498 -38.236906)
			(xy 85.511132 -37.741352) (xy 85.511132 -37.726366) (xy 85.511729 -37.678186) (xy 85.521051 -37.582278)
			(xy 85.539578 -37.487716) (xy 85.552788 -37.441378) (xy 85.552788 -37.441124) (xy 85.555328 -37.432234)
			(xy 85.555328 -37.427916) (xy 85.554566 -37.42055) (xy 85.552534 -37.41039) (xy 85.551772 -37.405564)
			(xy 85.551264 -37.403024) (xy 85.548724 -37.397436) (xy 85.53287 -37.360044) (xy 85.506633 -37.283175)
			(xy 85.486802 -37.20441) (xy 85.473511 -37.124282) (xy 85.466851 -37.043332) (xy 85.466428 -37.00272)
			(xy 85.466428 -36.99764) (xy 85.466199 -36.990602) (xy 85.462324 -36.977071) (xy 85.458808 -36.97097)
			(xy 85.452966 -36.96335) (xy 85.452712 -36.963096) (xy 85.405468 -36.912296) (xy 85.396578 -36.908232)
			(xy 85.371432 -36.896294) (xy 85.362288 -36.895532) (xy 85.336208 -36.892796) (xy 85.285098 -36.881071)
			(xy 85.260434 -36.872164) (xy 85.237851 -36.863187) (xy 85.194974 -36.840311) (xy 85.155354 -36.812169)
			(xy 85.137244 -36.795964) (xy 85.1177 -36.777287) (xy 85.083548 -36.735382) (xy 85.055652 -36.689077)
			(xy 85.034573 -36.639297) (xy 85.020731 -36.587041) (xy 85.017102 -36.560252) (xy 85.016086 -36.55187)
			(xy 85.014562 -36.515802) (xy 85.014562 -36.515294) (xy 85.015117 -36.486405) (xy 85.02387 -36.429293)
			(xy 85.04113 -36.374152) (xy 85.066503 -36.322243) (xy 85.099409 -36.274749) (xy 85.139097 -36.232758)
			(xy 85.18466 -36.197227) (xy 85.235057 -36.168968) (xy 85.289137 -36.148627) (xy 85.345665 -36.136669)
			(xy 85.37448 -36.134548) (xy 85.385656 -36.133786) (xy 85.394292 -36.129468) (xy 85.398004 -36.1275)
			(xy 85.404773 -36.122523) (xy 85.407754 -36.119562) (xy 85.44433 -36.077652) (xy 85.445092 -36.07689)
			(xy 85.458046 -36.06165) (xy 85.459062 -36.06038) (xy 85.459824 -36.059364) (xy 85.465412 -36.052506)
			(xy 85.467952 -36.044632) (xy 85.469287 -36.039928) (xy 85.470317 -36.030206) (xy 85.469984 -36.025328)
			(xy 85.468232 -36.004226) (xy 85.466325 -35.96192) (xy 85.466174 -35.940746) (xy 85.466174 -35.940238)
			(xy 85.466428 -35.92576) (xy 85.466428 -35.601656) (xy 85.466174 -35.597084) (xy 85.46592 -35.594798)
			(xy 85.464421 -35.586336) (xy 85.456631 -35.571027) (xy 85.45068 -35.564826) (xy 85.443822 -35.55873)
			(xy 85.38718 -35.509708) (xy 85.384132 -35.507168) (xy 85.380068 -35.505644) (xy 85.358986 -35.508692)
			(xy 85.358478 -35.508692) (xy 85.339567 -35.511425) (xy 85.301584 -35.515619) (xy 85.282532 -35.517074)
			(xy 85.265919 -35.518261) (xy 85.232638 -35.519658) (xy 85.215984 -35.519868) (xy 85.20303 -35.519868)
			(xy 85.156634 -35.518989) (xy 85.064301 -35.50967) (xy 84.973233 -35.491808) (xy 84.88422 -35.465558)
			(xy 84.798033 -35.431147) (xy 84.715418 -35.388873) (xy 84.67598 -35.36442) (xy 84.673948 -35.364928)
			(xy 84.669884 -35.36569) (xy 84.652886 -35.368566) (xy 84.618543 -35.371622) (xy 84.601304 -35.371786)
			(xy 84.600796 -35.371786) (xy 84.573716 -35.371312) (xy 84.5201 -35.363654) (xy 84.468106 -35.348491)
			(xy 84.418778 -35.326129) (xy 84.373107 -35.297016) (xy 84.332012 -35.261738) (xy 84.296318 -35.221004)
			(xy 84.266742 -35.175633) (xy 84.243879 -35.126535) (xy 84.228187 -35.074698) (xy 84.219983 -35.021162)
			(xy 84.219288 -34.994088) (xy 84.219288 -34.990024) (xy 84.219797 -34.96277) (xy 84.227586 -34.90882)
			(xy 84.242953 -34.856522) (xy 84.253832 -34.831528) (xy 84.256118 -34.826448) (xy 84.257896 -34.818066)
			(xy 84.243697 -34.770172) (xy 84.223816 -34.672268) (xy 84.213815 -34.572869) (xy 84.213192 -34.522918)
			(xy 84.213192 -34.52241) (xy 84.213626 -34.479823) (xy 84.220865 -34.394958) (xy 84.235317 -34.31102)
			(xy 84.256877 -34.228621) (xy 84.285386 -34.148361) (xy 84.3026 -34.109406) (xy 84.305786 -34.100273)
			(xy 84.305789 -34.080946) (xy 84.3026 -34.071814) (xy 84.28539 -34.032858) (xy 84.256894 -33.952595)
			(xy 84.23534 -33.870195) (xy 84.220886 -33.786259) (xy 84.213636 -33.701396) (xy 84.213192 -33.65881)
			(xy 84.213682 -33.611663) (xy 84.222463 -33.517779) (xy 84.230718 -33.471358) (xy 84.236172 -33.443925)
			(xy 84.249771 -33.389664) (xy 84.257896 -33.3629) (xy 84.25688 -33.358328) (xy 84.253324 -33.34766)
			(xy 84.240234 -33.317098) (xy 84.223632 -33.252725) (xy 84.220304 -33.219644) (xy 84.220304 -33.216342)
			(xy 84.22005 -33.215834) (xy 84.219796 -33.2105) (xy 84.219796 -33.209484) (xy 84.219288 -33.194244)
			(xy 84.219288 -33.19018) (xy 84.219768 -33.163033) (xy 84.227468 -33.109289) (xy 84.242709 -33.057179)
			(xy 84.265185 -33.007756) (xy 84.29444 -32.962018) (xy 84.329883 -32.92089) (xy 84.3708 -32.885203)
			(xy 84.416362 -32.855676) (xy 84.465651 -32.832907) (xy 84.517669 -32.817356) (xy 84.571367 -32.809336)
			(xy 84.59851 -32.808672) (xy 84.601304 -32.808672) (xy 84.618544 -32.808827) (xy 84.652888 -32.811876)
			(xy 84.669884 -32.814768) (xy 84.676742 -32.816038) (xy 84.716083 -32.791746) (xy 84.798449 -32.749724)
			(xy 84.884351 -32.715507) (xy 84.973053 -32.68939) (xy 85.063791 -32.671597) (xy 85.155787 -32.662281)
			(xy 85.202014 -32.661352) (xy 85.214206 -32.661352) (xy 85.260844 -32.662072) (xy 85.353684 -32.671139)
			(xy 85.445271 -32.688836) (xy 85.534805 -32.71501) (xy 85.621504 -32.749431) (xy 85.704608 -32.791799)
			(xy 85.744304 -32.816292) (xy 85.753448 -32.814514) (xy 85.769704 -32.811974) (xy 85.779504 -32.8107)
			(xy 85.799199 -32.809049) (xy 85.809074 -32.808672) (xy 85.822536 -32.808672) (xy 85.823552 -32.808418)
			(xy 85.825076 -32.808418) (xy 85.835839 -32.808652) (xy 85.857314 -32.810179) (xy 85.868002 -32.811466)
			(xy 85.86851 -32.811466) (xy 85.886588 -32.813916) (xy 85.922208 -32.821804) (xy 85.93963 -32.827214)
			(xy 85.94344 -32.828484) (xy 85.953854 -32.830008) (xy 85.961792 -32.830543) (xy 85.977337 -32.827189)
			(xy 85.984334 -32.823404) (xy 86.059264 -32.770318) (xy 86.062058 -32.76727) (xy 86.0679 -32.759904)
			(xy 86.067392 -32.741108) (xy 86.067392 -32.722312) (xy 86.067826 -32.679725) (xy 86.075065 -32.59486)
			(xy 86.089517 -32.510922) (xy 86.111076 -32.428523) (xy 86.139586 -32.348263) (xy 86.1568 -32.309308)
			(xy 86.159986 -32.300175) (xy 86.159991 -32.280847) (xy 86.1568 -32.271716) (xy 86.139609 -32.232807)
			(xy 86.111138 -32.152642) (xy 86.089593 -32.070345) (xy 86.07513 -31.986514) (xy 86.067855 -31.901755)
			(xy 86.067392 -31.85922) (xy 86.067392 -31.822136) (xy 86.06409 -31.816802) (xy 86.060026 -31.81096)
			(xy 86.028276 -31.787592) (xy 86.027768 -31.787592) (xy 85.977984 -31.751778) (xy 85.965792 -31.75)
			(xy 85.953346 -31.747968) (xy 85.932264 -31.75508) (xy 85.922866 -31.757874) (xy 85.91169 -31.760922)
			(xy 85.889191 -31.766143) (xy 85.843344 -31.771745) (xy 85.82025 -31.772098) (xy 85.819234 -31.772098)
			(xy 85.802896 -31.771925) (xy 85.770339 -31.769125) (xy 85.75421 -31.76651) (xy 85.744558 -31.764732)
			(xy 85.704626 -31.789408) (xy 85.620965 -31.831997) (xy 85.533672 -31.866531) (xy 85.443518 -31.892705)
			(xy 85.351302 -31.910288) (xy 85.257842 -31.919124) (xy 85.210904 -31.919672) (xy 85.21065 -31.919672)
			(xy 85.210904 -31.919926) (xy 85.210396 -31.919926) (xy 85.165674 -31.919413) (xy 85.07659 -31.911382)
			(xy 84.988583 -31.895411) (xy 84.902358 -31.871629) (xy 84.818607 -31.840226) (xy 84.738002 -31.801455)
			(xy 84.699348 -31.778956) (xy 84.695792 -31.77667) (xy 84.690618 -31.774404) (xy 84.679594 -31.771959)
			(xy 84.673948 -31.771844) (xy 84.600796 -31.771844) (xy 84.573648 -31.771365) (xy 84.5199 -31.763667)
			(xy 84.467786 -31.748428) (xy 84.418359 -31.725954) (xy 84.372617 -31.6967) (xy 84.331485 -31.661256)
			(xy 84.295792 -31.62034) (xy 84.266261 -31.574777) (xy 84.243487 -31.525487) (xy 84.227931 -31.473467)
			(xy 84.219907 -31.419767) (xy 84.219288 -31.392622) (xy 84.219288 -31.389828) (xy 84.219781 -31.361597)
			(xy 84.228068 -31.305748) (xy 84.244497 -31.251731) (xy 84.256118 -31.225998) (xy 84.257896 -31.218632)
			(xy 84.243859 -31.171265) (xy 84.224097 -31.074463) (xy 84.213984 -30.976183) (xy 84.213192 -30.926786)
			(xy 84.213192 -30.922468) (xy 84.213628 -30.879882) (xy 84.220871 -30.795018) (xy 84.235326 -30.711081)
			(xy 84.256888 -30.628683) (xy 84.285401 -30.548425) (xy 84.3026 -30.509464) (xy 84.305778 -30.500331)
			(xy 84.305767 -30.48101) (xy 84.3026 -30.471872) (xy 84.285388 -30.432916) (xy 84.256887 -30.352654)
			(xy 84.235328 -30.270254) (xy 84.220869 -30.186318) (xy 84.213614 -30.101454) (xy 84.213192 -30.058868)
			(xy 84.213192 -30.05836) (xy 84.213836 -30.008319) (xy 84.223911 -29.908744) (xy 84.243894 -29.810676)
			(xy 84.25815 -29.762704) (xy 84.256372 -29.755084) (xy 84.254086 -29.750258) (xy 84.243079 -29.725168)
			(xy 84.22757 -29.672621) (xy 84.219749 -29.618394) (xy 84.219288 -29.591) (xy 84.219288 -29.590238)
			(xy 84.219749 -29.562983) (xy 84.227501 -29.509028) (xy 84.242854 -29.456725) (xy 84.265494 -29.40714)
			(xy 84.294961 -29.361282) (xy 84.330655 -29.320085) (xy 84.371848 -29.284386) (xy 84.417703 -29.254914)
			(xy 84.467286 -29.232269) (xy 84.519587 -29.21691) (xy 84.573541 -29.209152) (xy 84.600796 -29.20873)
			(xy 84.602574 -29.20873) (xy 84.619686 -29.208905) (xy 84.653774 -29.21196) (xy 84.670646 -29.214826)
			(xy 84.672424 -29.21508) (xy 84.676996 -29.215588) (xy 84.677758 -29.215588) (xy 84.71764 -29.191036)
			(xy 84.801174 -29.148679) (xy 84.888315 -29.114347) (xy 84.978293 -29.088344) (xy 85.070314 -29.070899)
			(xy 85.163566 -29.062166) (xy 85.210396 -29.061664) (xy 85.232748 -29.061918) (xy 85.277718 -29.063411)
			(xy 85.367136 -29.073499) (xy 85.45528 -29.091602) (xy 85.541435 -29.117575) (xy 85.624899 -29.151204)
			(xy 85.704994 -29.192218) (xy 85.743288 -29.215842) (xy 85.74659 -29.215842) (xy 85.764694 -29.212511)
			(xy 85.801335 -29.208953) (xy 85.819742 -29.20873) (xy 85.819996 -29.20873) (xy 85.821012 -29.20873)
			(xy 85.822536 -29.20873) (xy 85.852454 -29.209438) (xy 85.911524 -29.219013) (xy 85.940138 -29.22778)
			(xy 85.943948 -29.22905) (xy 85.953346 -29.230574) (xy 85.961697 -29.231153) (xy 85.978023 -29.227511)
			(xy 85.98535 -29.223462) (xy 86.049104 -29.177742) (xy 86.057232 -29.1719) (xy 86.060282 -29.169353)
			(xy 86.065637 -29.163482) (xy 86.0679 -29.160216) (xy 86.067392 -29.141674) (xy 86.067392 -29.12237)
			(xy 86.067828 -29.079784) (xy 86.07507 -28.99492) (xy 86.089525 -28.910983) (xy 86.111088 -28.828585)
			(xy 86.1396 -28.748327) (xy 86.1568 -28.709366) (xy 86.159978 -28.700233) (xy 86.159968 -28.680911)
			(xy 86.1568 -28.671774) (xy 86.139588 -28.632818) (xy 86.111086 -28.552556) (xy 86.089528 -28.470156)
			(xy 86.075068 -28.38622) (xy 86.067814 -28.301356) (xy 86.067392 -28.25877) (xy 86.06788 -28.211623)
			(xy 86.076654 -28.117738) (xy 86.084918 -28.071318) (xy 86.088565 -28.052831) (xy 86.097076 -28.016118)
			(xy 86.101936 -27.997912) (xy 86.112096 -27.96286) (xy 86.112096 -27.962606) (xy 86.110318 -27.954224)
			(xy 86.108032 -27.949144) (xy 86.107778 -27.948636) (xy 86.097234 -27.924428) (xy 86.082175 -27.873819)
			(xy 86.074257 -27.821614) (xy 86.073488 -27.79522) (xy 86.073488 -27.789886) (xy 86.073988 -27.762645)
			(xy 86.08177 -27.70872) (xy 86.097143 -27.656451) (xy 86.119796 -27.6069) (xy 86.149269 -27.561076)
			(xy 86.18496 -27.519911) (xy 86.226144 -27.484242) (xy 86.271985 -27.454796) (xy 86.321548 -27.43217)
			(xy 86.373825 -27.416825) (xy 86.427754 -27.409073) (xy 86.454996 -27.408632) (xy 86.471721 -27.40881)
			(xy 86.505044 -27.411732) (xy 86.521544 -27.414474) (xy 86.531196 -27.415998) (xy 86.578694 -27.387804)
			(xy 86.595966 -27.378152) (xy 86.599776 -27.368754) (xy 86.619588 -27.295348) (xy 86.619334 -27.281632)
			(xy 86.617556 -27.275028) (xy 86.613238 -27.259534) (xy 86.61019 -27.2542) (xy 86.598494 -27.232664)
			(xy 86.580075 -27.187249) (xy 86.567615 -27.139853) (xy 86.561317 -27.091251) (xy 86.560914 -27.066748)
			(xy 86.560914 -27.057604) (xy 86.561168 -27.05354) (xy 86.561168 -27.052778) (xy 86.563454 -27.022552)
			(xy 86.566558 -26.998918) (xy 86.577905 -26.95262) (xy 86.59495 -26.908104) (xy 86.605872 -26.886916)
			(xy 86.618701 -26.863799) (xy 86.64977 -26.821021) (xy 86.68645 -26.782944) (xy 86.706964 -26.766266)
			(xy 86.708996 -26.764742) (xy 86.716108 -26.757884) (xy 86.729062 -26.742136) (xy 86.731602 -26.736802)
			(xy 86.734142 -26.725118) (xy 86.730078 -26.647394) (xy 86.72957 -26.634948) (xy 86.711282 -26.603452)
			(xy 86.70671 -26.59888) (xy 86.695534 -26.58745) (xy 86.689184 -26.583132) (xy 86.667285 -26.567859)
			(xy 86.627573 -26.532173) (xy 86.593221 -26.491301) (xy 86.5649 -26.446041) (xy 86.54316 -26.397277)
			(xy 86.528428 -26.345959) (xy 86.520989 -26.293089) (xy 86.520528 -26.266394) (xy 86.521014 -26.239143)
			(xy 86.52877 -26.185195) (xy 86.544125 -26.1329) (xy 86.566767 -26.083323) (xy 86.596233 -26.037473)
			(xy 86.631924 -25.996282) (xy 86.673115 -25.960591) (xy 86.718965 -25.931125) (xy 86.768542 -25.908483)
			(xy 86.820837 -25.893128) (xy 86.874785 -25.885372) (xy 86.929287 -25.885372) (xy 86.983235 -25.893128)
			(xy 87.03553 -25.908483) (xy 87.085107 -25.931125) (xy 87.130957 -25.960591) (xy 87.172148 -25.996282)
			(xy 87.207839 -26.037473) (xy 87.237305 -26.083323) (xy 87.259947 -26.1329) (xy 87.275302 -26.185195)
			(xy 87.283058 -26.239143) (xy 87.283544 -26.266394) (xy 87.282992 -26.295552) (xy 87.274121 -26.35319)
			(xy 87.256584 -26.408808) (xy 87.230791 -26.46111) (xy 87.19734 -26.508879) (xy 87.157012 -26.551003)
			(xy 87.134192 -26.569162) (xy 87.131398 -26.571194) (xy 87.124794 -26.577798) (xy 87.120222 -26.58364)
			(xy 87.116152 -26.589982) (xy 87.111504 -26.60431) (xy 87.111078 -26.611834) (xy 87.114888 -26.69667)
			(xy 87.119714 -26.706068) (xy 87.12073 -26.708354) (xy 87.13343 -26.72969) (xy 87.137748 -26.734008)
			(xy 87.148924 -26.745438) (xy 87.155274 -26.749756) (xy 87.177134 -26.764967) (xy 87.216785 -26.800521)
			(xy 87.251101 -26.841247) (xy 87.279414 -26.886354) (xy 87.301172 -26.934963) (xy 87.315951 -26.986127)
			(xy 87.323465 -27.038851) (xy 87.32393 -27.065478) (xy 87.32393 -27.07005) (xy 87.323086 -27.100326)
			(xy 87.313003 -27.160046) (xy 87.303864 -27.188922) (xy 87.300562 -27.198828) (xy 87.30107 -27.20848)
			(xy 87.301521 -27.21357) (xy 87.304201 -27.223428) (xy 87.306404 -27.228038) (xy 87.319612 -27.254454)
			(xy 87.334344 -27.283664) (xy 87.334852 -27.284426) (xy 87.335614 -27.28595) (xy 87.339678 -27.292046)
			(xy 87.346536 -27.299158) (xy 87.351616 -27.303476) (xy 87.363554 -27.307286) (xy 87.403352 -27.320229)
			(xy 87.458668 -27.342846) (xy 94.52356 -27.342846) (xy 94.52356 -26.479246) (xy 94.52405 -26.449278)
			(xy 94.531873 -26.389856) (xy 94.547386 -26.331963) (xy 94.570322 -26.27659) (xy 94.600289 -26.224684)
			(xy 94.636776 -26.177134) (xy 94.679156 -26.134754) (xy 94.726706 -26.098267) (xy 94.778612 -26.0683)
			(xy 94.833985 -26.045364) (xy 94.891878 -26.029851) (xy 94.9513 -26.022028) (xy 95.011236 -26.022028)
			(xy 95.070658 -26.029851) (xy 95.128551 -26.045364) (xy 95.183924 -26.0683) (xy 95.23583 -26.098267)
			(xy 95.28338 -26.134754) (xy 95.32576 -26.177134) (xy 95.362247 -26.224684) (xy 95.392214 -26.27659)
			(xy 95.41515 -26.331963) (xy 95.422899 -26.360882) (xy 97.089466 -26.360882) (xy 97.093537 -26.30526)
			(xy 97.105663 -26.250823) (xy 97.125586 -26.198732) (xy 97.152882 -26.150097) (xy 97.186968 -26.105954)
			(xy 97.227117 -26.067245) (xy 97.272475 -26.034794) (xy 97.322075 -26.009293) (xy 97.374859 -25.991286)
			(xy 97.429702 -25.981156) (xy 97.485436 -25.979119) (xy 97.540873 -25.985219) (xy 97.59483 -25.999325)
			(xy 97.646159 -26.021137) (xy 97.693765 -26.050191) (xy 97.736633 -26.085866) (xy 97.77385 -26.127403)
			(xy 97.804623 -26.173916) (xy 97.828295 -26.224413) (xy 97.844363 -26.27782) (xy 97.850531 -26.319734)
			(xy 102.841804 -26.319734) (xy 102.845875 -26.264112) (xy 102.858001 -26.209675) (xy 102.877924 -26.157584)
			(xy 102.90522 -26.108949) (xy 102.939306 -26.064806) (xy 102.979455 -26.026097) (xy 103.024813 -25.993646)
			(xy 103.074413 -25.968145) (xy 103.127197 -25.950138) (xy 103.18204 -25.940008) (xy 103.237774 -25.937971)
			(xy 103.293211 -25.944071) (xy 103.347168 -25.958177) (xy 103.398497 -25.979989) (xy 103.446103 -26.009043)
			(xy 103.475768 -26.03373) (xy 121.368056 -26.03373) (xy 121.372127 -25.978108) (xy 121.384253 -25.923671)
			(xy 121.404176 -25.87158) (xy 121.431472 -25.822945) (xy 121.465558 -25.778802) (xy 121.505707 -25.740093)
			(xy 121.551065 -25.707642) (xy 121.600665 -25.682141) (xy 121.653449 -25.664134) (xy 121.708292 -25.654004)
			(xy 121.764026 -25.651967) (xy 121.819463 -25.658067) (xy 121.87342 -25.672173) (xy 121.924749 -25.693985)
			(xy 121.972355 -25.723039) (xy 122.015223 -25.758714) (xy 122.05244 -25.800251) (xy 122.083213 -25.846764)
			(xy 122.106885 -25.897261) (xy 122.122953 -25.950668) (xy 122.131073 -26.005844) (xy 122.131582 -26.03373)
			(xy 122.131073 -26.061616) (xy 122.122953 -26.116792) (xy 122.106885 -26.170199) (xy 122.083213 -26.220696)
			(xy 122.05244 -26.267209) (xy 122.015223 -26.308746) (xy 121.972355 -26.344421) (xy 121.924749 -26.373475)
			(xy 121.87342 -26.395287) (xy 121.819463 -26.409393) (xy 121.764026 -26.415493) (xy 121.708292 -26.413456)
			(xy 121.653449 -26.403326) (xy 121.600665 -26.385319) (xy 121.551065 -26.359818) (xy 121.505707 -26.327367)
			(xy 121.465558 -26.288658) (xy 121.431472 -26.244515) (xy 121.404176 -26.19588) (xy 121.384253 -26.143789)
			(xy 121.372127 -26.089352) (xy 121.368056 -26.03373) (xy 103.475768 -26.03373) (xy 103.488971 -26.044718)
			(xy 103.526188 -26.086255) (xy 103.556961 -26.132768) (xy 103.580633 -26.183265) (xy 103.596701 -26.236672)
			(xy 103.604821 -26.291848) (xy 103.60533 -26.319734) (xy 103.604821 -26.34762) (xy 103.596701 -26.402796)
			(xy 103.580633 -26.456203) (xy 103.556961 -26.5067) (xy 103.526188 -26.553213) (xy 103.488971 -26.59475)
			(xy 103.446103 -26.630425) (xy 103.398497 -26.659479) (xy 103.347168 -26.681291) (xy 103.293211 -26.695397)
			(xy 103.237774 -26.701497) (xy 103.18204 -26.69946) (xy 103.127197 -26.68933) (xy 103.074413 -26.671323)
			(xy 103.024813 -26.645822) (xy 102.979455 -26.613371) (xy 102.939306 -26.574662) (xy 102.90522 -26.530519)
			(xy 102.877924 -26.481884) (xy 102.858001 -26.429793) (xy 102.845875 -26.375356) (xy 102.841804 -26.319734)
			(xy 97.850531 -26.319734) (xy 97.852483 -26.332996) (xy 97.852992 -26.360882) (xy 97.852483 -26.388768)
			(xy 97.844363 -26.443944) (xy 97.828295 -26.497351) (xy 97.804623 -26.547848) (xy 97.77385 -26.594361)
			(xy 97.736633 -26.635898) (xy 97.693765 -26.671573) (xy 97.646159 -26.700627) (xy 97.59483 -26.722439)
			(xy 97.540873 -26.736545) (xy 97.485436 -26.742645) (xy 97.429702 -26.740608) (xy 97.374859 -26.730478)
			(xy 97.322075 -26.712471) (xy 97.272475 -26.68697) (xy 97.227117 -26.654519) (xy 97.186968 -26.61581)
			(xy 97.152882 -26.571667) (xy 97.125586 -26.523032) (xy 97.105663 -26.470941) (xy 97.093537 -26.416504)
			(xy 97.089466 -26.360882) (xy 95.422899 -26.360882) (xy 95.430663 -26.389856) (xy 95.438486 -26.449278)
			(xy 95.438976 -26.479246) (xy 95.438976 -26.971244) (xy 98.850956 -26.971244) (xy 98.855027 -26.915622)
			(xy 98.867153 -26.861185) (xy 98.887076 -26.809094) (xy 98.914372 -26.760459) (xy 98.948458 -26.716316)
			(xy 98.988607 -26.677607) (xy 99.033965 -26.645156) (xy 99.083565 -26.619655) (xy 99.136349 -26.601648)
			(xy 99.191192 -26.591518) (xy 99.246926 -26.589481) (xy 99.302363 -26.595581) (xy 99.35632 -26.609687)
			(xy 99.407649 -26.631499) (xy 99.455255 -26.660553) (xy 99.498123 -26.696228) (xy 99.53534 -26.737765)
			(xy 99.566113 -26.784278) (xy 99.589785 -26.834775) (xy 99.605853 -26.888182) (xy 99.613973 -26.943358)
			(xy 99.614482 -26.971244) (xy 99.613973 -26.99913) (xy 99.605853 -27.054306) (xy 99.589785 -27.107713)
			(xy 99.566113 -27.15821) (xy 99.53534 -27.204723) (xy 99.498123 -27.24626) (xy 99.455255 -27.281935)
			(xy 99.407649 -27.310989) (xy 99.35632 -27.332801) (xy 99.302363 -27.346907) (xy 99.246926 -27.353007)
			(xy 99.191192 -27.35097) (xy 99.136349 -27.34084) (xy 99.083565 -27.322833) (xy 99.033965 -27.297332)
			(xy 98.988607 -27.264881) (xy 98.948458 -27.226172) (xy 98.914372 -27.182029) (xy 98.887076 -27.133394)
			(xy 98.867153 -27.081303) (xy 98.855027 -27.026866) (xy 98.850956 -26.971244) (xy 95.438976 -26.971244)
			(xy 95.438976 -27.342846) (xy 95.438486 -27.372814) (xy 95.430663 -27.432236) (xy 95.41515 -27.490129)
			(xy 95.392214 -27.545502) (xy 95.362247 -27.597408) (xy 95.32576 -27.644958) (xy 95.28338 -27.687338)
			(xy 95.23583 -27.723825) (xy 95.183924 -27.753792) (xy 95.128551 -27.776728) (xy 95.070658 -27.792241)
			(xy 95.011236 -27.800064) (xy 94.9513 -27.800064) (xy 94.891878 -27.792241) (xy 94.833985 -27.776728)
			(xy 94.778612 -27.753792) (xy 94.726706 -27.723825) (xy 94.679156 -27.687338) (xy 94.636776 -27.644958)
			(xy 94.600289 -27.597408) (xy 94.570322 -27.545502) (xy 94.547386 -27.490129) (xy 94.531873 -27.432236)
			(xy 94.52405 -27.372814) (xy 94.52356 -27.342846) (xy 87.458668 -27.342846) (xy 87.480822 -27.351904)
			(xy 87.555365 -27.389961) (xy 87.591138 -27.41168) (xy 87.599774 -27.41168) (xy 87.611974 -27.410169)
			(xy 87.636504 -27.408519) (xy 87.648796 -27.408378) (xy 87.6681 -27.408886) (xy 87.677752 -27.409648)
			(xy 87.706805 -27.412388) (xy 87.763649 -27.425579) (xy 87.817818 -27.447281) (xy 87.868045 -27.476987)
			(xy 87.913157 -27.514002) (xy 87.933022 -27.535378) (xy 87.933276 -27.535632) (xy 87.940818 -27.543148)
			(xy 87.960237 -27.551822) (xy 87.970868 -27.552396) (xy 88.011 -27.552396) (xy 88.054518 -27.552857)
			(xy 88.141222 -27.560444) (xy 88.226935 -27.575561) (xy 88.311004 -27.598091) (xy 88.392789 -27.627864)
			(xy 88.471667 -27.664653) (xy 88.547039 -27.708178) (xy 88.618328 -27.758108) (xy 88.684995 -27.814062)
			(xy 88.716104 -27.844496) (xy 89.98585 -29.114242) (xy 96.847152 -29.114242) (xy 96.847152 -28.250642)
			(xy 96.847642 -28.220658) (xy 96.85547 -28.161202) (xy 96.870991 -28.103277) (xy 96.89394 -28.047873)
			(xy 96.923924 -27.995939) (xy 96.96043 -27.948363) (xy 97.002835 -27.905958) (xy 97.050411 -27.869452)
			(xy 97.102345 -27.839468) (xy 97.157749 -27.816519) (xy 97.215674 -27.800998) (xy 97.27513 -27.79317)
			(xy 97.335098 -27.79317) (xy 97.394554 -27.800998) (xy 97.452479 -27.816519) (xy 97.507883 -27.839468)
			(xy 97.559817 -27.869452) (xy 97.607393 -27.905958) (xy 97.649798 -27.948363) (xy 97.686304 -27.995939)
			(xy 97.716288 -28.047873) (xy 97.739237 -28.103277) (xy 97.754758 -28.161202) (xy 97.762586 -28.220658)
			(xy 97.763076 -28.250642) (xy 97.763076 -28.469082) (xy 101.752398 -28.469082) (xy 101.756469 -28.41346)
			(xy 101.768595 -28.359023) (xy 101.788518 -28.306932) (xy 101.815814 -28.258297) (xy 101.8499 -28.214154)
			(xy 101.890049 -28.175445) (xy 101.935407 -28.142994) (xy 101.985007 -28.117493) (xy 102.037791 -28.099486)
			(xy 102.092634 -28.089356) (xy 102.148368 -28.087319) (xy 102.203805 -28.093419) (xy 102.257762 -28.107525)
			(xy 102.309091 -28.129337) (xy 102.325147 -28.139136) (xy 118.49811 -28.139136) (xy 118.502181 -28.083514)
			(xy 118.514307 -28.029077) (xy 118.53423 -27.976986) (xy 118.561526 -27.928351) (xy 118.595612 -27.884208)
			(xy 118.635761 -27.845499) (xy 118.681119 -27.813048) (xy 118.730719 -27.787547) (xy 118.783503 -27.76954)
			(xy 118.838346 -27.75941) (xy 118.89408 -27.757373) (xy 118.949517 -27.763473) (xy 119.003474 -27.777579)
			(xy 119.054803 -27.799391) (xy 119.102409 -27.828445) (xy 119.145277 -27.86412) (xy 119.182494 -27.905657)
			(xy 119.213267 -27.95217) (xy 119.236939 -28.002667) (xy 119.253007 -28.056074) (xy 119.261127 -28.11125)
			(xy 119.261636 -28.139136) (xy 119.76811 -28.139136) (xy 119.772181 -28.083514) (xy 119.784307 -28.029077)
			(xy 119.80423 -27.976986) (xy 119.831526 -27.928351) (xy 119.865612 -27.884208) (xy 119.905761 -27.845499)
			(xy 119.951119 -27.813048) (xy 120.000719 -27.787547) (xy 120.053503 -27.76954) (xy 120.108346 -27.75941)
			(xy 120.16408 -27.757373) (xy 120.219517 -27.763473) (xy 120.273474 -27.777579) (xy 120.324803 -27.799391)
			(xy 120.372409 -27.828445) (xy 120.415277 -27.86412) (xy 120.452494 -27.905657) (xy 120.483267 -27.95217)
			(xy 120.506939 -28.002667) (xy 120.523007 -28.056074) (xy 120.531127 -28.11125) (xy 120.531636 -28.139136)
			(xy 120.531127 -28.167022) (xy 120.523007 -28.222198) (xy 120.506939 -28.275605) (xy 120.483267 -28.326102)
			(xy 120.452494 -28.372615) (xy 120.415277 -28.414152) (xy 120.372409 -28.449827) (xy 120.324803 -28.478881)
			(xy 120.273474 -28.500693) (xy 120.219517 -28.514799) (xy 120.16408 -28.520899) (xy 120.108346 -28.518862)
			(xy 120.053503 -28.508732) (xy 120.000719 -28.490725) (xy 119.951119 -28.465224) (xy 119.905761 -28.432773)
			(xy 119.865612 -28.394064) (xy 119.831526 -28.349921) (xy 119.80423 -28.301286) (xy 119.784307 -28.249195)
			(xy 119.772181 -28.194758) (xy 119.76811 -28.139136) (xy 119.261636 -28.139136) (xy 119.261127 -28.167022)
			(xy 119.253007 -28.222198) (xy 119.236939 -28.275605) (xy 119.213267 -28.326102) (xy 119.182494 -28.372615)
			(xy 119.145277 -28.414152) (xy 119.102409 -28.449827) (xy 119.054803 -28.478881) (xy 119.003474 -28.500693)
			(xy 118.949517 -28.514799) (xy 118.89408 -28.520899) (xy 118.838346 -28.518862) (xy 118.783503 -28.508732)
			(xy 118.730719 -28.490725) (xy 118.681119 -28.465224) (xy 118.635761 -28.432773) (xy 118.595612 -28.394064)
			(xy 118.561526 -28.349921) (xy 118.53423 -28.301286) (xy 118.514307 -28.249195) (xy 118.502181 -28.194758)
			(xy 118.49811 -28.139136) (xy 102.325147 -28.139136) (xy 102.356697 -28.158391) (xy 102.399565 -28.194066)
			(xy 102.436782 -28.235603) (xy 102.467555 -28.282116) (xy 102.491227 -28.332613) (xy 102.507295 -28.38602)
			(xy 102.515415 -28.441196) (xy 102.515924 -28.469082) (xy 102.515415 -28.496968) (xy 102.507295 -28.552144)
			(xy 102.491227 -28.605551) (xy 102.467555 -28.656048) (xy 102.436782 -28.702561) (xy 102.399565 -28.744098)
			(xy 102.356697 -28.779773) (xy 102.309091 -28.808827) (xy 102.257762 -28.830639) (xy 102.203805 -28.844745)
			(xy 102.148368 -28.850845) (xy 102.092634 -28.848808) (xy 102.037791 -28.838678) (xy 101.985007 -28.820671)
			(xy 101.935407 -28.79517) (xy 101.890049 -28.762719) (xy 101.8499 -28.72401) (xy 101.815814 -28.679867)
			(xy 101.788518 -28.631232) (xy 101.768595 -28.579141) (xy 101.756469 -28.524704) (xy 101.752398 -28.469082)
			(xy 97.763076 -28.469082) (xy 97.763076 -29.114242) (xy 97.762586 -29.144226) (xy 97.754758 -29.203682)
			(xy 97.739237 -29.261607) (xy 97.716288 -29.317011) (xy 97.686304 -29.368945) (xy 97.649798 -29.416521)
			(xy 97.607393 -29.458926) (xy 97.559817 -29.495432) (xy 97.507883 -29.525416) (xy 97.452479 -29.548365)
			(xy 97.394554 -29.563886) (xy 97.335098 -29.571714) (xy 97.27513 -29.571714) (xy 97.215674 -29.563886)
			(xy 97.157749 -29.548365) (xy 97.102345 -29.525416) (xy 97.050411 -29.495432) (xy 97.002835 -29.458926)
			(xy 96.96043 -29.416521) (xy 96.923924 -29.368945) (xy 96.89394 -29.317011) (xy 96.870991 -29.261607)
			(xy 96.85547 -29.203682) (xy 96.847642 -29.144226) (xy 96.847152 -29.114242) (xy 89.98585 -29.114242)
			(xy 91.256866 -30.385258) (xy 91.290559 -30.41975) (xy 91.351843 -30.494199) (xy 91.405655 -30.574217)
			(xy 91.451492 -30.659054) (xy 91.470734 -30.703266) (xy 91.562515 -30.92069) (xy 99.48926 -30.92069)
			(xy 99.48926 -30.05709) (xy 99.48975 -30.027106) (xy 99.497578 -29.96765) (xy 99.513099 -29.909725)
			(xy 99.536048 -29.854321) (xy 99.566032 -29.802387) (xy 99.602538 -29.754811) (xy 99.644943 -29.712406)
			(xy 99.692519 -29.6759) (xy 99.744453 -29.645916) (xy 99.799857 -29.622967) (xy 99.857782 -29.607446)
			(xy 99.917238 -29.599618) (xy 99.977206 -29.599618) (xy 100.036662 -29.607446) (xy 100.094587 -29.622967)
			(xy 100.149991 -29.645916) (xy 100.201925 -29.6759) (xy 100.249501 -29.712406) (xy 100.291906 -29.754811)
			(xy 100.328412 -29.802387) (xy 100.358396 -29.854321) (xy 100.381345 -29.909725) (xy 100.396866 -29.96765)
			(xy 100.404694 -30.027106) (xy 100.405184 -30.05709) (xy 100.405184 -30.376876) (xy 116.989098 -30.376876)
			(xy 116.989672 -30.347961) (xy 116.998389 -30.290793) (xy 117.015636 -30.235595) (xy 117.041017 -30.183633)
			(xy 117.073951 -30.136098) (xy 117.113683 -30.094078) (xy 117.136164 -30.075886) (xy 117.144978 -30.068286)
			(xy 117.155155 -30.047379) (xy 117.155722 -30.035754) (xy 117.155722 -29.955998) (xy 117.155162 -29.944369)
			(xy 117.144987 -29.92346) (xy 117.136164 -29.915866) (xy 117.113657 -29.897703) (xy 117.073925 -29.855677)
			(xy 117.04099 -29.808135) (xy 117.015606 -29.756169) (xy 116.998354 -29.700967) (xy 116.98963 -29.643794)
			(xy 116.989098 -29.614876) (xy 116.989584 -29.587625) (xy 116.99734 -29.533677) (xy 117.012695 -29.481382)
			(xy 117.035337 -29.431805) (xy 117.064803 -29.385955) (xy 117.100494 -29.344764) (xy 117.141685 -29.309073)
			(xy 117.187535 -29.279607) (xy 117.237112 -29.256965) (xy 117.289407 -29.24161) (xy 117.343355 -29.233854)
			(xy 117.397857 -29.233854) (xy 117.451805 -29.24161) (xy 117.5041 -29.256965) (xy 117.553677 -29.279607)
			(xy 117.599527 -29.309073) (xy 117.640718 -29.344764) (xy 117.676409 -29.385955) (xy 117.705875 -29.431805)
			(xy 117.728517 -29.481382) (xy 117.743872 -29.533677) (xy 117.751628 -29.587625) (xy 117.752114 -29.614876)
			(xy 117.751611 -29.643794) (xy 117.742884 -29.700967) (xy 117.725625 -29.756168) (xy 117.70023 -29.80813)
			(xy 117.667282 -29.855663) (xy 117.627536 -29.897678) (xy 117.605048 -29.915866) (xy 117.596257 -29.923489)
			(xy 117.586067 -29.944378) (xy 117.58549 -29.955998) (xy 117.58549 -30.035754) (xy 117.586016 -30.047387)
			(xy 117.596215 -30.068296) (xy 117.605048 -30.075886) (xy 117.627535 -30.094073) (xy 117.667268 -30.136095)
			(xy 117.700205 -30.183631) (xy 117.725592 -30.235593) (xy 117.742848 -30.290791) (xy 117.751578 -30.34796)
			(xy 117.752114 -30.376876) (xy 120.029224 -30.376876) (xy 120.029788 -30.347961) (xy 120.038506 -30.290791)
			(xy 120.055754 -30.235593) (xy 120.081137 -30.183631) (xy 120.114073 -30.136096) (xy 120.153808 -30.094077)
			(xy 120.17629 -30.075886) (xy 120.185092 -30.068274) (xy 120.195279 -30.047377) (xy 120.195848 -30.035754)
			(xy 120.195848 -29.955998) (xy 120.195314 -29.944365) (xy 120.185123 -29.923454) (xy 120.17629 -29.915866)
			(xy 120.153788 -29.897697) (xy 120.114055 -29.855672) (xy 120.081118 -29.808133) (xy 120.055733 -29.756167)
			(xy 120.038481 -29.700966) (xy 120.029756 -29.643793) (xy 120.029224 -29.614876) (xy 120.02971 -29.587625)
			(xy 120.037466 -29.533677) (xy 120.052821 -29.481382) (xy 120.075463 -29.431805) (xy 120.104929 -29.385955)
			(xy 120.14062 -29.344764) (xy 120.181811 -29.309073) (xy 120.227661 -29.279607) (xy 120.277238 -29.256965)
			(xy 120.329533 -29.24161) (xy 120.383481 -29.233854) (xy 120.437983 -29.233854) (xy 120.491931 -29.24161)
			(xy 120.544226 -29.256965) (xy 120.593803 -29.279607) (xy 120.639653 -29.309073) (xy 120.680844 -29.344764)
			(xy 120.716535 -29.385955) (xy 120.746001 -29.431805) (xy 120.768643 -29.481382) (xy 120.783998 -29.533677)
			(xy 120.791754 -29.587625) (xy 120.79224 -29.614876) (xy 120.791727 -29.643793) (xy 120.783 -29.700966)
			(xy 120.765743 -29.756166) (xy 120.74035 -29.808128) (xy 120.707405 -29.855662) (xy 120.667661 -29.897677)
			(xy 120.645174 -29.915866) (xy 120.636388 -29.923493) (xy 120.626194 -29.944379) (xy 120.625616 -29.955998)
			(xy 120.625616 -30.035754) (xy 120.626133 -30.047389) (xy 120.636337 -30.068298) (xy 120.645174 -30.075886)
			(xy 120.667645 -30.094092) (xy 120.707382 -30.136107) (xy 120.740324 -30.183639) (xy 120.765714 -30.235598)
			(xy 120.782973 -30.290793) (xy 120.791704 -30.347961) (xy 120.79224 -30.376876) (xy 120.791754 -30.404127)
			(xy 120.783998 -30.458075) (xy 120.768643 -30.51037) (xy 120.746001 -30.559947) (xy 120.716535 -30.605797)
			(xy 120.680844 -30.646988) (xy 120.639653 -30.682679) (xy 120.593803 -30.712145) (xy 120.544226 -30.734787)
			(xy 120.491931 -30.750142) (xy 120.437983 -30.757898) (xy 120.383481 -30.757898) (xy 120.329533 -30.750142)
			(xy 120.277238 -30.734787) (xy 120.227661 -30.712145) (xy 120.181811 -30.682679) (xy 120.14062 -30.646988)
			(xy 120.104929 -30.605797) (xy 120.075463 -30.559947) (xy 120.052821 -30.51037) (xy 120.037466 -30.458075)
			(xy 120.02971 -30.404127) (xy 120.029224 -30.376876) (xy 117.752114 -30.376876) (xy 117.751628 -30.404127)
			(xy 117.743872 -30.458075) (xy 117.728517 -30.51037) (xy 117.705875 -30.559947) (xy 117.676409 -30.605797)
			(xy 117.640718 -30.646988) (xy 117.599527 -30.682679) (xy 117.553677 -30.712145) (xy 117.5041 -30.734787)
			(xy 117.451805 -30.750142) (xy 117.397857 -30.757898) (xy 117.343355 -30.757898) (xy 117.289407 -30.750142)
			(xy 117.237112 -30.734787) (xy 117.187535 -30.712145) (xy 117.141685 -30.682679) (xy 117.100494 -30.646988)
			(xy 117.064803 -30.605797) (xy 117.035337 -30.559947) (xy 117.012695 -30.51037) (xy 116.99734 -30.458075)
			(xy 116.989584 -30.404127) (xy 116.989098 -30.376876) (xy 100.405184 -30.376876) (xy 100.405184 -30.92069)
			(xy 100.404694 -30.950674) (xy 100.396866 -31.01013) (xy 100.381345 -31.068055) (xy 100.358396 -31.123459)
			(xy 100.328412 -31.175393) (xy 100.291906 -31.222969) (xy 100.249501 -31.265374) (xy 100.201925 -31.30188)
			(xy 100.149991 -31.331864) (xy 100.094587 -31.354813) (xy 100.036662 -31.370334) (xy 99.977206 -31.378162)
			(xy 99.917238 -31.378162) (xy 99.857782 -31.370334) (xy 99.799857 -31.354813) (xy 99.744453 -31.331864)
			(xy 99.692519 -31.30188) (xy 99.644943 -31.265374) (xy 99.602538 -31.222969) (xy 99.566032 -31.175393)
			(xy 99.536048 -31.123459) (xy 99.513099 -31.068055) (xy 99.497578 -31.01013) (xy 99.48975 -30.950674)
			(xy 99.48926 -30.92069) (xy 91.562515 -30.92069) (xy 91.596718 -31.001716) (xy 91.599258 -31.005526)
			(xy 91.62497 -31.045427) (xy 91.669497 -31.129266) (xy 91.688158 -31.172912) (xy 92.326866 -32.714184)
			(xy 96.847152 -32.714184) (xy 96.847152 -31.850584) (xy 96.847642 -31.8206) (xy 96.85547 -31.761144)
			(xy 96.870991 -31.703219) (xy 96.89394 -31.647815) (xy 96.923924 -31.595881) (xy 96.96043 -31.548305)
			(xy 97.002835 -31.5059) (xy 97.050411 -31.469394) (xy 97.102345 -31.43941) (xy 97.157749 -31.416461)
			(xy 97.215674 -31.40094) (xy 97.27513 -31.393112) (xy 97.335098 -31.393112) (xy 97.394554 -31.40094)
			(xy 97.452479 -31.416461) (xy 97.507883 -31.43941) (xy 97.559817 -31.469394) (xy 97.607393 -31.5059)
			(xy 97.649798 -31.548305) (xy 97.66482 -31.567882) (xy 117.098824 -31.567882) (xy 117.102895 -31.51226)
			(xy 117.115021 -31.457823) (xy 117.134944 -31.405732) (xy 117.16224 -31.357097) (xy 117.196326 -31.312954)
			(xy 117.236475 -31.274245) (xy 117.281833 -31.241794) (xy 117.331433 -31.216293) (xy 117.384217 -31.198286)
			(xy 117.43906 -31.188156) (xy 117.494794 -31.186119) (xy 117.550231 -31.192219) (xy 117.604188 -31.206325)
			(xy 117.655517 -31.228137) (xy 117.703123 -31.257191) (xy 117.745991 -31.292866) (xy 117.783208 -31.334403)
			(xy 117.813981 -31.380916) (xy 117.837653 -31.431413) (xy 117.853721 -31.48482) (xy 117.861841 -31.539996)
			(xy 117.86235 -31.567882) (xy 117.861841 -31.595768) (xy 117.853721 -31.650944) (xy 117.837653 -31.704351)
			(xy 117.830661 -31.719266) (xy 118.385588 -31.719266) (xy 118.389659 -31.663644) (xy 118.401785 -31.609207)
			(xy 118.421708 -31.557116) (xy 118.449004 -31.508481) (xy 118.48309 -31.464338) (xy 118.523239 -31.425629)
			(xy 118.568597 -31.393178) (xy 118.618197 -31.367677) (xy 118.670981 -31.34967) (xy 118.725824 -31.33954)
			(xy 118.781558 -31.337503) (xy 118.836995 -31.343603) (xy 118.890952 -31.357709) (xy 118.942281 -31.379521)
			(xy 118.989887 -31.408575) (xy 119.032755 -31.44425) (xy 119.069972 -31.485787) (xy 119.100745 -31.5323)
			(xy 119.124417 -31.582797) (xy 119.140485 -31.636204) (xy 119.144635 -31.664402) (xy 119.661176 -31.664402)
			(xy 119.665247 -31.60878) (xy 119.677373 -31.554343) (xy 119.697296 -31.502252) (xy 119.724592 -31.453617)
			(xy 119.758678 -31.409474) (xy 119.798827 -31.370765) (xy 119.844185 -31.338314) (xy 119.893785 -31.312813)
			(xy 119.946569 -31.294806) (xy 120.001412 -31.284676) (xy 120.057146 -31.282639) (xy 120.112583 -31.288739)
			(xy 120.16654 -31.302845) (xy 120.217869 -31.324657) (xy 120.265475 -31.353711) (xy 120.308343 -31.389386)
			(xy 120.34556 -31.430923) (xy 120.376333 -31.477436) (xy 120.400005 -31.527933) (xy 120.416073 -31.58134)
			(xy 120.424193 -31.636516) (xy 120.424702 -31.664402) (xy 120.424193 -31.692288) (xy 120.416073 -31.747464)
			(xy 120.407133 -31.777178) (xy 120.92635 -31.777178) (xy 120.930421 -31.721556) (xy 120.942547 -31.667119)
			(xy 120.96247 -31.615028) (xy 120.989766 -31.566393) (xy 121.023852 -31.52225) (xy 121.064001 -31.483541)
			(xy 121.109359 -31.45109) (xy 121.158959 -31.425589) (xy 121.211743 -31.407582) (xy 121.266586 -31.397452)
			(xy 121.32232 -31.395415) (xy 121.377757 -31.401515) (xy 121.431714 -31.415621) (xy 121.483043 -31.437433)
			(xy 121.530649 -31.466487) (xy 121.573517 -31.502162) (xy 121.610734 -31.543699) (xy 121.641507 -31.590212)
			(xy 121.665179 -31.640709) (xy 121.681247 -31.694116) (xy 121.689367 -31.749292) (xy 121.689876 -31.777178)
			(xy 121.689367 -31.805064) (xy 121.681247 -31.86024) (xy 121.665179 -31.913647) (xy 121.641507 -31.964144)
			(xy 121.610734 -32.010657) (xy 121.573517 -32.052194) (xy 121.530649 -32.087869) (xy 121.483043 -32.116923)
			(xy 121.431714 -32.138735) (xy 121.377757 -32.152841) (xy 121.32232 -32.158941) (xy 121.266586 -32.156904)
			(xy 121.211743 -32.146774) (xy 121.158959 -32.128767) (xy 121.109359 -32.103266) (xy 121.064001 -32.070815)
			(xy 121.023852 -32.032106) (xy 120.989766 -31.987963) (xy 120.96247 -31.939328) (xy 120.942547 -31.887237)
			(xy 120.930421 -31.8328) (xy 120.92635 -31.777178) (xy 120.407133 -31.777178) (xy 120.400005 -31.800871)
			(xy 120.376333 -31.851368) (xy 120.34556 -31.897881) (xy 120.308343 -31.939418) (xy 120.265475 -31.975093)
			(xy 120.217869 -32.004147) (xy 120.16654 -32.025959) (xy 120.112583 -32.040065) (xy 120.057146 -32.046165)
			(xy 120.001412 -32.044128) (xy 119.946569 -32.033998) (xy 119.893785 -32.015991) (xy 119.844185 -31.99049)
			(xy 119.798827 -31.958039) (xy 119.758678 -31.91933) (xy 119.724592 -31.875187) (xy 119.697296 -31.826552)
			(xy 119.677373 -31.774461) (xy 119.665247 -31.720024) (xy 119.661176 -31.664402) (xy 119.144635 -31.664402)
			(xy 119.148605 -31.69138) (xy 119.149114 -31.719266) (xy 119.148605 -31.747152) (xy 119.140485 -31.802328)
			(xy 119.124417 -31.855735) (xy 119.100745 -31.906232) (xy 119.069972 -31.952745) (xy 119.032755 -31.994282)
			(xy 118.989887 -32.029957) (xy 118.942281 -32.059011) (xy 118.890952 -32.080823) (xy 118.836995 -32.094929)
			(xy 118.781558 -32.101029) (xy 118.725824 -32.098992) (xy 118.670981 -32.088862) (xy 118.618197 -32.070855)
			(xy 118.568597 -32.045354) (xy 118.523239 -32.012903) (xy 118.48309 -31.974194) (xy 118.449004 -31.930051)
			(xy 118.421708 -31.881416) (xy 118.401785 -31.829325) (xy 118.389659 -31.774888) (xy 118.385588 -31.719266)
			(xy 117.830661 -31.719266) (xy 117.813981 -31.754848) (xy 117.783208 -31.801361) (xy 117.745991 -31.842898)
			(xy 117.703123 -31.878573) (xy 117.655517 -31.907627) (xy 117.604188 -31.929439) (xy 117.550231 -31.943545)
			(xy 117.494794 -31.949645) (xy 117.43906 -31.947608) (xy 117.384217 -31.937478) (xy 117.331433 -31.919471)
			(xy 117.281833 -31.89397) (xy 117.236475 -31.861519) (xy 117.196326 -31.82281) (xy 117.16224 -31.778667)
			(xy 117.134944 -31.730032) (xy 117.115021 -31.677941) (xy 117.102895 -31.623504) (xy 117.098824 -31.567882)
			(xy 97.66482 -31.567882) (xy 97.686304 -31.595881) (xy 97.716288 -31.647815) (xy 97.739237 -31.703219)
			(xy 97.754758 -31.761144) (xy 97.762586 -31.8206) (xy 97.763076 -31.850584) (xy 97.763076 -32.714184)
			(xy 97.762586 -32.744168) (xy 97.754758 -32.803624) (xy 97.739237 -32.861549) (xy 97.716288 -32.916953)
			(xy 97.686304 -32.968887) (xy 97.649798 -33.016463) (xy 97.607393 -33.058868) (xy 97.559817 -33.095374)
			(xy 97.507883 -33.125358) (xy 97.452479 -33.148307) (xy 97.394554 -33.163828) (xy 97.335098 -33.171656)
			(xy 97.27513 -33.171656) (xy 97.215674 -33.163828) (xy 97.157749 -33.148307) (xy 97.102345 -33.125358)
			(xy 97.050411 -33.095374) (xy 97.002835 -33.058868) (xy 96.96043 -33.016463) (xy 96.923924 -32.968887)
			(xy 96.89394 -32.916953) (xy 96.870991 -32.861549) (xy 96.85547 -32.803624) (xy 96.847642 -32.744168)
			(xy 96.847152 -32.714184) (xy 92.326866 -32.714184) (xy 92.366338 -32.809434) (xy 92.368202 -32.813769)
			(xy 92.373313 -32.8217) (xy 92.376498 -32.825182) (xy 92.382848 -32.831786) (xy 92.394024 -32.83712)
			(xy 92.395294 -32.837628) (xy 92.395802 -32.837882) (xy 92.398342 -32.838898) (xy 92.422336 -32.849604)
			(xy 92.467382 -32.876645) (xy 92.508293 -32.90961) (xy 92.544294 -32.947877) (xy 92.574704 -32.990722)
			(xy 92.598949 -33.037333) (xy 92.616569 -33.08683) (xy 92.62237 -33.112456) (xy 92.623386 -33.117536)
			(xy 92.623386 -33.11779) (xy 92.625672 -33.128458) (xy 92.627704 -33.14446) (xy 92.630244 -33.181036)
			(xy 92.630244 -33.200594) (xy 92.629482 -33.216596) (xy 92.629482 -33.217104) (xy 92.628466 -33.233614)
			(xy 92.627704 -33.239202) (xy 92.627196 -33.242758) (xy 92.627196 -33.243266) (xy 92.62366 -33.265396)
			(xy 92.612076 -33.30869) (xy 92.604082 -33.329626) (xy 92.60078 -33.3375) (xy 92.598748 -33.347152)
			(xy 92.598748 -33.34766) (xy 92.597478 -33.360614) (xy 92.59773 -33.364181) (xy 92.599132 -33.371194)
			(xy 92.600272 -33.374584) (xy 92.738448 -33.708594) (xy 92.742258 -33.717738) (xy 92.827094 -33.921954)
			(xy 92.827094 -33.922462) (xy 93.079268 -34.520886) (xy 99.48926 -34.520886) (xy 99.48926 -33.657286)
			(xy 99.48975 -33.627302) (xy 99.497578 -33.567846) (xy 99.513099 -33.509921) (xy 99.536048 -33.454517)
			(xy 99.566032 -33.402583) (xy 99.602538 -33.355007) (xy 99.644943 -33.312602) (xy 99.692519 -33.276096)
			(xy 99.744453 -33.246112) (xy 99.799857 -33.223163) (xy 99.857782 -33.207642) (xy 99.917238 -33.199814)
			(xy 99.977206 -33.199814) (xy 100.036662 -33.207642) (xy 100.094587 -33.223163) (xy 100.149991 -33.246112)
			(xy 100.201925 -33.276096) (xy 100.249501 -33.312602) (xy 100.291906 -33.355007) (xy 100.328412 -33.402583)
			(xy 100.358396 -33.454517) (xy 100.381345 -33.509921) (xy 100.396866 -33.567846) (xy 100.404694 -33.627302)
			(xy 100.405184 -33.657286) (xy 100.405184 -34.520886) (xy 100.404694 -34.55087) (xy 100.396866 -34.610326)
			(xy 100.381345 -34.668251) (xy 100.358396 -34.723655) (xy 100.328412 -34.775589) (xy 100.291906 -34.823165)
			(xy 100.249501 -34.86557) (xy 100.201925 -34.902076) (xy 100.149991 -34.93206) (xy 100.094587 -34.955009)
			(xy 100.036662 -34.97053) (xy 99.977206 -34.978358) (xy 99.917238 -34.978358) (xy 99.857782 -34.97053)
			(xy 99.799857 -34.955009) (xy 99.744453 -34.93206) (xy 99.692519 -34.902076) (xy 99.644943 -34.86557)
			(xy 99.602538 -34.823165) (xy 99.566032 -34.775589) (xy 99.536048 -34.723655) (xy 99.513099 -34.668251)
			(xy 99.497578 -34.610326) (xy 99.48975 -34.55087) (xy 99.48926 -34.520886) (xy 93.079268 -34.520886)
			(xy 93.28531 -35.009836) (xy 93.392711 -35.264852) (xy 120.002552 -35.264852) (xy 120.006623 -35.20923)
			(xy 120.018749 -35.154793) (xy 120.038672 -35.102702) (xy 120.065968 -35.054067) (xy 120.100054 -35.009924)
			(xy 120.140203 -34.971215) (xy 120.185561 -34.938764) (xy 120.235161 -34.913263) (xy 120.287945 -34.895256)
			(xy 120.342788 -34.885126) (xy 120.398522 -34.883089) (xy 120.453959 -34.889189) (xy 120.507916 -34.903295)
			(xy 120.559245 -34.925107) (xy 120.606851 -34.954161) (xy 120.649719 -34.989836) (xy 120.686936 -35.031373)
			(xy 120.717709 -35.077886) (xy 120.741381 -35.128383) (xy 120.757449 -35.18179) (xy 120.765569 -35.236966)
			(xy 120.766078 -35.264852) (xy 120.765569 -35.292738) (xy 120.757449 -35.347914) (xy 120.741381 -35.401321)
			(xy 120.717709 -35.451818) (xy 120.686936 -35.498331) (xy 120.649719 -35.539868) (xy 120.606851 -35.575543)
			(xy 120.559245 -35.604597) (xy 120.507916 -35.626409) (xy 120.453959 -35.640515) (xy 120.398522 -35.646615)
			(xy 120.342788 -35.644578) (xy 120.287945 -35.634448) (xy 120.235161 -35.616441) (xy 120.185561 -35.59094)
			(xy 120.140203 -35.558489) (xy 120.100054 -35.51978) (xy 120.065968 -35.475637) (xy 120.038672 -35.427002)
			(xy 120.018749 -35.374911) (xy 120.006623 -35.320474) (xy 120.002552 -35.264852) (xy 93.392711 -35.264852)
			(xy 93.65041 -35.876738) (xy 108.817408 -35.876738) (xy 108.821479 -35.821116) (xy 108.833605 -35.766679)
			(xy 108.853528 -35.714588) (xy 108.880824 -35.665953) (xy 108.91491 -35.62181) (xy 108.955059 -35.583101)
			(xy 109.000417 -35.55065) (xy 109.050017 -35.525149) (xy 109.102801 -35.507142) (xy 109.157644 -35.497012)
			(xy 109.213378 -35.494975) (xy 109.268815 -35.501075) (xy 109.322772 -35.515181) (xy 109.374101 -35.536993)
			(xy 109.421707 -35.566047) (xy 109.464575 -35.601722) (xy 109.501792 -35.643259) (xy 109.532565 -35.689772)
			(xy 109.556237 -35.740269) (xy 109.572305 -35.793676) (xy 109.580425 -35.848852) (xy 109.580934 -35.876738)
			(xy 112.889028 -35.876738) (xy 112.893099 -35.821116) (xy 112.905225 -35.766679) (xy 112.925148 -35.714588)
			(xy 112.952444 -35.665953) (xy 112.98653 -35.62181) (xy 113.026679 -35.583101) (xy 113.072037 -35.55065)
			(xy 113.121637 -35.525149) (xy 113.174421 -35.507142) (xy 113.229264 -35.497012) (xy 113.284998 -35.494975)
			(xy 113.340435 -35.501075) (xy 113.394392 -35.515181) (xy 113.445721 -35.536993) (xy 113.493327 -35.566047)
			(xy 113.536195 -35.601722) (xy 113.573412 -35.643259) (xy 113.604185 -35.689772) (xy 113.627857 -35.740269)
			(xy 113.643925 -35.793676) (xy 113.652045 -35.848852) (xy 113.652554 -35.876738) (xy 113.652045 -35.904624)
			(xy 113.643925 -35.9598) (xy 113.627857 -36.013207) (xy 113.604185 -36.063704) (xy 113.573412 -36.110217)
			(xy 113.536195 -36.151754) (xy 113.493327 -36.187429) (xy 113.445721 -36.216483) (xy 113.394392 -36.238295)
			(xy 113.340435 -36.252401) (xy 113.284998 -36.258501) (xy 113.229264 -36.256464) (xy 113.174421 -36.246334)
			(xy 113.121637 -36.228327) (xy 113.072037 -36.202826) (xy 113.026679 -36.170375) (xy 112.98653 -36.131666)
			(xy 112.952444 -36.087523) (xy 112.925148 -36.038888) (xy 112.905225 -35.986797) (xy 112.893099 -35.93236)
			(xy 112.889028 -35.876738) (xy 109.580934 -35.876738) (xy 109.580425 -35.904624) (xy 109.572305 -35.9598)
			(xy 109.556237 -36.013207) (xy 109.532565 -36.063704) (xy 109.501792 -36.110217) (xy 109.464575 -36.151754)
			(xy 109.421707 -36.187429) (xy 109.374101 -36.216483) (xy 109.322772 -36.238295) (xy 109.268815 -36.252401)
			(xy 109.213378 -36.258501) (xy 109.157644 -36.256464) (xy 109.102801 -36.246334) (xy 109.050017 -36.228327)
			(xy 109.000417 -36.202826) (xy 108.955059 -36.170375) (xy 108.91491 -36.131666) (xy 108.880824 -36.087523)
			(xy 108.853528 -36.038888) (xy 108.833605 -35.986797) (xy 108.821479 -35.93236) (xy 108.817408 -35.876738)
			(xy 93.65041 -35.876738) (xy 93.917095 -36.50996) (xy 110.714026 -36.50996) (xy 110.718097 -36.454338)
			(xy 110.730223 -36.399901) (xy 110.750146 -36.34781) (xy 110.777442 -36.299175) (xy 110.811528 -36.255032)
			(xy 110.851677 -36.216323) (xy 110.897035 -36.183872) (xy 110.946635 -36.158371) (xy 110.999419 -36.140364)
			(xy 111.054262 -36.130234) (xy 111.109996 -36.128197) (xy 111.165433 -36.134297) (xy 111.21939 -36.148403)
			(xy 111.270719 -36.170215) (xy 111.318325 -36.199269) (xy 111.361193 -36.234944) (xy 111.39841 -36.276481)
			(xy 111.429183 -36.322994) (xy 111.452855 -36.373491) (xy 111.468923 -36.426898) (xy 111.472848 -36.453572)
			(xy 114.028726 -36.453572) (xy 114.032797 -36.39795) (xy 114.044923 -36.343513) (xy 114.064846 -36.291422)
			(xy 114.092142 -36.242787) (xy 114.126228 -36.198644) (xy 114.166377 -36.159935) (xy 114.211735 -36.127484)
			(xy 114.261335 -36.101983) (xy 114.314119 -36.083976) (xy 114.368962 -36.073846) (xy 114.424696 -36.071809)
			(xy 114.480133 -36.077909) (xy 114.53409 -36.092015) (xy 114.585419 -36.113827) (xy 114.633025 -36.142881)
			(xy 114.675893 -36.178556) (xy 114.71311 -36.220093) (xy 114.743883 -36.266606) (xy 114.753419 -36.286948)
			(xy 121.300492 -36.286948) (xy 121.304563 -36.231326) (xy 121.316689 -36.176889) (xy 121.336612 -36.124798)
			(xy 121.363908 -36.076163) (xy 121.397994 -36.03202) (xy 121.438143 -35.993311) (xy 121.483501 -35.96086)
			(xy 121.533101 -35.935359) (xy 121.585885 -35.917352) (xy 121.640728 -35.907222) (xy 121.696462 -35.905185)
			(xy 121.751899 -35.911285) (xy 121.805856 -35.925391) (xy 121.857185 -35.947203) (xy 121.904791 -35.976257)
			(xy 121.947659 -36.011932) (xy 121.984876 -36.053469) (xy 122.015649 -36.099982) (xy 122.039321 -36.150479)
			(xy 122.055389 -36.203886) (xy 122.063509 -36.259062) (xy 122.064018 -36.286948) (xy 122.063509 -36.314834)
			(xy 122.055389 -36.37001) (xy 122.039321 -36.423417) (xy 122.015649 -36.473914) (xy 121.984876 -36.520427)
			(xy 121.947659 -36.561964) (xy 121.904791 -36.597639) (xy 121.857185 -36.626693) (xy 121.805856 -36.648505)
			(xy 121.751899 -36.662611) (xy 121.696462 -36.668711) (xy 121.640728 -36.666674) (xy 121.585885 -36.656544)
			(xy 121.533101 -36.638537) (xy 121.483501 -36.613036) (xy 121.438143 -36.580585) (xy 121.397994 -36.541876)
			(xy 121.363908 -36.497733) (xy 121.336612 -36.449098) (xy 121.316689 -36.397007) (xy 121.304563 -36.34257)
			(xy 121.300492 -36.286948) (xy 114.753419 -36.286948) (xy 114.767555 -36.317103) (xy 114.783623 -36.37051)
			(xy 114.791743 -36.425686) (xy 114.792252 -36.453572) (xy 114.791743 -36.481458) (xy 114.783623 -36.536634)
			(xy 114.767555 -36.590041) (xy 114.743883 -36.640538) (xy 114.71311 -36.687051) (xy 114.675893 -36.728588)
			(xy 114.633025 -36.764263) (xy 114.585419 -36.793317) (xy 114.53409 -36.815129) (xy 114.480133 -36.829235)
			(xy 114.424696 -36.835335) (xy 114.368962 -36.833298) (xy 114.314119 -36.823168) (xy 114.261335 -36.805161)
			(xy 114.211735 -36.77966) (xy 114.166377 -36.747209) (xy 114.126228 -36.7085) (xy 114.092142 -36.664357)
			(xy 114.064846 -36.615722) (xy 114.044923 -36.563631) (xy 114.032797 -36.509194) (xy 114.028726 -36.453572)
			(xy 111.472848 -36.453572) (xy 111.477043 -36.482074) (xy 111.477552 -36.50996) (xy 111.477043 -36.537846)
			(xy 111.468923 -36.593022) (xy 111.452855 -36.646429) (xy 111.429183 -36.696926) (xy 111.39841 -36.743439)
			(xy 111.361193 -36.784976) (xy 111.318325 -36.820651) (xy 111.270719 -36.849705) (xy 111.21939 -36.871517)
			(xy 111.165433 -36.885623) (xy 111.109996 -36.891723) (xy 111.054262 -36.889686) (xy 110.999419 -36.879556)
			(xy 110.946635 -36.861549) (xy 110.897035 -36.836048) (xy 110.851677 -36.803597) (xy 110.811528 -36.764888)
			(xy 110.777442 -36.720745) (xy 110.750146 -36.67211) (xy 110.730223 -36.620019) (xy 110.718097 -36.565582)
			(xy 110.714026 -36.50996) (xy 93.917095 -36.50996) (xy 94.163134 -37.09416) (xy 94.182668 -37.142217)
			(xy 94.212828 -37.241479) (xy 94.223332 -37.29228) (xy 94.258639 -37.47516) (xy 107.85932 -37.47516)
			(xy 107.863391 -37.419538) (xy 107.875517 -37.365101) (xy 107.89544 -37.31301) (xy 107.922736 -37.264375)
			(xy 107.956822 -37.220232) (xy 107.996971 -37.181523) (xy 108.042329 -37.149072) (xy 108.091929 -37.123571)
			(xy 108.144713 -37.105564) (xy 108.199556 -37.095434) (xy 108.25529 -37.093397) (xy 108.310727 -37.099497)
			(xy 108.364684 -37.113603) (xy 108.416013 -37.135415) (xy 108.463619 -37.164469) (xy 108.506487 -37.200144)
			(xy 108.543704 -37.241681) (xy 108.574477 -37.288194) (xy 108.598149 -37.338691) (xy 108.614217 -37.392098)
			(xy 108.622337 -37.447274) (xy 108.622846 -37.47516) (xy 108.622337 -37.503046) (xy 108.614217 -37.558222)
			(xy 108.598149 -37.611629) (xy 108.574477 -37.662126) (xy 108.574324 -37.662358) (xy 110.048546 -37.662358)
			(xy 110.052617 -37.606736) (xy 110.064743 -37.552299) (xy 110.084666 -37.500208) (xy 110.111962 -37.451573)
			(xy 110.146048 -37.40743) (xy 110.186197 -37.368721) (xy 110.231555 -37.33627) (xy 110.281155 -37.310769)
			(xy 110.333939 -37.292762) (xy 110.388782 -37.282632) (xy 110.444516 -37.280595) (xy 110.499953 -37.286695)
			(xy 110.55391 -37.300801) (xy 110.605239 -37.322613) (xy 110.652845 -37.351667) (xy 110.695713 -37.387342)
			(xy 110.73293 -37.428879) (xy 110.763703 -37.475392) (xy 110.787375 -37.525889) (xy 110.803443 -37.579296)
			(xy 110.811563 -37.634472) (xy 110.812072 -37.662358) (xy 110.811563 -37.690244) (xy 110.803443 -37.74542)
			(xy 110.794809 -37.774118) (xy 121.564906 -37.774118) (xy 121.568977 -37.718496) (xy 121.581103 -37.664059)
			(xy 121.601026 -37.611968) (xy 121.628322 -37.563333) (xy 121.662408 -37.51919) (xy 121.702557 -37.480481)
			(xy 121.747915 -37.44803) (xy 121.797515 -37.422529) (xy 121.850299 -37.404522) (xy 121.905142 -37.394392)
			(xy 121.960876 -37.392355) (xy 122.016313 -37.398455) (xy 122.07027 -37.412561) (xy 122.121599 -37.434373)
			(xy 122.169205 -37.463427) (xy 122.212073 -37.499102) (xy 122.24929 -37.540639) (xy 122.280063 -37.587152)
			(xy 122.303735 -37.637649) (xy 122.319803 -37.691056) (xy 122.327923 -37.746232) (xy 122.328432 -37.774118)
			(xy 122.327923 -37.802004) (xy 122.319803 -37.85718) (xy 122.303735 -37.910587) (xy 122.280063 -37.961084)
			(xy 122.24929 -38.007597) (xy 122.212073 -38.049134) (xy 122.169205 -38.084809) (xy 122.121599 -38.113863)
			(xy 122.07027 -38.135675) (xy 122.016313 -38.149781) (xy 121.960876 -38.155881) (xy 121.905142 -38.153844)
			(xy 121.850299 -38.143714) (xy 121.797515 -38.125707) (xy 121.747915 -38.100206) (xy 121.702557 -38.067755)
			(xy 121.662408 -38.029046) (xy 121.628322 -37.984903) (xy 121.601026 -37.936268) (xy 121.581103 -37.884177)
			(xy 121.568977 -37.82974) (xy 121.564906 -37.774118) (xy 110.794809 -37.774118) (xy 110.787375 -37.798827)
			(xy 110.763703 -37.849324) (xy 110.73293 -37.895837) (xy 110.695713 -37.937374) (xy 110.652845 -37.973049)
			(xy 110.605239 -38.002103) (xy 110.55391 -38.023915) (xy 110.499953 -38.038021) (xy 110.444516 -38.044121)
			(xy 110.388782 -38.042084) (xy 110.333939 -38.031954) (xy 110.281155 -38.013947) (xy 110.231555 -37.988446)
			(xy 110.186197 -37.955995) (xy 110.146048 -37.917286) (xy 110.111962 -37.873143) (xy 110.084666 -37.824508)
			(xy 110.064743 -37.772417) (xy 110.052617 -37.71798) (xy 110.048546 -37.662358) (xy 108.574324 -37.662358)
			(xy 108.543704 -37.708639) (xy 108.506487 -37.750176) (xy 108.463619 -37.785851) (xy 108.416013 -37.814905)
			(xy 108.364684 -37.836717) (xy 108.310727 -37.850823) (xy 108.25529 -37.856923) (xy 108.199556 -37.854886)
			(xy 108.144713 -37.844756) (xy 108.091929 -37.826749) (xy 108.042329 -37.801248) (xy 107.996971 -37.768797)
			(xy 107.956822 -37.730088) (xy 107.922736 -37.685945) (xy 107.89544 -37.63731) (xy 107.875517 -37.585219)
			(xy 107.863391 -37.530782) (xy 107.85932 -37.47516) (xy 94.258639 -37.47516) (xy 94.333568 -37.863272)
			(xy 94.337309 -37.882907) (xy 94.343406 -37.922416) (xy 94.34576 -37.942266) (xy 94.348606 -37.969673)
			(xy 94.351654 -38.024695) (xy 94.351856 -38.052248) (xy 94.351637 -38.080123) (xy 94.348458 -38.135781)
			(xy 94.345506 -38.1635) (xy 94.308676 -38.49116) (xy 94.281852 -38.729952) (xy 113.801097 -38.729952)
			(xy 113.801097 -38.675448) (xy 113.808855 -38.621499) (xy 113.824211 -38.569204) (xy 113.846854 -38.519626)
			(xy 113.876323 -38.473776) (xy 113.912018 -38.432587) (xy 113.953211 -38.396897) (xy 113.999065 -38.367433)
			(xy 114.048645 -38.344796) (xy 114.100942 -38.329445) (xy 114.154892 -38.321694) (xy 114.182144 -38.321234)
			(xy 114.210447 -38.321752) (xy 114.266435 -38.330097) (xy 114.320575 -38.346626) (xy 114.371676 -38.370976)
			(xy 114.418616 -38.402613) (xy 114.460364 -38.440841) (xy 114.496003 -38.48482) (xy 114.51082 -38.50894)
			(xy 114.518425 -38.520969) (xy 114.539042 -38.540571) (xy 114.564273 -38.553713) (xy 114.592152 -38.559374)
			(xy 114.62051 -38.557111) (xy 114.647139 -38.547101) (xy 114.669966 -38.530123) (xy 114.678968 -38.5191)
			(xy 114.697178 -38.496243) (xy 114.739336 -38.455778) (xy 114.787167 -38.422209) (xy 114.839554 -38.396318)
			(xy 114.895274 -38.378712) (xy 114.953026 -38.3698) (xy 114.982244 -38.36924) (xy 115.009497 -38.369633)
			(xy 115.063446 -38.377395) (xy 115.115742 -38.392756) (xy 115.16532 -38.415403) (xy 115.211171 -38.444874)
			(xy 115.252361 -38.48057) (xy 115.288052 -38.521764) (xy 115.317518 -38.567618) (xy 115.340159 -38.617199)
			(xy 115.355514 -38.669497) (xy 115.36327 -38.723447) (xy 115.36327 -38.777953) (xy 115.355514 -38.831903)
			(xy 115.340159 -38.884201) (xy 115.317518 -38.933782) (xy 115.288052 -38.979636) (xy 115.252361 -39.02083)
			(xy 115.211171 -39.056526) (xy 115.16532 -39.085997) (xy 115.115742 -39.108644) (xy 115.063446 -39.124005)
			(xy 115.009497 -39.131767) (xy 114.982244 -39.132256) (xy 114.95394 -39.131752) (xy 114.897951 -39.123406)
			(xy 114.843811 -39.106874) (xy 114.79271 -39.082522) (xy 114.74577 -39.050883) (xy 114.704022 -39.012653)
			(xy 114.668385 -38.968671) (xy 114.653568 -38.94455) (xy 114.645978 -38.93251) (xy 114.625357 -38.91291)
			(xy 114.600124 -38.899769) (xy 114.572242 -38.89411) (xy 114.543882 -38.896375) (xy 114.517251 -38.906387)
			(xy 114.494423 -38.923366) (xy 114.48542 -38.93439) (xy 114.467215 -38.95725) (xy 114.425056 -38.997716)
			(xy 114.377224 -39.031285) (xy 114.324836 -39.057175) (xy 114.269115 -39.074781) (xy 114.211362 -39.083691)
			(xy 114.182144 -39.08425) (xy 114.154892 -39.083706) (xy 114.100942 -39.075955) (xy 114.048645 -39.060604)
			(xy 113.999065 -39.037967) (xy 113.953211 -39.008503) (xy 113.912018 -38.972813) (xy 113.876323 -38.931624)
			(xy 113.846854 -38.885774) (xy 113.824211 -38.836196) (xy 113.808855 -38.783901) (xy 113.801097 -38.729952)
			(xy 94.281852 -38.729952) (xy 94.251526 -38.999922) (xy 94.251272 -39.00551) (xy 94.251272 -39.270432)
			(xy 94.250639 -39.320247) (xy 94.240587 -39.41937) (xy 94.231206 -39.468298) (xy 94.160848 -39.812722)
			(xy 94.160086 -39.817294) (xy 94.142716 -39.97198) (xy 115.995956 -39.97198) (xy 116.000027 -39.916358)
			(xy 116.012153 -39.861921) (xy 116.032076 -39.80983) (xy 116.059372 -39.761195) (xy 116.093458 -39.717052)
			(xy 116.133607 -39.678343) (xy 116.178965 -39.645892) (xy 116.228565 -39.620391) (xy 116.281349 -39.602384)
			(xy 116.336192 -39.592254) (xy 116.391926 -39.590217) (xy 116.447363 -39.596317) (xy 116.50132 -39.610423)
			(xy 116.552649 -39.632235) (xy 116.600255 -39.661289) (xy 116.643123 -39.696964) (xy 116.68034 -39.738501)
			(xy 116.711113 -39.785014) (xy 116.734785 -39.835511) (xy 116.750853 -39.888918) (xy 116.758973 -39.944094)
			(xy 116.759482 -39.97198) (xy 116.758973 -39.999866) (xy 116.750853 -40.055042) (xy 116.734785 -40.108449)
			(xy 116.711113 -40.158946) (xy 116.68034 -40.205459) (xy 116.643123 -40.246996) (xy 116.600255 -40.282671)
			(xy 116.552649 -40.311725) (xy 116.50132 -40.333537) (xy 116.447363 -40.347643) (xy 116.391926 -40.353743)
			(xy 116.336192 -40.351706) (xy 116.281349 -40.341576) (xy 116.228565 -40.323569) (xy 116.178965 -40.298068)
			(xy 116.133607 -40.265617) (xy 116.093458 -40.226908) (xy 116.059372 -40.182765) (xy 116.032076 -40.13413)
			(xy 116.012153 -40.082039) (xy 116.000027 -40.027602) (xy 115.995956 -39.97198) (xy 94.142716 -39.97198)
			(xy 94.135956 -40.032178) (xy 94.130876 -40.076882) (xy 94.128098 -40.100332) (xy 94.120601 -40.146961)
			(xy 94.11589 -40.1701) (xy 93.987366 -40.784272) (xy 93.986328 -40.789883) (xy 93.986459 -40.801291)
			(xy 93.98762 -40.806878) (xy 93.989776 -40.814539) (xy 93.998052 -40.828124) (xy 94.003876 -40.833548)
			(xy 94.020894 -40.848026) (xy 94.021402 -40.848026) (xy 94.04985 -40.873426) (xy 94.058994 -40.87749)
			(xy 94.069662 -40.881554) (xy 94.094228 -40.871443) (xy 94.145406 -40.857199) (xy 94.19804 -40.850011)
			(xy 94.224602 -40.84955) (xy 94.224856 -40.84955) (xy 94.251896 -40.850002) (xy 94.305463 -40.857434)
			(xy 94.357499 -40.872165) (xy 94.407014 -40.893913) (xy 94.453066 -40.922265) (xy 94.494781 -40.956682)
			(xy 94.5134 -40.976296) (xy 94.520258 -40.976804) (xy 94.590616 -40.976804) (xy 94.596458 -40.97655)
			(xy 94.615095 -40.956915) (xy 94.656837 -40.922443) (xy 94.702925 -40.894043) (xy 94.752483 -40.872254)
			(xy 94.804568 -40.857492) (xy 94.858188 -40.850037) (xy 94.885256 -40.84955) (xy 94.913257 -40.850023)
			(xy 94.968689 -40.857987) (xy 95.022424 -40.87376) (xy 95.073366 -40.897019) (xy 95.12048 -40.927293)
			(xy 95.162805 -40.963963) (xy 95.199481 -41.006285) (xy 95.229759 -41.053395) (xy 95.253025 -41.104335)
			(xy 95.268803 -41.158068) (xy 95.276774 -41.213499) (xy 95.276774 -41.269501) (xy 95.268803 -41.324932)
			(xy 95.253025 -41.378665) (xy 95.229759 -41.429605) (xy 95.199481 -41.476715) (xy 95.162805 -41.519037)
			(xy 95.12048 -41.555707) (xy 95.073366 -41.585981) (xy 95.022424 -41.60924) (xy 94.968689 -41.625013)
			(xy 94.913257 -41.632977) (xy 94.885256 -41.633394) (xy 94.858185 -41.632941) (xy 94.804558 -41.625494)
			(xy 94.752468 -41.610734) (xy 94.702906 -41.588942) (xy 94.656816 -41.560534) (xy 94.615077 -41.526049)
			(xy 94.596458 -41.506394) (xy 94.590616 -41.50614) (xy 94.519496 -41.50614) (xy 94.513654 -41.506394)
			(xy 94.495019 -41.526033) (xy 94.453279 -41.56051) (xy 94.407191 -41.588916) (xy 94.357633 -41.610709)
			(xy 94.305547 -41.625475) (xy 94.251925 -41.632933) (xy 94.224856 -41.633394) (xy 94.198656 -41.632955)
			(xy 94.146724 -41.62597) (xy 94.096185 -41.61213) (xy 94.047939 -41.591681) (xy 94.002847 -41.564989)
			(xy 93.961712 -41.532529) (xy 93.94317 -41.514014) (xy 93.937328 -41.512998) (xy 93.933104 -41.512327)
			(xy 93.924553 -41.512207) (xy 93.92031 -41.512744) (xy 93.908626 -41.51503) (xy 93.876622 -41.525444)
			(xy 93.858588 -41.531286) (xy 93.830648 -41.54043) (xy 93.82887 -41.541192) (xy 93.459468 -43.305222)
			(xy 96.307148 -43.305222) (xy 96.307615 -43.277852) (xy 96.315431 -43.223672) (xy 96.330919 -43.171169)
			(xy 96.353761 -43.121422) (xy 96.383486 -43.075455) (xy 96.401128 -43.054524) (xy 96.401382 -43.05427)
			(xy 96.406943 -43.047166) (xy 96.413205 -43.030263) (xy 96.413574 -43.02125) (xy 96.413574 -42.954194)
			(xy 96.413226 -42.945176) (xy 96.406973 -42.928259) (xy 96.401382 -42.921174) (xy 96.401128 -42.921174)
			(xy 96.401128 -42.92092) (xy 96.383489 -42.899988) (xy 96.353776 -42.854015) (xy 96.33094 -42.804268)
			(xy 96.315449 -42.751767) (xy 96.307621 -42.697591) (xy 96.307148 -42.670222) (xy 96.307699 -42.641484)
			(xy 96.316317 -42.584659) (xy 96.333362 -42.529769) (xy 96.358447 -42.478057) (xy 96.391005 -42.430692)
			(xy 96.410272 -42.409364) (xy 96.416876 -42.402506) (xy 96.423988 -42.384472) (xy 96.423988 -42.295572)
			(xy 96.416876 -42.277538) (xy 96.410272 -42.27068) (xy 96.391025 -42.249333) (xy 96.358464 -42.201973)
			(xy 96.333374 -42.150264) (xy 96.316325 -42.095377) (xy 96.307702 -42.038553) (xy 96.307699 -41.981079)
			(xy 96.316318 -41.924255) (xy 96.333363 -41.869366) (xy 96.358448 -41.817655) (xy 96.391005 -41.770292)
			(xy 96.410272 -41.748964) (xy 96.416876 -41.742106) (xy 96.423988 -41.724072) (xy 96.423988 -41.635172)
			(xy 96.416876 -41.617138) (xy 96.410272 -41.61028) (xy 96.391017 -41.588939) (xy 96.358448 -41.541581)
			(xy 96.333351 -41.489873) (xy 96.316297 -41.434985) (xy 96.307671 -41.37816) (xy 96.307148 -41.349422)
			(xy 96.307634 -41.322171) (xy 96.31539 -41.268223) (xy 96.330745 -41.215928) (xy 96.353387 -41.166351)
			(xy 96.382853 -41.120501) (xy 96.418544 -41.07931) (xy 96.459735 -41.043619) (xy 96.505585 -41.014153)
			(xy 96.555162 -40.991511) (xy 96.607457 -40.976156) (xy 96.661405 -40.9684) (xy 96.715907 -40.9684)
			(xy 96.739028 -40.971724) (xy 116.694202 -40.971724) (xy 116.698273 -40.916102) (xy 116.710399 -40.861665)
			(xy 116.730322 -40.809574) (xy 116.757618 -40.760939) (xy 116.791704 -40.716796) (xy 116.831853 -40.678087)
			(xy 116.877211 -40.645636) (xy 116.926811 -40.620135) (xy 116.979595 -40.602128) (xy 117.034438 -40.591998)
			(xy 117.090172 -40.589961) (xy 117.145609 -40.596061) (xy 117.199566 -40.610167) (xy 117.250895 -40.631979)
			(xy 117.298501 -40.661033) (xy 117.341369 -40.696708) (xy 117.378586 -40.738245) (xy 117.409359 -40.784758)
			(xy 117.433031 -40.835255) (xy 117.449099 -40.888662) (xy 117.457219 -40.943838) (xy 117.457728 -40.971724)
			(xy 117.457219 -40.99961) (xy 117.449099 -41.054786) (xy 117.433031 -41.108193) (xy 117.409359 -41.15869)
			(xy 117.378586 -41.205203) (xy 117.341369 -41.24674) (xy 117.298501 -41.282415) (xy 117.250895 -41.311469)
			(xy 117.199566 -41.333281) (xy 117.145609 -41.347387) (xy 117.090172 -41.353487) (xy 117.034438 -41.35145)
			(xy 116.979595 -41.34132) (xy 116.926811 -41.323313) (xy 116.877211 -41.297812) (xy 116.831853 -41.265361)
			(xy 116.791704 -41.226652) (xy 116.757618 -41.182509) (xy 116.730322 -41.133874) (xy 116.710399 -41.081783)
			(xy 116.698273 -41.027346) (xy 116.694202 -40.971724) (xy 96.739028 -40.971724) (xy 96.769855 -40.976156)
			(xy 96.82215 -40.991511) (xy 96.871727 -41.014153) (xy 96.917577 -41.043619) (xy 96.958768 -41.07931)
			(xy 96.994459 -41.120501) (xy 97.023925 -41.166351) (xy 97.046567 -41.215928) (xy 97.061922 -41.268223)
			(xy 97.069678 -41.322171) (xy 97.070164 -41.349422) (xy 97.069637 -41.378161) (xy 97.061012 -41.434987)
			(xy 97.043962 -41.489877) (xy 97.018872 -41.541589) (xy 96.986309 -41.588952) (xy 96.96704 -41.61028)
			(xy 96.960436 -41.617138) (xy 96.953324 -41.635172) (xy 96.953324 -41.724072) (xy 96.960436 -41.742106)
			(xy 96.96704 -41.748964) (xy 96.986334 -41.770271) (xy 97.018902 -41.817636) (xy 97.043995 -41.869351)
			(xy 97.061045 -41.924245) (xy 97.069666 -41.981076) (xy 97.069664 -42.038557) (xy 97.061037 -42.095387)
			(xy 97.043983 -42.150279) (xy 97.018886 -42.201992) (xy 96.986314 -42.249354) (xy 96.96704 -42.27068)
			(xy 96.960436 -42.277538) (xy 96.953324 -42.295572) (xy 96.953324 -42.384472) (xy 96.960436 -42.402506)
			(xy 96.96704 -42.409364) (xy 96.986318 -42.430685) (xy 97.018884 -42.478048) (xy 97.043975 -42.529761)
			(xy 97.061024 -42.584654) (xy 97.069645 -42.641483) (xy 97.070164 -42.670222) (xy 97.06972 -42.697593)
			(xy 97.061898 -42.751773) (xy 97.046404 -42.804277) (xy 97.025847 -42.849038) (xy 98.89185 -42.849038)
			(xy 98.895921 -42.793416) (xy 98.908047 -42.738979) (xy 98.92797 -42.686888) (xy 98.955266 -42.638253)
			(xy 98.989352 -42.59411) (xy 99.029501 -42.555401) (xy 99.074859 -42.52295) (xy 99.124459 -42.497449)
			(xy 99.177243 -42.479442) (xy 99.232086 -42.469312) (xy 99.28782 -42.467275) (xy 99.343257 -42.473375)
			(xy 99.397214 -42.487481) (xy 99.448543 -42.509293) (xy 99.496149 -42.538347) (xy 99.539017 -42.574022)
			(xy 99.576234 -42.615559) (xy 99.607007 -42.662072) (xy 99.630679 -42.712569) (xy 99.646747 -42.765976)
			(xy 99.654867 -42.821152) (xy 99.655228 -42.84091) (xy 104.932986 -42.84091) (xy 104.937057 -42.785288)
			(xy 104.949183 -42.730851) (xy 104.969106 -42.67876) (xy 104.996402 -42.630125) (xy 105.030488 -42.585982)
			(xy 105.070637 -42.547273) (xy 105.115995 -42.514822) (xy 105.165595 -42.489321) (xy 105.218379 -42.471314)
			(xy 105.273222 -42.461184) (xy 105.328956 -42.459147) (xy 105.384393 -42.465247) (xy 105.43835 -42.479353)
			(xy 105.489679 -42.501165) (xy 105.537285 -42.530219) (xy 105.580153 -42.565894) (xy 105.61737 -42.607431)
			(xy 105.648143 -42.653944) (xy 105.671815 -42.704441) (xy 105.687883 -42.757848) (xy 105.696003 -42.813024)
			(xy 105.696512 -42.84091) (xy 105.696003 -42.868796) (xy 105.687883 -42.923972) (xy 105.671815 -42.977379)
			(xy 105.648143 -43.027876) (xy 105.61737 -43.074389) (xy 105.580153 -43.115926) (xy 105.537285 -43.151601)
			(xy 105.489679 -43.180655) (xy 105.43835 -43.202467) (xy 105.384393 -43.216573) (xy 105.328956 -43.222673)
			(xy 105.273222 -43.220636) (xy 105.218379 -43.210506) (xy 105.165595 -43.192499) (xy 105.115995 -43.166998)
			(xy 105.070637 -43.134547) (xy 105.030488 -43.095838) (xy 104.996402 -43.051695) (xy 104.969106 -43.00306)
			(xy 104.949183 -42.950969) (xy 104.937057 -42.896532) (xy 104.932986 -42.84091) (xy 99.655228 -42.84091)
			(xy 99.655376 -42.849038) (xy 99.654867 -42.876924) (xy 99.646747 -42.9321) (xy 99.630679 -42.985507)
			(xy 99.607007 -43.036004) (xy 99.576234 -43.082517) (xy 99.539017 -43.124054) (xy 99.496149 -43.159729)
			(xy 99.448543 -43.188783) (xy 99.397214 -43.210595) (xy 99.343257 -43.224701) (xy 99.28782 -43.230801)
			(xy 99.232086 -43.228764) (xy 99.177243 -43.218634) (xy 99.124459 -43.200627) (xy 99.074859 -43.175126)
			(xy 99.029501 -43.142675) (xy 98.989352 -43.103966) (xy 98.955266 -43.059823) (xy 98.92797 -43.011188)
			(xy 98.908047 -42.959097) (xy 98.895921 -42.90466) (xy 98.89185 -42.849038) (xy 97.025847 -42.849038)
			(xy 97.023557 -42.854024) (xy 96.993828 -42.899989) (xy 96.976184 -42.92092) (xy 96.97593 -42.921174)
			(xy 96.97034 -42.928258) (xy 96.964097 -42.945177) (xy 96.963738 -42.954194) (xy 96.963738 -43.02125)
			(xy 96.964111 -43.030265) (xy 96.970346 -43.047183) (xy 96.97593 -43.05427) (xy 96.976184 -43.05427)
			(xy 96.976184 -43.054524) (xy 96.993798 -43.075476) (xy 97.023515 -43.121443) (xy 97.046355 -43.171185)
			(xy 97.061852 -43.223682) (xy 97.069687 -43.277854) (xy 97.070164 -43.305222) (xy 97.069678 -43.332473)
			(xy 97.061922 -43.386421) (xy 97.046567 -43.438716) (xy 97.023925 -43.488293) (xy 96.994459 -43.534143)
			(xy 96.958768 -43.575334) (xy 96.917577 -43.611025) (xy 96.871727 -43.640491) (xy 96.82215 -43.663133)
			(xy 96.769855 -43.678488) (xy 96.715907 -43.686244) (xy 96.661405 -43.686244) (xy 96.607457 -43.678488)
			(xy 96.555162 -43.663133) (xy 96.505585 -43.640491) (xy 96.459735 -43.611025) (xy 96.418544 -43.575334)
			(xy 96.382853 -43.534143) (xy 96.353387 -43.488293) (xy 96.330745 -43.438716) (xy 96.31539 -43.386421)
			(xy 96.307634 -43.332473) (xy 96.307148 -43.305222) (xy 93.459468 -43.305222) (xy 93.430852 -43.441874)
			(xy 93.369235 -43.73626) (xy 98.212908 -43.73626) (xy 98.216979 -43.680638) (xy 98.229105 -43.626201)
			(xy 98.249028 -43.57411) (xy 98.276324 -43.525475) (xy 98.31041 -43.481332) (xy 98.350559 -43.442623)
			(xy 98.395917 -43.410172) (xy 98.445517 -43.384671) (xy 98.498301 -43.366664) (xy 98.553144 -43.356534)
			(xy 98.608878 -43.354497) (xy 98.664315 -43.360597) (xy 98.718272 -43.374703) (xy 98.769601 -43.396515)
			(xy 98.817207 -43.425569) (xy 98.860075 -43.461244) (xy 98.897292 -43.502781) (xy 98.928065 -43.549294)
			(xy 98.951737 -43.599791) (xy 98.967805 -43.653198) (xy 98.975925 -43.708374) (xy 98.976434 -43.73626)
			(xy 98.975925 -43.764146) (xy 98.967805 -43.819322) (xy 98.956496 -43.85691) (xy 102.71963 -43.85691)
			(xy 102.723701 -43.801288) (xy 102.735827 -43.746851) (xy 102.75575 -43.69476) (xy 102.783046 -43.646125)
			(xy 102.817132 -43.601982) (xy 102.857281 -43.563273) (xy 102.902639 -43.530822) (xy 102.952239 -43.505321)
			(xy 103.005023 -43.487314) (xy 103.059866 -43.477184) (xy 103.1156 -43.475147) (xy 103.171037 -43.481247)
			(xy 103.224994 -43.495353) (xy 103.276323 -43.517165) (xy 103.323929 -43.546219) (xy 103.366797 -43.581894)
			(xy 103.404014 -43.623431) (xy 103.434787 -43.669944) (xy 103.458459 -43.720441) (xy 103.474527 -43.773848)
			(xy 103.482647 -43.829024) (xy 103.483156 -43.85691) (xy 103.482647 -43.884796) (xy 103.474527 -43.939972)
			(xy 103.458459 -43.993379) (xy 103.434787 -44.043876) (xy 103.404014 -44.090389) (xy 103.366797 -44.131926)
			(xy 103.323929 -44.167601) (xy 103.276323 -44.196655) (xy 103.224994 -44.218467) (xy 103.171037 -44.232573)
			(xy 103.1156 -44.238673) (xy 103.059866 -44.236636) (xy 103.005023 -44.226506) (xy 102.952239 -44.208499)
			(xy 102.902639 -44.182998) (xy 102.857281 -44.150547) (xy 102.817132 -44.111838) (xy 102.783046 -44.067695)
			(xy 102.75575 -44.01906) (xy 102.735827 -43.966969) (xy 102.723701 -43.912532) (xy 102.71963 -43.85691)
			(xy 98.956496 -43.85691) (xy 98.951737 -43.872729) (xy 98.928065 -43.923226) (xy 98.897292 -43.969739)
			(xy 98.860075 -44.011276) (xy 98.817207 -44.046951) (xy 98.769601 -44.076005) (xy 98.718272 -44.097817)
			(xy 98.664315 -44.111923) (xy 98.608878 -44.118023) (xy 98.553144 -44.115986) (xy 98.498301 -44.105856)
			(xy 98.445517 -44.087849) (xy 98.395917 -44.062348) (xy 98.350559 -44.029897) (xy 98.31041 -43.991188)
			(xy 98.276324 -43.947045) (xy 98.249028 -43.89841) (xy 98.229105 -43.846319) (xy 98.216979 -43.791882)
			(xy 98.212908 -43.73626) (xy 93.369235 -43.73626) (xy 93.080769 -45.114464) (xy 98.065334 -45.114464)
			(xy 98.069405 -45.058842) (xy 98.081531 -45.004405) (xy 98.101454 -44.952314) (xy 98.12875 -44.903679)
			(xy 98.162836 -44.859536) (xy 98.202985 -44.820827) (xy 98.248343 -44.788376) (xy 98.297943 -44.762875)
			(xy 98.350727 -44.744868) (xy 98.40557 -44.734738) (xy 98.461304 -44.732701) (xy 98.516741 -44.738801)
			(xy 98.570698 -44.752907) (xy 98.622027 -44.774719) (xy 98.669633 -44.803773) (xy 98.712501 -44.839448)
			(xy 98.742483 -44.87291) (xy 104.932986 -44.87291) (xy 104.937057 -44.817288) (xy 104.949183 -44.762851)
			(xy 104.969106 -44.71076) (xy 104.996402 -44.662125) (xy 105.030488 -44.617982) (xy 105.070637 -44.579273)
			(xy 105.115995 -44.546822) (xy 105.165595 -44.521321) (xy 105.218379 -44.503314) (xy 105.273222 -44.493184)
			(xy 105.328956 -44.491147) (xy 105.384393 -44.497247) (xy 105.43835 -44.511353) (xy 105.489679 -44.533165)
			(xy 105.537285 -44.562219) (xy 105.580153 -44.597894) (xy 105.61737 -44.639431) (xy 105.648143 -44.685944)
			(xy 105.671815 -44.736441) (xy 105.687883 -44.789848) (xy 105.696003 -44.845024) (xy 105.696512 -44.87291)
			(xy 105.696003 -44.900796) (xy 105.687883 -44.955972) (xy 105.671815 -45.009379) (xy 105.648143 -45.059876)
			(xy 105.61737 -45.106389) (xy 105.580153 -45.147926) (xy 105.537285 -45.183601) (xy 105.489679 -45.212655)
			(xy 105.43835 -45.234467) (xy 105.384393 -45.248573) (xy 105.328956 -45.254673) (xy 105.273222 -45.252636)
			(xy 105.218379 -45.242506) (xy 105.165595 -45.224499) (xy 105.115995 -45.198998) (xy 105.070637 -45.166547)
			(xy 105.030488 -45.127838) (xy 104.996402 -45.083695) (xy 104.969106 -45.03506) (xy 104.949183 -44.982969)
			(xy 104.937057 -44.928532) (xy 104.932986 -44.87291) (xy 98.742483 -44.87291) (xy 98.749718 -44.880985)
			(xy 98.780491 -44.927498) (xy 98.804163 -44.977995) (xy 98.820231 -45.031402) (xy 98.828351 -45.086578)
			(xy 98.82886 -45.114464) (xy 98.828351 -45.14235) (xy 98.820231 -45.197526) (xy 98.804163 -45.250933)
			(xy 98.780491 -45.30143) (xy 98.749718 -45.347943) (xy 98.744076 -45.35424) (xy 102.703628 -45.35424)
			(xy 102.707699 -45.298618) (xy 102.719825 -45.244181) (xy 102.739748 -45.19209) (xy 102.767044 -45.143455)
			(xy 102.80113 -45.099312) (xy 102.841279 -45.060603) (xy 102.886637 -45.028152) (xy 102.936237 -45.002651)
			(xy 102.989021 -44.984644) (xy 103.043864 -44.974514) (xy 103.099598 -44.972477) (xy 103.155035 -44.978577)
			(xy 103.208992 -44.992683) (xy 103.260321 -45.014495) (xy 103.307927 -45.043549) (xy 103.350795 -45.079224)
			(xy 103.388012 -45.120761) (xy 103.418785 -45.167274) (xy 103.442457 -45.217771) (xy 103.458525 -45.271178)
			(xy 103.466645 -45.326354) (xy 103.467154 -45.35424) (xy 103.466645 -45.382126) (xy 103.458525 -45.437302)
			(xy 103.442457 -45.490709) (xy 103.418785 -45.541206) (xy 103.388012 -45.587719) (xy 103.350795 -45.629256)
			(xy 103.307927 -45.664931) (xy 103.260321 -45.693985) (xy 103.208992 -45.715797) (xy 103.155035 -45.729903)
			(xy 103.099598 -45.736003) (xy 103.043864 -45.733966) (xy 102.989021 -45.723836) (xy 102.936237 -45.705829)
			(xy 102.886637 -45.680328) (xy 102.841279 -45.647877) (xy 102.80113 -45.609168) (xy 102.767044 -45.565025)
			(xy 102.739748 -45.51639) (xy 102.719825 -45.464299) (xy 102.707699 -45.409862) (xy 102.703628 -45.35424)
			(xy 98.744076 -45.35424) (xy 98.712501 -45.38948) (xy 98.669633 -45.425155) (xy 98.622027 -45.454209)
			(xy 98.570698 -45.476021) (xy 98.516741 -45.490127) (xy 98.461304 -45.496227) (xy 98.40557 -45.49419)
			(xy 98.350727 -45.48406) (xy 98.297943 -45.466053) (xy 98.248343 -45.440552) (xy 98.202985 -45.408101)
			(xy 98.162836 -45.369392) (xy 98.12875 -45.325249) (xy 98.101454 -45.276614) (xy 98.081531 -45.224523)
			(xy 98.069405 -45.170086) (xy 98.065334 -45.114464) (xy 93.080769 -45.114464) (xy 92.878215 -46.082204)
			(xy 96.052386 -46.082204) (xy 96.052881 -46.054953) (xy 96.060637 -46.001006) (xy 96.075992 -45.948712)
			(xy 96.098632 -45.899135) (xy 96.128097 -45.853285) (xy 96.163788 -45.812095) (xy 96.204977 -45.776403)
			(xy 96.250826 -45.746937) (xy 96.300402 -45.724295) (xy 96.352696 -45.708939) (xy 96.406643 -45.701182)
			(xy 96.433894 -45.700696) (xy 96.460796 -45.701163) (xy 96.514066 -45.708734) (xy 96.565744 -45.723712)
			(xy 96.614806 -45.745802) (xy 96.660279 -45.774563) (xy 96.70126 -45.809427) (xy 96.736938 -45.849702)
			(xy 96.752156 -45.871892) (xy 96.759268 -45.882814) (xy 96.782128 -45.894752) (xy 96.894396 -45.89272)
			(xy 96.916748 -45.879766) (xy 96.923606 -45.86859) (xy 96.938537 -45.844995) (xy 96.974214 -45.802043)
			(xy 97.015771 -45.76475) (xy 97.06232 -45.733912) (xy 97.112865 -45.710187) (xy 97.166329 -45.694083)
			(xy 97.22157 -45.685943) (xy 97.249488 -45.685456) (xy 97.276481 -45.685924) (xy 97.329929 -45.693528)
			(xy 97.381772 -45.708587) (xy 97.430977 -45.730799) (xy 97.476561 -45.759723) (xy 97.497392 -45.776896)
			(xy 97.50552 -45.784008) (xy 97.526094 -45.790104) (xy 97.611438 -45.779182) (xy 97.621978 -45.777387)
			(xy 97.640263 -45.766348) (xy 97.646744 -45.757846) (xy 97.662076 -45.7366) (xy 97.697667 -45.698147)
			(xy 97.738188 -45.66493) (xy 97.782874 -45.637573) (xy 97.830886 -45.616592) (xy 97.881318 -45.602382)
			(xy 97.93322 -45.595211) (xy 97.959418 -45.594778) (xy 97.986667 -45.595293) (xy 98.040611 -45.603052)
			(xy 98.092902 -45.618408) (xy 98.142475 -45.641049) (xy 98.188321 -45.670515) (xy 98.229508 -45.706205)
			(xy 98.265196 -45.747393) (xy 98.294659 -45.793241) (xy 98.317298 -45.842815) (xy 98.332652 -45.895106)
			(xy 98.340408 -45.949051) (xy 98.340408 -46.003549) (xy 98.332652 -46.057493) (xy 98.317298 -46.109785)
			(xy 98.294659 -46.159359) (xy 98.265196 -46.205207) (xy 98.229508 -46.246395) (xy 98.188321 -46.282085)
			(xy 98.142475 -46.311551) (xy 98.092902 -46.334192) (xy 98.040611 -46.349548) (xy 97.986667 -46.357307)
			(xy 97.959418 -46.357794) (xy 97.932426 -46.357311) (xy 97.878979 -46.349708) (xy 97.827136 -46.334653)
			(xy 97.777931 -46.312444) (xy 97.732346 -46.283525) (xy 97.711514 -46.266354) (xy 97.703386 -46.259242)
			(xy 97.682812 -46.253146) (xy 97.597468 -46.264068) (xy 97.586922 -46.265834) (xy 97.568641 -46.276896)
			(xy 97.562162 -46.285404) (xy 97.544551 -46.309706) (xy 97.502954 -46.352964) (xy 97.479358 -46.37151)
			(xy 97.471484 -46.377352) (xy 97.46107 -46.394878) (xy 97.447862 -46.485302) (xy 97.452688 -46.504606)
			(xy 97.45853 -46.51248) (xy 97.45853 -46.512734) (xy 97.476028 -46.537482) (xy 97.503833 -46.591333)
			(xy 97.522771 -46.648904) (xy 97.529974 -46.693836) (xy 102.676198 -46.693836) (xy 102.676684 -46.666585)
			(xy 102.68444 -46.612637) (xy 102.699795 -46.560342) (xy 102.722437 -46.510765) (xy 102.751903 -46.464915)
			(xy 102.787594 -46.423724) (xy 102.828785 -46.388033) (xy 102.874635 -46.358567) (xy 102.924212 -46.335925)
			(xy 102.976507 -46.32057) (xy 103.030455 -46.312814) (xy 103.084957 -46.312814) (xy 103.138905 -46.32057)
			(xy 103.1912 -46.335925) (xy 103.240777 -46.358567) (xy 103.286627 -46.388033) (xy 103.327818 -46.423724)
			(xy 103.363509 -46.464915) (xy 103.392975 -46.510765) (xy 103.415617 -46.560342) (xy 103.430972 -46.612637)
			(xy 103.438728 -46.666585) (xy 103.439214 -46.693836) (xy 103.438739 -46.720263) (xy 103.43143 -46.772611)
			(xy 103.416957 -46.823446) (xy 103.395598 -46.871793) (xy 103.382064 -46.894496) (xy 103.38181 -46.89475)
			(xy 103.376473 -46.904768) (xy 103.374218 -46.927318) (xy 103.377492 -46.938184) (xy 103.403654 -47.01286)
			(xy 103.408037 -47.023376) (xy 103.424126 -47.039464) (xy 103.434642 -47.043848) (xy 103.434896 -47.043848)
			(xy 103.459415 -47.052889) (xy 103.505867 -47.076838) (xy 103.548617 -47.106899) (xy 103.586867 -47.14251)
			(xy 103.619902 -47.183006) (xy 103.647104 -47.22763) (xy 103.667965 -47.275548) (xy 103.682094 -47.325863)
			(xy 103.689227 -47.377635) (xy 103.689658 -47.403766) (xy 103.689172 -47.431017) (xy 103.687649 -47.441612)
			(xy 104.961688 -47.441612) (xy 104.965759 -47.38599) (xy 104.977885 -47.331553) (xy 104.997808 -47.279462)
			(xy 105.025104 -47.230827) (xy 105.05919 -47.186684) (xy 105.099339 -47.147975) (xy 105.144697 -47.115524)
			(xy 105.194297 -47.090023) (xy 105.247081 -47.072016) (xy 105.301924 -47.061886) (xy 105.357658 -47.059849)
			(xy 105.413095 -47.065949) (xy 105.467052 -47.080055) (xy 105.518381 -47.101867) (xy 105.565987 -47.130921)
			(xy 105.608855 -47.166596) (xy 105.646072 -47.208133) (xy 105.676845 -47.254646) (xy 105.700517 -47.305143)
			(xy 105.716585 -47.35855) (xy 105.724705 -47.413726) (xy 105.725214 -47.441612) (xy 105.724705 -47.469498)
			(xy 105.716585 -47.524674) (xy 105.700517 -47.578081) (xy 105.676845 -47.628578) (xy 105.646072 -47.675091)
			(xy 105.608855 -47.716628) (xy 105.565987 -47.752303) (xy 105.518381 -47.781357) (xy 105.467052 -47.803169)
			(xy 105.413095 -47.817275) (xy 105.357658 -47.823375) (xy 105.301924 -47.821338) (xy 105.247081 -47.811208)
			(xy 105.194297 -47.793201) (xy 105.144697 -47.7677) (xy 105.099339 -47.735249) (xy 105.05919 -47.69654)
			(xy 105.025104 -47.652397) (xy 104.997808 -47.603762) (xy 104.977885 -47.551671) (xy 104.965759 -47.497234)
			(xy 104.961688 -47.441612) (xy 103.687649 -47.441612) (xy 103.681416 -47.484965) (xy 103.666061 -47.53726)
			(xy 103.643419 -47.586837) (xy 103.613953 -47.632687) (xy 103.578262 -47.673878) (xy 103.537071 -47.709569)
			(xy 103.491221 -47.739035) (xy 103.441644 -47.761677) (xy 103.389349 -47.777032) (xy 103.335401 -47.784788)
			(xy 103.280899 -47.784788) (xy 103.226951 -47.777032) (xy 103.174656 -47.761677) (xy 103.125079 -47.739035)
			(xy 103.079229 -47.709569) (xy 103.038038 -47.673878) (xy 103.002347 -47.632687) (xy 102.972881 -47.586837)
			(xy 102.950239 -47.53726) (xy 102.934884 -47.484965) (xy 102.927128 -47.431017) (xy 102.926642 -47.403766)
			(xy 102.92711 -47.377338) (xy 102.93442 -47.32499) (xy 102.948895 -47.274155) (xy 102.970256 -47.225809)
			(xy 102.983792 -47.203106) (xy 102.984046 -47.202852) (xy 102.989381 -47.192833) (xy 102.99164 -47.170284)
			(xy 102.988364 -47.159418) (xy 102.962202 -47.084742) (xy 102.957838 -47.074216) (xy 102.941736 -47.058132)
			(xy 102.931214 -47.053754) (xy 102.93096 -47.053754) (xy 102.906453 -47.044679) (xy 102.860001 -47.020738)
			(xy 102.817249 -46.990683) (xy 102.778996 -46.955076) (xy 102.74596 -46.914584) (xy 102.718756 -46.869963)
			(xy 102.697894 -46.822049) (xy 102.683763 -46.771736) (xy 102.676629 -46.719966) (xy 102.676198 -46.693836)
			(xy 97.529974 -46.693836) (xy 97.532364 -46.708745) (xy 97.532952 -46.739048) (xy 97.532467 -46.766298)
			(xy 97.524705 -46.820244) (xy 97.509346 -46.872536) (xy 97.486703 -46.92211) (xy 97.457235 -46.967958)
			(xy 97.421544 -47.009147) (xy 97.380355 -47.044838) (xy 97.334507 -47.074304) (xy 97.284932 -47.096947)
			(xy 97.23264 -47.112306) (xy 97.178694 -47.120067) (xy 97.151444 -47.120556) (xy 97.12541 -47.120133)
			(xy 97.073826 -47.113039) (xy 97.023684 -47.099004) (xy 96.975913 -47.078288) (xy 96.9314 -47.051275)
			(xy 96.910906 -47.035212) (xy 96.903154 -47.029462) (xy 96.884739 -47.023726) (xy 96.875092 -47.024036)
			(xy 96.795336 -47.030386) (xy 96.777556 -47.039022) (xy 96.771206 -47.046388) (xy 96.753045 -47.066053)
			(xy 96.712133 -47.100573) (xy 96.6668 -47.12904) (xy 96.617935 -47.150894) (xy 96.566495 -47.165708)
			(xy 96.513491 -47.173189) (xy 96.486726 -47.173642) (xy 96.459477 -47.173098) (xy 96.405533 -47.165346)
			(xy 96.353242 -47.149995) (xy 96.303667 -47.12736) (xy 96.257818 -47.0979) (xy 96.216628 -47.062214)
			(xy 96.180936 -47.02103) (xy 96.151469 -46.975186) (xy 96.128826 -46.925615) (xy 96.113467 -46.873326)
			(xy 96.105707 -46.819383) (xy 96.105218 -46.792134) (xy 96.105738 -46.76336) (xy 96.114389 -46.706465)
			(xy 96.131486 -46.651514) (xy 96.156641 -46.599754) (xy 96.189283 -46.552359) (xy 96.208596 -46.531022)
			(xy 96.215962 -46.523148) (xy 96.223074 -46.503336) (xy 96.215708 -46.40707) (xy 96.205802 -46.388274)
			(xy 96.19742 -46.38167) (xy 96.175235 -46.363445) (xy 96.136025 -46.32151) (xy 96.10354 -46.274174)
			(xy 96.078511 -46.222506) (xy 96.061505 -46.167672) (xy 96.052904 -46.110909) (xy 96.052386 -46.082204)
			(xy 92.878215 -46.082204) (xy 92.761308 -46.64075) (xy 92.419764 -48.30699) (xy 102.553768 -48.30699)
			(xy 102.557839 -48.251368) (xy 102.569965 -48.196931) (xy 102.589888 -48.14484) (xy 102.617184 -48.096205)
			(xy 102.65127 -48.052062) (xy 102.691419 -48.013353) (xy 102.736777 -47.980902) (xy 102.786377 -47.955401)
			(xy 102.839161 -47.937394) (xy 102.894004 -47.927264) (xy 102.949738 -47.925227) (xy 103.005175 -47.931327)
			(xy 103.059132 -47.945433) (xy 103.110461 -47.967245) (xy 103.158067 -47.996299) (xy 103.200935 -48.031974)
			(xy 103.238152 -48.073511) (xy 103.268925 -48.120024) (xy 103.292597 -48.170521) (xy 103.308665 -48.223928)
			(xy 103.316785 -48.279104) (xy 103.317294 -48.30699) (xy 103.316785 -48.334876) (xy 103.308665 -48.390052)
			(xy 103.292597 -48.443459) (xy 103.268925 -48.493956) (xy 103.238152 -48.540469) (xy 103.200935 -48.582006)
			(xy 103.158067 -48.617681) (xy 103.110461 -48.646735) (xy 103.059132 -48.668547) (xy 103.005175 -48.682653)
			(xy 102.949738 -48.688753) (xy 102.894004 -48.686716) (xy 102.839161 -48.676586) (xy 102.786377 -48.658579)
			(xy 102.736777 -48.633078) (xy 102.691419 -48.600627) (xy 102.65127 -48.561918) (xy 102.617184 -48.517775)
			(xy 102.589888 -48.46914) (xy 102.569965 -48.417049) (xy 102.557839 -48.362612) (xy 102.553768 -48.30699)
			(xy 92.419764 -48.30699) (xy 92.328339 -48.753014) (xy 99.168202 -48.753014) (xy 99.172273 -48.697392)
			(xy 99.184399 -48.642955) (xy 99.204322 -48.590864) (xy 99.231618 -48.542229) (xy 99.265704 -48.498086)
			(xy 99.305853 -48.459377) (xy 99.351211 -48.426926) (xy 99.400811 -48.401425) (xy 99.453595 -48.383418)
			(xy 99.508438 -48.373288) (xy 99.564172 -48.371251) (xy 99.619609 -48.377351) (xy 99.673566 -48.391457)
			(xy 99.724895 -48.413269) (xy 99.772501 -48.442323) (xy 99.815369 -48.477998) (xy 99.852586 -48.519535)
			(xy 99.883359 -48.566048) (xy 99.907031 -48.616545) (xy 99.923099 -48.669952) (xy 99.931219 -48.725128)
			(xy 99.931728 -48.753014) (xy 99.931219 -48.7809) (xy 99.923099 -48.836076) (xy 99.920655 -48.8442)
			(xy 100.18725 -48.8442) (xy 100.191321 -48.788578) (xy 100.203447 -48.734141) (xy 100.22337 -48.68205)
			(xy 100.250666 -48.633415) (xy 100.284752 -48.589272) (xy 100.324901 -48.550563) (xy 100.370259 -48.518112)
			(xy 100.419859 -48.492611) (xy 100.472643 -48.474604) (xy 100.527486 -48.464474) (xy 100.58322 -48.462437)
			(xy 100.638657 -48.468537) (xy 100.692614 -48.482643) (xy 100.743943 -48.504455) (xy 100.791549 -48.533509)
			(xy 100.834417 -48.569184) (xy 100.871634 -48.610721) (xy 100.902407 -48.657234) (xy 100.926079 -48.707731)
			(xy 100.942147 -48.761138) (xy 100.950267 -48.816314) (xy 100.950776 -48.8442) (xy 100.950267 -48.872086)
			(xy 100.947269 -48.89246) (xy 101.213918 -48.89246) (xy 101.217989 -48.836838) (xy 101.230115 -48.782401)
			(xy 101.250038 -48.73031) (xy 101.277334 -48.681675) (xy 101.31142 -48.637532) (xy 101.351569 -48.598823)
			(xy 101.396927 -48.566372) (xy 101.446527 -48.540871) (xy 101.499311 -48.522864) (xy 101.554154 -48.512734)
			(xy 101.609888 -48.510697) (xy 101.665325 -48.516797) (xy 101.719282 -48.530903) (xy 101.770611 -48.552715)
			(xy 101.818217 -48.581769) (xy 101.861085 -48.617444) (xy 101.898302 -48.658981) (xy 101.929075 -48.705494)
			(xy 101.952747 -48.755991) (xy 101.968815 -48.809398) (xy 101.976935 -48.864574) (xy 101.977444 -48.89246)
			(xy 101.976935 -48.920346) (xy 101.974497 -48.93691) (xy 104.932986 -48.93691) (xy 104.937057 -48.881288)
			(xy 104.949183 -48.826851) (xy 104.969106 -48.77476) (xy 104.996402 -48.726125) (xy 105.030488 -48.681982)
			(xy 105.070637 -48.643273) (xy 105.115995 -48.610822) (xy 105.165595 -48.585321) (xy 105.218379 -48.567314)
			(xy 105.273222 -48.557184) (xy 105.328956 -48.555147) (xy 105.384393 -48.561247) (xy 105.43835 -48.575353)
			(xy 105.489679 -48.597165) (xy 105.537285 -48.626219) (xy 105.580153 -48.661894) (xy 105.61737 -48.703431)
			(xy 105.648143 -48.749944) (xy 105.671815 -48.800441) (xy 105.687883 -48.853848) (xy 105.696003 -48.909024)
			(xy 105.696512 -48.93691) (xy 105.696003 -48.964796) (xy 105.687883 -49.019972) (xy 105.671815 -49.073379)
			(xy 105.648143 -49.123876) (xy 105.61737 -49.170389) (xy 105.580153 -49.211926) (xy 105.537285 -49.247601)
			(xy 105.489679 -49.276655) (xy 105.43835 -49.298467) (xy 105.384393 -49.312573) (xy 105.328956 -49.318673)
			(xy 105.273222 -49.316636) (xy 105.218379 -49.306506) (xy 105.165595 -49.288499) (xy 105.115995 -49.262998)
			(xy 105.070637 -49.230547) (xy 105.030488 -49.191838) (xy 104.996402 -49.147695) (xy 104.969106 -49.09906)
			(xy 104.949183 -49.046969) (xy 104.937057 -48.992532) (xy 104.932986 -48.93691) (xy 101.974497 -48.93691)
			(xy 101.968815 -48.975522) (xy 101.952747 -49.028929) (xy 101.929075 -49.079426) (xy 101.898302 -49.125939)
			(xy 101.861085 -49.167476) (xy 101.818217 -49.203151) (xy 101.770611 -49.232205) (xy 101.719282 -49.254017)
			(xy 101.665325 -49.268123) (xy 101.609888 -49.274223) (xy 101.554154 -49.272186) (xy 101.499311 -49.262056)
			(xy 101.446527 -49.244049) (xy 101.396927 -49.218548) (xy 101.351569 -49.186097) (xy 101.31142 -49.147388)
			(xy 101.277334 -49.103245) (xy 101.250038 -49.05461) (xy 101.230115 -49.002519) (xy 101.217989 -48.948082)
			(xy 101.213918 -48.89246) (xy 100.947269 -48.89246) (xy 100.942147 -48.927262) (xy 100.926079 -48.980669)
			(xy 100.902407 -49.031166) (xy 100.871634 -49.077679) (xy 100.834417 -49.119216) (xy 100.791549 -49.154891)
			(xy 100.743943 -49.183945) (xy 100.692614 -49.205757) (xy 100.638657 -49.219863) (xy 100.58322 -49.225963)
			(xy 100.527486 -49.223926) (xy 100.472643 -49.213796) (xy 100.419859 -49.195789) (xy 100.370259 -49.170288)
			(xy 100.324901 -49.137837) (xy 100.284752 -49.099128) (xy 100.250666 -49.054985) (xy 100.22337 -49.00635)
			(xy 100.203447 -48.954259) (xy 100.191321 -48.899822) (xy 100.18725 -48.8442) (xy 99.920655 -48.8442)
			(xy 99.907031 -48.889483) (xy 99.883359 -48.93998) (xy 99.852586 -48.986493) (xy 99.815369 -49.02803)
			(xy 99.772501 -49.063705) (xy 99.724895 -49.092759) (xy 99.673566 -49.114571) (xy 99.619609 -49.128677)
			(xy 99.564172 -49.134777) (xy 99.508438 -49.13274) (xy 99.453595 -49.12261) (xy 99.400811 -49.104603)
			(xy 99.351211 -49.079102) (xy 99.305853 -49.046651) (xy 99.265704 -49.007942) (xy 99.231618 -48.963799)
			(xy 99.204322 -48.915164) (xy 99.184399 -48.863073) (xy 99.172273 -48.808636) (xy 99.168202 -48.753014)
			(xy 92.328339 -48.753014) (xy 92.269818 -49.03851) (xy 92.190062 -49.429162) (xy 92.1893 -49.436274)
			(xy 92.1893 -49.95291) (xy 104.932986 -49.95291) (xy 104.937057 -49.897288) (xy 104.949183 -49.842851)
			(xy 104.969106 -49.79076) (xy 104.996402 -49.742125) (xy 105.030488 -49.697982) (xy 105.070637 -49.659273)
			(xy 105.115995 -49.626822) (xy 105.165595 -49.601321) (xy 105.218379 -49.583314) (xy 105.273222 -49.573184)
			(xy 105.328956 -49.571147) (xy 105.384393 -49.577247) (xy 105.43835 -49.591353) (xy 105.489679 -49.613165)
			(xy 105.537285 -49.642219) (xy 105.580153 -49.677894) (xy 105.61737 -49.719431) (xy 105.648143 -49.765944)
			(xy 105.671815 -49.816441) (xy 105.687883 -49.869848) (xy 105.696003 -49.925024) (xy 105.696512 -49.95291)
			(xy 105.696003 -49.980796) (xy 105.687883 -50.035972) (xy 105.671815 -50.089379) (xy 105.648143 -50.139876)
			(xy 105.61737 -50.186389) (xy 105.580153 -50.227926) (xy 105.537285 -50.263601) (xy 105.489679 -50.292655)
			(xy 105.43835 -50.314467) (xy 105.384393 -50.328573) (xy 105.328956 -50.334673) (xy 105.273222 -50.332636)
			(xy 105.218379 -50.322506) (xy 105.165595 -50.304499) (xy 105.115995 -50.278998) (xy 105.070637 -50.246547)
			(xy 105.030488 -50.207838) (xy 104.996402 -50.163695) (xy 104.969106 -50.11506) (xy 104.949183 -50.062969)
			(xy 104.937057 -50.008532) (xy 104.932986 -49.95291) (xy 92.1893 -49.95291) (xy 92.1893 -51.019456)
			(xy 102.749348 -51.019456) (xy 102.753419 -50.963834) (xy 102.765545 -50.909397) (xy 102.785468 -50.857306)
			(xy 102.812764 -50.808671) (xy 102.84685 -50.764528) (xy 102.886999 -50.725819) (xy 102.932357 -50.693368)
			(xy 102.981957 -50.667867) (xy 103.034741 -50.64986) (xy 103.089584 -50.63973) (xy 103.145318 -50.637693)
			(xy 103.200755 -50.643793) (xy 103.254712 -50.657899) (xy 103.306041 -50.679711) (xy 103.353647 -50.708765)
			(xy 103.396515 -50.74444) (xy 103.433732 -50.785977) (xy 103.464505 -50.83249) (xy 103.488177 -50.882987)
			(xy 103.504245 -50.936394) (xy 103.512365 -50.99157) (xy 103.512874 -51.019456) (xy 103.512365 -51.047342)
			(xy 103.504245 -51.102518) (xy 103.488177 -51.155925) (xy 103.464505 -51.206422) (xy 103.433732 -51.252935)
			(xy 103.396515 -51.294472) (xy 103.353647 -51.330147) (xy 103.306041 -51.359201) (xy 103.254712 -51.381013)
			(xy 103.200755 -51.395119) (xy 103.145318 -51.401219) (xy 103.089584 -51.399182) (xy 103.034741 -51.389052)
			(xy 102.981957 -51.371045) (xy 102.932357 -51.345544) (xy 102.886999 -51.313093) (xy 102.84685 -51.274384)
			(xy 102.812764 -51.230241) (xy 102.785468 -51.181606) (xy 102.765545 -51.129515) (xy 102.753419 -51.075078)
			(xy 102.749348 -51.019456) (xy 92.1893 -51.019456) (xy 92.1893 -52.035456) (xy 104.941114 -52.035456)
			(xy 104.945185 -51.979834) (xy 104.957311 -51.925397) (xy 104.977234 -51.873306) (xy 105.00453 -51.824671)
			(xy 105.038616 -51.780528) (xy 105.078765 -51.741819) (xy 105.124123 -51.709368) (xy 105.173723 -51.683867)
			(xy 105.226507 -51.66586) (xy 105.28135 -51.65573) (xy 105.337084 -51.653693) (xy 105.392521 -51.659793)
			(xy 105.446478 -51.673899) (xy 105.497807 -51.695711) (xy 105.545413 -51.724765) (xy 105.588281 -51.76044)
			(xy 105.625498 -51.801977) (xy 105.656271 -51.84849) (xy 105.679943 -51.898987) (xy 105.696011 -51.952394)
			(xy 105.704131 -52.00757) (xy 105.70464 -52.035456) (xy 105.704131 -52.063342) (xy 105.696011 -52.118518)
			(xy 105.679943 -52.171925) (xy 105.656271 -52.222422) (xy 105.625498 -52.268935) (xy 105.588281 -52.310472)
			(xy 105.545413 -52.346147) (xy 105.497807 -52.375201) (xy 105.446478 -52.397013) (xy 105.392521 -52.411119)
			(xy 105.337084 -52.417219) (xy 105.28135 -52.415182) (xy 105.226507 -52.405052) (xy 105.173723 -52.387045)
			(xy 105.124123 -52.361544) (xy 105.078765 -52.329093) (xy 105.038616 -52.290384) (xy 105.00453 -52.246241)
			(xy 104.977234 -52.197606) (xy 104.957311 -52.145515) (xy 104.945185 -52.091078) (xy 104.941114 -52.035456)
			(xy 92.1893 -52.035456) (xy 92.1893 -52.548536) (xy 92.189405 -52.552883) (xy 92.190929 -52.561444)
			(xy 92.192348 -52.565554) (xy 92.200222 -52.587906) (xy 92.205302 -52.594256) (xy 92.220128 -52.614306)
			(xy 92.245007 -52.657521) (xy 92.264044 -52.703609) (xy 92.276916 -52.751784) (xy 92.283404 -52.801225)
			(xy 92.283788 -52.826158) (xy 92.283788 -52.826666) (xy 92.283411 -52.851717) (xy 92.276896 -52.901394)
			(xy 92.263948 -52.949793) (xy 92.244789 -52.996087) (xy 92.219746 -53.039481) (xy 92.204794 -53.059584)
			(xy 92.203778 -53.0606) (xy 92.197936 -53.06949) (xy 92.19438 -53.076602) (xy 92.19057 -53.087524)
			(xy 92.1893 -53.0987) (xy 92.1893 -53.180234) (xy 92.189554 -53.18506) (xy 92.190062 -53.188616)
			(xy 92.191078 -53.195474) (xy 92.19311 -53.203348) (xy 92.19565 -53.210968) (xy 92.199206 -53.221128)
			(xy 92.203016 -53.225954) (xy 92.203016 -53.226208) (xy 92.20454 -53.22824) (xy 92.204794 -53.228494)
			(xy 92.219852 -53.248825) (xy 92.24505 -53.292698) (xy 92.264239 -53.339512) (xy 92.277084 -53.388449)
			(xy 92.283359 -53.438653) (xy 92.283534 -53.463952) (xy 92.282983 -53.488849) (xy 92.276209 -53.538186)
			(xy 92.26307 -53.586221) (xy 92.24379 -53.632137) (xy 92.218698 -53.675153) (xy 92.203778 -53.695092)
			(xy 92.200476 -53.699156) (xy 92.19438 -53.711348) (xy 92.19057 -53.72227) (xy 92.1893 -53.733446)
			(xy 92.1893 -53.815234) (xy 92.189554 -53.82006) (xy 92.190062 -53.823616) (xy 92.191078 -53.830474)
			(xy 92.19311 -53.838348) (xy 92.19565 -53.845968) (xy 92.199206 -53.856128) (xy 92.203016 -53.860954)
			(xy 92.203016 -53.861208) (xy 92.20454 -53.86324) (xy 92.204794 -53.863494) (xy 92.219852 -53.883825)
			(xy 92.24505 -53.927698) (xy 92.264239 -53.974512) (xy 92.277084 -54.023449) (xy 92.283359 -54.073653)
			(xy 92.283534 -54.098952) (xy 92.282983 -54.123849) (xy 92.276209 -54.173186) (xy 92.26307 -54.221221)
			(xy 92.24379 -54.267137) (xy 92.218698 -54.310153) (xy 92.203778 -54.330092) (xy 92.200476 -54.334156)
			(xy 92.19438 -54.346348) (xy 92.19057 -54.35727) (xy 92.1893 -54.368446) (xy 92.1893 -54.464966)
			(xy 92.19184 -54.475888) (xy 92.194634 -54.481476) (xy 92.200222 -54.49316) (xy 92.203524 -54.497478)
			(xy 92.218648 -54.517603) (xy 92.244038 -54.561074) (xy 92.263495 -54.607505) (xy 92.276682 -54.65609)
			(xy 92.283369 -54.705987) (xy 92.283788 -54.731158) (xy 92.283788 -54.737508) (xy 92.283026 -54.75224)
			(xy 92.280993 -54.780259) (xy 92.278774 -54.791102) (xy 94.176342 -54.791102) (xy 94.176799 -54.763731)
			(xy 94.184617 -54.709551) (xy 94.200108 -54.657048) (xy 94.222952 -54.607301) (xy 94.252679 -54.561335)
			(xy 94.270322 -54.540404) (xy 94.270576 -54.54015) (xy 94.276157 -54.53306) (xy 94.282405 -54.516146)
			(xy 94.282768 -54.50713) (xy 94.282768 -54.440074) (xy 94.28243 -54.431055) (xy 94.27617 -54.414138)
			(xy 94.270576 -54.407054) (xy 94.270322 -54.407054) (xy 94.270322 -54.4068) (xy 94.252683 -54.385866)
			(xy 94.222959 -54.339898) (xy 94.200114 -54.290152) (xy 94.184618 -54.23765) (xy 94.176789 -54.183472)
			(xy 94.176789 -54.128731) (xy 94.184617 -54.074553) (xy 94.200113 -54.022051) (xy 94.222958 -53.972305)
			(xy 94.252682 -53.926337) (xy 94.270322 -53.905404) (xy 94.270576 -53.90515) (xy 94.276157 -53.89806)
			(xy 94.282405 -53.881146) (xy 94.282768 -53.87213) (xy 94.282768 -53.805074) (xy 94.28243 -53.796055)
			(xy 94.27617 -53.779138) (xy 94.270576 -53.772054) (xy 94.270322 -53.772054) (xy 94.270322 -53.7718)
			(xy 94.252683 -53.750866) (xy 94.222959 -53.704898) (xy 94.200114 -53.655152) (xy 94.184618 -53.60265)
			(xy 94.176789 -53.548472) (xy 94.176789 -53.493731) (xy 94.184617 -53.439553) (xy 94.200113 -53.387051)
			(xy 94.222958 -53.337305) (xy 94.252682 -53.291337) (xy 94.270322 -53.270404) (xy 94.270576 -53.27015)
			(xy 94.276157 -53.26306) (xy 94.282405 -53.246146) (xy 94.282768 -53.23713) (xy 94.282768 -53.170074)
			(xy 94.28243 -53.161055) (xy 94.27617 -53.144138) (xy 94.270576 -53.137054) (xy 94.270322 -53.137054)
			(xy 94.270322 -53.1368) (xy 94.252673 -53.115876) (xy 94.222962 -53.069901) (xy 94.200127 -53.020152)
			(xy 94.184639 -52.967649) (xy 94.176814 -52.913472) (xy 94.176342 -52.886102) (xy 94.176828 -52.858851)
			(xy 94.184584 -52.804903) (xy 94.199939 -52.752608) (xy 94.222581 -52.703031) (xy 94.252047 -52.657181)
			(xy 94.287738 -52.61599) (xy 94.328929 -52.580299) (xy 94.374779 -52.550833) (xy 94.424356 -52.528191)
			(xy 94.476651 -52.512836) (xy 94.530599 -52.50508) (xy 94.585101 -52.50508) (xy 94.639049 -52.512836)
			(xy 94.691344 -52.528191) (xy 94.730453 -52.546052) (xy 99.679473 -52.546052) (xy 99.679473 -52.491548)
			(xy 99.68723 -52.437599) (xy 99.702586 -52.385303) (xy 99.725228 -52.335725) (xy 99.754695 -52.289874)
			(xy 99.790387 -52.248683) (xy 99.831579 -52.212991) (xy 99.87743 -52.183525) (xy 99.927009 -52.160884)
			(xy 99.979305 -52.145529) (xy 100.033254 -52.137773) (xy 100.060506 -52.13731) (xy 100.087876 -52.13777)
			(xy 100.142056 -52.145589) (xy 100.194559 -52.161079) (xy 100.244306 -52.183922) (xy 100.290273 -52.213648)
			(xy 100.311204 -52.23129) (xy 100.311458 -52.231544) (xy 100.318549 -52.237124) (xy 100.335462 -52.243374)
			(xy 100.344478 -52.243736) (xy 100.411534 -52.243736) (xy 100.420552 -52.243388) (xy 100.437468 -52.237133)
			(xy 100.444554 -52.231544) (xy 100.444554 -52.23129) (xy 100.444808 -52.23129) (xy 100.465741 -52.213649)
			(xy 100.511709 -52.183925) (xy 100.561455 -52.161079) (xy 100.613957 -52.145583) (xy 100.668135 -52.137754)
			(xy 100.722877 -52.137754) (xy 100.777055 -52.145583) (xy 100.829557 -52.161079) (xy 100.879303 -52.183925)
			(xy 100.925271 -52.213649) (xy 100.946204 -52.23129) (xy 100.946458 -52.231544) (xy 100.953549 -52.237124)
			(xy 100.970462 -52.243374) (xy 100.979478 -52.243736) (xy 101.046534 -52.243736) (xy 101.055552 -52.243388)
			(xy 101.072468 -52.237133) (xy 101.079554 -52.231544) (xy 101.079554 -52.23129) (xy 101.079808 -52.23129)
			(xy 101.100725 -52.213632) (xy 101.146702 -52.183923) (xy 101.196453 -52.161091) (xy 101.248957 -52.145605)
			(xy 101.303136 -52.137781) (xy 101.330506 -52.13731) (xy 101.357758 -52.13776) (xy 101.411708 -52.145518)
			(xy 101.464004 -52.160874) (xy 101.513583 -52.183517) (xy 101.559435 -52.212985) (xy 101.600626 -52.248678)
			(xy 101.636319 -52.28987) (xy 101.665786 -52.335722) (xy 101.688428 -52.385301) (xy 101.703783 -52.437598)
			(xy 101.71154 -52.491548) (xy 101.71154 -52.546052) (xy 101.705595 -52.587398) (xy 102.75519 -52.587398)
			(xy 102.759261 -52.531776) (xy 102.771387 -52.477339) (xy 102.79131 -52.425248) (xy 102.818606 -52.376613)
			(xy 102.852692 -52.33247) (xy 102.892841 -52.293761) (xy 102.938199 -52.26131) (xy 102.987799 -52.235809)
			(xy 103.040583 -52.217802) (xy 103.095426 -52.207672) (xy 103.15116 -52.205635) (xy 103.206597 -52.211735)
			(xy 103.260554 -52.225841) (xy 103.311883 -52.247653) (xy 103.359489 -52.276707) (xy 103.402357 -52.312382)
			(xy 103.439574 -52.353919) (xy 103.470347 -52.400432) (xy 103.494019 -52.450929) (xy 103.510087 -52.504336)
			(xy 103.517683 -52.555953) (xy 122.683979 -52.555953) (xy 122.683979 -52.501447) (xy 122.691737 -52.447497)
			(xy 122.707093 -52.3952) (xy 122.729737 -52.345621) (xy 122.759206 -52.299769) (xy 122.794901 -52.258578)
			(xy 122.836095 -52.222887) (xy 122.881949 -52.193421) (xy 122.93153 -52.170782) (xy 122.983828 -52.15543)
			(xy 123.037779 -52.147677) (xy 123.065032 -52.147216) (xy 123.092403 -52.147659) (xy 123.146583 -52.155482)
			(xy 123.199087 -52.170976) (xy 123.248833 -52.193823) (xy 123.294799 -52.223552) (xy 123.31573 -52.241196)
			(xy 123.315984 -52.24145) (xy 123.323067 -52.247042) (xy 123.339987 -52.253284) (xy 123.349004 -52.253642)
			(xy 123.41606 -52.253642) (xy 123.425076 -52.253278) (xy 123.441994 -52.247037) (xy 123.44908 -52.24145)
			(xy 123.44908 -52.241196) (xy 123.449334 -52.241196) (xy 123.47028 -52.223574) (xy 123.516249 -52.19386)
			(xy 123.565993 -52.17102) (xy 123.61849 -52.155525) (xy 123.672664 -52.147693) (xy 123.700032 -52.147216)
			(xy 123.727283 -52.147656) (xy 123.781231 -52.155417) (xy 123.833525 -52.170776) (xy 123.883102 -52.19342)
			(xy 123.928951 -52.222889) (xy 123.97014 -52.258583) (xy 124.00583 -52.299775) (xy 124.035295 -52.345626)
			(xy 124.057936 -52.395205) (xy 124.07329 -52.4475) (xy 124.081046 -52.501448) (xy 124.081046 -52.555952)
			(xy 124.07329 -52.6099) (xy 124.057936 -52.662195) (xy 124.035295 -52.711774) (xy 124.00583 -52.757625)
			(xy 123.97014 -52.798817) (xy 123.928951 -52.834511) (xy 123.883102 -52.86398) (xy 123.833525 -52.886624)
			(xy 123.781231 -52.901983) (xy 123.727283 -52.909744) (xy 123.700032 -52.910232) (xy 123.672662 -52.909764)
			(xy 123.618482 -52.901949) (xy 123.565978 -52.886461) (xy 123.516231 -52.86362) (xy 123.470265 -52.833894)
			(xy 123.449334 -52.816252) (xy 123.44908 -52.815998) (xy 123.442004 -52.810397) (xy 123.425079 -52.804159)
			(xy 123.41606 -52.803806) (xy 123.349004 -52.803806) (xy 123.339987 -52.804164) (xy 123.32307 -52.810411)
			(xy 123.315984 -52.815998) (xy 123.315984 -52.816252) (xy 123.31573 -52.816252) (xy 123.294791 -52.833883)
			(xy 123.248821 -52.863598) (xy 123.199075 -52.886436) (xy 123.146576 -52.901929) (xy 123.092401 -52.909758)
			(xy 123.065032 -52.910232) (xy 123.037779 -52.909723) (xy 122.983828 -52.90197) (xy 122.93153 -52.886618)
			(xy 122.881949 -52.863979) (xy 122.836095 -52.834513) (xy 122.794901 -52.798822) (xy 122.759206 -52.757631)
			(xy 122.729737 -52.711779) (xy 122.707093 -52.6622) (xy 122.691737 -52.609903) (xy 122.683979 -52.555953)
			(xy 103.517683 -52.555953) (xy 103.518207 -52.559512) (xy 103.518716 -52.587398) (xy 103.518207 -52.615284)
			(xy 103.510087 -52.67046) (xy 103.494019 -52.723867) (xy 103.470347 -52.774364) (xy 103.439574 -52.820877)
			(xy 103.402357 -52.862414) (xy 103.359489 -52.898089) (xy 103.311883 -52.927143) (xy 103.260554 -52.948955)
			(xy 103.206597 -52.963061) (xy 103.15116 -52.969161) (xy 103.095426 -52.967124) (xy 103.040583 -52.956994)
			(xy 102.987799 -52.938987) (xy 102.938199 -52.913486) (xy 102.892841 -52.881035) (xy 102.852692 -52.842326)
			(xy 102.818606 -52.798183) (xy 102.79131 -52.749548) (xy 102.771387 -52.697457) (xy 102.759261 -52.64302)
			(xy 102.75519 -52.587398) (xy 101.705595 -52.587398) (xy 101.703783 -52.600002) (xy 101.688428 -52.652299)
			(xy 101.665786 -52.701878) (xy 101.636319 -52.74773) (xy 101.600626 -52.788922) (xy 101.559435 -52.824615)
			(xy 101.513583 -52.854083) (xy 101.464004 -52.876726) (xy 101.411708 -52.892082) (xy 101.357758 -52.89984)
			(xy 101.330506 -52.900326) (xy 101.303135 -52.899874) (xy 101.248955 -52.892056) (xy 101.196451 -52.876564)
			(xy 101.146704 -52.853719) (xy 101.100738 -52.82399) (xy 101.079808 -52.806346) (xy 101.079554 -52.806092)
			(xy 101.072457 -52.800521) (xy 101.055548 -52.794265) (xy 101.046534 -52.7939) (xy 100.979478 -52.7939)
			(xy 100.97046 -52.794247) (xy 100.953543 -52.800501) (xy 100.946458 -52.806092) (xy 100.946204 -52.806346)
			(xy 100.925271 -52.823987) (xy 100.879303 -52.853711) (xy 100.829557 -52.876557) (xy 100.777055 -52.892053)
			(xy 100.722877 -52.899882) (xy 100.668135 -52.899882) (xy 100.613957 -52.892053) (xy 100.561455 -52.876557)
			(xy 100.511709 -52.853711) (xy 100.465741 -52.823987) (xy 100.444808 -52.806346) (xy 100.444554 -52.806092)
			(xy 100.437457 -52.800521) (xy 100.420548 -52.794265) (xy 100.411534 -52.7939) (xy 100.344478 -52.7939)
			(xy 100.33546 -52.794247) (xy 100.318543 -52.800501) (xy 100.311458 -52.806092) (xy 100.311458 -52.806346)
			(xy 100.311204 -52.806346) (xy 100.290274 -52.823988) (xy 100.244302 -52.853701) (xy 100.194554 -52.876538)
			(xy 100.142052 -52.892028) (xy 100.087875 -52.899854) (xy 100.060506 -52.900326) (xy 100.033254 -52.899827)
			(xy 99.979305 -52.892071) (xy 99.927009 -52.876716) (xy 99.87743 -52.854075) (xy 99.831579 -52.824609)
			(xy 99.790387 -52.788917) (xy 99.754695 -52.747726) (xy 99.725228 -52.701875) (xy 99.702586 -52.652297)
			(xy 99.68723 -52.600001) (xy 99.679473 -52.546052) (xy 94.730453 -52.546052) (xy 94.740921 -52.550833)
			(xy 94.786771 -52.580299) (xy 94.827962 -52.61599) (xy 94.863653 -52.657181) (xy 94.893119 -52.703031)
			(xy 94.915761 -52.752608) (xy 94.931116 -52.804903) (xy 94.938872 -52.858851) (xy 94.939358 -52.886102)
			(xy 94.938903 -52.913473) (xy 94.931084 -52.967653) (xy 94.915593 -53.020156) (xy 94.892749 -53.069903)
			(xy 94.863021 -53.115869) (xy 94.845378 -53.1368) (xy 94.845124 -53.137054) (xy 94.839542 -53.144143)
			(xy 94.833294 -53.161058) (xy 94.832932 -53.170074) (xy 94.832932 -53.23713) (xy 94.833268 -53.246149)
			(xy 94.839529 -53.263066) (xy 94.845124 -53.27015) (xy 94.845378 -53.27015) (xy 94.845378 -53.270404)
			(xy 94.86302 -53.291335) (xy 94.892745 -53.337303) (xy 94.91559 -53.38705) (xy 94.931086 -53.439552)
			(xy 94.938914 -53.493731) (xy 94.938914 -53.548472) (xy 94.931085 -53.602651) (xy 94.915589 -53.655153)
			(xy 94.892743 -53.704899) (xy 94.863019 -53.750867) (xy 94.846448 -53.77053) (xy 95.21063 -53.77053)
			(xy 95.211158 -53.741613) (xy 95.219884 -53.684442) (xy 95.237139 -53.629243) (xy 95.262529 -53.577281)
			(xy 95.295471 -53.529747) (xy 95.335211 -53.48773) (xy 95.357696 -53.46954) (xy 95.366475 -53.461905)
			(xy 95.376674 -53.441026) (xy 95.377254 -53.429408) (xy 95.377254 -53.349652) (xy 95.376744 -53.338016)
			(xy 95.366536 -53.317106) (xy 95.357696 -53.30952) (xy 95.335221 -53.291319) (xy 95.295486 -53.249301)
			(xy 95.262546 -53.201768) (xy 95.237156 -53.149809) (xy 95.219898 -53.094613) (xy 95.211166 -53.037445)
			(xy 95.21063 -53.00853) (xy 95.211083 -52.981276) (xy 95.218837 -52.927323) (xy 95.234191 -52.875023)
			(xy 95.256833 -52.82544) (xy 95.286302 -52.779585) (xy 95.321997 -52.738391) (xy 95.363191 -52.702697)
			(xy 95.409047 -52.673229) (xy 95.45863 -52.650589) (xy 95.510931 -52.635236) (xy 95.564884 -52.627483)
			(xy 95.592138 -52.627022) (xy 95.618453 -52.627457) (xy 95.670583 -52.634698) (xy 95.721227 -52.649023)
			(xy 95.769426 -52.670161) (xy 95.814269 -52.697713) (xy 95.854907 -52.731158) (xy 95.873062 -52.750212)
			(xy 95.880594 -52.757601) (xy 95.899866 -52.766132) (xy 95.9104 -52.766722) (xy 95.985076 -52.766722)
			(xy 95.995625 -52.766187) (xy 96.01492 -52.757655) (xy 96.022414 -52.750212) (xy 96.040572 -52.731159)
			(xy 96.081201 -52.697701) (xy 96.126041 -52.670141) (xy 96.174241 -52.649002) (xy 96.224888 -52.634685)
			(xy 96.277022 -52.62746) (xy 96.303338 -52.627022) (xy 96.330592 -52.627443) (xy 96.384543 -52.635205)
			(xy 96.436841 -52.650566) (xy 96.48642 -52.673214) (xy 96.532272 -52.702687) (xy 96.573463 -52.738386)
			(xy 96.609154 -52.779583) (xy 96.638618 -52.825439) (xy 96.661257 -52.875023) (xy 96.676609 -52.927323)
			(xy 96.684362 -52.981276) (xy 96.684846 -53.00853) (xy 96.684382 -53.036197) (xy 96.682151 -53.051456)
			(xy 104.941114 -53.051456) (xy 104.945185 -52.995834) (xy 104.957311 -52.941397) (xy 104.977234 -52.889306)
			(xy 105.00453 -52.840671) (xy 105.038616 -52.796528) (xy 105.078765 -52.757819) (xy 105.124123 -52.725368)
			(xy 105.173723 -52.699867) (xy 105.226507 -52.68186) (xy 105.28135 -52.67173) (xy 105.337084 -52.669693)
			(xy 105.392521 -52.675793) (xy 105.446478 -52.689899) (xy 105.497807 -52.711711) (xy 105.545413 -52.740765)
			(xy 105.588281 -52.77644) (xy 105.625498 -52.817977) (xy 105.656271 -52.86449) (xy 105.679943 -52.914987)
			(xy 105.696011 -52.968394) (xy 105.704131 -53.02357) (xy 105.70464 -53.051456) (xy 105.704131 -53.079342)
			(xy 105.696011 -53.134518) (xy 105.679943 -53.187925) (xy 105.656271 -53.238422) (xy 105.625498 -53.284935)
			(xy 105.588281 -53.326472) (xy 105.545413 -53.362147) (xy 105.497807 -53.391201) (xy 105.446478 -53.413013)
			(xy 105.392521 -53.427119) (xy 105.337084 -53.433219) (xy 105.28135 -53.431182) (xy 105.226507 -53.421052)
			(xy 105.173723 -53.403045) (xy 105.124123 -53.377544) (xy 105.078765 -53.345093) (xy 105.038616 -53.306384)
			(xy 105.00453 -53.262241) (xy 104.977234 -53.213606) (xy 104.957311 -53.161515) (xy 104.945185 -53.107078)
			(xy 104.941114 -53.051456) (xy 96.682151 -53.051456) (xy 96.676377 -53.09095) (xy 96.660554 -53.143973)
			(xy 96.637244 -53.194158) (xy 96.606934 -53.240454) (xy 96.570261 -53.28189) (xy 96.527991 -53.317599)
			(xy 96.50476 -53.332634) (xy 96.495071 -53.339256) (xy 96.482633 -53.359128) (xy 96.480884 -53.370734)
			(xy 96.47301 -53.450744) (xy 96.47237 -53.462382) (xy 96.480457 -53.484219) (xy 96.488504 -53.492654)
			(xy 96.488758 -53.492908) (xy 96.507317 -53.511011) (xy 96.5399 -53.551337) (xy 96.566716 -53.595706)
			(xy 96.587273 -53.643301) (xy 96.601191 -53.693242) (xy 96.608212 -53.744608) (xy 96.608646 -53.77053)
			(xy 96.60815 -53.79778) (xy 96.600391 -53.851726) (xy 96.585034 -53.904018) (xy 96.562392 -53.953593)
			(xy 96.532926 -53.999441) (xy 96.497236 -54.04063) (xy 96.456048 -54.076321) (xy 96.4102 -54.105788)
			(xy 96.360625 -54.128431) (xy 96.308333 -54.143789) (xy 96.254388 -54.15155) (xy 96.227138 -54.152038)
			(xy 96.199768 -54.151565) (xy 96.145588 -54.143751) (xy 96.093085 -54.128264) (xy 96.043338 -54.105424)
			(xy 95.997371 -54.075699) (xy 95.97644 -54.058058) (xy 95.976186 -54.057804) (xy 95.969107 -54.052206)
			(xy 95.952185 -54.045966) (xy 95.943166 -54.045612) (xy 95.87611 -54.045612) (xy 95.867093 -54.045971)
			(xy 95.850176 -54.052217) (xy 95.84309 -54.057804) (xy 95.84309 -54.058058) (xy 95.842836 -54.058058)
			(xy 95.821896 -54.075687) (xy 95.775926 -54.105402) (xy 95.726181 -54.12824) (xy 95.673681 -54.143734)
			(xy 95.619507 -54.151563) (xy 95.592138 -54.152038) (xy 95.564887 -54.151509) (xy 95.51094 -54.143758)
			(xy 95.458646 -54.128409) (xy 95.409068 -54.105773) (xy 95.363216 -54.076312) (xy 95.322023 -54.040625)
			(xy 95.286329 -53.999439) (xy 95.25686 -53.953592) (xy 95.234215 -53.904018) (xy 95.218856 -53.851726)
			(xy 95.211095 -53.79778) (xy 95.21063 -53.77053) (xy 94.846448 -53.77053) (xy 94.845378 -53.7718)
			(xy 94.845124 -53.772054) (xy 94.839542 -53.779143) (xy 94.833294 -53.796058) (xy 94.832932 -53.805074)
			(xy 94.832932 -53.87213) (xy 94.833268 -53.881149) (xy 94.839529 -53.898066) (xy 94.845124 -53.90515)
			(xy 94.845378 -53.90515) (xy 94.845378 -53.905404) (xy 94.86302 -53.926335) (xy 94.892745 -53.972303)
			(xy 94.91559 -54.02205) (xy 94.931086 -54.074552) (xy 94.938914 -54.128731) (xy 94.938914 -54.183472)
			(xy 94.931085 -54.237651) (xy 94.915589 -54.290153) (xy 94.901796 -54.320186) (xy 97.130362 -54.320186)
			(xy 97.130805 -54.292815) (xy 97.138626 -54.238634) (xy 97.15412 -54.18613) (xy 97.176967 -54.136384)
			(xy 97.206698 -54.090418) (xy 97.224342 -54.069488) (xy 97.224596 -54.069234) (xy 97.230174 -54.062142)
			(xy 97.236426 -54.045229) (xy 97.236788 -54.036214) (xy 97.236788 -53.969158) (xy 97.236406 -53.960144)
			(xy 97.230176 -53.943226) (xy 97.224596 -53.936138) (xy 97.224342 -53.936138) (xy 97.224342 -53.935884)
			(xy 97.206735 -53.914926) (xy 97.177017 -53.868961) (xy 97.154174 -53.81922) (xy 97.138676 -53.766725)
			(xy 97.13084 -53.712553) (xy 97.130362 -53.685186) (xy 97.130848 -53.657935) (xy 97.138604 -53.603987)
			(xy 97.153959 -53.551692) (xy 97.176601 -53.502115) (xy 97.206067 -53.456265) (xy 97.241758 -53.415074)
			(xy 97.282949 -53.379383) (xy 97.328799 -53.349917) (xy 97.378376 -53.327275) (xy 97.430671 -53.31192)
			(xy 97.484619 -53.304164) (xy 97.539121 -53.304164) (xy 97.593069 -53.31192) (xy 97.645364 -53.327275)
			(xy 97.694941 -53.349917) (xy 97.740791 -53.379383) (xy 97.781982 -53.415074) (xy 97.817673 -53.456265)
			(xy 97.843564 -53.496552) (xy 122.233664 -53.496552) (xy 122.233664 -53.442048) (xy 122.24142 -53.388099)
			(xy 122.256776 -53.335803) (xy 122.279417 -53.286225) (xy 122.308883 -53.240374) (xy 122.344575 -53.199182)
			(xy 122.385766 -53.163489) (xy 122.431616 -53.134022) (xy 122.481194 -53.111379) (xy 122.53349 -53.096022)
			(xy 122.587438 -53.088264) (xy 122.61469 -53.087778) (xy 122.642061 -53.088231) (xy 122.696241 -53.096049)
			(xy 122.748745 -53.11154) (xy 122.798492 -53.134385) (xy 122.844458 -53.164114) (xy 122.865388 -53.181758)
			(xy 122.865642 -53.182012) (xy 122.87274 -53.187582) (xy 122.889648 -53.193838) (xy 122.898662 -53.194204)
			(xy 122.965718 -53.194204) (xy 122.974736 -53.193855) (xy 122.991652 -53.187602) (xy 122.998738 -53.182012)
			(xy 122.998738 -53.181758) (xy 122.998992 -53.181758) (xy 123.019911 -53.164102) (xy 123.065888 -53.134394)
			(xy 123.115639 -53.111562) (xy 123.168142 -53.096075) (xy 123.22232 -53.08825) (xy 123.24969 -53.087778)
			(xy 123.276942 -53.088269) (xy 123.330892 -53.096024) (xy 123.383189 -53.111379) (xy 123.432769 -53.13402)
			(xy 123.478622 -53.163486) (xy 123.519814 -53.199179) (xy 123.555508 -53.24037) (xy 123.584975 -53.286222)
			(xy 123.607618 -53.335801) (xy 123.622974 -53.388098) (xy 123.630731 -53.442048) (xy 123.630731 -53.496552)
			(xy 123.622974 -53.550502) (xy 123.607618 -53.602799) (xy 123.584975 -53.652378) (xy 123.555508 -53.69823)
			(xy 123.519814 -53.739421) (xy 123.478622 -53.775114) (xy 123.432769 -53.80458) (xy 123.383189 -53.827221)
			(xy 123.330892 -53.842576) (xy 123.276942 -53.850331) (xy 123.24969 -53.850794) (xy 123.222319 -53.850335)
			(xy 123.16814 -53.842516) (xy 123.115637 -53.827025) (xy 123.06589 -53.804182) (xy 123.019924 -53.774456)
			(xy 122.998992 -53.756814) (xy 122.998738 -53.75656) (xy 122.991648 -53.750978) (xy 122.974734 -53.74473)
			(xy 122.965718 -53.744368) (xy 122.898662 -53.744368) (xy 122.889644 -53.744714) (xy 122.872728 -53.75097)
			(xy 122.865642 -53.75656) (xy 122.865642 -53.756814) (xy 122.865388 -53.756814) (xy 122.844435 -53.774427)
			(xy 122.798468 -53.804143) (xy 122.748726 -53.826983) (xy 122.69623 -53.84248) (xy 122.642058 -53.850316)
			(xy 122.61469 -53.850794) (xy 122.587438 -53.850336) (xy 122.53349 -53.842578) (xy 122.481194 -53.827221)
			(xy 122.431616 -53.804578) (xy 122.385766 -53.775111) (xy 122.344575 -53.739418) (xy 122.308883 -53.698226)
			(xy 122.279417 -53.652375) (xy 122.256776 -53.602797) (xy 122.24142 -53.550501) (xy 122.233664 -53.496552)
			(xy 97.843564 -53.496552) (xy 97.847139 -53.502115) (xy 97.869781 -53.551692) (xy 97.885136 -53.603987)
			(xy 97.892892 -53.657935) (xy 97.893378 -53.685186) (xy 97.892909 -53.712556) (xy 97.885093 -53.766735)
			(xy 97.869605 -53.819239) (xy 97.846763 -53.868986) (xy 97.817039 -53.914952) (xy 97.799398 -53.935884)
			(xy 97.799144 -53.936138) (xy 97.793571 -53.943233) (xy 97.787317 -53.960144) (xy 97.786952 -53.969158)
			(xy 97.786952 -54.036214) (xy 97.787291 -54.045233) (xy 97.79355 -54.06215) (xy 97.799144 -54.069234)
			(xy 97.799398 -54.069234) (xy 97.799398 -54.069488) (xy 97.817045 -54.090414) (xy 97.846755 -54.136388)
			(xy 97.86959 -54.186137) (xy 97.885079 -54.23864) (xy 97.892905 -54.292816) (xy 97.893378 -54.320186)
			(xy 97.892892 -54.347437) (xy 97.885136 -54.401385) (xy 97.869781 -54.45368) (xy 97.847139 -54.503257)
			(xy 97.817673 -54.549107) (xy 97.781982 -54.590298) (xy 97.740791 -54.625989) (xy 97.694941 -54.655455)
			(xy 97.645364 -54.678097) (xy 97.593069 -54.693452) (xy 97.539121 -54.701208) (xy 97.484619 -54.701208)
			(xy 97.430671 -54.693452) (xy 97.378376 -54.678097) (xy 97.328799 -54.655455) (xy 97.282949 -54.625989)
			(xy 97.241758 -54.590298) (xy 97.206067 -54.549107) (xy 97.176601 -54.503257) (xy 97.153959 -54.45368)
			(xy 97.138604 -54.401385) (xy 97.130848 -54.347437) (xy 97.130362 -54.320186) (xy 94.901796 -54.320186)
			(xy 94.892743 -54.339899) (xy 94.863019 -54.385867) (xy 94.845378 -54.4068) (xy 94.845124 -54.407054)
			(xy 94.839542 -54.414143) (xy 94.833294 -54.431058) (xy 94.832932 -54.440074) (xy 94.832932 -54.50713)
			(xy 94.833268 -54.516149) (xy 94.839529 -54.533066) (xy 94.845124 -54.54015) (xy 94.845378 -54.54015)
			(xy 94.845378 -54.540404) (xy 94.863029 -54.561327) (xy 94.89274 -54.607302) (xy 94.915574 -54.657052)
			(xy 94.931062 -54.709554) (xy 94.938886 -54.763732) (xy 94.939003 -54.770528) (xy 98.070924 -54.770528)
			(xy 98.071401 -54.743158) (xy 98.079215 -54.688979) (xy 98.094701 -54.636476) (xy 98.117541 -54.586729)
			(xy 98.147264 -54.540762) (xy 98.164904 -54.51983) (xy 98.165158 -54.519576) (xy 98.170768 -54.512505)
			(xy 98.176999 -54.495576) (xy 98.17735 -54.486556) (xy 98.17735 -54.4195) (xy 98.177004 -54.410482)
			(xy 98.17075 -54.393564) (xy 98.165158 -54.38648) (xy 98.164904 -54.38648) (xy 98.164904 -54.386226)
			(xy 98.147264 -54.365294) (xy 98.117552 -54.319322) (xy 98.094716 -54.269574) (xy 98.079226 -54.217073)
			(xy 98.071398 -54.162897) (xy 98.070924 -54.135528) (xy 98.07141 -54.108277) (xy 98.079166 -54.054329)
			(xy 98.094521 -54.002034) (xy 98.117163 -53.952457) (xy 98.146629 -53.906607) (xy 98.18232 -53.865416)
			(xy 98.223511 -53.829725) (xy 98.269361 -53.800259) (xy 98.318938 -53.777617) (xy 98.371233 -53.762262)
			(xy 98.425181 -53.754506) (xy 98.479683 -53.754506) (xy 98.533631 -53.762262) (xy 98.585926 -53.777617)
			(xy 98.635503 -53.800259) (xy 98.681353 -53.829725) (xy 98.722544 -53.865416) (xy 98.758235 -53.906607)
			(xy 98.787701 -53.952457) (xy 98.792776 -53.96357) (xy 102.771954 -53.96357) (xy 102.776025 -53.907948)
			(xy 102.788151 -53.853511) (xy 102.808074 -53.80142) (xy 102.83537 -53.752785) (xy 102.869456 -53.708642)
			(xy 102.909605 -53.669933) (xy 102.954963 -53.637482) (xy 103.004563 -53.611981) (xy 103.057347 -53.593974)
			(xy 103.11219 -53.583844) (xy 103.167924 -53.581807) (xy 103.223361 -53.587907) (xy 103.277318 -53.602013)
			(xy 103.328647 -53.623825) (xy 103.376253 -53.652879) (xy 103.419121 -53.688554) (xy 103.456338 -53.730091)
			(xy 103.487111 -53.776604) (xy 103.510783 -53.827101) (xy 103.526851 -53.880508) (xy 103.534971 -53.935684)
			(xy 103.53548 -53.96357) (xy 103.534971 -53.991456) (xy 103.526851 -54.046632) (xy 103.510783 -54.100039)
			(xy 103.487111 -54.150536) (xy 103.456338 -54.197049) (xy 103.419121 -54.238586) (xy 103.376253 -54.274261)
			(xy 103.328647 -54.303315) (xy 103.277318 -54.325127) (xy 103.223361 -54.339233) (xy 103.167924 -54.345333)
			(xy 103.11219 -54.343296) (xy 103.057347 -54.333166) (xy 103.004563 -54.315159) (xy 102.954963 -54.289658)
			(xy 102.909605 -54.257207) (xy 102.869456 -54.218498) (xy 102.83537 -54.174355) (xy 102.808074 -54.12572)
			(xy 102.788151 -54.073629) (xy 102.776025 -54.019192) (xy 102.771954 -53.96357) (xy 98.792776 -53.96357)
			(xy 98.810343 -54.002034) (xy 98.825698 -54.054329) (xy 98.833454 -54.108277) (xy 98.83394 -54.135528)
			(xy 98.833505 -54.1629) (xy 98.825682 -54.217081) (xy 98.810186 -54.269585) (xy 98.787337 -54.319331)
			(xy 98.757605 -54.365296) (xy 98.73996 -54.386226) (xy 98.739706 -54.38648) (xy 98.734122 -54.393569)
			(xy 98.727874 -54.410484) (xy 98.727514 -54.4195) (xy 98.727514 -54.486556) (xy 98.727889 -54.495571)
			(xy 98.734124 -54.512488) (xy 98.739706 -54.519576) (xy 98.73996 -54.519576) (xy 98.73996 -54.51983)
			(xy 98.757574 -54.540783) (xy 98.787291 -54.586749) (xy 98.810132 -54.636491) (xy 98.825629 -54.688988)
			(xy 98.833463 -54.74316) (xy 98.83394 -54.770528) (xy 98.833454 -54.797779) (xy 98.825698 -54.851727)
			(xy 98.810343 -54.904022) (xy 98.787701 -54.953599) (xy 98.764917 -54.989051) (xy 120.001268 -54.989051)
			(xy 120.001268 -54.934549) (xy 120.009024 -54.880601) (xy 120.024379 -54.828306) (xy 120.047019 -54.778729)
			(xy 120.076485 -54.732878) (xy 120.112176 -54.691687) (xy 120.153365 -54.655995) (xy 120.199215 -54.626527)
			(xy 120.248791 -54.603884) (xy 120.301085 -54.588527) (xy 120.355033 -54.580769) (xy 120.382284 -54.580282)
			(xy 120.410375 -54.58079) (xy 120.465952 -54.589014) (xy 120.51972 -54.605303) (xy 120.570518 -54.629304)
			(xy 120.617245 -54.660497) (xy 120.65889 -54.698207) (xy 120.694553 -54.741618) (xy 120.709436 -54.765448)
			(xy 120.71477 -54.774338) (xy 120.731788 -54.78653) (xy 120.825006 -54.80685) (xy 120.84558 -54.802532)
			(xy 120.854216 -54.79669) (xy 120.878273 -54.78068) (xy 120.930207 -54.75534) (xy 120.985367 -54.738117)
			(xy 121.042493 -54.729405) (xy 121.071386 -54.728872) (xy 121.098636 -54.729391) (xy 121.152581 -54.737145)
			(xy 121.204874 -54.752498) (xy 121.25445 -54.775136) (xy 121.300299 -54.804599) (xy 121.341489 -54.840287)
			(xy 121.377181 -54.881473) (xy 121.406648 -54.92732) (xy 121.42929 -54.976894) (xy 121.444647 -55.029185)
			(xy 121.452406 -55.08313) (xy 121.452894 -55.11038) (xy 121.452418 -55.13775) (xy 121.444603 -55.191929)
			(xy 121.429116 -55.244432) (xy 121.406276 -55.294179) (xy 121.376554 -55.340146) (xy 121.358914 -55.361078)
			(xy 121.35866 -55.361332) (xy 121.353091 -55.36843) (xy 121.346835 -55.385338) (xy 121.346468 -55.394352)
			(xy 121.346468 -55.461408) (xy 121.346828 -55.470424) (xy 121.353074 -55.487341) (xy 121.35866 -55.494428)
			(xy 121.358914 -55.494428) (xy 121.358914 -55.494682) (xy 121.376533 -55.515631) (xy 121.406256 -55.561597)
			(xy 121.4291 -55.611341) (xy 121.444596 -55.66384) (xy 121.452426 -55.718016) (xy 121.452428 -55.772754)
			(xy 121.444602 -55.82693) (xy 121.42911 -55.879431) (xy 121.40627 -55.929176) (xy 121.376552 -55.975144)
			(xy 121.358914 -55.996078) (xy 121.35866 -55.996332) (xy 121.353091 -56.00343) (xy 121.346835 -56.020338)
			(xy 121.346468 -56.029352) (xy 121.346468 -56.096408) (xy 121.346828 -56.105424) (xy 121.353074 -56.122341)
			(xy 121.35866 -56.129428) (xy 121.358914 -56.129428) (xy 121.358914 -56.129682) (xy 121.37656 -56.150608)
			(xy 121.406271 -56.196583) (xy 121.429105 -56.246332) (xy 121.444594 -56.298834) (xy 121.452421 -56.35301)
			(xy 121.452894 -56.38038) (xy 121.452408 -56.407631) (xy 121.444652 -56.461579) (xy 121.429297 -56.513874)
			(xy 121.406655 -56.563451) (xy 121.377189 -56.609301) (xy 121.341498 -56.650492) (xy 121.300307 -56.686183)
			(xy 121.254457 -56.715649) (xy 121.20488 -56.738291) (xy 121.152585 -56.753646) (xy 121.098637 -56.761402)
			(xy 121.044135 -56.761402) (xy 120.990187 -56.753646) (xy 120.937892 -56.738291) (xy 120.888315 -56.715649)
			(xy 120.842465 -56.686183) (xy 120.801274 -56.650492) (xy 120.765583 -56.609301) (xy 120.736117 -56.563451)
			(xy 120.713475 -56.513874) (xy 120.69812 -56.461579) (xy 120.690364 -56.407631) (xy 120.689878 -56.38038)
			(xy 120.690313 -56.353008) (xy 120.698136 -56.298827) (xy 120.713631 -56.246323) (xy 120.73648 -56.196577)
			(xy 120.766213 -56.150612) (xy 120.783858 -56.129682) (xy 120.784112 -56.129428) (xy 120.789694 -56.122339)
			(xy 120.795943 -56.105424) (xy 120.796304 -56.096408) (xy 120.796304 -56.029352) (xy 120.795921 -56.020338)
			(xy 120.789691 -56.003421) (xy 120.784112 -55.996332) (xy 120.783858 -55.996332) (xy 120.783858 -55.996078)
			(xy 120.766196 -55.975162) (xy 120.73647 -55.929192) (xy 120.713624 -55.879443) (xy 120.698128 -55.826938)
			(xy 120.690301 -55.772757) (xy 120.690303 -55.718013) (xy 120.698134 -55.663832) (xy 120.713635 -55.611329)
			(xy 120.736485 -55.561582) (xy 120.766215 -55.515614) (xy 120.783858 -55.494682) (xy 120.784112 -55.494428)
			(xy 120.789694 -55.487339) (xy 120.795943 -55.470424) (xy 120.796304 -55.461408) (xy 120.796304 -55.394352)
			(xy 120.795921 -55.385338) (xy 120.789691 -55.368421) (xy 120.784112 -55.361332) (xy 120.783858 -55.360824)
			(xy 120.772912 -55.348091) (xy 120.753072 -55.320999) (xy 120.744234 -55.306722) (xy 120.7389 -55.297832)
			(xy 120.721882 -55.28564) (xy 120.628664 -55.26532) (xy 120.60809 -55.269638) (xy 120.599454 -55.27548)
			(xy 120.575403 -55.2915) (xy 120.523467 -55.316838) (xy 120.468305 -55.334059) (xy 120.411178 -55.342767)
			(xy 120.382284 -55.343298) (xy 120.355033 -55.342831) (xy 120.301085 -55.335073) (xy 120.248791 -55.319716)
			(xy 120.199215 -55.297073) (xy 120.153365 -55.267605) (xy 120.112176 -55.231913) (xy 120.076485 -55.190722)
			(xy 120.047019 -55.144871) (xy 120.024379 -55.095294) (xy 120.009024 -55.042999) (xy 120.001268 -54.989051)
			(xy 98.764917 -54.989051) (xy 98.758235 -54.999449) (xy 98.722544 -55.04064) (xy 98.681353 -55.076331)
			(xy 98.635503 -55.105797) (xy 98.585926 -55.128439) (xy 98.533631 -55.143794) (xy 98.479683 -55.15155)
			(xy 98.425181 -55.15155) (xy 98.371233 -55.143794) (xy 98.318938 -55.128439) (xy 98.269361 -55.105797)
			(xy 98.223511 -55.076331) (xy 98.18232 -55.04064) (xy 98.146629 -54.999449) (xy 98.117163 -54.953599)
			(xy 98.094521 -54.904022) (xy 98.079166 -54.851727) (xy 98.07141 -54.797779) (xy 98.070924 -54.770528)
			(xy 94.939003 -54.770528) (xy 94.939358 -54.791102) (xy 94.938872 -54.818353) (xy 94.931116 -54.872301)
			(xy 94.915761 -54.924596) (xy 94.893119 -54.974173) (xy 94.863653 -55.020023) (xy 94.827962 -55.061214)
			(xy 94.786771 -55.096905) (xy 94.740921 -55.126371) (xy 94.691344 -55.149013) (xy 94.639049 -55.164368)
			(xy 94.585101 -55.172124) (xy 94.530599 -55.172124) (xy 94.476651 -55.164368) (xy 94.424356 -55.149013)
			(xy 94.374779 -55.126371) (xy 94.328929 -55.096905) (xy 94.287738 -55.061214) (xy 94.252047 -55.020023)
			(xy 94.222581 -54.974173) (xy 94.199939 -54.924596) (xy 94.184584 -54.872301) (xy 94.176828 -54.818353)
			(xy 94.176342 -54.791102) (xy 92.278774 -54.791102) (xy 92.269732 -54.835296) (xy 92.250521 -54.888085)
			(xy 92.223776 -54.937487) (xy 92.207334 -54.960266) (xy 92.206572 -54.961282) (xy 92.200984 -54.96941)
			(xy 92.192348 -54.993286) (xy 92.190942 -54.997465) (xy 92.189416 -55.00615) (xy 92.1893 -55.010558)
			(xy 92.1893 -55.722266) (xy 103.833928 -55.722266) (xy 103.837999 -55.666644) (xy 103.850125 -55.612207)
			(xy 103.870048 -55.560116) (xy 103.897344 -55.511481) (xy 103.93143 -55.467338) (xy 103.971579 -55.428629)
			(xy 104.016937 -55.396178) (xy 104.066537 -55.370677) (xy 104.119321 -55.35267) (xy 104.174164 -55.34254)
			(xy 104.229898 -55.340503) (xy 104.285335 -55.346603) (xy 104.339292 -55.360709) (xy 104.390621 -55.382521)
			(xy 104.438227 -55.411575) (xy 104.449373 -55.420851) (xy 118.324868 -55.420851) (xy 118.324868 -55.366349)
			(xy 118.332624 -55.312401) (xy 118.347979 -55.260106) (xy 118.370619 -55.210529) (xy 118.400085 -55.164678)
			(xy 118.435776 -55.123487) (xy 118.476965 -55.087795) (xy 118.522815 -55.058327) (xy 118.572391 -55.035684)
			(xy 118.624685 -55.020327) (xy 118.678633 -55.012569) (xy 118.705884 -55.012082) (xy 118.732197 -55.012566)
			(xy 118.784325 -55.019798) (xy 118.834967 -55.034114) (xy 118.883166 -55.055244) (xy 118.92801 -55.082787)
			(xy 118.968651 -55.116222) (xy 118.986808 -55.135272) (xy 118.994328 -55.142675) (xy 119.013609 -55.1512)
			(xy 119.024146 -55.151782) (xy 119.098822 -55.151782) (xy 119.109369 -55.15123) (xy 119.128665 -55.142711)
			(xy 119.13616 -55.135272) (xy 119.154288 -55.116189) (xy 119.194924 -55.082735) (xy 119.23977 -55.055181)
			(xy 119.287977 -55.034047) (xy 119.338629 -55.019736) (xy 119.390766 -55.012517) (xy 119.417084 -55.012082)
			(xy 119.444337 -55.012564) (xy 119.498288 -55.020319) (xy 119.550587 -55.035673) (xy 119.600167 -55.058314)
			(xy 119.646021 -55.087781) (xy 119.687215 -55.123474) (xy 119.722909 -55.164666) (xy 119.752378 -55.210519)
			(xy 119.775021 -55.260098) (xy 119.790377 -55.312396) (xy 119.798135 -55.366347) (xy 119.798135 -55.420853)
			(xy 119.790377 -55.474804) (xy 119.775021 -55.527102) (xy 119.752378 -55.576681) (xy 119.722909 -55.622534)
			(xy 119.687215 -55.663726) (xy 119.646021 -55.699419) (xy 119.600167 -55.728886) (xy 119.550587 -55.751527)
			(xy 119.498288 -55.766881) (xy 119.444337 -55.774636) (xy 119.417084 -55.775098) (xy 119.39077 -55.774642)
			(xy 119.338641 -55.767405) (xy 119.287998 -55.753084) (xy 119.239799 -55.731949) (xy 119.194955 -55.704401)
			(xy 119.154316 -55.67096) (xy 119.13616 -55.651908) (xy 119.128654 -55.644488) (xy 119.109362 -55.635974)
			(xy 119.098822 -55.635398) (xy 119.024146 -55.635398) (xy 119.013598 -55.635939) (xy 118.994302 -55.644466)
			(xy 118.986808 -55.651908) (xy 118.968643 -55.670954) (xy 118.928015 -55.704412) (xy 118.883177 -55.731972)
			(xy 118.834978 -55.753112) (xy 118.784332 -55.767431) (xy 118.7322 -55.774658) (xy 118.705884 -55.775098)
			(xy 118.678633 -55.774631) (xy 118.624685 -55.766873) (xy 118.572391 -55.751516) (xy 118.522815 -55.728873)
			(xy 118.476965 -55.699405) (xy 118.435776 -55.663713) (xy 118.400085 -55.622522) (xy 118.370619 -55.576671)
			(xy 118.347979 -55.527094) (xy 118.332624 -55.474799) (xy 118.324868 -55.420851) (xy 104.449373 -55.420851)
			(xy 104.481095 -55.44725) (xy 104.518312 -55.488787) (xy 104.549085 -55.5353) (xy 104.572757 -55.585797)
			(xy 104.588825 -55.639204) (xy 104.596945 -55.69438) (xy 104.597454 -55.722266) (xy 104.596945 -55.750152)
			(xy 104.588825 -55.805328) (xy 104.572757 -55.858735) (xy 104.549085 -55.909232) (xy 104.518312 -55.955745)
			(xy 104.481095 -55.997282) (xy 104.438227 -56.032957) (xy 104.390621 -56.062011) (xy 104.339292 -56.083823)
			(xy 104.285335 -56.097929) (xy 104.229898 -56.104029) (xy 104.174164 -56.101992) (xy 104.119321 -56.091862)
			(xy 104.066537 -56.073855) (xy 104.016937 -56.048354) (xy 103.971579 -56.015903) (xy 103.93143 -55.977194)
			(xy 103.897344 -55.933051) (xy 103.870048 -55.884416) (xy 103.850125 -55.832325) (xy 103.837999 -55.777888)
			(xy 103.833928 -55.722266) (xy 92.1893 -55.722266) (xy 92.1893 -55.939436) (xy 92.189554 -55.94985)
			(xy 92.189554 -55.950866) (xy 92.1893 -55.968138) (xy 92.1893 -55.972456) (xy 92.189046 -55.973472)
			(xy 92.18422 -56.17972) (xy 92.176092 -56.531764) (xy 92.175838 -56.541924) (xy 92.185236 -56.566054)
			(xy 92.186872 -56.569962) (xy 92.191207 -56.577239) (xy 92.193872 -56.580532) (xy 92.19692 -56.584088)
			(xy 92.197682 -56.585104) (xy 92.198698 -56.586374) (xy 92.198952 -56.586628) (xy 92.216859 -56.609676)
			(xy 92.246192 -56.660133) (xy 92.267495 -56.714469) (xy 92.28027 -56.771417) (xy 92.282772 -56.800496)
			(xy 92.283534 -56.82234) (xy 92.283534 -56.82742) (xy 92.282938 -56.855806) (xy 92.274382 -56.911931)
			(xy 92.257609 -56.966171) (xy 92.239918 -57.002934) (xy 99.563428 -57.002934) (xy 99.563927 -56.974842)
			(xy 99.572151 -56.919264) (xy 99.58844 -56.865494) (xy 99.612441 -56.814696) (xy 99.643636 -56.767969)
			(xy 99.681348 -56.726324) (xy 99.724763 -56.690664) (xy 99.748594 -56.675782) (xy 99.757484 -56.670448)
			(xy 99.769676 -56.65343) (xy 99.789996 -56.560212) (xy 99.785678 -56.539638) (xy 99.779836 -56.531002)
			(xy 99.763839 -56.506936) (xy 99.738494 -56.455006) (xy 99.721268 -56.399848) (xy 99.712552 -56.342724)
			(xy 99.712018 -56.313832) (xy 99.712485 -56.286579) (xy 99.720238 -56.232627) (xy 99.735592 -56.180327)
			(xy 99.758232 -56.130746) (xy 99.787699 -56.084891) (xy 99.823393 -56.043697) (xy 99.864586 -56.008003)
			(xy 99.91044 -55.978535) (xy 99.960022 -55.955894) (xy 100.012321 -55.94054) (xy 100.066273 -55.932786)
			(xy 100.093526 -55.932324) (xy 100.120897 -55.932769) (xy 100.175077 -55.940591) (xy 100.227581 -55.956085)
			(xy 100.277327 -55.978931) (xy 100.323293 -56.00866) (xy 100.344224 -56.026304) (xy 100.344478 -56.026558)
			(xy 100.351562 -56.032148) (xy 100.368481 -56.038391) (xy 100.377498 -56.03875) (xy 100.444554 -56.03875)
			(xy 100.45357 -56.038382) (xy 100.470488 -56.032143) (xy 100.477574 -56.026558) (xy 100.477574 -56.026304)
			(xy 100.477828 -56.026304) (xy 100.498761 -56.008663) (xy 100.544729 -55.978939) (xy 100.594475 -55.956093)
			(xy 100.646977 -55.940597) (xy 100.701155 -55.932768) (xy 100.755897 -55.932768) (xy 100.810075 -55.940597)
			(xy 100.862577 -55.956093) (xy 100.912323 -55.978939) (xy 100.958291 -56.008663) (xy 100.979224 -56.026304)
			(xy 100.979478 -56.026558) (xy 100.986562 -56.032148) (xy 101.003481 -56.038391) (xy 101.012498 -56.03875)
			(xy 101.079554 -56.03875) (xy 101.08857 -56.038382) (xy 101.105488 -56.032143) (xy 101.112574 -56.026558)
			(xy 101.112574 -56.026304) (xy 101.112828 -56.026304) (xy 101.133777 -56.008686) (xy 101.179745 -55.978971)
			(xy 101.229488 -55.956131) (xy 101.281985 -55.940635) (xy 101.336158 -55.932801) (xy 101.363526 -55.932324)
			(xy 101.390778 -55.932748) (xy 101.444728 -55.940508) (xy 101.497024 -55.955866) (xy 101.546602 -55.978511)
			(xy 101.592453 -56.00798) (xy 101.633643 -56.043675) (xy 101.669335 -56.084868) (xy 101.698801 -56.130721)
			(xy 101.721443 -56.180301) (xy 101.736798 -56.232598) (xy 101.744554 -56.286548) (xy 101.744554 -56.297068)
			(xy 102.086408 -56.297068) (xy 102.090479 -56.241446) (xy 102.102605 -56.187009) (xy 102.122528 -56.134918)
			(xy 102.149824 -56.086283) (xy 102.18391 -56.04214) (xy 102.224059 -56.003431) (xy 102.269417 -55.97098)
			(xy 102.319017 -55.945479) (xy 102.371801 -55.927472) (xy 102.426644 -55.917342) (xy 102.482378 -55.915305)
			(xy 102.537815 -55.921405) (xy 102.591772 -55.935511) (xy 102.643101 -55.957323) (xy 102.690707 -55.986377)
			(xy 102.733575 -56.022052) (xy 102.770792 -56.063589) (xy 102.801565 -56.110102) (xy 102.825237 -56.160599)
			(xy 102.841305 -56.214006) (xy 102.849425 -56.269182) (xy 102.849934 -56.297068) (xy 102.849425 -56.324954)
			(xy 102.841305 -56.38013) (xy 102.825237 -56.433537) (xy 102.801565 -56.484034) (xy 102.770792 -56.530547)
			(xy 102.733575 -56.572084) (xy 102.690707 -56.607759) (xy 102.643101 -56.636813) (xy 102.591772 -56.658625)
			(xy 102.537815 -56.672731) (xy 102.482378 -56.678831) (xy 102.426644 -56.676794) (xy 102.371801 -56.666664)
			(xy 102.319017 -56.648657) (xy 102.269417 -56.623156) (xy 102.224059 -56.590705) (xy 102.18391 -56.551996)
			(xy 102.149824 -56.507853) (xy 102.122528 -56.459218) (xy 102.102605 -56.407127) (xy 102.090479 -56.35269)
			(xy 102.086408 -56.297068) (xy 101.744554 -56.297068) (xy 101.744554 -56.341052) (xy 101.736798 -56.395002)
			(xy 101.721443 -56.447299) (xy 101.698801 -56.496879) (xy 101.669335 -56.542732) (xy 101.633643 -56.583925)
			(xy 101.592453 -56.61962) (xy 101.546602 -56.649089) (xy 101.497024 -56.671734) (xy 101.444728 -56.687092)
			(xy 101.390778 -56.694852) (xy 101.363526 -56.69534) (xy 101.336156 -56.694873) (xy 101.281976 -56.687058)
			(xy 101.229472 -56.67157) (xy 101.179725 -56.648728) (xy 101.133759 -56.619002) (xy 101.112828 -56.60136)
			(xy 101.112574 -56.601106) (xy 101.10547 -56.595545) (xy 101.088567 -56.589283) (xy 101.079554 -56.588914)
			(xy 101.012498 -56.588914) (xy 101.003481 -56.589267) (xy 100.986564 -56.595517) (xy 100.979478 -56.601106)
			(xy 100.979478 -56.60136) (xy 100.979224 -56.60136) (xy 100.958291 -56.619001) (xy 100.912323 -56.648725)
			(xy 100.862577 -56.671571) (xy 100.810075 -56.687067) (xy 100.755897 -56.694896) (xy 100.701155 -56.694896)
			(xy 100.646977 -56.687067) (xy 100.594475 -56.671571) (xy 100.544729 -56.648725) (xy 100.498761 -56.619001)
			(xy 100.477828 -56.60136) (xy 100.477574 -56.601106) (xy 100.47047 -56.595545) (xy 100.453567 -56.589283)
			(xy 100.444554 -56.588914) (xy 100.377498 -56.588914) (xy 100.368481 -56.589267) (xy 100.351564 -56.595517)
			(xy 100.344478 -56.601106) (xy 100.34397 -56.60136) (xy 100.331235 -56.612303) (xy 100.304144 -56.632145)
			(xy 100.289868 -56.640984) (xy 100.280978 -56.646318) (xy 100.268786 -56.663336) (xy 100.248466 -56.756554)
			(xy 100.252784 -56.777128) (xy 100.258626 -56.785764) (xy 100.274616 -56.809834) (xy 100.29996 -56.861764)
			(xy 100.317188 -56.91692) (xy 100.325907 -56.974042) (xy 100.326444 -57.002934) (xy 100.325958 -57.030185)
			(xy 100.318202 -57.084133) (xy 100.302847 -57.136428) (xy 100.280205 -57.186005) (xy 100.250739 -57.231855)
			(xy 100.215048 -57.273046) (xy 100.173857 -57.308737) (xy 100.128007 -57.338203) (xy 100.07843 -57.360845)
			(xy 100.026135 -57.3762) (xy 99.972187 -57.383956) (xy 99.917685 -57.383956) (xy 99.863737 -57.3762)
			(xy 99.811442 -57.360845) (xy 99.761865 -57.338203) (xy 99.716015 -57.308737) (xy 99.674824 -57.273046)
			(xy 99.639133 -57.231855) (xy 99.609667 -57.186005) (xy 99.587025 -57.136428) (xy 99.57167 -57.084133)
			(xy 99.563914 -57.030185) (xy 99.563428 -57.002934) (xy 92.239918 -57.002934) (xy 92.23299 -57.01733)
			(xy 92.201068 -57.064279) (xy 92.182188 -57.085484) (xy 92.176092 -57.092088) (xy 92.1639 -57.12079)
			(xy 92.162376 -57.129172) (xy 92.162122 -57.131712) (xy 92.161614 -57.145682) (xy 92.16136 -57.15889)
			(xy 92.161106 -57.169304) (xy 92.168472 -57.1881) (xy 92.175584 -57.195466) (xy 92.195702 -57.216936)
			(xy 92.229756 -57.264914) (xy 92.256039 -57.317552) (xy 92.273928 -57.373601) (xy 92.283 -57.431733)
			(xy 92.283534 -57.46115) (xy 92.283534 -57.46242) (xy 92.28328 -57.478422) (xy 92.283026 -57.48274)
			(xy 92.282843 -57.48528) (xy 120.706132 -57.48528) (xy 120.710203 -57.429658) (xy 120.722329 -57.375221)
			(xy 120.742252 -57.32313) (xy 120.769548 -57.274495) (xy 120.803634 -57.230352) (xy 120.843783 -57.191643)
			(xy 120.889141 -57.159192) (xy 120.938741 -57.133691) (xy 120.991525 -57.115684) (xy 121.046368 -57.105554)
			(xy 121.102102 -57.103517) (xy 121.157539 -57.109617) (xy 121.211496 -57.123723) (xy 121.262825 -57.145535)
			(xy 121.310431 -57.174589) (xy 121.353299 -57.210264) (xy 121.390516 -57.251801) (xy 121.421289 -57.298314)
			(xy 121.444961 -57.348811) (xy 121.461029 -57.402218) (xy 121.469149 -57.457394) (xy 121.469658 -57.48528)
			(xy 121.469149 -57.513166) (xy 121.461029 -57.568342) (xy 121.444961 -57.621749) (xy 121.421289 -57.672246)
			(xy 121.390516 -57.718759) (xy 121.353299 -57.760296) (xy 121.310431 -57.795971) (xy 121.262825 -57.825025)
			(xy 121.211496 -57.846837) (xy 121.157539 -57.860943) (xy 121.102102 -57.867043) (xy 121.046368 -57.865006)
			(xy 120.991525 -57.854876) (xy 120.938741 -57.836869) (xy 120.889141 -57.811368) (xy 120.843783 -57.778917)
			(xy 120.803634 -57.740208) (xy 120.769548 -57.696065) (xy 120.742252 -57.64743) (xy 120.722329 -57.595339)
			(xy 120.710203 -57.540902) (xy 120.706132 -57.48528) (xy 92.282843 -57.48528) (xy 92.281217 -57.507822)
			(xy 92.271828 -57.557225) (xy 92.256026 -57.604966) (xy 92.245434 -57.627774) (xy 92.22971 -57.658511)
			(xy 92.188939 -57.714222) (xy 92.164408 -57.738518) (xy 92.158566 -57.743852) (xy 92.154756 -57.75071)
			(xy 92.150184 -57.76214) (xy 92.149676 -57.76468) (xy 92.146882 -57.778396) (xy 92.146628 -57.779412)
			(xy 92.146628 -57.78119) (xy 92.152978 -57.795922) (xy 92.162122 -57.817004) (xy 92.169234 -57.824116)
			(xy 92.190476 -57.845785) (xy 92.226508 -57.894606) (xy 92.254358 -57.948515) (xy 92.273324 -58.006152)
			(xy 92.282928 -58.066065) (xy 92.283534 -58.096404) (xy 92.283456 -58.109142) (xy 92.281802 -58.134563)
			(xy 92.280232 -58.147204) (xy 92.279978 -58.149998) (xy 92.275464 -58.178128) (xy 92.259172 -58.232719)
			(xy 92.234928 -58.284273) (xy 92.219526 -58.30824) (xy 92.213938 -58.316368) (xy 92.21089 -58.320686)
			(xy 92.204794 -58.329068) (xy 92.200476 -58.334148) (xy 92.195904 -58.341514) (xy 92.194888 -58.343546)
			(xy 92.192428 -58.348872) (xy 92.189737 -58.360288) (xy 92.189554 -58.366152) (xy 92.189554 -58.387234)
			(xy 92.18941 -58.392673) (xy 92.1871 -58.403304) (xy 92.184982 -58.408316) (xy 92.178886 -58.421778)
			(xy 92.175262 -58.43044) (xy 92.174026 -58.449162) (xy 92.179652 -58.467062) (xy 92.185236 -58.47461)
			(xy 92.190824 -58.481722) (xy 92.19438 -58.486294) (xy 92.194888 -58.487056) (xy 92.196412 -58.488834)
			(xy 92.212629 -58.509221) (xy 92.239973 -58.553559) (xy 92.26104 -58.601202) (xy 92.275437 -58.651266)
			(xy 92.279499 -58.679334) (xy 99.995228 -58.679334) (xy 99.995642 -58.653018) (xy 100.002887 -58.600887)
			(xy 100.017216 -58.550243) (xy 100.038358 -58.502044) (xy 100.065914 -58.457202) (xy 100.099362 -58.416565)
			(xy 100.118418 -58.39841) (xy 100.12582 -58.390889) (xy 100.134344 -58.371608) (xy 100.134928 -58.361072)
			(xy 100.134928 -58.286396) (xy 100.134406 -58.275846) (xy 100.125865 -58.256551) (xy 100.118418 -58.249058)
			(xy 100.099353 -58.230912) (xy 100.065896 -58.190281) (xy 100.038337 -58.145439) (xy 100.017201 -58.097236)
			(xy 100.002886 -58.046586) (xy 99.995664 -57.994451) (xy 99.995228 -57.968134) (xy 99.995714 -57.940883)
			(xy 100.00347 -57.886935) (xy 100.018825 -57.83464) (xy 100.041467 -57.785063) (xy 100.070933 -57.739213)
			(xy 100.106624 -57.698022) (xy 100.147815 -57.662331) (xy 100.193665 -57.632865) (xy 100.243242 -57.610223)
			(xy 100.295537 -57.594868) (xy 100.349485 -57.587112) (xy 100.403987 -57.587112) (xy 100.457935 -57.594868)
			(xy 100.51023 -57.610223) (xy 100.559807 -57.632865) (xy 100.605657 -57.662331) (xy 100.646848 -57.698022)
			(xy 100.682539 -57.739213) (xy 100.712005 -57.785063) (xy 100.734647 -57.83464) (xy 100.750002 -57.886935)
			(xy 100.757758 -57.940883) (xy 100.758244 -57.968134) (xy 100.757817 -57.99445) (xy 100.750577 -58.046581)
			(xy 100.743309 -58.072274) (xy 103.99344 -58.072274) (xy 103.997511 -58.016652) (xy 104.009637 -57.962215)
			(xy 104.02956 -57.910124) (xy 104.056856 -57.861489) (xy 104.090942 -57.817346) (xy 104.131091 -57.778637)
			(xy 104.176449 -57.746186) (xy 104.226049 -57.720685) (xy 104.278833 -57.702678) (xy 104.333676 -57.692548)
			(xy 104.38941 -57.690511) (xy 104.444847 -57.696611) (xy 104.498804 -57.710717) (xy 104.550133 -57.732529)
			(xy 104.597739 -57.761583) (xy 104.640607 -57.797258) (xy 104.677824 -57.838795) (xy 104.708597 -57.885308)
			(xy 104.732269 -57.935805) (xy 104.748337 -57.989212) (xy 104.756457 -58.044388) (xy 104.756966 -58.072274)
			(xy 104.756896 -58.076084) (xy 121.458226 -58.076084) (xy 121.462297 -58.020462) (xy 121.474423 -57.966025)
			(xy 121.494346 -57.913934) (xy 121.521642 -57.865299) (xy 121.555728 -57.821156) (xy 121.595877 -57.782447)
			(xy 121.641235 -57.749996) (xy 121.690835 -57.724495) (xy 121.743619 -57.706488) (xy 121.798462 -57.696358)
			(xy 121.854196 -57.694321) (xy 121.909633 -57.700421) (xy 121.96359 -57.714527) (xy 122.014919 -57.736339)
			(xy 122.062525 -57.765393) (xy 122.105393 -57.801068) (xy 122.14261 -57.842605) (xy 122.158946 -57.867296)
			(xy 123.74321 -57.867296) (xy 123.747281 -57.811674) (xy 123.759407 -57.757237) (xy 123.77933 -57.705146)
			(xy 123.806626 -57.656511) (xy 123.840712 -57.612368) (xy 123.880861 -57.573659) (xy 123.926219 -57.541208)
			(xy 123.975819 -57.515707) (xy 124.028603 -57.4977) (xy 124.083446 -57.48757) (xy 124.13918 -57.485533)
			(xy 124.194617 -57.491633) (xy 124.248574 -57.505739) (xy 124.299903 -57.527551) (xy 124.347509 -57.556605)
			(xy 124.390377 -57.59228) (xy 124.427594 -57.633817) (xy 124.458367 -57.68033) (xy 124.482039 -57.730827)
			(xy 124.498107 -57.784234) (xy 124.506227 -57.83941) (xy 124.506736 -57.867296) (xy 124.506227 -57.895182)
			(xy 124.498107 -57.950358) (xy 124.482039 -58.003765) (xy 124.458367 -58.054262) (xy 124.427594 -58.100775)
			(xy 124.390377 -58.142312) (xy 124.347509 -58.177987) (xy 124.299903 -58.207041) (xy 124.248574 -58.228853)
			(xy 124.194617 -58.242959) (xy 124.13918 -58.249059) (xy 124.083446 -58.247022) (xy 124.028603 -58.236892)
			(xy 123.975819 -58.218885) (xy 123.926219 -58.193384) (xy 123.880861 -58.160933) (xy 123.840712 -58.122224)
			(xy 123.806626 -58.078081) (xy 123.77933 -58.029446) (xy 123.759407 -57.977355) (xy 123.747281 -57.922918)
			(xy 123.74321 -57.867296) (xy 122.158946 -57.867296) (xy 122.173383 -57.889118) (xy 122.197055 -57.939615)
			(xy 122.213123 -57.993022) (xy 122.221243 -58.048198) (xy 122.221752 -58.076084) (xy 122.221243 -58.10397)
			(xy 122.213123 -58.159146) (xy 122.197055 -58.212553) (xy 122.173383 -58.26305) (xy 122.14261 -58.309563)
			(xy 122.105393 -58.3511) (xy 122.062525 -58.386775) (xy 122.014919 -58.415829) (xy 121.96359 -58.437641)
			(xy 121.909633 -58.451747) (xy 121.854196 -58.457847) (xy 121.798462 -58.45581) (xy 121.743619 -58.44568)
			(xy 121.690835 -58.427673) (xy 121.641235 -58.402172) (xy 121.595877 -58.369721) (xy 121.555728 -58.331012)
			(xy 121.521642 -58.286869) (xy 121.494346 -58.238234) (xy 121.474423 -58.186143) (xy 121.462297 -58.131706)
			(xy 121.458226 -58.076084) (xy 104.756896 -58.076084) (xy 104.756457 -58.10016) (xy 104.748337 -58.155336)
			(xy 104.732269 -58.208743) (xy 104.708597 -58.25924) (xy 104.677824 -58.305753) (xy 104.640607 -58.34729)
			(xy 104.597739 -58.382965) (xy 104.550133 -58.412019) (xy 104.498804 -58.433831) (xy 104.444847 -58.447937)
			(xy 104.38941 -58.454037) (xy 104.333676 -58.452) (xy 104.278833 -58.44187) (xy 104.226049 -58.423863)
			(xy 104.176449 -58.398362) (xy 104.131091 -58.365911) (xy 104.090942 -58.327202) (xy 104.056856 -58.283059)
			(xy 104.02956 -58.234424) (xy 104.009637 -58.182333) (xy 103.997511 -58.127896) (xy 103.99344 -58.072274)
			(xy 100.743309 -58.072274) (xy 100.736251 -58.097225) (xy 100.715111 -58.145424) (xy 100.687557 -58.190266)
			(xy 100.65411 -58.230903) (xy 100.635054 -58.249058) (xy 100.627677 -58.256601) (xy 100.619137 -58.275864)
			(xy 100.618544 -58.286396) (xy 100.618544 -58.361072) (xy 100.619062 -58.371623) (xy 100.627604 -58.390919)
			(xy 100.635054 -58.39841) (xy 100.654118 -58.416557) (xy 100.687572 -58.45719) (xy 100.715129 -58.502032)
			(xy 100.736265 -58.550234) (xy 100.739371 -58.561224) (xy 122.66244 -58.561224) (xy 122.666511 -58.505602)
			(xy 122.678637 -58.451165) (xy 122.69856 -58.399074) (xy 122.725856 -58.350439) (xy 122.759942 -58.306296)
			(xy 122.800091 -58.267587) (xy 122.845449 -58.235136) (xy 122.895049 -58.209635) (xy 122.947833 -58.191628)
			(xy 123.002676 -58.181498) (xy 123.05841 -58.179461) (xy 123.113847 -58.185561) (xy 123.167804 -58.199667)
			(xy 123.219133 -58.221479) (xy 123.266739 -58.250533) (xy 123.309607 -58.286208) (xy 123.346824 -58.327745)
			(xy 123.377597 -58.374258) (xy 123.401269 -58.424755) (xy 123.417337 -58.478162) (xy 123.425457 -58.533338)
			(xy 123.425966 -58.561224) (xy 123.425457 -58.58911) (xy 123.417337 -58.644286) (xy 123.401269 -58.697693)
			(xy 123.377597 -58.74819) (xy 123.346824 -58.794703) (xy 123.309607 -58.83624) (xy 123.266739 -58.871915)
			(xy 123.219133 -58.900969) (xy 123.167804 -58.922781) (xy 123.113847 -58.936887) (xy 123.05841 -58.942987)
			(xy 123.002676 -58.94095) (xy 122.947833 -58.93082) (xy 122.895049 -58.912813) (xy 122.845449 -58.887312)
			(xy 122.800091 -58.854861) (xy 122.759942 -58.816152) (xy 122.725856 -58.772009) (xy 122.69856 -58.723374)
			(xy 122.678637 -58.671283) (xy 122.666511 -58.616846) (xy 122.66244 -58.561224) (xy 100.739371 -58.561224)
			(xy 100.750581 -58.600883) (xy 100.757806 -58.653018) (xy 100.758244 -58.679334) (xy 100.757758 -58.706585)
			(xy 100.750002 -58.760533) (xy 100.734647 -58.812828) (xy 100.712005 -58.862405) (xy 100.682539 -58.908255)
			(xy 100.646848 -58.949446) (xy 100.605657 -58.985137) (xy 100.559807 -59.014603) (xy 100.51023 -59.037245)
			(xy 100.457935 -59.0526) (xy 100.403987 -59.060356) (xy 100.349485 -59.060356) (xy 100.295537 -59.0526)
			(xy 100.243242 -59.037245) (xy 100.193665 -59.014603) (xy 100.147815 -58.985137) (xy 100.106624 -58.949446)
			(xy 100.070933 -58.908255) (xy 100.041467 -58.862405) (xy 100.018825 -58.812828) (xy 100.00347 -58.760533)
			(xy 99.995714 -58.706585) (xy 99.995228 -58.679334) (xy 92.279499 -58.679334) (xy 92.282898 -58.702822)
			(xy 92.283534 -58.728864) (xy 92.283534 -58.730896) (xy 92.283534 -58.731658) (xy 92.283534 -58.732166)
			(xy 92.282969 -58.761085) (xy 92.274173 -58.818251) (xy 92.256837 -58.873432) (xy 92.231361 -58.925358)
			(xy 92.19833 -58.972837) (xy 92.158502 -59.014779) (xy 92.13596 -59.032902) (xy 92.135706 -59.032902)
			(xy 92.131395 -59.03649) (xy 92.12434 -59.045206) (xy 92.121736 -59.050174) (xy 92.119196 -59.055254)
			(xy 92.116402 -59.065922) (xy 92.113851 -59.174634) (xy 121.193304 -59.174634) (xy 121.197375 -59.119012)
			(xy 121.209501 -59.064575) (xy 121.229424 -59.012484) (xy 121.25672 -58.963849) (xy 121.290806 -58.919706)
			(xy 121.330955 -58.880997) (xy 121.376313 -58.848546) (xy 121.425913 -58.823045) (xy 121.478697 -58.805038)
			(xy 121.53354 -58.794908) (xy 121.589274 -58.792871) (xy 121.644711 -58.798971) (xy 121.698668 -58.813077)
			(xy 121.749997 -58.834889) (xy 121.797603 -58.863943) (xy 121.840471 -58.899618) (xy 121.877688 -58.941155)
			(xy 121.908461 -58.987668) (xy 121.932133 -59.038165) (xy 121.948201 -59.091572) (xy 121.956321 -59.146748)
			(xy 121.95683 -59.174634) (xy 121.956321 -59.20252) (xy 121.948201 -59.257696) (xy 121.932133 -59.311103)
			(xy 121.908461 -59.3616) (xy 121.877688 -59.408113) (xy 121.840471 -59.44965) (xy 121.797603 -59.485325)
			(xy 121.749997 -59.514379) (xy 121.698668 -59.536191) (xy 121.644711 -59.550297) (xy 121.589274 -59.556397)
			(xy 121.53354 -59.55436) (xy 121.478697 -59.54423) (xy 121.425913 -59.526223) (xy 121.376313 -59.500722)
			(xy 121.330955 -59.468271) (xy 121.290806 -59.429562) (xy 121.25672 -59.385419) (xy 121.229424 -59.336784)
			(xy 121.209501 -59.284693) (xy 121.197375 -59.230256) (xy 121.193304 -59.174634) (xy 92.113851 -59.174634)
			(xy 92.094034 -60.01925) (xy 100.135684 -60.01925) (xy 100.135684 -59.96475) (xy 100.14344 -59.910804)
			(xy 100.158794 -59.85851) (xy 100.181434 -59.808935) (xy 100.210899 -59.763086) (xy 100.246589 -59.721896)
			(xy 100.287777 -59.686205) (xy 100.333626 -59.656739) (xy 100.383201 -59.634098) (xy 100.435494 -59.618742)
			(xy 100.48944 -59.610984) (xy 100.51669 -59.610498) (xy 100.54406 -59.61097) (xy 100.598239 -59.618787)
			(xy 100.650742 -59.634274) (xy 100.700489 -59.657115) (xy 100.746456 -59.686838) (xy 100.767388 -59.704478)
			(xy 100.767642 -59.704732) (xy 100.774738 -59.710304) (xy 100.791648 -59.716558) (xy 100.800662 -59.716924)
			(xy 100.867718 -59.716924) (xy 100.876735 -59.716571) (xy 100.893652 -59.71032) (xy 100.900738 -59.704732)
			(xy 100.900738 -59.704478) (xy 100.900992 -59.704478) (xy 100.921925 -59.686837) (xy 100.967893 -59.657113)
			(xy 101.017639 -59.634267) (xy 101.070141 -59.618771) (xy 101.124319 -59.610942) (xy 101.179061 -59.610942)
			(xy 101.233239 -59.618771) (xy 101.285741 -59.634267) (xy 101.335487 -59.657113) (xy 101.381455 -59.686837)
			(xy 101.402388 -59.704478) (xy 101.402642 -59.704732) (xy 101.409738 -59.710304) (xy 101.426648 -59.716558)
			(xy 101.435662 -59.716924) (xy 101.502718 -59.716924) (xy 101.511735 -59.716571) (xy 101.528652 -59.71032)
			(xy 101.535738 -59.704732) (xy 101.535738 -59.704478) (xy 101.535992 -59.704478) (xy 101.556913 -59.686826)
			(xy 101.60289 -59.657117) (xy 101.65264 -59.634284) (xy 101.705143 -59.618796) (xy 101.75932 -59.61097)
			(xy 101.78669 -59.610498) (xy 101.813944 -59.610949) (xy 101.867897 -59.618705) (xy 101.920196 -59.63406)
			(xy 101.969779 -59.656702) (xy 102.015634 -59.68617) (xy 102.056828 -59.721865) (xy 102.092524 -59.763058)
			(xy 102.121993 -59.808913) (xy 102.144636 -59.858494) (xy 102.159993 -59.910794) (xy 102.167751 -59.964746)
			(xy 102.167751 -60.019254) (xy 102.159993 -60.073206) (xy 102.144636 -60.125506) (xy 102.121993 -60.175087)
			(xy 102.092524 -60.220942) (xy 102.056828 -60.262135) (xy 102.015634 -60.29783) (xy 101.969779 -60.327298)
			(xy 101.920196 -60.34994) (xy 101.867897 -60.365295) (xy 101.813944 -60.373051) (xy 101.78669 -60.373514)
			(xy 101.75932 -60.37305) (xy 101.705141 -60.365231) (xy 101.652638 -60.349742) (xy 101.602891 -60.326899)
			(xy 101.556924 -60.297175) (xy 101.535992 -60.279534) (xy 101.535738 -60.27928) (xy 101.528646 -60.273701)
			(xy 101.511733 -60.26745) (xy 101.502718 -60.267088) (xy 101.435662 -60.267088) (xy 101.426644 -60.267429)
			(xy 101.409727 -60.273688) (xy 101.402642 -60.27928) (xy 101.402388 -60.279534) (xy 101.381455 -60.297175)
			(xy 101.335487 -60.326899) (xy 101.285741 -60.349745) (xy 101.233239 -60.365241) (xy 101.179061 -60.37307)
			(xy 101.124319 -60.37307) (xy 101.070141 -60.365241) (xy 101.017639 -60.349745) (xy 100.967893 -60.326899)
			(xy 100.921925 -60.297175) (xy 100.900992 -60.279534) (xy 100.900738 -60.27928) (xy 100.893646 -60.273701)
			(xy 100.876733 -60.26745) (xy 100.867718 -60.267088) (xy 100.800662 -60.267088) (xy 100.791644 -60.267429)
			(xy 100.774727 -60.273688) (xy 100.767642 -60.27928) (xy 100.767642 -60.279534) (xy 100.767388 -60.279534)
			(xy 100.746438 -60.297151) (xy 100.70047 -60.326865) (xy 100.650727 -60.349704) (xy 100.59823 -60.365201)
			(xy 100.544058 -60.373036) (xy 100.51669 -60.373514) (xy 100.48944 -60.373016) (xy 100.435494 -60.365258)
			(xy 100.383201 -60.349902) (xy 100.333626 -60.327261) (xy 100.287777 -60.297795) (xy 100.246589 -60.262104)
			(xy 100.210899 -60.220914) (xy 100.181434 -60.175065) (xy 100.158794 -60.12549) (xy 100.14344 -60.073196)
			(xy 100.135684 -60.01925) (xy 92.094034 -60.01925) (xy 92.079626 -60.633356) (xy 123.897134 -60.633356)
			(xy 123.901205 -60.577734) (xy 123.913331 -60.523297) (xy 123.933254 -60.471206) (xy 123.96055 -60.422571)
			(xy 123.994636 -60.378428) (xy 124.034785 -60.339719) (xy 124.080143 -60.307268) (xy 124.129743 -60.281767)
			(xy 124.182527 -60.26376) (xy 124.23737 -60.25363) (xy 124.293104 -60.251593) (xy 124.348541 -60.257693)
			(xy 124.402498 -60.271799) (xy 124.453827 -60.293611) (xy 124.501433 -60.322665) (xy 124.544301 -60.35834)
			(xy 124.581518 -60.399877) (xy 124.612291 -60.44639) (xy 124.635963 -60.496887) (xy 124.652031 -60.550294)
			(xy 124.660151 -60.60547) (xy 124.66066 -60.633356) (xy 124.660151 -60.661242) (xy 124.652031 -60.716418)
			(xy 124.635963 -60.769825) (xy 124.612291 -60.820322) (xy 124.581518 -60.866835) (xy 124.544301 -60.908372)
			(xy 124.501433 -60.944047) (xy 124.453827 -60.973101) (xy 124.402498 -60.994913) (xy 124.348541 -61.009019)
			(xy 124.293104 -61.015119) (xy 124.23737 -61.013082) (xy 124.182527 -61.002952) (xy 124.129743 -60.984945)
			(xy 124.080143 -60.959444) (xy 124.034785 -60.926993) (xy 123.994636 -60.888284) (xy 123.96055 -60.844141)
			(xy 123.933254 -60.795506) (xy 123.913331 -60.743415) (xy 123.901205 -60.688978) (xy 123.897134 -60.633356)
			(xy 92.079626 -60.633356) (xy 92.075508 -60.80887) (xy 92.074041 -60.852875) (xy 92.064245 -60.940381)
			(xy 92.05595 -60.983622) (xy 91.96197 -61.453268) (xy 91.961716 -61.454538) (xy 91.955914 -61.487812)
			(xy 122.40463 -61.487812) (xy 122.408701 -61.43219) (xy 122.420827 -61.377753) (xy 122.44075 -61.325662)
			(xy 122.468046 -61.277027) (xy 122.502132 -61.232884) (xy 122.542281 -61.194175) (xy 122.587639 -61.161724)
			(xy 122.637239 -61.136223) (xy 122.690023 -61.118216) (xy 122.744866 -61.108086) (xy 122.8006 -61.106049)
			(xy 122.856037 -61.112149) (xy 122.909994 -61.126255) (xy 122.961323 -61.148067) (xy 123.008929 -61.177121)
			(xy 123.051797 -61.212796) (xy 123.089014 -61.254333) (xy 123.119787 -61.300846) (xy 123.143459 -61.351343)
			(xy 123.159527 -61.40475) (xy 123.167647 -61.459926) (xy 123.168156 -61.487812) (xy 123.167647 -61.515698)
			(xy 123.159527 -61.570874) (xy 123.143459 -61.624281) (xy 123.119787 -61.674778) (xy 123.089014 -61.721291)
			(xy 123.051797 -61.762828) (xy 123.008929 -61.798503) (xy 122.961323 -61.827557) (xy 122.909994 -61.849369)
			(xy 122.856037 -61.863475) (xy 122.8006 -61.869575) (xy 122.744866 -61.867538) (xy 122.690023 -61.857408)
			(xy 122.637239 -61.839401) (xy 122.587639 -61.8139) (xy 122.542281 -61.781449) (xy 122.502132 -61.74274)
			(xy 122.468046 -61.698597) (xy 122.44075 -61.649962) (xy 122.420827 -61.597871) (xy 122.408701 -61.543434)
			(xy 122.40463 -61.487812) (xy 91.955914 -61.487812) (xy 91.95308 -61.504068) (xy 91.830673 -62.121034)
			(xy 120.342404 -62.121034) (xy 120.346475 -62.065412) (xy 120.358601 -62.010975) (xy 120.378524 -61.958884)
			(xy 120.40582 -61.910249) (xy 120.439906 -61.866106) (xy 120.480055 -61.827397) (xy 120.525413 -61.794946)
			(xy 120.575013 -61.769445) (xy 120.627797 -61.751438) (xy 120.68264 -61.741308) (xy 120.738374 -61.739271)
			(xy 120.793811 -61.745371) (xy 120.847768 -61.759477) (xy 120.899097 -61.781289) (xy 120.946703 -61.810343)
			(xy 120.989571 -61.846018) (xy 121.026788 -61.887555) (xy 121.057561 -61.934068) (xy 121.081233 -61.984565)
			(xy 121.097301 -62.037972) (xy 121.105421 -62.093148) (xy 121.10593 -62.121034) (xy 121.105421 -62.14892)
			(xy 121.097301 -62.204096) (xy 121.081233 -62.257503) (xy 121.057561 -62.308) (xy 121.026788 -62.354513)
			(xy 120.989571 -62.39605) (xy 120.946703 -62.431725) (xy 120.899097 -62.460779) (xy 120.847768 -62.482591)
			(xy 120.793811 -62.496697) (xy 120.738374 -62.502797) (xy 120.68264 -62.50076) (xy 120.627797 -62.49063)
			(xy 120.575013 -62.472623) (xy 120.525413 -62.447122) (xy 120.480055 -62.414671) (xy 120.439906 -62.375962)
			(xy 120.40582 -62.331819) (xy 120.378524 -62.283184) (xy 120.358601 -62.231093) (xy 120.346475 -62.176656)
			(xy 120.342404 -62.121034) (xy 91.830673 -62.121034) (xy 91.613917 -63.213552) (xy 100.120665 -63.213552)
			(xy 100.120665 -63.159048) (xy 100.128422 -63.105098) (xy 100.143778 -63.052801) (xy 100.16642 -63.003222)
			(xy 100.195888 -62.95737) (xy 100.231581 -62.916178) (xy 100.272773 -62.880485) (xy 100.318625 -62.851018)
			(xy 100.368205 -62.828377) (xy 100.420502 -62.813021) (xy 100.474452 -62.805265) (xy 100.501704 -62.804802)
			(xy 100.529074 -62.805265) (xy 100.583254 -62.813084) (xy 100.635757 -62.828573) (xy 100.685504 -62.851416)
			(xy 100.73147 -62.881141) (xy 100.752402 -62.898782) (xy 100.752656 -62.899036) (xy 100.759748 -62.904614)
			(xy 100.776661 -62.910865) (xy 100.785676 -62.911228) (xy 100.852732 -62.911228) (xy 100.86175 -62.91088)
			(xy 100.878666 -62.904626) (xy 100.885752 -62.899036) (xy 100.885752 -62.898782) (xy 100.886006 -62.898782)
			(xy 100.906939 -62.881141) (xy 100.952907 -62.851417) (xy 101.002653 -62.828571) (xy 101.055155 -62.813075)
			(xy 101.109333 -62.805246) (xy 101.164075 -62.805246) (xy 101.218253 -62.813075) (xy 101.270755 -62.828571)
			(xy 101.320501 -62.851417) (xy 101.366469 -62.881141) (xy 101.387402 -62.898782) (xy 101.387656 -62.899036)
			(xy 101.394748 -62.904614) (xy 101.411661 -62.910865) (xy 101.420676 -62.911228) (xy 101.487732 -62.911228)
			(xy 101.49675 -62.91088) (xy 101.513666 -62.904626) (xy 101.520752 -62.899036) (xy 101.520752 -62.898782)
			(xy 101.521006 -62.898782) (xy 101.541923 -62.881124) (xy 101.5879 -62.851415) (xy 101.637651 -62.828583)
			(xy 101.690155 -62.813097) (xy 101.744334 -62.805273) (xy 101.771704 -62.804802) (xy 101.798956 -62.805268)
			(xy 101.852904 -62.813025) (xy 101.9052 -62.828381) (xy 101.954778 -62.851023) (xy 102.000629 -62.88049)
			(xy 102.04182 -62.916183) (xy 102.077512 -62.957374) (xy 102.106979 -63.003225) (xy 102.12962 -63.052804)
			(xy 102.139436 -63.086234) (xy 117.487698 -63.086234) (xy 117.491769 -63.030612) (xy 117.503895 -62.976175)
			(xy 117.523818 -62.924084) (xy 117.551114 -62.875449) (xy 117.5852 -62.831306) (xy 117.625349 -62.792597)
			(xy 117.670707 -62.760146) (xy 117.720307 -62.734645) (xy 117.773091 -62.716638) (xy 117.827934 -62.706508)
			(xy 117.883668 -62.704471) (xy 117.939105 -62.710571) (xy 117.993062 -62.724677) (xy 118.013208 -62.733238)
			(xy 123.76625 -62.733238) (xy 123.766253 -62.67873) (xy 123.774012 -62.624778) (xy 123.789371 -62.57248)
			(xy 123.812017 -62.522899) (xy 123.841488 -62.477047) (xy 123.877185 -62.435855) (xy 123.91838 -62.400162)
			(xy 123.964236 -62.370696) (xy 124.013819 -62.348056) (xy 124.066119 -62.332703) (xy 124.120072 -62.32495)
			(xy 124.147326 -62.324488) (xy 124.170881 -62.324863) (xy 124.217625 -62.330724) (xy 124.240544 -62.336172)
			(xy 124.2543 -62.339208) (xy 124.28245 -62.338353) (xy 124.309298 -62.329846) (xy 124.332804 -62.314336)
			(xy 124.351185 -62.292998) (xy 124.363044 -62.267454) (xy 124.367481 -62.239643) (xy 124.364159 -62.211677)
			(xy 124.359162 -62.198504) (xy 124.349851 -62.175114) (xy 124.336726 -62.126514) (xy 124.330103 -62.076609)
			(xy 124.329698 -62.051438) (xy 124.330114 -62.024182) (xy 124.337867 -61.970224) (xy 124.35322 -61.917918)
			(xy 124.37586 -61.86833) (xy 124.405328 -61.822469) (xy 124.441022 -61.781268) (xy 124.482217 -61.745567)
			(xy 124.528073 -61.716092) (xy 124.577657 -61.693443) (xy 124.62996 -61.678081) (xy 124.683917 -61.670319)
			(xy 124.738429 -61.670315) (xy 124.792387 -61.678069) (xy 124.844692 -61.693424) (xy 124.894279 -61.716066)
			(xy 124.94014 -61.745534) (xy 124.981339 -61.78123) (xy 125.017039 -61.822425) (xy 125.046513 -61.868282)
			(xy 125.069161 -61.917867) (xy 125.084521 -61.97017) (xy 125.092282 -62.024127) (xy 125.092284 -62.078639)
			(xy 125.084529 -62.132597) (xy 125.069173 -62.184902) (xy 125.046529 -62.234489) (xy 125.017059 -62.280348)
			(xy 124.981363 -62.321547) (xy 124.940166 -62.357246) (xy 124.894308 -62.386718) (xy 124.844723 -62.409365)
			(xy 124.792419 -62.424724) (xy 124.738462 -62.432483) (xy 124.711206 -62.432946) (xy 124.687652 -62.432564)
			(xy 124.640907 -62.426708) (xy 124.617988 -62.421262) (xy 124.604232 -62.418212) (xy 124.576076 -62.41906)
			(xy 124.549222 -62.427563) (xy 124.525709 -62.443075) (xy 124.507325 -62.464417) (xy 124.495467 -62.489968)
			(xy 124.491035 -62.517786) (xy 124.494367 -62.545757) (xy 124.49937 -62.55893) (xy 124.508692 -62.582315)
			(xy 124.521813 -62.630918) (xy 124.528431 -62.680824) (xy 124.528834 -62.705996) (xy 124.528349 -62.73325)
			(xy 124.520592 -62.787202) (xy 124.505236 -62.839501) (xy 124.482593 -62.889083) (xy 124.453124 -62.934937)
			(xy 124.41743 -62.976131) (xy 124.376236 -63.011826) (xy 124.330381 -63.041294) (xy 124.2808 -63.063937)
			(xy 124.2285 -63.079293) (xy 124.174548 -63.087049) (xy 124.12004 -63.087048) (xy 124.066088 -63.07929)
			(xy 124.013789 -63.063933) (xy 123.964208 -63.041288) (xy 123.918355 -63.011818) (xy 123.877162 -62.976123)
			(xy 123.841468 -62.934928) (xy 123.812001 -62.889072) (xy 123.78936 -62.83949) (xy 123.774005 -62.78719)
			(xy 123.76625 -62.733238) (xy 118.013208 -62.733238) (xy 118.044391 -62.746489) (xy 118.091997 -62.775543)
			(xy 118.134865 -62.811218) (xy 118.172082 -62.852755) (xy 118.202855 -62.899268) (xy 118.226527 -62.949765)
			(xy 118.242595 -63.003172) (xy 118.250715 -63.058348) (xy 118.251224 -63.086234) (xy 118.250715 -63.11412)
			(xy 118.242595 -63.169296) (xy 118.226527 -63.222703) (xy 118.202855 -63.2732) (xy 118.202702 -63.273432)
			(xy 119.676924 -63.273432) (xy 119.680995 -63.21781) (xy 119.693121 -63.163373) (xy 119.713044 -63.111282)
			(xy 119.74034 -63.062647) (xy 119.774426 -63.018504) (xy 119.814575 -62.979795) (xy 119.859933 -62.947344)
			(xy 119.909533 -62.921843) (xy 119.962317 -62.903836) (xy 120.01716 -62.893706) (xy 120.072894 -62.891669)
			(xy 120.128331 -62.897769) (xy 120.182288 -62.911875) (xy 120.233617 -62.933687) (xy 120.281223 -62.962741)
			(xy 120.324091 -62.998416) (xy 120.361308 -63.039953) (xy 120.392081 -63.086466) (xy 120.415753 -63.136963)
			(xy 120.431821 -63.19037) (xy 120.439941 -63.245546) (xy 120.44045 -63.273432) (xy 120.439941 -63.301318)
			(xy 120.431821 -63.356494) (xy 120.415753 -63.409901) (xy 120.392081 -63.460398) (xy 120.361308 -63.506911)
			(xy 120.324091 -63.548448) (xy 120.281223 -63.584123) (xy 120.233617 -63.613177) (xy 120.182288 -63.634989)
			(xy 120.128331 -63.649095) (xy 120.072894 -63.655195) (xy 120.01716 -63.653158) (xy 119.962317 -63.643028)
			(xy 119.909533 -63.625021) (xy 119.859933 -63.59952) (xy 119.814575 -63.567069) (xy 119.774426 -63.52836)
			(xy 119.74034 -63.484217) (xy 119.713044 -63.435582) (xy 119.693121 -63.383491) (xy 119.680995 -63.329054)
			(xy 119.676924 -63.273432) (xy 118.202702 -63.273432) (xy 118.172082 -63.319713) (xy 118.134865 -63.36125)
			(xy 118.091997 -63.396925) (xy 118.044391 -63.425979) (xy 117.993062 -63.447791) (xy 117.939105 -63.461897)
			(xy 117.883668 -63.467997) (xy 117.827934 -63.46596) (xy 117.773091 -63.45583) (xy 117.720307 -63.437823)
			(xy 117.670707 -63.412322) (xy 117.625349 -63.379871) (xy 117.5852 -63.341162) (xy 117.551114 -63.297019)
			(xy 117.523818 -63.248384) (xy 117.503895 -63.196293) (xy 117.491769 -63.141856) (xy 117.487698 -63.086234)
			(xy 102.139436 -63.086234) (xy 102.144976 -63.105099) (xy 102.152732 -63.159048) (xy 102.152732 -63.213552)
			(xy 102.144976 -63.267501) (xy 102.12962 -63.319796) (xy 102.106979 -63.369375) (xy 102.077512 -63.415226)
			(xy 102.04182 -63.456417) (xy 102.000629 -63.49211) (xy 101.954778 -63.521577) (xy 101.9052 -63.544219)
			(xy 101.852904 -63.559575) (xy 101.798956 -63.567332) (xy 101.771704 -63.567818) (xy 101.744333 -63.56737)
			(xy 101.690152 -63.559551) (xy 101.637648 -63.544058) (xy 101.587902 -63.521212) (xy 101.541936 -63.491482)
			(xy 101.521006 -63.473838) (xy 101.520752 -63.473584) (xy 101.513656 -63.468011) (xy 101.496746 -63.461757)
			(xy 101.487732 -63.461392) (xy 101.420676 -63.461392) (xy 101.411658 -63.461739) (xy 101.394741 -63.467994)
			(xy 101.387656 -63.473584) (xy 101.387402 -63.473838) (xy 101.366469 -63.491479) (xy 101.320501 -63.521203)
			(xy 101.270755 -63.544049) (xy 101.218253 -63.559545) (xy 101.164075 -63.567374) (xy 101.109333 -63.567374)
			(xy 101.055155 -63.559545) (xy 101.002653 -63.544049) (xy 100.952907 -63.521203) (xy 100.906939 -63.491479)
			(xy 100.886006 -63.473838) (xy 100.885752 -63.473584) (xy 100.878656 -63.468011) (xy 100.861746 -63.461757)
			(xy 100.852732 -63.461392) (xy 100.785676 -63.461392) (xy 100.776658 -63.461739) (xy 100.759741 -63.467994)
			(xy 100.752656 -63.473584) (xy 100.752656 -63.473838) (xy 100.752402 -63.473838) (xy 100.731485 -63.491496)
			(xy 100.685508 -63.521204) (xy 100.635756 -63.544036) (xy 100.583252 -63.559522) (xy 100.529074 -63.567346)
			(xy 100.501704 -63.567818) (xy 100.474452 -63.567335) (xy 100.420502 -63.559579) (xy 100.368205 -63.544223)
			(xy 100.318625 -63.521582) (xy 100.272773 -63.492115) (xy 100.231581 -63.456422) (xy 100.195888 -63.41523)
			(xy 100.16642 -63.369378) (xy 100.143778 -63.319799) (xy 100.128422 -63.267502) (xy 100.120665 -63.213552)
			(xy 91.613917 -63.213552) (xy 91.239454 -65.100962) (xy 98.13239 -65.100962) (xy 98.136461 -65.04534)
			(xy 98.148587 -64.990903) (xy 98.16851 -64.938812) (xy 98.195806 -64.890177) (xy 98.229892 -64.846034)
			(xy 98.270041 -64.807325) (xy 98.315399 -64.774874) (xy 98.364999 -64.749373) (xy 98.417783 -64.731366)
			(xy 98.472626 -64.721236) (xy 98.52836 -64.719199) (xy 98.583797 -64.725299) (xy 98.637754 -64.739405)
			(xy 98.689083 -64.761217) (xy 98.736689 -64.790271) (xy 98.779557 -64.825946) (xy 98.816774 -64.867483)
			(xy 98.847547 -64.913996) (xy 98.871219 -64.964493) (xy 98.887287 -65.0179) (xy 98.895407 -65.073076)
			(xy 98.895916 -65.100962) (xy 98.895494 -65.124076) (xy 122.207526 -65.124076) (xy 122.211597 -65.068454)
			(xy 122.223723 -65.014017) (xy 122.243646 -64.961926) (xy 122.270942 -64.913291) (xy 122.305028 -64.869148)
			(xy 122.345177 -64.830439) (xy 122.390535 -64.797988) (xy 122.440135 -64.772487) (xy 122.492919 -64.75448)
			(xy 122.547762 -64.74435) (xy 122.603496 -64.742313) (xy 122.658933 -64.748413) (xy 122.71289 -64.762519)
			(xy 122.764219 -64.784331) (xy 122.811825 -64.813385) (xy 122.854693 -64.84906) (xy 122.89191 -64.890597)
			(xy 122.922683 -64.93711) (xy 122.946355 -64.987607) (xy 122.962423 -65.041014) (xy 122.970543 -65.09619)
			(xy 122.971052 -65.124076) (xy 122.970543 -65.151962) (xy 122.962423 -65.207138) (xy 122.946355 -65.260545)
			(xy 122.922683 -65.311042) (xy 122.89191 -65.357555) (xy 122.854693 -65.399092) (xy 122.811825 -65.434767)
			(xy 122.764219 -65.463821) (xy 122.71289 -65.485633) (xy 122.658933 -65.499739) (xy 122.603496 -65.505839)
			(xy 122.547762 -65.503802) (xy 122.492919 -65.493672) (xy 122.440135 -65.475665) (xy 122.390535 -65.450164)
			(xy 122.345177 -65.417713) (xy 122.305028 -65.379004) (xy 122.270942 -65.334861) (xy 122.243646 -65.286226)
			(xy 122.223723 -65.234135) (xy 122.211597 -65.179698) (xy 122.207526 -65.124076) (xy 98.895494 -65.124076)
			(xy 98.895407 -65.128848) (xy 98.887287 -65.184024) (xy 98.871219 -65.237431) (xy 98.847547 -65.287928)
			(xy 98.816774 -65.334441) (xy 98.779557 -65.375978) (xy 98.736689 -65.411653) (xy 98.689083 -65.440707)
			(xy 98.637754 -65.462519) (xy 98.583797 -65.476625) (xy 98.52836 -65.482725) (xy 98.472626 -65.480688)
			(xy 98.417783 -65.470558) (xy 98.364999 -65.452551) (xy 98.315399 -65.42705) (xy 98.270041 -65.394599)
			(xy 98.229892 -65.35589) (xy 98.195806 -65.311747) (xy 98.16851 -65.263112) (xy 98.148587 -65.211021)
			(xy 98.136461 -65.156584) (xy 98.13239 -65.100962) (xy 91.239454 -65.100962) (xy 91.109589 -65.75552)
			(xy 92.346524 -65.75552) (xy 92.350595 -65.699898) (xy 92.362721 -65.645461) (xy 92.382644 -65.59337)
			(xy 92.40994 -65.544735) (xy 92.444026 -65.500592) (xy 92.484175 -65.461883) (xy 92.529533 -65.429432)
			(xy 92.579133 -65.403931) (xy 92.631917 -65.385924) (xy 92.68676 -65.375794) (xy 92.742494 -65.373757)
			(xy 92.797931 -65.379857) (xy 92.851888 -65.393963) (xy 92.903217 -65.415775) (xy 92.950823 -65.444829)
			(xy 92.993691 -65.480504) (xy 93.030908 -65.522041) (xy 93.061681 -65.568554) (xy 93.085353 -65.619051)
			(xy 93.101421 -65.672458) (xy 93.109541 -65.727634) (xy 93.11005 -65.75552) (xy 93.109541 -65.783406)
			(xy 93.101421 -65.838582) (xy 93.085353 -65.891989) (xy 93.061681 -65.942486) (xy 93.030908 -65.988999)
			(xy 92.993691 -66.030536) (xy 92.950823 -66.066211) (xy 92.903217 -66.095265) (xy 92.851888 -66.117077)
			(xy 92.797931 -66.131183) (xy 92.742494 -66.137283) (xy 92.68676 -66.135246) (xy 92.631917 -66.125116)
			(xy 92.579133 -66.107109) (xy 92.529533 -66.081608) (xy 92.484175 -66.049157) (xy 92.444026 -66.010448)
			(xy 92.40994 -65.966305) (xy 92.382644 -65.91767) (xy 92.362721 -65.865579) (xy 92.350595 -65.811142)
			(xy 92.346524 -65.75552) (xy 91.109589 -65.75552) (xy 90.8371 -67.128949) (xy 92.366598 -67.128949)
			(xy 92.366598 -67.074451) (xy 92.374354 -67.020506) (xy 92.389708 -66.968215) (xy 92.412347 -66.918641)
			(xy 92.441811 -66.872794) (xy 92.4775 -66.831606) (xy 92.518687 -66.795916) (xy 92.564534 -66.766451)
			(xy 92.614108 -66.743811) (xy 92.666399 -66.728456) (xy 92.720343 -66.720699) (xy 92.747592 -66.720212)
			(xy 92.774962 -66.72068) (xy 92.829141 -66.728497) (xy 92.881645 -66.743985) (xy 92.931391 -66.766827)
			(xy 92.977358 -66.796551) (xy 92.99829 -66.814192) (xy 92.998544 -66.814446) (xy 93.005638 -66.820021)
			(xy 93.022549 -66.826273) (xy 93.031564 -66.826638) (xy 93.09862 -66.826638) (xy 93.107637 -66.826282)
			(xy 93.124553 -66.820033) (xy 93.13164 -66.814446) (xy 93.13164 -66.814192) (xy 93.131894 -66.814192)
			(xy 93.152816 -66.796541) (xy 93.198792 -66.766831) (xy 93.248542 -66.743998) (xy 93.301045 -66.728509)
			(xy 93.355222 -66.720684) (xy 93.382592 -66.720212) (xy 93.409847 -66.720634) (xy 93.463801 -66.728391)
			(xy 93.516103 -66.743747) (xy 93.565687 -66.76639) (xy 93.611543 -66.79586) (xy 93.652739 -66.831555)
			(xy 93.688436 -66.87275) (xy 93.717906 -66.918606) (xy 93.74055 -66.96819) (xy 93.755907 -67.020491)
			(xy 93.763665 -67.074445) (xy 93.763665 -67.128955) (xy 93.755907 -67.182909) (xy 93.74055 -67.23521)
			(xy 93.717906 -67.284794) (xy 93.688436 -67.33065) (xy 93.652739 -67.371845) (xy 93.611543 -67.40754)
			(xy 93.565687 -67.43701) (xy 93.516103 -67.459653) (xy 93.463801 -67.475009) (xy 93.409847 -67.482766)
			(xy 93.382592 -67.483228) (xy 93.355221 -67.482784) (xy 93.30104 -67.474964) (xy 93.248536 -67.45947)
			(xy 93.198789 -67.436623) (xy 93.152824 -67.406892) (xy 93.131894 -67.389248) (xy 93.13164 -67.388994)
			(xy 93.124547 -67.383417) (xy 93.107635 -67.377165) (xy 93.09862 -67.376802) (xy 93.031564 -67.376802)
			(xy 93.022545 -67.377142) (xy 93.005629 -67.383401) (xy 92.998544 -67.388994) (xy 92.998544 -67.389248)
			(xy 92.99829 -67.389248) (xy 92.977366 -67.406897) (xy 92.931392 -67.436609) (xy 92.881642 -67.459444)
			(xy 92.82914 -67.474933) (xy 92.774962 -67.482757) (xy 92.747592 -67.483228) (xy 92.720343 -67.482701)
			(xy 92.666399 -67.474944) (xy 92.614108 -67.459589) (xy 92.564534 -67.436949) (xy 92.518687 -67.407484)
			(xy 92.4775 -67.371794) (xy 92.441811 -67.330606) (xy 92.412347 -67.284759) (xy 92.389708 -67.235185)
			(xy 92.374354 -67.182894) (xy 92.366598 -67.128949) (xy 90.8371 -67.128949) (xy 90.765853 -67.488054)
			(xy 96.779078 -67.488054) (xy 96.783149 -67.432432) (xy 96.795275 -67.377995) (xy 96.815198 -67.325904)
			(xy 96.842494 -67.277269) (xy 96.87658 -67.233126) (xy 96.916729 -67.194417) (xy 96.962087 -67.161966)
			(xy 97.011687 -67.136465) (xy 97.064471 -67.118458) (xy 97.119314 -67.108328) (xy 97.175048 -67.106291)
			(xy 97.230485 -67.112391) (xy 97.284442 -67.126497) (xy 97.335771 -67.148309) (xy 97.383377 -67.177363)
			(xy 97.426245 -67.213038) (xy 97.463462 -67.254575) (xy 97.494235 -67.301088) (xy 97.517907 -67.351585)
			(xy 97.533975 -67.404992) (xy 97.542095 -67.460168) (xy 97.542604 -67.488054) (xy 97.542095 -67.51594)
			(xy 97.53891 -67.537584) (xy 98.071176 -67.537584) (xy 98.075247 -67.481962) (xy 98.087373 -67.427525)
			(xy 98.107296 -67.375434) (xy 98.134592 -67.326799) (xy 98.168678 -67.282656) (xy 98.208827 -67.243947)
			(xy 98.254185 -67.211496) (xy 98.303785 -67.185995) (xy 98.356569 -67.167988) (xy 98.411412 -67.157858)
			(xy 98.467146 -67.155821) (xy 98.522583 -67.161921) (xy 98.57654 -67.176027) (xy 98.627869 -67.197839)
			(xy 98.675475 -67.226893) (xy 98.718343 -67.262568) (xy 98.75556 -67.304105) (xy 98.786333 -67.350618)
			(xy 98.810005 -67.401115) (xy 98.826073 -67.454522) (xy 98.834193 -67.509698) (xy 98.834702 -67.537584)
			(xy 98.834193 -67.56547) (xy 98.830148 -67.592956) (xy 99.34524 -67.592956) (xy 99.349311 -67.537334)
			(xy 99.361437 -67.482897) (xy 99.38136 -67.430806) (xy 99.408656 -67.382171) (xy 99.442742 -67.338028)
			(xy 99.482891 -67.299319) (xy 99.528249 -67.266868) (xy 99.577849 -67.241367) (xy 99.630633 -67.22336)
			(xy 99.685476 -67.21323) (xy 99.74121 -67.211193) (xy 99.796647 -67.217293) (xy 99.850604 -67.231399)
			(xy 99.901933 -67.253211) (xy 99.949539 -67.282265) (xy 99.992407 -67.31794) (xy 100.029624 -67.359477)
			(xy 100.060397 -67.40599) (xy 100.084069 -67.456487) (xy 100.100137 -67.509894) (xy 100.108254 -67.565048)
			(xy 102.446616 -67.565048) (xy 102.446616 -67.510552) (xy 102.454371 -67.456612) (xy 102.469724 -67.404324)
			(xy 102.492362 -67.354753) (xy 102.521823 -67.308908) (xy 102.557509 -67.267722) (xy 102.598693 -67.232034)
			(xy 102.644537 -67.20257) (xy 102.694107 -67.17993) (xy 102.746394 -67.164575) (xy 102.800334 -67.156817)
			(xy 102.827582 -67.15633) (xy 102.854952 -67.156799) (xy 102.909131 -67.164615) (xy 102.961635 -67.180103)
			(xy 103.011382 -67.202944) (xy 103.057348 -67.232669) (xy 103.07828 -67.25031) (xy 103.078534 -67.250564)
			(xy 103.08563 -67.256137) (xy 103.10254 -67.26239) (xy 103.111554 -67.262756) (xy 103.17861 -67.262756)
			(xy 103.187629 -67.262414) (xy 103.204546 -67.256157) (xy 103.21163 -67.250564) (xy 103.21163 -67.25031)
			(xy 103.211884 -67.25031) (xy 103.232813 -67.232667) (xy 103.278786 -67.202955) (xy 103.328535 -67.18012)
			(xy 103.381036 -67.16463) (xy 103.435213 -67.156803) (xy 103.462582 -67.15633) (xy 103.489838 -67.156716)
			(xy 103.543797 -67.164471) (xy 103.596102 -67.179827) (xy 103.645689 -67.202471) (xy 103.691549 -67.231942)
			(xy 103.732748 -67.267639) (xy 103.768448 -67.308836) (xy 103.79792 -67.354695) (xy 103.820566 -67.404281)
			(xy 103.835925 -67.456586) (xy 103.843683 -67.510544) (xy 103.843683 -67.565056) (xy 103.835925 -67.619014)
			(xy 103.820566 -67.671319) (xy 103.79792 -67.720905) (xy 103.768448 -67.766764) (xy 103.732748 -67.807961)
			(xy 103.691549 -67.843658) (xy 103.645689 -67.873129) (xy 103.596102 -67.895773) (xy 103.543797 -67.911129)
			(xy 103.489838 -67.918884) (xy 103.462582 -67.919346) (xy 103.435211 -67.918904) (xy 103.38103 -67.911082)
			(xy 103.328526 -67.895588) (xy 103.27878 -67.872741) (xy 103.232814 -67.84301) (xy 103.211884 -67.825366)
			(xy 103.21163 -67.825112) (xy 103.204538 -67.819533) (xy 103.187625 -67.813281) (xy 103.17861 -67.81292)
			(xy 103.111554 -67.81292) (xy 103.102539 -67.813299) (xy 103.085622 -67.819531) (xy 103.078534 -67.825112)
			(xy 103.078534 -67.825366) (xy 103.07828 -67.825366) (xy 103.057324 -67.842976) (xy 103.011358 -67.872693)
			(xy 102.961617 -67.895535) (xy 102.909121 -67.911033) (xy 102.85495 -67.918868) (xy 102.827582 -67.919346)
			(xy 102.800334 -67.918783) (xy 102.746394 -67.911025) (xy 102.694107 -67.89567) (xy 102.644537 -67.87303)
			(xy 102.598693 -67.843566) (xy 102.557509 -67.807878) (xy 102.521823 -67.766692) (xy 102.492362 -67.720847)
			(xy 102.469724 -67.671276) (xy 102.454371 -67.618988) (xy 102.446616 -67.565048) (xy 100.108254 -67.565048)
			(xy 100.108257 -67.56507) (xy 100.108766 -67.592956) (xy 100.108257 -67.620842) (xy 100.100137 -67.676018)
			(xy 100.084069 -67.729425) (xy 100.060397 -67.779922) (xy 100.029624 -67.826435) (xy 99.992407 -67.867972)
			(xy 99.949539 -67.903647) (xy 99.901933 -67.932701) (xy 99.850604 -67.954513) (xy 99.796647 -67.968619)
			(xy 99.74121 -67.974719) (xy 99.685476 -67.972682) (xy 99.630633 -67.962552) (xy 99.577849 -67.944545)
			(xy 99.528249 -67.919044) (xy 99.482891 -67.886593) (xy 99.442742 -67.847884) (xy 99.408656 -67.803741)
			(xy 99.38136 -67.755106) (xy 99.361437 -67.703015) (xy 99.349311 -67.648578) (xy 99.34524 -67.592956)
			(xy 98.830148 -67.592956) (xy 98.826073 -67.620646) (xy 98.810005 -67.674053) (xy 98.786333 -67.72455)
			(xy 98.75556 -67.771063) (xy 98.718343 -67.8126) (xy 98.675475 -67.848275) (xy 98.627869 -67.877329)
			(xy 98.57654 -67.899141) (xy 98.522583 -67.913247) (xy 98.467146 -67.919347) (xy 98.411412 -67.91731)
			(xy 98.356569 -67.90718) (xy 98.303785 -67.889173) (xy 98.254185 -67.863672) (xy 98.208827 -67.831221)
			(xy 98.168678 -67.792512) (xy 98.134592 -67.748369) (xy 98.107296 -67.699734) (xy 98.087373 -67.647643)
			(xy 98.075247 -67.593206) (xy 98.071176 -67.537584) (xy 97.53891 -67.537584) (xy 97.533975 -67.571116)
			(xy 97.517907 -67.624523) (xy 97.494235 -67.67502) (xy 97.463462 -67.721533) (xy 97.426245 -67.76307)
			(xy 97.383377 -67.798745) (xy 97.335771 -67.827799) (xy 97.284442 -67.849611) (xy 97.230485 -67.863717)
			(xy 97.175048 -67.869817) (xy 97.119314 -67.86778) (xy 97.064471 -67.85765) (xy 97.011687 -67.839643)
			(xy 96.962087 -67.814142) (xy 96.916729 -67.781691) (xy 96.87658 -67.742982) (xy 96.842494 -67.698839)
			(xy 96.815198 -67.650204) (xy 96.795275 -67.598113) (xy 96.783149 -67.543676) (xy 96.779078 -67.488054)
			(xy 90.765853 -67.488054) (xy 90.5479 -68.586604) (xy 94.62516 -68.586604) (xy 94.625614 -68.559233)
			(xy 94.633432 -68.505053) (xy 94.648923 -68.452549) (xy 94.671768 -68.402802) (xy 94.701497 -68.356837)
			(xy 94.71914 -68.335906) (xy 94.719394 -68.335652) (xy 94.724964 -68.328554) (xy 94.731221 -68.311646)
			(xy 94.731586 -68.302632) (xy 94.731586 -68.235576) (xy 94.731243 -68.226558) (xy 94.724986 -68.209641)
			(xy 94.719394 -68.202556) (xy 94.71914 -68.202556) (xy 94.71914 -68.202302) (xy 94.701495 -68.181375)
			(xy 94.671782 -68.135401) (xy 94.648947 -68.085653) (xy 94.633458 -68.033151) (xy 94.625632 -67.978974)
			(xy 94.62516 -67.951604) (xy 94.625681 -67.924354) (xy 94.633437 -67.87041) (xy 94.64879 -67.818117)
			(xy 94.671428 -67.768542) (xy 94.700891 -67.722693) (xy 94.736578 -67.681504) (xy 94.777765 -67.645812)
			(xy 94.823611 -67.616345) (xy 94.873184 -67.593702) (xy 94.925474 -67.578344) (xy 94.979418 -67.570584)
			(xy 95.006668 -67.570096) (xy 95.032983 -67.570519) (xy 95.085114 -67.577763) (xy 95.135757 -67.592091)
			(xy 95.183956 -67.613232) (xy 95.228799 -67.640786) (xy 95.269436 -67.674231) (xy 95.287592 -67.693286)
			(xy 95.295117 -67.700684) (xy 95.314394 -67.709211) (xy 95.32493 -67.709796) (xy 95.399606 -67.709796)
			(xy 95.410158 -67.709285) (xy 95.429453 -67.700737) (xy 95.436944 -67.693286) (xy 95.455082 -67.674213)
			(xy 95.495716 -67.640758) (xy 95.54056 -67.613202) (xy 95.588764 -67.592067) (xy 95.639415 -67.577753)
			(xy 95.691551 -67.570532) (xy 95.717868 -67.570096) (xy 95.745238 -67.570582) (xy 95.799416 -67.578395)
			(xy 95.851919 -67.59388) (xy 95.901666 -67.616717) (xy 95.947634 -67.646437) (xy 95.968566 -67.664076)
			(xy 95.96882 -67.66433) (xy 95.975894 -67.669934) (xy 95.992821 -67.676169) (xy 96.00184 -67.676522)
			(xy 96.068896 -67.676522) (xy 96.077912 -67.676158) (xy 96.094829 -67.669915) (xy 96.101916 -67.66433)
			(xy 96.101916 -67.664076) (xy 96.10217 -67.664076) (xy 96.123099 -67.646434) (xy 96.169073 -67.616723)
			(xy 96.218822 -67.593888) (xy 96.271323 -67.578398) (xy 96.325499 -67.57057) (xy 96.352868 -67.570096)
			(xy 96.38012 -67.570585) (xy 96.43407 -67.578338) (xy 96.486368 -67.59369) (xy 96.535948 -67.616329)
			(xy 96.581802 -67.645794) (xy 96.622995 -67.681485) (xy 96.658689 -67.722676) (xy 96.688158 -67.768527)
			(xy 96.7108 -67.818106) (xy 96.726156 -67.870402) (xy 96.733913 -67.924352) (xy 96.734376 -67.951604)
			(xy 96.733918 -67.978975) (xy 96.726099 -68.033154) (xy 96.710609 -68.085658) (xy 96.687765 -68.135404)
			(xy 96.658038 -68.181371) (xy 96.640396 -68.202302) (xy 96.640142 -68.202556) (xy 96.634561 -68.209646)
			(xy 96.628312 -68.22656) (xy 96.62795 -68.235576) (xy 96.62795 -68.302632) (xy 96.628281 -68.311652)
			(xy 96.634545 -68.328569) (xy 96.640142 -68.335652) (xy 96.640396 -68.335652) (xy 96.640396 -68.335906)
			(xy 96.658051 -68.356825) (xy 96.68776 -68.402802) (xy 96.710593 -68.452552) (xy 96.726081 -68.505056)
			(xy 96.733904 -68.559234) (xy 96.734376 -68.586604) (xy 96.733948 -68.613858) (xy 96.72619 -68.667812)
			(xy 96.710832 -68.720113) (xy 96.694199 -68.75653) (xy 100.170234 -68.75653) (xy 100.170709 -68.72916)
			(xy 100.178524 -68.674981) (xy 100.19401 -68.622478) (xy 100.21685 -68.572731) (xy 100.246573 -68.526764)
			(xy 100.264214 -68.505832) (xy 100.264468 -68.505578) (xy 100.270078 -68.498508) (xy 100.276309 -68.481578)
			(xy 100.27666 -68.472558) (xy 100.27666 -68.405502) (xy 100.27631 -68.396484) (xy 100.270059 -68.379567)
			(xy 100.264468 -68.372482) (xy 100.264214 -68.372482) (xy 100.264214 -68.372228) (xy 100.246577 -68.351294)
			(xy 100.216864 -68.305322) (xy 100.194028 -68.255575) (xy 100.178536 -68.203075) (xy 100.170708 -68.148899)
			(xy 100.170234 -68.12153) (xy 100.170683 -68.094276) (xy 100.178437 -68.040322) (xy 100.193792 -67.988022)
			(xy 100.216434 -67.938439) (xy 100.245903 -67.892584) (xy 100.281598 -67.851389) (xy 100.322793 -67.815695)
			(xy 100.368649 -67.786228) (xy 100.418233 -67.763587) (xy 100.470534 -67.748235) (xy 100.524488 -67.740482)
			(xy 100.551742 -67.740022) (xy 100.579111 -67.740517) (xy 100.633289 -67.748327) (xy 100.685792 -67.763809)
			(xy 100.73554 -67.786644) (xy 100.781508 -67.816363) (xy 100.80244 -67.834002) (xy 100.802694 -67.834256)
			(xy 100.809773 -67.839853) (xy 100.826696 -67.846092) (xy 100.835714 -67.846448) (xy 100.90277 -67.846448)
			(xy 100.911787 -67.846088) (xy 100.928704 -67.839844) (xy 100.93579 -67.834256) (xy 100.93579 -67.834002)
			(xy 100.936044 -67.834002) (xy 100.956987 -67.816376) (xy 101.002956 -67.786662) (xy 101.052701 -67.763824)
			(xy 101.1052 -67.74833) (xy 101.159374 -67.740498) (xy 101.186742 -67.740022) (xy 101.213057 -67.740454)
			(xy 101.265188 -67.747695) (xy 101.315831 -67.762021) (xy 101.36403 -67.78316) (xy 101.408873 -67.810712)
			(xy 101.449511 -67.844157) (xy 101.467666 -67.863212) (xy 101.475197 -67.870603) (xy 101.49447 -67.879133)
			(xy 101.505004 -67.879722) (xy 101.57968 -67.879722) (xy 101.590229 -67.879189) (xy 101.609524 -67.870656)
			(xy 101.617018 -67.863212) (xy 101.635174 -67.844157) (xy 101.675803 -67.810699) (xy 101.720644 -67.78314)
			(xy 101.768844 -67.762001) (xy 101.819492 -67.747684) (xy 101.871626 -67.74046) (xy 101.897942 -67.740022)
			(xy 101.925196 -67.740439) (xy 101.979147 -67.748202) (xy 102.031445 -67.763564) (xy 102.081025 -67.786212)
			(xy 102.126876 -67.815685) (xy 102.168067 -67.851384) (xy 102.203758 -67.892581) (xy 102.233223 -67.938439)
			(xy 102.255861 -67.988022) (xy 102.271213 -68.040323) (xy 102.278966 -68.094276) (xy 102.27945 -68.12153)
			(xy 102.279014 -68.148901) (xy 102.271191 -68.203082) (xy 102.255695 -68.255586) (xy 102.232847 -68.305333)
			(xy 102.203115 -68.351298) (xy 102.18547 -68.372228) (xy 102.185216 -68.372482) (xy 102.179633 -68.379571)
			(xy 102.173384 -68.396486) (xy 102.173024 -68.405502) (xy 102.173024 -68.472558) (xy 102.173396 -68.481573)
			(xy 102.179633 -68.498491) (xy 102.185216 -68.505578) (xy 102.18547 -68.505578) (xy 102.18547 -68.505832)
			(xy 102.203086 -68.526783) (xy 102.232802 -68.57275) (xy 102.255643 -68.622493) (xy 102.27114 -68.674989)
			(xy 102.278973 -68.729162) (xy 102.27945 -68.75653) (xy 102.27895 -68.78378) (xy 102.271191 -68.837725)
			(xy 102.255834 -68.890017) (xy 102.233192 -68.939592) (xy 102.203727 -68.98544) (xy 102.168037 -69.026629)
			(xy 102.126849 -69.06232) (xy 102.081002 -69.091787) (xy 102.031428 -69.11443) (xy 101.979137 -69.129788)
			(xy 101.925192 -69.137549) (xy 101.897942 -69.138038) (xy 101.871626 -69.137629) (xy 101.819494 -69.130385)
			(xy 101.768849 -69.116056) (xy 101.72065 -69.094913) (xy 101.675808 -69.067355) (xy 101.635172 -69.033905)
			(xy 101.617018 -69.014848) (xy 101.609485 -69.00746) (xy 101.590214 -68.998926) (xy 101.57968 -68.998338)
			(xy 101.505004 -68.998338) (xy 101.494451 -68.998844) (xy 101.475156 -69.007394) (xy 101.467666 -69.014848)
			(xy 101.449529 -69.033922) (xy 101.408895 -69.067376) (xy 101.36405 -69.094931) (xy 101.315846 -69.116066)
			(xy 101.265195 -69.13038) (xy 101.213059 -69.137601) (xy 101.186742 -69.138038) (xy 101.159372 -69.137562)
			(xy 101.105193 -69.129749) (xy 101.052689 -69.114263) (xy 101.002942 -69.091423) (xy 100.956975 -69.061699)
			(xy 100.936044 -69.044058) (xy 100.93579 -69.043804) (xy 100.92871 -69.038208) (xy 100.911788 -69.031967)
			(xy 100.90277 -69.031612) (xy 100.835714 -69.031612) (xy 100.826697 -69.031973) (xy 100.80978 -69.038217)
			(xy 100.802694 -69.043804) (xy 100.802694 -69.044058) (xy 100.80244 -69.044058) (xy 100.781498 -69.061685)
			(xy 100.735529 -69.0914) (xy 100.685784 -69.114239) (xy 100.633285 -69.129733) (xy 100.579111 -69.137563)
			(xy 100.551742 -69.138038) (xy 100.524492 -69.137506) (xy 100.470545 -69.129755) (xy 100.41825 -69.114406)
			(xy 100.368672 -69.091771) (xy 100.32282 -69.06231) (xy 100.281628 -69.026623) (xy 100.245933 -68.985438)
			(xy 100.216464 -68.939591) (xy 100.193819 -68.890018) (xy 100.17846 -68.837726) (xy 100.170699 -68.78378)
			(xy 100.170234 -68.75653) (xy 96.694199 -68.75653) (xy 96.688186 -68.769695) (xy 96.658715 -68.81555)
			(xy 96.623018 -68.856743) (xy 96.581821 -68.892437) (xy 96.535963 -68.921904) (xy 96.486379 -68.944544)
			(xy 96.434077 -68.959898) (xy 96.380122 -68.967651) (xy 96.352868 -68.968112) (xy 96.325497 -68.967662)
			(xy 96.271318 -68.95984) (xy 96.218814 -68.944347) (xy 96.169068 -68.921502) (xy 96.123101 -68.891774)
			(xy 96.10217 -68.874132) (xy 96.101916 -68.873878) (xy 96.094831 -68.86829) (xy 96.077913 -68.862045)
			(xy 96.068896 -68.861686) (xy 96.00184 -68.861686) (xy 95.992825 -68.862065) (xy 95.975908 -68.868298)
			(xy 95.96882 -68.873878) (xy 95.96882 -68.874132) (xy 95.968566 -68.874132) (xy 95.947624 -68.891759)
			(xy 95.901653 -68.921471) (xy 95.851908 -68.944309) (xy 95.79941 -68.959803) (xy 95.745236 -68.967636)
			(xy 95.717868 -68.968112) (xy 95.691553 -68.967662) (xy 95.639424 -68.960423) (xy 95.588781 -68.9461)
			(xy 95.540583 -68.924965) (xy 95.49574 -68.897416) (xy 95.4551 -68.863975) (xy 95.436944 -68.844922)
			(xy 95.429405 -68.837541) (xy 95.410138 -68.829004) (xy 95.399606 -68.828412) (xy 95.32493 -68.828412)
			(xy 95.31438 -68.82894) (xy 95.295085 -68.837476) (xy 95.287592 -68.844922) (xy 95.269438 -68.863979)
			(xy 95.228807 -68.897435) (xy 95.183966 -68.924993) (xy 95.135766 -68.946131) (xy 95.085118 -68.960448)
			(xy 95.032984 -68.967673) (xy 95.006668 -68.968112) (xy 94.979416 -68.967652) (xy 94.925468 -68.959891)
			(xy 94.873173 -68.944532) (xy 94.823596 -68.921888) (xy 94.777746 -68.892418) (xy 94.736556 -68.856724)
			(xy 94.700865 -68.815532) (xy 94.671399 -68.76968) (xy 94.648758 -68.720101) (xy 94.633403 -68.667805)
			(xy 94.625646 -68.613856) (xy 94.62516 -68.586604) (xy 90.5479 -68.586604) (xy 89.958796 -71.555864)
			(xy 97.194368 -71.555864) (xy 97.198439 -71.500242) (xy 97.210565 -71.445805) (xy 97.230488 -71.393714)
			(xy 97.257784 -71.345079) (xy 97.29187 -71.300936) (xy 97.332019 -71.262227) (xy 97.377377 -71.229776)
			(xy 97.426977 -71.204275) (xy 97.479761 -71.186268) (xy 97.534604 -71.176138) (xy 97.590338 -71.174101)
			(xy 97.645775 -71.180201) (xy 97.699732 -71.194307) (xy 97.751061 -71.216119) (xy 97.798667 -71.245173)
			(xy 97.841535 -71.280848) (xy 97.878752 -71.322385) (xy 97.909525 -71.368898) (xy 97.933197 -71.419395)
			(xy 97.949265 -71.472802) (xy 97.957385 -71.527978) (xy 97.957894 -71.555864) (xy 97.957385 -71.58375)
			(xy 97.951546 -71.623428) (xy 98.703382 -71.623428) (xy 98.707453 -71.567806) (xy 98.719579 -71.513369)
			(xy 98.739502 -71.461278) (xy 98.766798 -71.412643) (xy 98.800884 -71.3685) (xy 98.841033 -71.329791)
			(xy 98.886391 -71.29734) (xy 98.935991 -71.271839) (xy 98.988775 -71.253832) (xy 99.043618 -71.243702)
			(xy 99.099352 -71.241665) (xy 99.154789 -71.247765) (xy 99.208746 -71.261871) (xy 99.260075 -71.283683)
			(xy 99.307681 -71.312737) (xy 99.350549 -71.348412) (xy 99.387766 -71.389949) (xy 99.418539 -71.436462)
			(xy 99.442211 -71.486959) (xy 99.458279 -71.540366) (xy 99.466399 -71.595542) (xy 99.466908 -71.623428)
			(xy 99.466399 -71.651314) (xy 99.458279 -71.70649) (xy 99.442211 -71.759897) (xy 99.418539 -71.810394)
			(xy 99.387766 -71.856907) (xy 99.350549 -71.898444) (xy 99.307681 -71.934119) (xy 99.260075 -71.963173)
			(xy 99.208746 -71.984985) (xy 99.154789 -71.999091) (xy 99.099352 -72.005191) (xy 99.043618 -72.003154)
			(xy 98.988775 -71.993024) (xy 98.935991 -71.975017) (xy 98.886391 -71.949516) (xy 98.841033 -71.917065)
			(xy 98.800884 -71.878356) (xy 98.766798 -71.834213) (xy 98.739502 -71.785578) (xy 98.719579 -71.733487)
			(xy 98.707453 -71.67905) (xy 98.703382 -71.623428) (xy 97.951546 -71.623428) (xy 97.949265 -71.638926)
			(xy 97.933197 -71.692333) (xy 97.909525 -71.74283) (xy 97.878752 -71.789343) (xy 97.841535 -71.83088)
			(xy 97.798667 -71.866555) (xy 97.751061 -71.895609) (xy 97.699732 -71.917421) (xy 97.645775 -71.931527)
			(xy 97.590338 -71.937627) (xy 97.534604 -71.93559) (xy 97.479761 -71.92546) (xy 97.426977 -71.907453)
			(xy 97.377377 -71.881952) (xy 97.332019 -71.849501) (xy 97.29187 -71.810792) (xy 97.257784 -71.766649)
			(xy 97.230488 -71.718014) (xy 97.210565 -71.665923) (xy 97.198439 -71.611486) (xy 97.194368 -71.555864)
			(xy 89.958796 -71.555864) (xy 89.511501 -73.810368) (xy 90.899486 -73.810368) (xy 90.903557 -73.754746)
			(xy 90.915683 -73.700309) (xy 90.935606 -73.648218) (xy 90.962902 -73.599583) (xy 90.996988 -73.55544)
			(xy 91.037137 -73.516731) (xy 91.082495 -73.48428) (xy 91.132095 -73.458779) (xy 91.184879 -73.440772)
			(xy 91.239722 -73.430642) (xy 91.295456 -73.428605) (xy 91.350893 -73.434705) (xy 91.40485 -73.448811)
			(xy 91.456179 -73.470623) (xy 91.503785 -73.499677) (xy 91.546653 -73.535352) (xy 91.58387 -73.576889)
			(xy 91.614643 -73.623402) (xy 91.638315 -73.673899) (xy 91.654383 -73.727306) (xy 91.662503 -73.782482)
			(xy 91.663012 -73.810368) (xy 91.662503 -73.838254) (xy 91.654383 -73.89343) (xy 91.638315 -73.946837)
			(xy 91.614643 -73.997334) (xy 91.58387 -74.043847) (xy 91.546653 -74.085384) (xy 91.503785 -74.121059)
			(xy 91.456179 -74.150113) (xy 91.40485 -74.171925) (xy 91.350893 -74.186031) (xy 91.295456 -74.192131)
			(xy 91.239722 -74.190094) (xy 91.184879 -74.179964) (xy 91.132095 -74.161957) (xy 91.082495 -74.136456)
			(xy 91.037137 -74.104005) (xy 90.996988 -74.065296) (xy 90.962902 -74.021153) (xy 90.935606 -73.972518)
			(xy 90.915683 -73.920427) (xy 90.903557 -73.86599) (xy 90.899486 -73.810368) (xy 89.511501 -73.810368)
			(xy 88.806187 -77.365367) (xy 105.150162 -77.365367) (xy 105.150162 -77.305433) (xy 105.157985 -77.246011)
			(xy 105.173496 -77.188119) (xy 105.19643 -77.132746) (xy 105.226396 -77.08084) (xy 105.26288 -77.03329)
			(xy 105.305258 -76.990908) (xy 105.352805 -76.954419) (xy 105.404708 -76.924449) (xy 105.460079 -76.901509)
			(xy 105.51797 -76.885993) (xy 105.577391 -76.878165) (xy 105.607358 -76.877672) (xy 106.470958 -76.877672)
			(xy 106.500928 -76.878178) (xy 106.560354 -76.885997) (xy 106.618252 -76.901506) (xy 106.67363 -76.92444)
			(xy 106.72554 -76.954406) (xy 106.773095 -76.990892) (xy 106.81548 -77.033273) (xy 106.851971 -77.080825)
			(xy 106.881942 -77.132732) (xy 106.904881 -77.188108) (xy 106.920395 -77.246004) (xy 106.928219 -77.305431)
			(xy 106.928219 -77.365367) (xy 109.150162 -77.365367) (xy 109.150162 -77.305433) (xy 109.157984 -77.246012)
			(xy 109.173495 -77.18812) (xy 109.196429 -77.132748) (xy 109.226394 -77.080843) (xy 109.262878 -77.033292)
			(xy 109.305255 -76.990911) (xy 109.352801 -76.954422) (xy 109.404703 -76.924452) (xy 109.460073 -76.901511)
			(xy 109.517963 -76.885994) (xy 109.577383 -76.878165) (xy 109.60735 -76.877672) (xy 110.47095 -76.877672)
			(xy 110.50092 -76.878178) (xy 110.560347 -76.885996) (xy 110.618246 -76.901504) (xy 110.673625 -76.924437)
			(xy 110.725536 -76.954403) (xy 110.773092 -76.990889) (xy 110.815478 -77.03327) (xy 110.851969 -77.080822)
			(xy 110.881941 -77.13273) (xy 110.90488 -77.188107) (xy 110.920395 -77.246003) (xy 110.928219 -77.30543)
			(xy 110.928219 -77.36537) (xy 110.920395 -77.424797) (xy 110.90488 -77.482693) (xy 110.881941 -77.53807)
			(xy 110.851969 -77.589978) (xy 110.815478 -77.63753) (xy 110.773092 -77.679911) (xy 110.725536 -77.716397)
			(xy 110.673625 -77.746363) (xy 110.618246 -77.769296) (xy 110.560347 -77.784804) (xy 110.50092 -77.792622)
			(xy 110.47095 -77.793088) (xy 109.60735 -77.793088) (xy 109.577383 -77.792635) (xy 109.517963 -77.784806)
			(xy 109.460073 -77.769289) (xy 109.404703 -77.746348) (xy 109.352801 -77.716378) (xy 109.305255 -77.679889)
			(xy 109.262878 -77.637508) (xy 109.226394 -77.589957) (xy 109.196429 -77.538052) (xy 109.173495 -77.48268)
			(xy 109.157984 -77.424788) (xy 109.150162 -77.365367) (xy 106.928219 -77.365367) (xy 106.928219 -77.365369)
			(xy 106.920395 -77.424796) (xy 106.904881 -77.482692) (xy 106.881942 -77.538068) (xy 106.851971 -77.589975)
			(xy 106.81548 -77.637527) (xy 106.773095 -77.679908) (xy 106.72554 -77.716394) (xy 106.67363 -77.74636)
			(xy 106.618252 -77.769294) (xy 106.560354 -77.784803) (xy 106.500928 -77.792622) (xy 106.470958 -77.793088)
			(xy 105.607358 -77.793088) (xy 105.577391 -77.792635) (xy 105.51797 -77.784807) (xy 105.460079 -77.769291)
			(xy 105.404708 -77.746351) (xy 105.352805 -77.716381) (xy 105.305258 -77.679892) (xy 105.26288 -77.63751)
			(xy 105.226396 -77.58996) (xy 105.19643 -77.538054) (xy 105.173496 -77.482681) (xy 105.157985 -77.424789)
			(xy 105.150162 -77.365367) (xy 88.806187 -77.365367) (xy 88.655006 -78.127367) (xy 107.150162 -78.127367)
			(xy 107.150162 -78.067433) (xy 107.157984 -78.008012) (xy 107.173496 -77.950119) (xy 107.19643 -77.894747)
			(xy 107.226395 -77.842842) (xy 107.262879 -77.795291) (xy 107.305256 -77.752909) (xy 107.352803 -77.716421)
			(xy 107.404706 -77.68645) (xy 107.460076 -77.66351) (xy 107.517966 -77.647993) (xy 107.577387 -77.640165)
			(xy 107.607354 -77.639672) (xy 108.470954 -77.639672) (xy 108.500924 -77.640178) (xy 108.560351 -77.647996)
			(xy 108.618249 -77.663505) (xy 108.673627 -77.686438) (xy 108.725538 -77.716405) (xy 108.773094 -77.752891)
			(xy 108.815479 -77.795272) (xy 108.85197 -77.842823) (xy 108.881941 -77.894731) (xy 108.90488 -77.950107)
			(xy 108.920395 -78.008004) (xy 108.928219 -78.06743) (xy 108.928219 -78.12737) (xy 108.920395 -78.186796)
			(xy 108.90488 -78.244693) (xy 108.881941 -78.300069) (xy 108.85197 -78.351977) (xy 108.815479 -78.399528)
			(xy 108.773093 -78.441909) (xy 108.725538 -78.478395) (xy 108.673627 -78.508362) (xy 108.618249 -78.531295)
			(xy 108.560351 -78.546804) (xy 108.500924 -78.554622) (xy 108.470954 -78.555088) (xy 107.607354 -78.555088)
			(xy 107.577387 -78.554635) (xy 107.517966 -78.546807) (xy 107.460076 -78.53129) (xy 107.404706 -78.50835)
			(xy 107.352803 -78.478379) (xy 107.305256 -78.441891) (xy 107.262879 -78.399509) (xy 107.226395 -78.351958)
			(xy 107.19643 -78.300053) (xy 107.173496 -78.244681) (xy 107.157984 -78.186788) (xy 107.150162 -78.127367)
			(xy 88.655006 -78.127367) (xy 88.348312 -79.673196) (xy 88.347043 -79.681909) (xy 88.349855 -79.699276)
			(xy 88.358427 -79.71464) (xy 88.364822 -79.720694) (xy 88.383872 -79.736696) (xy 88.401906 -79.751682)
			(xy 88.405305 -79.754395) (xy 88.412838 -79.758742) (xy 88.416892 -79.760318) (xy 88.425528 -79.763366)
			(xy 88.445086 -79.763366) (xy 88.451944 -79.762858) (xy 88.464644 -79.760318) (xy 88.468454 -79.759048)
			(xy 88.468962 -79.758794) (xy 88.485218 -79.75346) (xy 88.486234 -79.752952) (xy 88.684608 -79.686912)
			(xy 88.684862 -79.686912) (xy 88.74252 -79.70012) (xy 88.74887 -79.718154) (xy 88.750191 -79.722283)
			(xy 88.751598 -79.730837) (xy 88.751664 -79.735172) (xy 88.751664 -79.738982) (xy 88.752163 -79.747985)
			(xy 88.758667 -79.764789) (xy 88.770592 -79.778298) (xy 88.778334 -79.782924) (xy 88.803852 -79.797342)
			(xy 88.850525 -79.832791) (xy 88.891226 -79.874962) (xy 88.924998 -79.922862) (xy 88.951045 -79.975364)
			(xy 88.968755 -80.031233) (xy 88.975886 -80.077352) (xy 102.068087 -80.077352) (xy 102.068087 -80.022848)
			(xy 102.075844 -79.9689) (xy 102.0912 -79.916605) (xy 102.113842 -79.867027) (xy 102.14331 -79.821177)
			(xy 102.179003 -79.779987) (xy 102.220195 -79.744297) (xy 102.266047 -79.714832) (xy 102.315626 -79.692192)
			(xy 102.367922 -79.67684) (xy 102.42187 -79.669086) (xy 102.449122 -79.668624) (xy 102.476493 -79.669071)
			(xy 102.530673 -79.676893) (xy 102.583177 -79.692386) (xy 102.632923 -79.715232) (xy 102.678889 -79.744961)
			(xy 102.69982 -79.762604) (xy 102.700074 -79.762858) (xy 102.707159 -79.768447) (xy 102.724077 -79.774691)
			(xy 102.733094 -79.77505) (xy 102.80015 -79.77505) (xy 102.809166 -79.77468) (xy 102.826083 -79.768443)
			(xy 102.83317 -79.762858) (xy 102.83317 -79.762604) (xy 102.833424 -79.762604) (xy 102.854374 -79.744988)
			(xy 102.900342 -79.715272) (xy 102.950085 -79.692432) (xy 103.002582 -79.676935) (xy 103.056754 -79.669101)
			(xy 103.084122 -79.668624) (xy 103.111375 -79.669047) (xy 103.165324 -79.676807) (xy 103.217621 -79.692165)
			(xy 103.267199 -79.71481) (xy 103.313051 -79.744279) (xy 103.354242 -79.779974) (xy 103.389934 -79.821167)
			(xy 103.419401 -79.86702) (xy 103.442042 -79.9166) (xy 103.457398 -79.968897) (xy 103.465154 -80.022847)
			(xy 103.465154 -80.077353) (xy 103.457398 -80.131303) (xy 103.442042 -80.1836) (xy 103.419401 -80.23318)
			(xy 103.389934 -80.279033) (xy 103.354242 -80.320226) (xy 103.313051 -80.355921) (xy 103.267199 -80.38539)
			(xy 103.217621 -80.408035) (xy 103.165324 -80.423393) (xy 103.111375 -80.431153) (xy 103.084122 -80.43164)
			(xy 103.056752 -80.431176) (xy 103.002572 -80.42336) (xy 102.950068 -80.407871) (xy 102.900321 -80.385028)
			(xy 102.854355 -80.355302) (xy 102.833424 -80.33766) (xy 102.83317 -80.337406) (xy 102.826067 -80.331843)
			(xy 102.809163 -80.325582) (xy 102.80015 -80.325214) (xy 102.733094 -80.325214) (xy 102.724076 -80.325565)
			(xy 102.707159 -80.331816) (xy 102.700074 -80.337406) (xy 102.700074 -80.33766) (xy 102.69982 -80.33766)
			(xy 102.678886 -80.355297) (xy 102.632914 -80.38501) (xy 102.583167 -80.407847) (xy 102.530667 -80.423339)
			(xy 102.476491 -80.431167) (xy 102.449122 -80.43164) (xy 102.42187 -80.431114) (xy 102.367922 -80.42336)
			(xy 102.315626 -80.408008) (xy 102.266047 -80.385368) (xy 102.220195 -80.355903) (xy 102.179003 -80.320213)
			(xy 102.14331 -80.279023) (xy 102.113842 -80.233173) (xy 102.0912 -80.183595) (xy 102.075844 -80.1313)
			(xy 102.068087 -80.077352) (xy 88.975886 -80.077352) (xy 88.977711 -80.089154) (xy 88.978232 -80.118458)
			(xy 88.977772 -80.145713) (xy 88.97002 -80.19967) (xy 88.954668 -80.251975) (xy 88.932028 -80.301562)
			(xy 88.902562 -80.347422) (xy 88.866868 -80.388621) (xy 88.825675 -80.424322) (xy 88.77982 -80.453796)
			(xy 88.730237 -80.476445) (xy 88.677935 -80.491806) (xy 88.623979 -80.499567) (xy 88.596724 -80.499966)
			(xy 88.567356 -80.49942) (xy 88.509314 -80.49041) (xy 88.453338 -80.472614) (xy 88.40075 -80.446452)
			(xy 88.35279 -80.412543) (xy 88.331294 -80.392524) (xy 88.329262 -80.390492) (xy 88.325252 -80.387153)
			(xy 88.316163 -80.382029) (xy 88.311228 -80.380332) (xy 88.300306 -80.376776) (xy 88.28405 -80.37957)
			(xy 88.283034 -80.379824) (xy 88.231726 -80.395826) (xy 88.225223 -80.398116) (xy 88.213643 -80.405587)
			(xy 88.208866 -80.410558) (xy 88.204802 -80.415384) (xy 88.19896 -80.427068) (xy 88.1507 -80.669638)
			(xy 88.140286 -80.721454) (xy 88.139074 -80.728959) (xy 88.140613 -80.744074) (xy 88.143334 -80.751172)
			(xy 88.146128 -80.757776) (xy 88.15578 -80.76946) (xy 88.15959 -80.772) (xy 88.207596 -80.80375)
			(xy 88.215194 -80.808394) (xy 88.232498 -80.812546) (xy 88.241378 -80.811878) (xy 88.243918 -80.81137)
			(xy 88.265508 -80.80502) (xy 88.271858 -80.800956) (xy 88.295264 -80.786284) (xy 88.345404 -80.7631)
			(xy 88.398359 -80.747373) (xy 88.453026 -80.73943) (xy 88.480646 -80.73898) (xy 88.481154 -80.73898)
			(xy 88.50841 -80.73944) (xy 88.562368 -80.747192) (xy 88.614673 -80.762544) (xy 88.66426 -80.785185)
			(xy 88.710121 -80.814653) (xy 88.75132 -80.850347) (xy 88.78702 -80.891543) (xy 88.816493 -80.937399)
			(xy 88.83914 -80.986984) (xy 88.854499 -81.039287) (xy 88.862257 -81.093244) (xy 88.862257 -81.147756)
			(xy 88.854499 -81.201713) (xy 88.83914 -81.254016) (xy 88.816493 -81.303601) (xy 88.78702 -81.349457)
			(xy 88.75132 -81.390653) (xy 88.710121 -81.426347) (xy 88.66426 -81.455815) (xy 88.614673 -81.478456)
			(xy 88.562368 -81.493808) (xy 88.50841 -81.50156) (xy 88.481154 -81.501996) (xy 88.47201 -81.501996)
			(xy 88.44691 -81.501016) (xy 88.397278 -81.493274) (xy 88.349092 -81.479082) (xy 88.303187 -81.458686)
			(xy 88.260357 -81.432438) (xy 88.240616 -81.416906) (xy 88.220449 -81.399969) (xy 88.18451 -81.361474)
			(xy 88.168988 -81.340198) (xy 88.165432 -81.334864) (xy 88.16086 -81.3308) (xy 88.160606 -81.330546)
			(xy 88.151208 -81.323434) (xy 88.14308 -81.319116) (xy 88.135968 -81.31556) (xy 88.132666 -81.313528)
			(xy 88.130634 -81.312766) (xy 88.130634 -81.312512) (xy 88.126513 -81.310721) (xy 88.11783 -81.308415)
			(xy 88.113362 -81.30794) (xy 88.100916 -81.308448) (xy 88.085422 -81.311496) (xy 88.052656 -81.317846)
			(xy 88.043164 -81.320441) (xy 88.027023 -81.331662) (xy 88.016316 -81.34815) (xy 88.014048 -81.357724)
			(xy 87.918499 -81.839308) (xy 88.80551 -81.839308) (xy 88.809581 -81.783686) (xy 88.821707 -81.729249)
			(xy 88.84163 -81.677158) (xy 88.868926 -81.628523) (xy 88.903012 -81.58438) (xy 88.943161 -81.545671)
			(xy 88.988519 -81.51322) (xy 89.038119 -81.487719) (xy 89.090903 -81.469712) (xy 89.145746 -81.459582)
			(xy 89.20148 -81.457545) (xy 89.256917 -81.463645) (xy 89.310874 -81.477751) (xy 89.362203 -81.499563)
			(xy 89.409809 -81.528617) (xy 89.452677 -81.564292) (xy 89.489894 -81.605829) (xy 89.520667 -81.652342)
			(xy 89.544339 -81.702839) (xy 89.560407 -81.756246) (xy 89.567781 -81.806352) (xy 108.258065 -81.806352)
			(xy 108.258065 -81.751848) (xy 108.265822 -81.697898) (xy 108.281178 -81.645601) (xy 108.30382 -81.596022)
			(xy 108.333287 -81.55017) (xy 108.36898 -81.508979) (xy 108.410172 -81.473286) (xy 108.456024 -81.443819)
			(xy 108.505603 -81.421177) (xy 108.5579 -81.405822) (xy 108.61185 -81.398065) (xy 108.639102 -81.397602)
			(xy 108.666802 -81.398114) (xy 108.721622 -81.406101) (xy 108.77471 -81.421936) (xy 108.824948 -81.445285)
			(xy 108.87128 -81.475658) (xy 108.912729 -81.512415) (xy 108.948423 -81.554782) (xy 108.977612 -81.601868)
			(xy 108.999681 -81.652682) (xy 109.007402 -81.679288) (xy 109.010196 -81.69021) (xy 109.024674 -81.707482)
			(xy 109.1057 -81.74482) (xy 109.116051 -81.748972) (xy 109.138326 -81.748843) (xy 109.148626 -81.744566)
			(xy 109.14888 -81.744566) (xy 109.174458 -81.733036) (xy 109.228148 -81.716757) (xy 109.283642 -81.708507)
			(xy 109.311694 -81.70799) (xy 109.338947 -81.708457) (xy 109.392898 -81.716213) (xy 109.445197 -81.731569)
			(xy 109.494777 -81.754211) (xy 109.540631 -81.783678) (xy 109.581824 -81.819372) (xy 109.617518 -81.860564)
			(xy 109.646987 -81.906418) (xy 109.660534 -81.936082) (xy 110.531146 -81.936082) (xy 110.535217 -81.88046)
			(xy 110.547343 -81.826023) (xy 110.567266 -81.773932) (xy 110.594562 -81.725297) (xy 110.628648 -81.681154)
			(xy 110.668797 -81.642445) (xy 110.714155 -81.609994) (xy 110.763755 -81.584493) (xy 110.816539 -81.566486)
			(xy 110.871382 -81.556356) (xy 110.927116 -81.554319) (xy 110.982553 -81.560419) (xy 111.03651 -81.574525)
			(xy 111.087839 -81.596337) (xy 111.135445 -81.625391) (xy 111.178313 -81.661066) (xy 111.21553 -81.702603)
			(xy 111.246303 -81.749116) (xy 111.269975 -81.799613) (xy 111.286043 -81.85302) (xy 111.294163 -81.908196)
			(xy 111.294672 -81.936082) (xy 111.294163 -81.963968) (xy 111.286043 -82.019144) (xy 111.269975 -82.072551)
			(xy 111.246303 -82.123048) (xy 111.21553 -82.169561) (xy 111.178313 -82.211098) (xy 111.135445 -82.246773)
			(xy 111.087839 -82.275827) (xy 111.03651 -82.297639) (xy 110.982553 -82.311745) (xy 110.927116 -82.317845)
			(xy 110.871382 -82.315808) (xy 110.816539 -82.305678) (xy 110.763755 -82.287671) (xy 110.714155 -82.26217)
			(xy 110.668797 -82.229719) (xy 110.628648 -82.19101) (xy 110.594562 -82.146867) (xy 110.567266 -82.098232)
			(xy 110.547343 -82.046141) (xy 110.535217 -81.991704) (xy 110.531146 -81.936082) (xy 109.660534 -81.936082)
			(xy 109.669629 -81.955998) (xy 109.684986 -82.008296) (xy 109.692743 -82.062247) (xy 109.692743 -82.116753)
			(xy 109.684986 -82.170704) (xy 109.669629 -82.223002) (xy 109.646987 -82.272582) (xy 109.617518 -82.318436)
			(xy 109.581824 -82.359628) (xy 109.540631 -82.395322) (xy 109.494777 -82.424789) (xy 109.445197 -82.447431)
			(xy 109.392898 -82.462787) (xy 109.338947 -82.470543) (xy 109.311694 -82.471006) (xy 109.283994 -82.470492)
			(xy 109.229174 -82.462505) (xy 109.176087 -82.446669) (xy 109.125849 -82.42332) (xy 109.079518 -82.392947)
			(xy 109.038069 -82.356191) (xy 109.002374 -82.313825) (xy 108.973185 -82.266739) (xy 108.951115 -82.215926)
			(xy 108.943394 -82.18932) (xy 108.9406 -82.178398) (xy 108.926122 -82.161126) (xy 108.845096 -82.123788)
			(xy 108.834746 -82.119633) (xy 108.81247 -82.119764) (xy 108.80217 -82.124042) (xy 108.801916 -82.124042)
			(xy 108.776339 -82.135574) (xy 108.722648 -82.151852) (xy 108.667154 -82.160101) (xy 108.639102 -82.160618)
			(xy 108.61185 -82.160135) (xy 108.5579 -82.152378) (xy 108.505603 -82.137023) (xy 108.456024 -82.114381)
			(xy 108.410172 -82.084914) (xy 108.36898 -82.049221) (xy 108.333287 -82.00803) (xy 108.30382 -81.962178)
			(xy 108.281178 -81.912599) (xy 108.265822 -81.860302) (xy 108.258065 -81.806352) (xy 89.567781 -81.806352)
			(xy 89.568527 -81.811422) (xy 89.569036 -81.839308) (xy 89.568527 -81.867194) (xy 89.560407 -81.92237)
			(xy 89.544339 -81.975777) (xy 89.520667 -82.026274) (xy 89.489894 -82.072787) (xy 89.452677 -82.114324)
			(xy 89.409809 -82.149999) (xy 89.362203 -82.179053) (xy 89.310874 -82.200865) (xy 89.309371 -82.201258)
			(xy 107.056934 -82.201258) (xy 107.061005 -82.145636) (xy 107.073131 -82.091199) (xy 107.093054 -82.039108)
			(xy 107.12035 -81.990473) (xy 107.154436 -81.94633) (xy 107.194585 -81.907621) (xy 107.239943 -81.87517)
			(xy 107.289543 -81.849669) (xy 107.342327 -81.831662) (xy 107.39717 -81.821532) (xy 107.452904 -81.819495)
			(xy 107.508341 -81.825595) (xy 107.562298 -81.839701) (xy 107.613627 -81.861513) (xy 107.661233 -81.890567)
			(xy 107.704101 -81.926242) (xy 107.741318 -81.967779) (xy 107.772091 -82.014292) (xy 107.795763 -82.064789)
			(xy 107.811831 -82.118196) (xy 107.819951 -82.173372) (xy 107.82046 -82.201258) (xy 107.819951 -82.229144)
			(xy 107.811831 -82.28432) (xy 107.795763 -82.337727) (xy 107.772091 -82.388224) (xy 107.741318 -82.434737)
			(xy 107.704101 -82.476274) (xy 107.661233 -82.511949) (xy 107.613627 -82.541003) (xy 107.562298 -82.562815)
			(xy 107.552051 -82.565494) (xy 111.707166 -82.565494) (xy 111.711237 -82.509872) (xy 111.723363 -82.455435)
			(xy 111.743286 -82.403344) (xy 111.770582 -82.354709) (xy 111.804668 -82.310566) (xy 111.844817 -82.271857)
			(xy 111.890175 -82.239406) (xy 111.939775 -82.213905) (xy 111.992559 -82.195898) (xy 112.047402 -82.185768)
			(xy 112.103136 -82.183731) (xy 112.158573 -82.189831) (xy 112.21253 -82.203937) (xy 112.263859 -82.225749)
			(xy 112.311465 -82.254803) (xy 112.354333 -82.290478) (xy 112.39155 -82.332015) (xy 112.422323 -82.378528)
			(xy 112.445995 -82.429025) (xy 112.462063 -82.482432) (xy 112.470183 -82.537608) (xy 112.470692 -82.565494)
			(xy 112.470183 -82.59338) (xy 112.462063 -82.648556) (xy 112.445995 -82.701963) (xy 112.422323 -82.75246)
			(xy 112.39155 -82.798973) (xy 112.354333 -82.84051) (xy 112.311465 -82.876185) (xy 112.263859 -82.905239)
			(xy 112.21253 -82.927051) (xy 112.158573 -82.941157) (xy 112.103136 -82.947257) (xy 112.047402 -82.94522)
			(xy 111.992559 -82.93509) (xy 111.939775 -82.917083) (xy 111.890175 -82.891582) (xy 111.844817 -82.859131)
			(xy 111.804668 -82.820422) (xy 111.770582 -82.776279) (xy 111.743286 -82.727644) (xy 111.723363 -82.675553)
			(xy 111.711237 -82.621116) (xy 111.707166 -82.565494) (xy 107.552051 -82.565494) (xy 107.508341 -82.576921)
			(xy 107.452904 -82.583021) (xy 107.39717 -82.580984) (xy 107.342327 -82.570854) (xy 107.289543 -82.552847)
			(xy 107.239943 -82.527346) (xy 107.194585 -82.494895) (xy 107.154436 -82.456186) (xy 107.12035 -82.412043)
			(xy 107.093054 -82.363408) (xy 107.073131 -82.311317) (xy 107.061005 -82.25688) (xy 107.056934 -82.201258)
			(xy 89.309371 -82.201258) (xy 89.256917 -82.214971) (xy 89.20148 -82.221071) (xy 89.145746 -82.219034)
			(xy 89.090903 -82.208904) (xy 89.038119 -82.190897) (xy 88.988519 -82.165396) (xy 88.943161 -82.132945)
			(xy 88.903012 -82.094236) (xy 88.868926 -82.050093) (xy 88.84163 -82.001458) (xy 88.821707 -81.949367)
			(xy 88.809581 -81.89493) (xy 88.80551 -81.839308) (xy 87.918499 -81.839308) (xy 87.768372 -82.595974)
			(xy 105.060748 -82.595974) (xy 105.064819 -82.540352) (xy 105.076945 -82.485915) (xy 105.096868 -82.433824)
			(xy 105.124164 -82.385189) (xy 105.15825 -82.341046) (xy 105.198399 -82.302337) (xy 105.243757 -82.269886)
			(xy 105.293357 -82.244385) (xy 105.346141 -82.226378) (xy 105.400984 -82.216248) (xy 105.456718 -82.214211)
			(xy 105.512155 -82.220311) (xy 105.566112 -82.234417) (xy 105.617441 -82.256229) (xy 105.665047 -82.285283)
			(xy 105.707915 -82.320958) (xy 105.745132 -82.362495) (xy 105.775905 -82.409008) (xy 105.799577 -82.459505)
			(xy 105.815645 -82.512912) (xy 105.823765 -82.568088) (xy 105.824274 -82.595974) (xy 105.823765 -82.62386)
			(xy 105.815645 -82.679036) (xy 105.799577 -82.732443) (xy 105.775905 -82.78294) (xy 105.745132 -82.829453)
			(xy 105.707915 -82.87099) (xy 105.665047 -82.906665) (xy 105.617441 -82.935719) (xy 105.566112 -82.957531)
			(xy 105.512155 -82.971637) (xy 105.456718 -82.977737) (xy 105.400984 -82.9757) (xy 105.346141 -82.96557)
			(xy 105.293357 -82.947563) (xy 105.243757 -82.922062) (xy 105.198399 -82.889611) (xy 105.15825 -82.850902)
			(xy 105.124164 -82.806759) (xy 105.096868 -82.758124) (xy 105.076945 -82.706033) (xy 105.064819 -82.651596)
			(xy 105.060748 -82.595974) (xy 87.768372 -82.595974) (xy 87.21811 -85.3694) (xy 88.294462 -85.3694)
			(xy 88.298533 -85.313778) (xy 88.310659 -85.259341) (xy 88.330582 -85.20725) (xy 88.357878 -85.158615)
			(xy 88.391964 -85.114472) (xy 88.432113 -85.075763) (xy 88.477471 -85.043312) (xy 88.527071 -85.017811)
			(xy 88.579855 -84.999804) (xy 88.634698 -84.989674) (xy 88.690432 -84.987637) (xy 88.745869 -84.993737)
			(xy 88.799826 -85.007843) (xy 88.851155 -85.029655) (xy 88.898761 -85.058709) (xy 88.941629 -85.094384)
			(xy 88.978846 -85.135921) (xy 89.009619 -85.182434) (xy 89.033291 -85.232931) (xy 89.049359 -85.286338)
			(xy 89.057479 -85.341514) (xy 89.057988 -85.3694) (xy 89.057479 -85.397286) (xy 89.049359 -85.452462)
			(xy 89.033291 -85.505869) (xy 89.009619 -85.556366) (xy 88.978846 -85.602879) (xy 88.941629 -85.644416)
			(xy 88.898761 -85.680091) (xy 88.851155 -85.709145) (xy 88.799826 -85.730957) (xy 88.745869 -85.745063)
			(xy 88.690432 -85.751163) (xy 88.634698 -85.749126) (xy 88.579855 -85.738996) (xy 88.527071 -85.720989)
			(xy 88.477471 -85.695488) (xy 88.432113 -85.663037) (xy 88.391964 -85.624328) (xy 88.357878 -85.580185)
			(xy 88.330582 -85.53155) (xy 88.310659 -85.479459) (xy 88.298533 -85.425022) (xy 88.294462 -85.3694)
			(xy 87.21811 -85.3694) (xy 86.300921 -89.9922) (xy 92.469968 -89.9922) (xy 92.474039 -89.936578)
			(xy 92.486165 -89.882141) (xy 92.506088 -89.83005) (xy 92.533384 -89.781415) (xy 92.56747 -89.737272)
			(xy 92.607619 -89.698563) (xy 92.652977 -89.666112) (xy 92.702577 -89.640611) (xy 92.755361 -89.622604)
			(xy 92.810204 -89.612474) (xy 92.865938 -89.610437) (xy 92.921375 -89.616537) (xy 92.975332 -89.630643)
			(xy 93.026661 -89.652455) (xy 93.074267 -89.681509) (xy 93.117135 -89.717184) (xy 93.154352 -89.758721)
			(xy 93.185125 -89.805234) (xy 93.208797 -89.855731) (xy 93.213174 -89.87028) (xy 93.9579 -89.87028)
			(xy 93.961971 -89.814658) (xy 93.974097 -89.760221) (xy 93.99402 -89.70813) (xy 94.021316 -89.659495)
			(xy 94.055402 -89.615352) (xy 94.095551 -89.576643) (xy 94.140909 -89.544192) (xy 94.190509 -89.518691)
			(xy 94.243293 -89.500684) (xy 94.298136 -89.490554) (xy 94.35387 -89.488517) (xy 94.409307 -89.494617)
			(xy 94.463264 -89.508723) (xy 94.514593 -89.530535) (xy 94.562199 -89.559589) (xy 94.605067 -89.595264)
			(xy 94.642284 -89.636801) (xy 94.673057 -89.683314) (xy 94.696729 -89.733811) (xy 94.712797 -89.787218)
			(xy 94.720917 -89.842394) (xy 94.721426 -89.87028) (xy 94.720917 -89.898166) (xy 94.712797 -89.953342)
			(xy 94.696729 -90.006749) (xy 94.673057 -90.057246) (xy 94.642284 -90.103759) (xy 94.605067 -90.145296)
			(xy 94.562199 -90.180971) (xy 94.514593 -90.210025) (xy 94.463264 -90.231837) (xy 94.409307 -90.245943)
			(xy 94.35387 -90.252043) (xy 94.298136 -90.250006) (xy 94.243293 -90.239876) (xy 94.190509 -90.221869)
			(xy 94.140909 -90.196368) (xy 94.095551 -90.163917) (xy 94.055402 -90.125208) (xy 94.021316 -90.081065)
			(xy 93.99402 -90.03243) (xy 93.974097 -89.980339) (xy 93.961971 -89.925902) (xy 93.9579 -89.87028)
			(xy 93.213174 -89.87028) (xy 93.224865 -89.909138) (xy 93.232985 -89.964314) (xy 93.233494 -89.9922)
			(xy 93.232985 -90.020086) (xy 93.224865 -90.075262) (xy 93.208797 -90.128669) (xy 93.185125 -90.179166)
			(xy 93.154352 -90.225679) (xy 93.117135 -90.267216) (xy 93.074267 -90.302891) (xy 93.026661 -90.331945)
			(xy 92.975332 -90.353757) (xy 92.921375 -90.367863) (xy 92.865938 -90.373963) (xy 92.810204 -90.371926)
			(xy 92.755361 -90.361796) (xy 92.702577 -90.343789) (xy 92.652977 -90.318288) (xy 92.607619 -90.285837)
			(xy 92.56747 -90.247128) (xy 92.533384 -90.202985) (xy 92.506088 -90.15435) (xy 92.486165 -90.102259)
			(xy 92.474039 -90.047822) (xy 92.469968 -89.9922) (xy 86.300921 -89.9922) (xy 85.392098 -94.572836)
			(xy 88.806526 -94.572836) (xy 88.810597 -94.517214) (xy 88.822723 -94.462777) (xy 88.842646 -94.410686)
			(xy 88.869942 -94.362051) (xy 88.904028 -94.317908) (xy 88.944177 -94.279199) (xy 88.989535 -94.246748)
			(xy 89.039135 -94.221247) (xy 89.091919 -94.20324) (xy 89.146762 -94.19311) (xy 89.202496 -94.191073)
			(xy 89.257933 -94.197173) (xy 89.31189 -94.211279) (xy 89.363219 -94.233091) (xy 89.410825 -94.262145)
			(xy 89.453693 -94.29782) (xy 89.49091 -94.339357) (xy 89.521683 -94.38587) (xy 89.545355 -94.436367)
			(xy 89.561423 -94.489774) (xy 89.569543 -94.54495) (xy 89.570052 -94.572836) (xy 89.569543 -94.600722)
			(xy 89.561423 -94.655898) (xy 89.545355 -94.709305) (xy 89.521683 -94.759802) (xy 89.49091 -94.806315)
			(xy 89.453693 -94.847852) (xy 89.410825 -94.883527) (xy 89.363219 -94.912581) (xy 89.31189 -94.934393)
			(xy 89.257933 -94.948499) (xy 89.202496 -94.954599) (xy 89.146762 -94.952562) (xy 89.091919 -94.942432)
			(xy 89.039135 -94.924425) (xy 88.989535 -94.898924) (xy 88.944177 -94.866473) (xy 88.904028 -94.827764)
			(xy 88.869942 -94.783621) (xy 88.842646 -94.734986) (xy 88.822723 -94.682895) (xy 88.810597 -94.628458)
			(xy 88.806526 -94.572836) (xy 85.392098 -94.572836) (xy 85.148237 -95.801942) (xy 88.641426 -95.801942)
			(xy 88.645497 -95.74632) (xy 88.657623 -95.691883) (xy 88.677546 -95.639792) (xy 88.704842 -95.591157)
			(xy 88.738928 -95.547014) (xy 88.779077 -95.508305) (xy 88.824435 -95.475854) (xy 88.874035 -95.450353)
			(xy 88.926819 -95.432346) (xy 88.981662 -95.422216) (xy 89.037396 -95.420179) (xy 89.092833 -95.426279)
			(xy 89.14679 -95.440385) (xy 89.198119 -95.462197) (xy 89.245725 -95.491251) (xy 89.288593 -95.526926)
			(xy 89.32581 -95.568463) (xy 89.356583 -95.614976) (xy 89.380255 -95.665473) (xy 89.396323 -95.71888)
			(xy 89.404443 -95.774056) (xy 89.404952 -95.801942) (xy 90.675206 -95.801942) (xy 90.675799 -95.771138)
			(xy 90.685731 -95.710337) (xy 90.705312 -95.651924) (xy 90.719148 -95.624396) (xy 90.719402 -95.623888)
			(xy 90.721879 -95.618567) (xy 90.724581 -95.607149) (xy 90.724736 -95.601282) (xy 90.724736 -95.378778)
			(xy 90.725184 -95.352689) (xy 90.733357 -95.301155) (xy 90.749497 -95.251536) (xy 90.773206 -95.205056)
			(xy 90.803901 -95.162861) (xy 90.822018 -95.144082) (xy 98.68281 -87.283544) (xy 98.689625 -87.276124)
			(xy 98.697359 -87.25754) (xy 98.697796 -87.247476) (xy 98.697796 -85.395054) (xy 98.698316 -85.36903)
			(xy 98.706484 -85.317626) (xy 98.722579 -85.268129) (xy 98.746208 -85.221753) (xy 98.776791 -85.179636)
			(xy 98.794824 -85.160866) (xy 100.675186 -83.280504) (xy 100.693949 -83.262463) (xy 100.736068 -83.231884)
			(xy 100.782446 -83.208258) (xy 100.831945 -83.192166) (xy 100.88335 -83.184002) (xy 100.909374 -83.183476)
			(xy 102.082854 -83.183476) (xy 102.108878 -83.183997) (xy 102.160281 -83.192165) (xy 102.209779 -83.208261)
			(xy 102.256155 -83.23189) (xy 102.298271 -83.262471) (xy 102.317042 -83.280504) (xy 102.395528 -83.35899)
			(xy 116.623592 -83.35899) (xy 116.623592 -82.49539) (xy 116.624082 -82.465422) (xy 116.631905 -82.406)
			(xy 116.647418 -82.348107) (xy 116.670354 -82.292734) (xy 116.700321 -82.240828) (xy 116.736808 -82.193278)
			(xy 116.779188 -82.150898) (xy 116.826738 -82.114411) (xy 116.878644 -82.084444) (xy 116.934017 -82.061508)
			(xy 116.99191 -82.045995) (xy 117.051332 -82.038172) (xy 117.111268 -82.038172) (xy 117.17069 -82.045995)
			(xy 117.228583 -82.061508) (xy 117.283956 -82.084444) (xy 117.335862 -82.114411) (xy 117.383412 -82.150898)
			(xy 117.425792 -82.193278) (xy 117.462279 -82.240828) (xy 117.492246 -82.292734) (xy 117.515182 -82.348107)
			(xy 117.530695 -82.406) (xy 117.538518 -82.465422) (xy 117.539008 -82.49539) (xy 117.539008 -83.35899)
			(xy 117.538518 -83.388958) (xy 117.530695 -83.44838) (xy 117.515182 -83.506273) (xy 117.492246 -83.561646)
			(xy 117.462279 -83.613552) (xy 117.425792 -83.661102) (xy 117.383412 -83.703482) (xy 117.335862 -83.739969)
			(xy 117.283956 -83.769936) (xy 117.228583 -83.792872) (xy 117.17069 -83.808385) (xy 117.111268 -83.816208)
			(xy 117.051332 -83.816208) (xy 116.99191 -83.808385) (xy 116.934017 -83.792872) (xy 116.878644 -83.769936)
			(xy 116.826738 -83.739969) (xy 116.779188 -83.703482) (xy 116.736808 -83.661102) (xy 116.700321 -83.613552)
			(xy 116.670354 -83.561646) (xy 116.647418 -83.506273) (xy 116.631905 -83.44838) (xy 116.624082 -83.388958)
			(xy 116.623592 -83.35899) (xy 102.395528 -83.35899) (xy 103.053896 -84.017358) (xy 103.071924 -84.036133)
			(xy 103.102505 -84.078249) (xy 103.126133 -84.124624) (xy 103.142228 -84.17412) (xy 103.145763 -84.196368)
			(xy 103.671382 -84.196368) (xy 103.679136 -84.142422) (xy 103.694488 -84.090128) (xy 103.717125 -84.040551)
			(xy 103.746588 -83.994701) (xy 103.782276 -83.95351) (xy 103.823462 -83.917817) (xy 103.869309 -83.888348)
			(xy 103.918883 -83.865705) (xy 103.971175 -83.850346) (xy 104.02512 -83.842586) (xy 104.05237 -83.842098)
			(xy 104.081108 -83.842641) (xy 104.137935 -83.851259) (xy 104.192825 -83.868304) (xy 104.244537 -83.893392)
			(xy 104.291901 -83.925953) (xy 104.313228 -83.945222) (xy 104.320034 -83.951039) (xy 104.336475 -83.958086)
			(xy 104.354334 -83.959104) (xy 104.363012 -83.956906) (xy 104.460548 -83.92668) (xy 104.478836 -83.906614)
			(xy 104.481884 -83.893406) (xy 104.488623 -83.865561) (xy 104.509369 -83.812161) (xy 104.537863 -83.762461)
			(xy 104.573465 -83.717578) (xy 104.615375 -83.678519) (xy 104.662651 -83.646163) (xy 104.714232 -83.621235)
			(xy 104.76896 -83.604297) (xy 104.825604 -83.595727) (xy 104.854248 -83.59521) (xy 104.881501 -83.595633)
			(xy 104.935452 -83.603397) (xy 104.987749 -83.618759) (xy 105.037328 -83.641407) (xy 105.083179 -83.67088)
			(xy 105.124369 -83.706578) (xy 105.16006 -83.747774) (xy 105.189525 -83.79363) (xy 105.212164 -83.843213)
			(xy 105.227517 -83.895512) (xy 105.235271 -83.949465) (xy 105.235756 -83.976718) (xy 105.235297 -84.004687)
			(xy 105.227138 -84.060028) (xy 105.210982 -84.113583) (xy 105.187177 -84.164203) (xy 105.156233 -84.210804)
			(xy 105.118813 -84.252384) (xy 105.09758 -84.270596) (xy 105.089452 -84.277454) (xy 105.0798 -84.296504)
			(xy 105.075228 -84.381848) (xy 105.075269 -84.392474) (xy 105.082871 -84.412288) (xy 105.08996 -84.420202)
			(xy 105.110456 -84.441743) (xy 105.145155 -84.490025) (xy 105.17194 -84.543108) (xy 105.18348 -84.578952)
			(xy 112.247678 -84.578952) (xy 112.251749 -84.52333) (xy 112.263875 -84.468893) (xy 112.283798 -84.416802)
			(xy 112.311094 -84.368167) (xy 112.34518 -84.324024) (xy 112.385329 -84.285315) (xy 112.430687 -84.252864)
			(xy 112.480287 -84.227363) (xy 112.533071 -84.209356) (xy 112.587914 -84.199226) (xy 112.643648 -84.197189)
			(xy 112.699085 -84.203289) (xy 112.753042 -84.217395) (xy 112.804371 -84.239207) (xy 112.851977 -84.268261)
			(xy 112.894845 -84.303936) (xy 112.932062 -84.345473) (xy 112.962835 -84.391986) (xy 112.986507 -84.442483)
			(xy 113.002575 -84.49589) (xy 113.010695 -84.551066) (xy 113.011204 -84.578952) (xy 113.010695 -84.606838)
			(xy 113.002575 -84.662014) (xy 112.986507 -84.715421) (xy 112.962835 -84.765918) (xy 112.932062 -84.812431)
			(xy 112.894845 -84.853968) (xy 112.851977 -84.889643) (xy 112.804371 -84.918697) (xy 112.753042 -84.940509)
			(xy 112.699085 -84.954615) (xy 112.643648 -84.960715) (xy 112.587914 -84.958678) (xy 112.533071 -84.948548)
			(xy 112.480287 -84.930541) (xy 112.430687 -84.90504) (xy 112.385329 -84.872589) (xy 112.34518 -84.83388)
			(xy 112.311094 -84.789737) (xy 112.283798 -84.741102) (xy 112.263875 -84.689011) (xy 112.251749 -84.634574)
			(xy 112.247678 -84.578952) (xy 105.18348 -84.578952) (xy 105.190161 -84.599704) (xy 105.199378 -84.658443)
			(xy 105.199942 -84.688172) (xy 105.199456 -84.715423) (xy 105.1917 -84.769371) (xy 105.176345 -84.821666)
			(xy 105.153703 -84.871243) (xy 105.124237 -84.917093) (xy 105.088546 -84.958284) (xy 105.047355 -84.993975)
			(xy 105.001505 -85.023441) (xy 104.951928 -85.046083) (xy 104.899633 -85.061438) (xy 104.845685 -85.069194)
			(xy 104.791183 -85.069194) (xy 104.737235 -85.061438) (xy 104.68494 -85.046083) (xy 104.635363 -85.023441)
			(xy 104.589513 -84.993975) (xy 104.548322 -84.958284) (xy 104.512631 -84.917093) (xy 104.483165 -84.871243)
			(xy 104.460523 -84.821666) (xy 104.445168 -84.769371) (xy 104.437412 -84.715423) (xy 104.436926 -84.688172)
			(xy 104.437384 -84.660203) (xy 104.445544 -84.604862) (xy 104.461701 -84.551308) (xy 104.485506 -84.500687)
			(xy 104.51645 -84.454087) (xy 104.553869 -84.412507) (xy 104.575102 -84.394294) (xy 104.58323 -84.387436)
			(xy 104.592882 -84.368386) (xy 104.597454 -84.283042) (xy 104.597423 -84.272416) (xy 104.589815 -84.2526)
			(xy 104.582722 -84.244688) (xy 104.567139 -84.22845) (xy 104.539509 -84.192921) (xy 104.527604 -84.173822)
			(xy 104.522338 -84.165688) (xy 104.506932 -84.153951) (xy 104.488273 -84.148761) (xy 104.469019 -84.150857)
			(xy 104.451913 -84.159942) (xy 104.439395 -84.17472) (xy 104.433245 -84.193086) (xy 104.43337 -84.202778)
			(xy 104.433878 -84.223606) (xy 104.433416 -84.250856) (xy 104.425659 -84.304802) (xy 104.410304 -84.357095)
			(xy 104.387663 -84.40667) (xy 104.358198 -84.452519) (xy 104.322507 -84.493707) (xy 104.281319 -84.529398)
			(xy 104.23547 -84.558863) (xy 104.185895 -84.581504) (xy 104.133602 -84.596859) (xy 104.079656 -84.604616)
			(xy 104.025156 -84.604617) (xy 103.97121 -84.596861) (xy 103.918917 -84.581508) (xy 103.869341 -84.558869)
			(xy 103.823491 -84.529405) (xy 103.782301 -84.493716) (xy 103.74661 -84.452528) (xy 103.717143 -84.406681)
			(xy 103.6945 -84.357106) (xy 103.679144 -84.304814) (xy 103.671385 -84.250868) (xy 103.671382 -84.196368)
			(xy 103.145763 -84.196368) (xy 103.150396 -84.225523) (xy 103.150924 -84.251546) (xy 103.150924 -85.54593)
			(xy 103.779826 -85.54593) (xy 103.783897 -85.490308) (xy 103.796023 -85.435871) (xy 103.815946 -85.38378)
			(xy 103.843242 -85.335145) (xy 103.877328 -85.291002) (xy 103.917477 -85.252293) (xy 103.962835 -85.219842)
			(xy 104.012435 -85.194341) (xy 104.065219 -85.176334) (xy 104.120062 -85.166204) (xy 104.175796 -85.164167)
			(xy 104.231233 -85.170267) (xy 104.28519 -85.184373) (xy 104.336519 -85.206185) (xy 104.384125 -85.235239)
			(xy 104.426993 -85.270914) (xy 104.46421 -85.312451) (xy 104.494983 -85.358964) (xy 104.494993 -85.358986)
			(xy 117.385592 -85.358986) (xy 117.385592 -84.495386) (xy 117.386082 -84.465418) (xy 117.393905 -84.405996)
			(xy 117.409418 -84.348103) (xy 117.432354 -84.29273) (xy 117.462321 -84.240824) (xy 117.498808 -84.193274)
			(xy 117.541188 -84.150894) (xy 117.588738 -84.114407) (xy 117.640644 -84.08444) (xy 117.696017 -84.061504)
			(xy 117.75391 -84.045991) (xy 117.813332 -84.038168) (xy 117.873268 -84.038168) (xy 117.93269 -84.045991)
			(xy 117.990583 -84.061504) (xy 118.045956 -84.08444) (xy 118.097862 -84.114407) (xy 118.145412 -84.150894)
			(xy 118.187792 -84.193274) (xy 118.224279 -84.240824) (xy 118.254246 -84.29273) (xy 118.277182 -84.348103)
			(xy 118.292695 -84.405996) (xy 118.300518 -84.465418) (xy 118.301008 -84.495386) (xy 118.301008 -85.358986)
			(xy 118.300518 -85.388954) (xy 118.292695 -85.448376) (xy 118.277182 -85.506269) (xy 118.254246 -85.561642)
			(xy 118.224279 -85.613548) (xy 118.187792 -85.661098) (xy 118.145412 -85.703478) (xy 118.097862 -85.739965)
			(xy 118.045956 -85.769932) (xy 117.990583 -85.792868) (xy 117.93269 -85.808381) (xy 117.873268 -85.816204)
			(xy 117.813332 -85.816204) (xy 117.75391 -85.808381) (xy 117.696017 -85.792868) (xy 117.640644 -85.769932)
			(xy 117.588738 -85.739965) (xy 117.541188 -85.703478) (xy 117.498808 -85.661098) (xy 117.462321 -85.613548)
			(xy 117.432354 -85.561642) (xy 117.409418 -85.506269) (xy 117.393905 -85.448376) (xy 117.386082 -85.388954)
			(xy 117.385592 -85.358986) (xy 104.494993 -85.358986) (xy 104.518655 -85.409461) (xy 104.534723 -85.462868)
			(xy 104.542843 -85.518044) (xy 104.543352 -85.54593) (xy 104.542843 -85.573816) (xy 104.534723 -85.628992)
			(xy 104.518655 -85.682399) (xy 104.494983 -85.732896) (xy 104.46421 -85.779409) (xy 104.440067 -85.806354)
			(xy 112.269957 -85.806354) (xy 112.269957 -85.751846) (xy 112.277715 -85.697892) (xy 112.293073 -85.645592)
			(xy 112.315717 -85.59601) (xy 112.345188 -85.550156) (xy 112.380885 -85.508963) (xy 112.422082 -85.473269)
			(xy 112.467938 -85.443802) (xy 112.517522 -85.421162) (xy 112.569824 -85.405808) (xy 112.623778 -85.398055)
			(xy 112.651032 -85.397594) (xy 112.678396 -85.398103) (xy 112.732566 -85.405903) (xy 112.785065 -85.421366)
			(xy 112.834814 -85.444174) (xy 112.880791 -85.473861) (xy 112.922053 -85.509815) (xy 112.957751 -85.551297)
			(xy 112.97285 -85.574124) (xy 112.980505 -85.585403) (xy 113.000689 -85.603712) (xy 113.025001 -85.616022)
			(xy 113.051705 -85.621454) (xy 113.078894 -85.619621) (xy 113.104626 -85.610653) (xy 113.127066 -85.595191)
			(xy 113.136172 -85.585046) (xy 113.154392 -85.564206) (xy 113.195801 -85.527471) (xy 113.242087 -85.497111)
			(xy 113.292276 -85.473762) (xy 113.345315 -85.457917) (xy 113.400087 -85.449907) (xy 113.427764 -85.44941)
			(xy 113.45502 -85.449834) (xy 113.508977 -85.457588) (xy 113.561282 -85.472941) (xy 113.610869 -85.495583)
			(xy 113.656729 -85.525051) (xy 113.697928 -85.560747) (xy 113.733627 -85.601942) (xy 113.7631 -85.647799)
			(xy 113.785746 -85.697384) (xy 113.801105 -85.749687) (xy 113.808863 -85.803644) (xy 113.808863 -85.858156)
			(xy 113.801105 -85.912113) (xy 113.785746 -85.964416) (xy 113.7631 -86.014001) (xy 113.733627 -86.059858)
			(xy 113.697928 -86.101053) (xy 113.656729 -86.136749) (xy 113.610869 -86.166217) (xy 113.561282 -86.188859)
			(xy 113.508977 -86.204212) (xy 113.45502 -86.211966) (xy 113.427764 -86.212426) (xy 113.400398 -86.211957)
			(xy 113.346225 -86.204155) (xy 113.293723 -86.188688) (xy 113.243973 -86.165873) (xy 113.197996 -86.13618)
			(xy 113.156736 -86.100218) (xy 113.121042 -86.058727) (xy 113.105946 -86.035896) (xy 113.098295 -86.024613)
			(xy 113.078112 -86.006301) (xy 113.053799 -85.993988) (xy 113.027093 -85.988555) (xy 112.999902 -85.99039)
			(xy 112.974168 -85.999361) (xy 112.951729 -86.014827) (xy 112.942624 -86.024974) (xy 112.924388 -86.0458)
			(xy 112.882984 -86.082539) (xy 112.836703 -86.112904) (xy 112.786516 -86.136255) (xy 112.733479 -86.152103)
			(xy 112.678709 -86.160113) (xy 112.651032 -86.16061) (xy 112.623778 -86.160145) (xy 112.569824 -86.152392)
			(xy 112.517522 -86.137038) (xy 112.467938 -86.114398) (xy 112.422081 -86.084931) (xy 112.380885 -86.049237)
			(xy 112.345188 -86.008044) (xy 112.315717 -85.96219) (xy 112.293073 -85.912608) (xy 112.277715 -85.860308)
			(xy 112.269957 -85.806354) (xy 104.440067 -85.806354) (xy 104.426993 -85.820946) (xy 104.384125 -85.856621)
			(xy 104.336519 -85.885675) (xy 104.28519 -85.907487) (xy 104.231233 -85.921593) (xy 104.175796 -85.927693)
			(xy 104.120062 -85.925656) (xy 104.065219 -85.915526) (xy 104.012435 -85.897519) (xy 103.962835 -85.872018)
			(xy 103.917477 -85.839567) (xy 103.877328 -85.800858) (xy 103.843242 -85.756715) (xy 103.815946 -85.70808)
			(xy 103.796023 -85.655989) (xy 103.783897 -85.601552) (xy 103.779826 -85.54593) (xy 103.150924 -85.54593)
			(xy 103.150924 -87.562944) (xy 103.933244 -87.562944) (xy 103.93373 -87.535693) (xy 103.941486 -87.481745)
			(xy 103.956841 -87.42945) (xy 103.979483 -87.379873) (xy 104.008949 -87.334023) (xy 104.04464 -87.292832)
			(xy 104.085831 -87.257141) (xy 104.131681 -87.227675) (xy 104.181258 -87.205033) (xy 104.233553 -87.189678)
			(xy 104.287501 -87.181922) (xy 104.342003 -87.181922) (xy 104.395951 -87.189678) (xy 104.448246 -87.205033)
			(xy 104.497823 -87.227675) (xy 104.543673 -87.257141) (xy 104.584864 -87.292832) (xy 104.620555 -87.334023)
			(xy 104.649817 -87.379556) (xy 112.261902 -87.379556) (xy 112.265973 -87.323934) (xy 112.278099 -87.269497)
			(xy 112.298022 -87.217406) (xy 112.325318 -87.168771) (xy 112.359404 -87.124628) (xy 112.399553 -87.085919)
			(xy 112.444911 -87.053468) (xy 112.494511 -87.027967) (xy 112.547295 -87.00996) (xy 112.602138 -86.99983)
			(xy 112.657872 -86.997793) (xy 112.713309 -87.003893) (xy 112.767266 -87.017999) (xy 112.818595 -87.039811)
			(xy 112.866201 -87.068865) (xy 112.909069 -87.10454) (xy 112.946286 -87.146077) (xy 112.977059 -87.19259)
			(xy 113.000731 -87.243087) (xy 113.016799 -87.296494) (xy 113.024919 -87.35167) (xy 113.025052 -87.358982)
			(xy 116.623592 -87.358982) (xy 116.623592 -86.495382) (xy 116.624082 -86.465414) (xy 116.631905 -86.405992)
			(xy 116.647418 -86.348099) (xy 116.670354 -86.292726) (xy 116.700321 -86.24082) (xy 116.736808 -86.19327)
			(xy 116.779188 -86.15089) (xy 116.826738 -86.114403) (xy 116.878644 -86.084436) (xy 116.934017 -86.0615)
			(xy 116.99191 -86.045987) (xy 117.051332 -86.038164) (xy 117.111268 -86.038164) (xy 117.17069 -86.045987)
			(xy 117.228583 -86.0615) (xy 117.283956 -86.084436) (xy 117.335862 -86.114403) (xy 117.383412 -86.15089)
			(xy 117.425792 -86.19327) (xy 117.462279 -86.24082) (xy 117.492246 -86.292726) (xy 117.515182 -86.348099)
			(xy 117.530695 -86.405992) (xy 117.538518 -86.465414) (xy 117.539008 -86.495382) (xy 117.539008 -87.358982)
			(xy 117.538518 -87.38895) (xy 117.530695 -87.448372) (xy 117.515182 -87.506265) (xy 117.492246 -87.561638)
			(xy 117.462279 -87.613544) (xy 117.425792 -87.661094) (xy 117.383412 -87.703474) (xy 117.335862 -87.739961)
			(xy 117.283956 -87.769928) (xy 117.228583 -87.792864) (xy 117.17069 -87.808377) (xy 117.111268 -87.8162)
			(xy 117.051332 -87.8162) (xy 116.99191 -87.808377) (xy 116.934017 -87.792864) (xy 116.878644 -87.769928)
			(xy 116.826738 -87.739961) (xy 116.779188 -87.703474) (xy 116.736808 -87.661094) (xy 116.700321 -87.613544)
			(xy 116.670354 -87.561638) (xy 116.647418 -87.506265) (xy 116.631905 -87.448372) (xy 116.624082 -87.38895)
			(xy 116.623592 -87.358982) (xy 113.025052 -87.358982) (xy 113.025428 -87.379556) (xy 113.024919 -87.407442)
			(xy 113.016799 -87.462618) (xy 113.000731 -87.516025) (xy 112.977059 -87.566522) (xy 112.946286 -87.613035)
			(xy 112.909069 -87.654572) (xy 112.866201 -87.690247) (xy 112.818595 -87.719301) (xy 112.767266 -87.741113)
			(xy 112.713309 -87.755219) (xy 112.657872 -87.761319) (xy 112.602138 -87.759282) (xy 112.547295 -87.749152)
			(xy 112.494511 -87.731145) (xy 112.444911 -87.705644) (xy 112.399553 -87.673193) (xy 112.359404 -87.634484)
			(xy 112.325318 -87.590341) (xy 112.298022 -87.541706) (xy 112.278099 -87.489615) (xy 112.265973 -87.435178)
			(xy 112.261902 -87.379556) (xy 104.649817 -87.379556) (xy 104.650021 -87.379873) (xy 104.672663 -87.42945)
			(xy 104.688018 -87.481745) (xy 104.695774 -87.535693) (xy 104.69626 -87.562944) (xy 104.695666 -87.593747)
			(xy 104.685735 -87.654549) (xy 104.666154 -87.712962) (xy 104.652318 -87.74049) (xy 104.649608 -87.746016)
			(xy 104.646648 -87.75796) (xy 104.646476 -87.764112) (xy 104.646476 -88.165178) (xy 104.646893 -88.175249)
			(xy 104.654617 -88.193848) (xy 104.661462 -88.201246) (xy 105.819373 -89.358978) (xy 117.385592 -89.358978)
			(xy 117.385592 -88.495378) (xy 117.386082 -88.46541) (xy 117.393905 -88.405988) (xy 117.409418 -88.348095)
			(xy 117.432354 -88.292722) (xy 117.462321 -88.240816) (xy 117.498808 -88.193266) (xy 117.541188 -88.150886)
			(xy 117.588738 -88.114399) (xy 117.640644 -88.084432) (xy 117.696017 -88.061496) (xy 117.75391 -88.045983)
			(xy 117.813332 -88.03816) (xy 117.873268 -88.03816) (xy 117.93269 -88.045983) (xy 117.990583 -88.061496)
			(xy 118.045956 -88.084432) (xy 118.097862 -88.114399) (xy 118.145412 -88.150886) (xy 118.187792 -88.193266)
			(xy 118.224279 -88.240816) (xy 118.254246 -88.292722) (xy 118.277182 -88.348095) (xy 118.288606 -88.39073)
			(xy 119.711722 -88.39073) (xy 119.715793 -88.335108) (xy 119.727919 -88.280671) (xy 119.747842 -88.22858)
			(xy 119.775138 -88.179945) (xy 119.809224 -88.135802) (xy 119.849373 -88.097093) (xy 119.894731 -88.064642)
			(xy 119.944331 -88.039141) (xy 119.997115 -88.021134) (xy 120.051958 -88.011004) (xy 120.107692 -88.008967)
			(xy 120.163129 -88.015067) (xy 120.217086 -88.029173) (xy 120.268415 -88.050985) (xy 120.316021 -88.080039)
			(xy 120.358889 -88.115714) (xy 120.396106 -88.157251) (xy 120.426879 -88.203764) (xy 120.450551 -88.254261)
			(xy 120.466619 -88.307668) (xy 120.474739 -88.362844) (xy 120.475248 -88.39073) (xy 120.474739 -88.418616)
			(xy 120.466619 -88.473792) (xy 120.450551 -88.527199) (xy 120.426879 -88.577696) (xy 120.396106 -88.624209)
			(xy 120.358889 -88.665746) (xy 120.316021 -88.701421) (xy 120.268415 -88.730475) (xy 120.217086 -88.752287)
			(xy 120.163129 -88.766393) (xy 120.107692 -88.772493) (xy 120.051958 -88.770456) (xy 119.997115 -88.760326)
			(xy 119.944331 -88.742319) (xy 119.894731 -88.716818) (xy 119.849373 -88.684367) (xy 119.809224 -88.645658)
			(xy 119.775138 -88.601515) (xy 119.747842 -88.55288) (xy 119.727919 -88.500789) (xy 119.715793 -88.446352)
			(xy 119.711722 -88.39073) (xy 118.288606 -88.39073) (xy 118.292695 -88.405988) (xy 118.300518 -88.46541)
			(xy 118.301008 -88.495378) (xy 118.301008 -89.358978) (xy 118.300518 -89.388946) (xy 118.292695 -89.448368)
			(xy 118.277182 -89.506261) (xy 118.265804 -89.53373) (xy 119.660414 -89.53373) (xy 119.664485 -89.478108)
			(xy 119.676611 -89.423671) (xy 119.696534 -89.37158) (xy 119.72383 -89.322945) (xy 119.757916 -89.278802)
			(xy 119.798065 -89.240093) (xy 119.843423 -89.207642) (xy 119.893023 -89.182141) (xy 119.945807 -89.164134)
			(xy 120.00065 -89.154004) (xy 120.056384 -89.151967) (xy 120.111821 -89.158067) (xy 120.165778 -89.172173)
			(xy 120.17621 -89.176606) (xy 124.546104 -89.176606) (xy 124.550175 -89.120984) (xy 124.562301 -89.066547)
			(xy 124.582224 -89.014456) (xy 124.60952 -88.965821) (xy 124.643606 -88.921678) (xy 124.683755 -88.882969)
			(xy 124.729113 -88.850518) (xy 124.778713 -88.825017) (xy 124.831497 -88.80701) (xy 124.88634 -88.79688)
			(xy 124.942074 -88.794843) (xy 124.997511 -88.800943) (xy 125.051468 -88.815049) (xy 125.102797 -88.836861)
			(xy 125.150403 -88.865915) (xy 125.193271 -88.90159) (xy 125.230488 -88.943127) (xy 125.261261 -88.98964)
			(xy 125.284933 -89.040137) (xy 125.301001 -89.093544) (xy 125.309121 -89.14872) (xy 125.30963 -89.176606)
			(xy 125.309121 -89.204492) (xy 125.301001 -89.259668) (xy 125.284933 -89.313075) (xy 125.261261 -89.363572)
			(xy 125.230488 -89.410085) (xy 125.193271 -89.451622) (xy 125.150403 -89.487297) (xy 125.102797 -89.516351)
			(xy 125.051468 -89.538163) (xy 124.997511 -89.552269) (xy 124.942074 -89.558369) (xy 124.88634 -89.556332)
			(xy 124.831497 -89.546202) (xy 124.778713 -89.528195) (xy 124.729113 -89.502694) (xy 124.683755 -89.470243)
			(xy 124.643606 -89.431534) (xy 124.60952 -89.387391) (xy 124.582224 -89.338756) (xy 124.562301 -89.286665)
			(xy 124.550175 -89.232228) (xy 124.546104 -89.176606) (xy 120.17621 -89.176606) (xy 120.217107 -89.193985)
			(xy 120.264713 -89.223039) (xy 120.307581 -89.258714) (xy 120.344798 -89.300251) (xy 120.375571 -89.346764)
			(xy 120.399243 -89.397261) (xy 120.415311 -89.450668) (xy 120.423431 -89.505844) (xy 120.42394 -89.53373)
			(xy 120.423431 -89.561616) (xy 120.415311 -89.616792) (xy 120.399243 -89.670199) (xy 120.375571 -89.720696)
			(xy 120.344798 -89.767209) (xy 120.307581 -89.808746) (xy 120.264713 -89.844421) (xy 120.217107 -89.873475)
			(xy 120.165778 -89.895287) (xy 120.111821 -89.909393) (xy 120.056384 -89.915493) (xy 120.00065 -89.913456)
			(xy 119.945807 -89.903326) (xy 119.893023 -89.885319) (xy 119.843423 -89.859818) (xy 119.798065 -89.827367)
			(xy 119.757916 -89.788658) (xy 119.72383 -89.744515) (xy 119.696534 -89.69588) (xy 119.676611 -89.643789)
			(xy 119.664485 -89.589352) (xy 119.660414 -89.53373) (xy 118.265804 -89.53373) (xy 118.254246 -89.561634)
			(xy 118.224279 -89.61354) (xy 118.187792 -89.66109) (xy 118.145412 -89.70347) (xy 118.097862 -89.739957)
			(xy 118.045956 -89.769924) (xy 117.990583 -89.79286) (xy 117.93269 -89.808373) (xy 117.873268 -89.816196)
			(xy 117.813332 -89.816196) (xy 117.75391 -89.808373) (xy 117.696017 -89.79286) (xy 117.640644 -89.769924)
			(xy 117.588738 -89.739957) (xy 117.541188 -89.70347) (xy 117.498808 -89.66109) (xy 117.462321 -89.61354)
			(xy 117.432354 -89.561634) (xy 117.409418 -89.506261) (xy 117.393905 -89.448368) (xy 117.386082 -89.388946)
			(xy 117.385592 -89.358978) (xy 105.819373 -89.358978) (xy 106.303572 -89.843102) (xy 106.310987 -89.849923)
			(xy 106.329575 -89.857654) (xy 106.33964 -89.858088) (xy 108.044488 -89.858088) (xy 108.055664 -89.855548)
			(xy 108.060998 -89.852754) (xy 108.062014 -89.852246) (xy 108.089486 -89.838517) (xy 108.147735 -89.819065)
			(xy 108.208347 -89.809192) (xy 108.239052 -89.808558) (xy 108.259989 -89.808846) (xy 108.301612 -89.813425)
			(xy 108.32211 -89.817702) (xy 108.33227 -89.819988) (xy 108.352082 -89.816178) (xy 108.430568 -89.764616)
			(xy 108.441998 -89.747598) (xy 108.443776 -89.737438) (xy 108.449137 -89.711594) (xy 108.466074 -89.661602)
			(xy 108.489739 -89.614422) (xy 108.51968 -89.570954) (xy 108.555326 -89.532027) (xy 108.595998 -89.498385)
			(xy 108.640917 -89.470669) (xy 108.689228 -89.449408) (xy 108.740009 -89.435009) (xy 108.792289 -89.427745)
			(xy 108.81868 -89.427304) (xy 108.845935 -89.427742) (xy 108.89989 -89.435496) (xy 108.952191 -89.450851)
			(xy 109.001776 -89.473493) (xy 109.047633 -89.502962) (xy 109.088829 -89.538657) (xy 109.124526 -89.579851)
			(xy 109.153997 -89.625707) (xy 109.176642 -89.67529) (xy 109.191999 -89.727591) (xy 109.199757 -89.781545)
			(xy 109.199757 -89.836055) (xy 109.193119 -89.882218) (xy 110.333026 -89.882218) (xy 110.337097 -89.826596)
			(xy 110.349223 -89.772159) (xy 110.369146 -89.720068) (xy 110.396442 -89.671433) (xy 110.430528 -89.62729)
			(xy 110.470677 -89.588581) (xy 110.516035 -89.55613) (xy 110.565635 -89.530629) (xy 110.618419 -89.512622)
			(xy 110.673262 -89.502492) (xy 110.728996 -89.500455) (xy 110.784433 -89.506555) (xy 110.83839 -89.520661)
			(xy 110.889719 -89.542473) (xy 110.937325 -89.571527) (xy 110.980193 -89.607202) (xy 111.01741 -89.648739)
			(xy 111.048183 -89.695252) (xy 111.071855 -89.745749) (xy 111.087923 -89.799156) (xy 111.096043 -89.854332)
			(xy 111.096552 -89.882218) (xy 111.096043 -89.910104) (xy 111.087923 -89.96528) (xy 111.071855 -90.018687)
			(xy 111.048183 -90.069184) (xy 111.01741 -90.115697) (xy 110.980193 -90.157234) (xy 110.937325 -90.192909)
			(xy 110.889719 -90.221963) (xy 110.83839 -90.243775) (xy 110.784433 -90.257881) (xy 110.728996 -90.263981)
			(xy 110.673262 -90.261944) (xy 110.618419 -90.251814) (xy 110.565635 -90.233807) (xy 110.516035 -90.208306)
			(xy 110.470677 -90.175855) (xy 110.430528 -90.137146) (xy 110.396442 -90.093003) (xy 110.369146 -90.044368)
			(xy 110.349223 -89.992277) (xy 110.337097 -89.93784) (xy 110.333026 -89.882218) (xy 109.193119 -89.882218)
			(xy 109.191999 -89.890009) (xy 109.176642 -89.94231) (xy 109.153997 -89.991893) (xy 109.124526 -90.037749)
			(xy 109.088829 -90.078943) (xy 109.047633 -90.114638) (xy 109.001776 -90.144107) (xy 108.952191 -90.166749)
			(xy 108.89989 -90.182104) (xy 108.845935 -90.189858) (xy 108.81868 -90.19032) (xy 108.797742 -90.190043)
			(xy 108.756119 -90.185456) (xy 108.735622 -90.181176) (xy 108.725462 -90.17889) (xy 108.70565 -90.1827)
			(xy 108.627164 -90.234262) (xy 108.615734 -90.25128) (xy 108.613956 -90.26144) (xy 108.613318 -90.264488)
			(xy 111.514634 -90.264488) (xy 111.518705 -90.208866) (xy 111.530831 -90.154429) (xy 111.550754 -90.102338)
			(xy 111.57805 -90.053703) (xy 111.612136 -90.00956) (xy 111.652285 -89.970851) (xy 111.697643 -89.9384)
			(xy 111.747243 -89.912899) (xy 111.800027 -89.894892) (xy 111.85487 -89.884762) (xy 111.910604 -89.882725)
			(xy 111.966041 -89.888825) (xy 112.019998 -89.902931) (xy 112.071327 -89.924743) (xy 112.118933 -89.953797)
			(xy 112.161801 -89.989472) (xy 112.199018 -90.031009) (xy 112.229791 -90.077522) (xy 112.253463 -90.128019)
			(xy 112.269531 -90.181426) (xy 112.277651 -90.236602) (xy 112.27816 -90.264488) (xy 112.277651 -90.292374)
			(xy 112.269531 -90.34755) (xy 112.253463 -90.400957) (xy 112.229791 -90.451454) (xy 112.199018 -90.497967)
			(xy 112.161801 -90.539504) (xy 112.118933 -90.575179) (xy 112.071327 -90.604233) (xy 112.019998 -90.626045)
			(xy 111.966041 -90.640151) (xy 111.910604 -90.646251) (xy 111.85487 -90.644214) (xy 111.800027 -90.634084)
			(xy 111.747243 -90.616077) (xy 111.697643 -90.590576) (xy 111.652285 -90.558125) (xy 111.612136 -90.519416)
			(xy 111.57805 -90.475273) (xy 111.550754 -90.426638) (xy 111.530831 -90.374547) (xy 111.518705 -90.32011)
			(xy 111.514634 -90.264488) (xy 108.613318 -90.264488) (xy 108.608549 -90.287274) (xy 108.591617 -90.337263)
			(xy 108.567957 -90.384442) (xy 108.538021 -90.427909) (xy 108.50238 -90.466836) (xy 108.461714 -90.50048)
			(xy 108.416799 -90.528197) (xy 108.368493 -90.549461) (xy 108.317718 -90.563863) (xy 108.265441 -90.571131)
			(xy 108.239052 -90.571574) (xy 108.208249 -90.57098) (xy 108.147447 -90.561048) (xy 108.089034 -90.541468)
			(xy 108.061506 -90.527632) (xy 108.060998 -90.527378) (xy 108.055671 -90.524916) (xy 108.044257 -90.522213)
			(xy 108.038392 -90.522044) (xy 106.181144 -90.522044) (xy 106.171492 -90.52179) (xy 106.167238 -90.521739)
			(xy 106.15881 -90.522881) (xy 106.154728 -90.524076) (xy 106.145748 -90.52719) (xy 106.13084 -90.538961)
			(xy 106.121243 -90.555353) (xy 106.118276 -90.574115) (xy 106.122346 -90.592669) (xy 106.127296 -90.600784)
			(xy 106.142423 -90.624369) (xy 106.166323 -90.675047) (xy 106.175755 -90.706194) (xy 124.7935 -90.706194)
			(xy 124.797571 -90.650572) (xy 124.809697 -90.596135) (xy 124.82962 -90.544044) (xy 124.856916 -90.495409)
			(xy 124.891002 -90.451266) (xy 124.931151 -90.412557) (xy 124.976509 -90.380106) (xy 125.026109 -90.354605)
			(xy 125.078893 -90.336598) (xy 125.133736 -90.326468) (xy 125.18947 -90.324431) (xy 125.244907 -90.330531)
			(xy 125.298864 -90.344637) (xy 125.350193 -90.366449) (xy 125.397799 -90.395503) (xy 125.440667 -90.431178)
			(xy 125.477884 -90.472715) (xy 125.508657 -90.519228) (xy 125.532329 -90.569725) (xy 125.548397 -90.623132)
			(xy 125.556517 -90.678308) (xy 125.557026 -90.706194) (xy 125.556517 -90.73408) (xy 125.548397 -90.789256)
			(xy 125.532329 -90.842663) (xy 125.508657 -90.89316) (xy 125.477884 -90.939673) (xy 125.440667 -90.98121)
			(xy 125.397799 -91.016885) (xy 125.350193 -91.045939) (xy 125.298864 -91.067751) (xy 125.244907 -91.081857)
			(xy 125.18947 -91.087957) (xy 125.133736 -91.08592) (xy 125.078893 -91.07579) (xy 125.026109 -91.057783)
			(xy 124.976509 -91.032282) (xy 124.931151 -90.999831) (xy 124.891002 -90.961122) (xy 124.856916 -90.916979)
			(xy 124.82962 -90.868344) (xy 124.809697 -90.816253) (xy 124.797571 -90.761816) (xy 124.7935 -90.706194)
			(xy 106.175755 -90.706194) (xy 106.182562 -90.728673) (xy 106.190791 -90.784097) (xy 106.191304 -90.812112)
			(xy 106.190818 -90.839363) (xy 106.183062 -90.893311) (xy 106.167707 -90.945606) (xy 106.145065 -90.995183)
			(xy 106.115599 -91.041033) (xy 106.079908 -91.082224) (xy 106.038717 -91.117915) (xy 105.992867 -91.147381)
			(xy 105.94329 -91.170023) (xy 105.890995 -91.185378) (xy 105.837047 -91.193134) (xy 105.782545 -91.193134)
			(xy 105.728597 -91.185378) (xy 105.676302 -91.170023) (xy 105.626725 -91.147381) (xy 105.580875 -91.117915)
			(xy 105.539684 -91.082224) (xy 105.503993 -91.041033) (xy 105.474527 -90.995183) (xy 105.451885 -90.945606)
			(xy 105.43653 -90.893311) (xy 105.428774 -90.839363) (xy 105.428288 -90.812112) (xy 105.428882 -90.782938)
			(xy 105.437786 -90.725272) (xy 105.45536 -90.669632) (xy 105.481192 -90.617313) (xy 105.514684 -90.569533)
			(xy 105.555054 -90.527403) (xy 105.601363 -90.491905) (xy 105.652533 -90.463865) (xy 105.707373 -90.443935)
			(xy 105.735882 -90.437716) (xy 105.749852 -90.434922) (xy 105.77068 -90.41638) (xy 105.800652 -90.317066)
			(xy 105.802982 -90.308153) (xy 105.801829 -90.289782) (xy 105.794211 -90.273026) (xy 105.787952 -90.266266)
			(xy 104.080056 -88.55837) (xy 104.062033 -88.539591) (xy 104.031454 -88.497475) (xy 104.007825 -88.451101)
			(xy 103.991729 -88.401606) (xy 103.983558 -88.350205) (xy 103.983028 -88.324182) (xy 103.983028 -87.764112)
			(xy 103.982835 -87.757962) (xy 103.979882 -87.746021) (xy 103.977186 -87.74049) (xy 103.963341 -87.712967)
			(xy 103.94378 -87.654548) (xy 103.933851 -87.593747) (xy 103.933244 -87.562944) (xy 103.150924 -87.562944)
			(xy 103.150924 -87.852504) (xy 103.151341 -87.862574) (xy 103.159067 -87.881172) (xy 103.16591 -87.888572)
			(xy 105.114344 -89.836752) (xy 105.132377 -89.855522) (xy 105.162955 -89.89764) (xy 105.186582 -89.944017)
			(xy 105.202676 -89.993513) (xy 105.210844 -90.044916) (xy 105.211372 -90.07094) (xy 105.211372 -91.199462)
			(xy 106.656884 -91.199462) (xy 106.660955 -91.14384) (xy 106.673081 -91.089403) (xy 106.693004 -91.037312)
			(xy 106.7203 -90.988677) (xy 106.754386 -90.944534) (xy 106.794535 -90.905825) (xy 106.839893 -90.873374)
			(xy 106.889493 -90.847873) (xy 106.942277 -90.829866) (xy 106.99712 -90.819736) (xy 107.052854 -90.817699)
			(xy 107.108291 -90.823799) (xy 107.162248 -90.837905) (xy 107.213577 -90.859717) (xy 107.261183 -90.888771)
			(xy 107.304051 -90.924446) (xy 107.341268 -90.965983) (xy 107.372041 -91.012496) (xy 107.395713 -91.062993)
			(xy 107.411781 -91.1164) (xy 107.419901 -91.171576) (xy 107.420285 -91.192604) (xy 108.032802 -91.192604)
			(xy 108.036873 -91.136982) (xy 108.048999 -91.082545) (xy 108.068922 -91.030454) (xy 108.096218 -90.981819)
			(xy 108.130304 -90.937676) (xy 108.170453 -90.898967) (xy 108.215811 -90.866516) (xy 108.265411 -90.841015)
			(xy 108.318195 -90.823008) (xy 108.373038 -90.812878) (xy 108.428772 -90.810841) (xy 108.484209 -90.816941)
			(xy 108.538166 -90.831047) (xy 108.589495 -90.852859) (xy 108.637101 -90.881913) (xy 108.679969 -90.917588)
			(xy 108.717186 -90.959125) (xy 108.747959 -91.005638) (xy 108.771631 -91.056135) (xy 108.787699 -91.109542)
			(xy 108.795819 -91.164718) (xy 108.796328 -91.192604) (xy 108.795819 -91.22049) (xy 108.787699 -91.275666)
			(xy 108.771631 -91.329073) (xy 108.747959 -91.37957) (xy 108.717389 -91.425776) (xy 118.321072 -91.425776)
			(xy 118.325143 -91.370154) (xy 118.337269 -91.315717) (xy 118.357192 -91.263626) (xy 118.384488 -91.214991)
			(xy 118.418574 -91.170848) (xy 118.458723 -91.132139) (xy 118.504081 -91.099688) (xy 118.553681 -91.074187)
			(xy 118.606465 -91.05618) (xy 118.661308 -91.04605) (xy 118.717042 -91.044013) (xy 118.772479 -91.050113)
			(xy 118.826436 -91.064219) (xy 118.877765 -91.086031) (xy 118.925371 -91.115085) (xy 118.968239 -91.15076)
			(xy 119.005456 -91.192297) (xy 119.036229 -91.23881) (xy 119.059901 -91.289307) (xy 119.075969 -91.342714)
			(xy 119.084089 -91.39789) (xy 119.084598 -91.425776) (xy 119.084089 -91.453662) (xy 119.082773 -91.462606)
			(xy 119.737884 -91.462606) (xy 119.741955 -91.406984) (xy 119.754081 -91.352547) (xy 119.774004 -91.300456)
			(xy 119.8013 -91.251821) (xy 119.835386 -91.207678) (xy 119.875535 -91.168969) (xy 119.920893 -91.136518)
			(xy 119.970493 -91.111017) (xy 120.023277 -91.09301) (xy 120.07812 -91.08288) (xy 120.133854 -91.080843)
			(xy 120.189291 -91.086943) (xy 120.243248 -91.101049) (xy 120.294577 -91.122861) (xy 120.342183 -91.151915)
			(xy 120.385051 -91.18759) (xy 120.422268 -91.229127) (xy 120.453041 -91.27564) (xy 120.476713 -91.326137)
			(xy 120.492781 -91.379544) (xy 120.500901 -91.43472) (xy 120.50141 -91.462606) (xy 120.500901 -91.490492)
			(xy 120.492781 -91.545668) (xy 120.476713 -91.599075) (xy 120.453041 -91.649572) (xy 120.422268 -91.696085)
			(xy 120.385051 -91.737622) (xy 120.342183 -91.773297) (xy 120.294577 -91.802351) (xy 120.243248 -91.824163)
			(xy 120.189291 -91.838269) (xy 120.133854 -91.844369) (xy 120.07812 -91.842332) (xy 120.023277 -91.832202)
			(xy 119.970493 -91.814195) (xy 119.920893 -91.788694) (xy 119.875535 -91.756243) (xy 119.835386 -91.717534)
			(xy 119.8013 -91.673391) (xy 119.774004 -91.624756) (xy 119.754081 -91.572665) (xy 119.741955 -91.518228)
			(xy 119.737884 -91.462606) (xy 119.082773 -91.462606) (xy 119.075969 -91.508838) (xy 119.059901 -91.562245)
			(xy 119.036229 -91.612742) (xy 119.005456 -91.659255) (xy 118.968239 -91.700792) (xy 118.925371 -91.736467)
			(xy 118.877765 -91.765521) (xy 118.826436 -91.787333) (xy 118.772479 -91.801439) (xy 118.717042 -91.807539)
			(xy 118.661308 -91.805502) (xy 118.606465 -91.795372) (xy 118.553681 -91.777365) (xy 118.504081 -91.751864)
			(xy 118.458723 -91.719413) (xy 118.418574 -91.680704) (xy 118.384488 -91.636561) (xy 118.357192 -91.587926)
			(xy 118.337269 -91.535835) (xy 118.325143 -91.481398) (xy 118.321072 -91.425776) (xy 108.717389 -91.425776)
			(xy 108.717186 -91.426083) (xy 108.679969 -91.46762) (xy 108.637101 -91.503295) (xy 108.589495 -91.532349)
			(xy 108.538166 -91.554161) (xy 108.484209 -91.568267) (xy 108.428772 -91.574367) (xy 108.373038 -91.57233)
			(xy 108.318195 -91.5622) (xy 108.265411 -91.544193) (xy 108.215811 -91.518692) (xy 108.170453 -91.486241)
			(xy 108.130304 -91.447532) (xy 108.096218 -91.403389) (xy 108.068922 -91.354754) (xy 108.048999 -91.302663)
			(xy 108.036873 -91.248226) (xy 108.032802 -91.192604) (xy 107.420285 -91.192604) (xy 107.42041 -91.199462)
			(xy 107.419901 -91.227348) (xy 107.411781 -91.282524) (xy 107.395713 -91.335931) (xy 107.372041 -91.386428)
			(xy 107.341268 -91.432941) (xy 107.304051 -91.474478) (xy 107.261183 -91.510153) (xy 107.213577 -91.539207)
			(xy 107.162248 -91.561019) (xy 107.108291 -91.575125) (xy 107.052854 -91.581225) (xy 106.99712 -91.579188)
			(xy 106.942277 -91.569058) (xy 106.889493 -91.551051) (xy 106.839893 -91.52555) (xy 106.794535 -91.493099)
			(xy 106.754386 -91.45439) (xy 106.7203 -91.410247) (xy 106.693004 -91.361612) (xy 106.673081 -91.309521)
			(xy 106.660955 -91.255084) (xy 106.656884 -91.199462) (xy 105.211372 -91.199462) (xy 105.211372 -91.829128)
			(xy 105.211764 -91.839201) (xy 105.219506 -91.8578) (xy 105.226358 -91.865196) (xy 105.541064 -92.179902)
			(xy 125.607824 -92.179902) (xy 125.611895 -92.12428) (xy 125.624021 -92.069843) (xy 125.643944 -92.017752)
			(xy 125.67124 -91.969117) (xy 125.705326 -91.924974) (xy 125.745475 -91.886265) (xy 125.790833 -91.853814)
			(xy 125.840433 -91.828313) (xy 125.893217 -91.810306) (xy 125.94806 -91.800176) (xy 126.003794 -91.798139)
			(xy 126.059231 -91.804239) (xy 126.113188 -91.818345) (xy 126.164517 -91.840157) (xy 126.212123 -91.869211)
			(xy 126.254991 -91.904886) (xy 126.292208 -91.946423) (xy 126.322981 -91.992936) (xy 126.346653 -92.043433)
			(xy 126.362721 -92.09684) (xy 126.370841 -92.152016) (xy 126.37135 -92.179902) (xy 126.370841 -92.207788)
			(xy 126.362721 -92.262964) (xy 126.346653 -92.316371) (xy 126.322981 -92.366868) (xy 126.292208 -92.413381)
			(xy 126.254991 -92.454918) (xy 126.212123 -92.490593) (xy 126.164517 -92.519647) (xy 126.113188 -92.541459)
			(xy 126.059231 -92.555565) (xy 126.003794 -92.561665) (xy 125.94806 -92.559628) (xy 125.893217 -92.549498)
			(xy 125.840433 -92.531491) (xy 125.790833 -92.50599) (xy 125.745475 -92.473539) (xy 125.705326 -92.43483)
			(xy 125.67124 -92.390687) (xy 125.643944 -92.342052) (xy 125.624021 -92.289961) (xy 125.611895 -92.235524)
			(xy 125.607824 -92.179902) (xy 105.541064 -92.179902) (xy 105.953052 -92.59189) (xy 105.960476 -92.5987)
			(xy 105.979057 -92.606438) (xy 105.98912 -92.606876) (xy 111.163862 -92.606876) (xy 111.189886 -92.607392)
			(xy 111.24129 -92.615561) (xy 111.290787 -92.631658) (xy 111.337163 -92.655288) (xy 111.379279 -92.685871)
			(xy 111.39805 -92.703904) (xy 112.528096 -93.83395) (xy 112.54612 -93.852729) (xy 112.576701 -93.894843)
			(xy 112.60033 -93.941218) (xy 112.616427 -93.990713) (xy 112.624596 -94.042115) (xy 112.625124 -94.068138)
			(xy 112.625124 -94.690184) (xy 112.625551 -94.700253) (xy 112.63327 -94.718851) (xy 112.64011 -94.726252)
			(xy 113.966752 -96.05264) (xy 113.971138 -96.056765) (xy 113.981408 -96.063044) (xy 113.987072 -96.065086)
			(xy 113.98758 -96.065086) (xy 114.0126 -96.073398) (xy 114.060284 -96.095887) (xy 114.10442 -96.124724)
			(xy 114.144168 -96.159361) (xy 114.17877 -96.199137) (xy 114.20757 -96.243298) (xy 114.230019 -96.291001)
			(xy 114.238278 -96.316038) (xy 114.238278 -96.316292) (xy 114.240266 -96.321982) (xy 114.246556 -96.332259)
			(xy 114.250724 -96.336612) (xy 114.400584 -96.486472) (xy 114.430556 -96.492568) (xy 114.44478 -96.486472)
			(xy 114.453913 -96.482265) (xy 114.468149 -96.468086) (xy 114.475854 -96.449529) (xy 114.476276 -96.439482)
			(xy 114.476276 -95.31096) (xy 114.475878 -95.300888) (xy 114.468139 -95.28229) (xy 114.46129 -95.274892)
			(xy 114.102134 -94.91599) (xy 114.079236 -94.892425) (xy 114.038272 -94.841049) (xy 114.003317 -94.785409)
			(xy 113.974811 -94.726205) (xy 113.953113 -94.664182) (xy 113.938496 -94.60012) (xy 113.931143 -94.534824)
			(xy 113.930684 -94.50197) (xy 113.930684 -94.501716) (xy 113.931204 -94.466317) (xy 113.939736 -94.396036)
			(xy 113.956678 -94.327295) (xy 113.981782 -94.261098) (xy 114.014682 -94.19841) (xy 114.054899 -94.140144)
			(xy 114.101846 -94.087151) (xy 114.154838 -94.040204) (xy 114.213103 -93.999986) (xy 114.275791 -93.967085)
			(xy 114.341988 -93.94198) (xy 114.410728 -93.925038) (xy 114.481009 -93.916505) (xy 114.516408 -93.915992)
			(xy 114.516662 -93.915992) (xy 114.549516 -93.916432) (xy 114.61481 -93.923801) (xy 114.678869 -93.938429)
			(xy 114.74089 -93.960132) (xy 114.800093 -93.988638) (xy 114.855735 -94.023588) (xy 114.907118 -94.064543)
			(xy 114.930682 -94.087442) (xy 115.133374 -94.290134) (xy 115.163346 -94.295976) (xy 115.17757 -94.290134)
			(xy 115.186619 -94.28585) (xy 115.200702 -94.271642) (xy 115.208325 -94.253146) (xy 115.208812 -94.243144)
			(xy 115.208812 -93.396308) (xy 115.209308 -93.362208) (xy 115.217225 -93.294468) (xy 115.232954 -93.228105)
			(xy 115.25628 -93.164017) (xy 115.286888 -93.103071) (xy 115.324365 -93.04609) (xy 115.368204 -92.993845)
			(xy 115.417811 -92.947042) (xy 115.472517 -92.906316) (xy 115.531581 -92.872215) (xy 115.594204 -92.845202)
			(xy 115.65954 -92.825642) (xy 115.726704 -92.813799) (xy 115.79479 -92.809834) (xy 115.862876 -92.813799)
			(xy 115.93004 -92.825642) (xy 115.995376 -92.845202) (xy 116.057999 -92.872215) (xy 116.117063 -92.906316)
			(xy 116.171769 -92.947042) (xy 116.221376 -92.993845) (xy 116.265215 -93.04609) (xy 116.302692 -93.103071)
			(xy 116.329031 -93.155516) (xy 118.878602 -93.155516) (xy 118.882673 -93.099894) (xy 118.894799 -93.045457)
			(xy 118.914722 -92.993366) (xy 118.942018 -92.944731) (xy 118.976104 -92.900588) (xy 119.016253 -92.861879)
			(xy 119.061611 -92.829428) (xy 119.111211 -92.803927) (xy 119.163995 -92.78592) (xy 119.218838 -92.77579)
			(xy 119.274572 -92.773753) (xy 119.330009 -92.779853) (xy 119.383966 -92.793959) (xy 119.435295 -92.815771)
			(xy 119.438033 -92.817442) (xy 124.345444 -92.817442) (xy 124.349515 -92.76182) (xy 124.361641 -92.707383)
			(xy 124.381564 -92.655292) (xy 124.40886 -92.606657) (xy 124.442946 -92.562514) (xy 124.483095 -92.523805)
			(xy 124.528453 -92.491354) (xy 124.578053 -92.465853) (xy 124.630837 -92.447846) (xy 124.68568 -92.437716)
			(xy 124.741414 -92.435679) (xy 124.796851 -92.441779) (xy 124.850808 -92.455885) (xy 124.902137 -92.477697)
			(xy 124.949743 -92.506751) (xy 124.992611 -92.542426) (xy 125.029828 -92.583963) (xy 125.060601 -92.630476)
			(xy 125.084273 -92.680973) (xy 125.100341 -92.73438) (xy 125.108461 -92.789556) (xy 125.10897 -92.817442)
			(xy 125.108461 -92.845328) (xy 125.100341 -92.900504) (xy 125.084273 -92.953911) (xy 125.060601 -93.004408)
			(xy 125.029828 -93.050921) (xy 124.992611 -93.092458) (xy 124.949743 -93.128133) (xy 124.902137 -93.157187)
			(xy 124.850808 -93.178999) (xy 124.796851 -93.193105) (xy 124.741414 -93.199205) (xy 124.68568 -93.197168)
			(xy 124.630837 -93.187038) (xy 124.578053 -93.169031) (xy 124.528453 -93.14353) (xy 124.483095 -93.111079)
			(xy 124.442946 -93.07237) (xy 124.40886 -93.028227) (xy 124.381564 -92.979592) (xy 124.361641 -92.927501)
			(xy 124.349515 -92.873064) (xy 124.345444 -92.817442) (xy 119.438033 -92.817442) (xy 119.482901 -92.844825)
			(xy 119.525769 -92.8805) (xy 119.562986 -92.922037) (xy 119.593759 -92.96855) (xy 119.617431 -93.019047)
			(xy 119.633499 -93.072454) (xy 119.641619 -93.12763) (xy 119.642128 -93.155516) (xy 119.641619 -93.183402)
			(xy 119.633499 -93.238578) (xy 119.617431 -93.291985) (xy 119.593759 -93.342482) (xy 119.562986 -93.388995)
			(xy 119.525769 -93.430532) (xy 119.482901 -93.466207) (xy 119.435295 -93.495261) (xy 119.383966 -93.517073)
			(xy 119.330009 -93.531179) (xy 119.274572 -93.537279) (xy 119.218838 -93.535242) (xy 119.163995 -93.525112)
			(xy 119.111211 -93.507105) (xy 119.061611 -93.481604) (xy 119.016253 -93.449153) (xy 118.976104 -93.410444)
			(xy 118.942018 -93.366301) (xy 118.914722 -93.317666) (xy 118.894799 -93.265575) (xy 118.882673 -93.211138)
			(xy 118.878602 -93.155516) (xy 116.329031 -93.155516) (xy 116.3333 -93.164017) (xy 116.356626 -93.228105)
			(xy 116.372355 -93.294468) (xy 116.380272 -93.362208) (xy 116.380768 -93.396308) (xy 116.380768 -93.748606)
			(xy 119.737884 -93.748606) (xy 119.741955 -93.692984) (xy 119.754081 -93.638547) (xy 119.774004 -93.586456)
			(xy 119.8013 -93.537821) (xy 119.835386 -93.493678) (xy 119.875535 -93.454969) (xy 119.920893 -93.422518)
			(xy 119.970493 -93.397017) (xy 120.023277 -93.37901) (xy 120.07812 -93.36888) (xy 120.133854 -93.366843)
			(xy 120.189291 -93.372943) (xy 120.243248 -93.387049) (xy 120.294577 -93.408861) (xy 120.342183 -93.437915)
			(xy 120.385051 -93.47359) (xy 120.422268 -93.515127) (xy 120.453041 -93.56164) (xy 120.476713 -93.612137)
			(xy 120.492781 -93.665544) (xy 120.500901 -93.72072) (xy 120.50141 -93.748606) (xy 121.975878 -93.748606)
			(xy 121.979949 -93.692984) (xy 121.992075 -93.638547) (xy 122.011998 -93.586456) (xy 122.039294 -93.537821)
			(xy 122.07338 -93.493678) (xy 122.113529 -93.454969) (xy 122.158887 -93.422518) (xy 122.208487 -93.397017)
			(xy 122.261271 -93.37901) (xy 122.316114 -93.36888) (xy 122.371848 -93.366843) (xy 122.427285 -93.372943)
			(xy 122.481242 -93.387049) (xy 122.532571 -93.408861) (xy 122.580177 -93.437915) (xy 122.623045 -93.47359)
			(xy 122.660262 -93.515127) (xy 122.691035 -93.56164) (xy 122.714707 -93.612137) (xy 122.730775 -93.665544)
			(xy 122.738895 -93.72072) (xy 122.739404 -93.748606) (xy 122.738895 -93.776492) (xy 122.730775 -93.831668)
			(xy 122.728178 -93.8403) (xy 125.868174 -93.8403) (xy 125.872245 -93.784678) (xy 125.884371 -93.730241)
			(xy 125.904294 -93.67815) (xy 125.93159 -93.629515) (xy 125.965676 -93.585372) (xy 126.005825 -93.546663)
			(xy 126.051183 -93.514212) (xy 126.100783 -93.488711) (xy 126.153567 -93.470704) (xy 126.20841 -93.460574)
			(xy 126.264144 -93.458537) (xy 126.319581 -93.464637) (xy 126.373538 -93.478743) (xy 126.424867 -93.500555)
			(xy 126.472473 -93.529609) (xy 126.515341 -93.565284) (xy 126.552558 -93.606821) (xy 126.583331 -93.653334)
			(xy 126.607003 -93.703831) (xy 126.623071 -93.757238) (xy 126.631191 -93.812414) (xy 126.6317 -93.8403)
			(xy 126.631191 -93.868186) (xy 126.623071 -93.923362) (xy 126.607003 -93.976769) (xy 126.583331 -94.027266)
			(xy 126.552558 -94.073779) (xy 126.515341 -94.115316) (xy 126.472473 -94.150991) (xy 126.424867 -94.180045)
			(xy 126.373538 -94.201857) (xy 126.319581 -94.215963) (xy 126.264144 -94.222063) (xy 126.20841 -94.220026)
			(xy 126.153567 -94.209896) (xy 126.100783 -94.191889) (xy 126.051183 -94.166388) (xy 126.005825 -94.133937)
			(xy 125.965676 -94.095228) (xy 125.93159 -94.051085) (xy 125.904294 -94.00245) (xy 125.884371 -93.950359)
			(xy 125.872245 -93.895922) (xy 125.868174 -93.8403) (xy 122.728178 -93.8403) (xy 122.714707 -93.885075)
			(xy 122.691035 -93.935572) (xy 122.660262 -93.982085) (xy 122.623045 -94.023622) (xy 122.580177 -94.059297)
			(xy 122.532571 -94.088351) (xy 122.481242 -94.110163) (xy 122.427285 -94.124269) (xy 122.371848 -94.130369)
			(xy 122.316114 -94.128332) (xy 122.261271 -94.118202) (xy 122.208487 -94.100195) (xy 122.158887 -94.074694)
			(xy 122.113529 -94.042243) (xy 122.07338 -94.003534) (xy 122.039294 -93.959391) (xy 122.011998 -93.910756)
			(xy 121.992075 -93.858665) (xy 121.979949 -93.804228) (xy 121.975878 -93.748606) (xy 120.50141 -93.748606)
			(xy 120.500901 -93.776492) (xy 120.492781 -93.831668) (xy 120.476713 -93.885075) (xy 120.453041 -93.935572)
			(xy 120.422268 -93.982085) (xy 120.385051 -94.023622) (xy 120.342183 -94.059297) (xy 120.294577 -94.088351)
			(xy 120.243248 -94.110163) (xy 120.189291 -94.124269) (xy 120.133854 -94.130369) (xy 120.07812 -94.128332)
			(xy 120.023277 -94.118202) (xy 119.970493 -94.100195) (xy 119.920893 -94.074694) (xy 119.875535 -94.042243)
			(xy 119.835386 -94.003534) (xy 119.8013 -93.959391) (xy 119.774004 -93.910756) (xy 119.754081 -93.858665)
			(xy 119.741955 -93.804228) (xy 119.737884 -93.748606) (xy 116.380768 -93.748606) (xy 116.380768 -94.891606)
			(xy 119.737884 -94.891606) (xy 119.741955 -94.835984) (xy 119.754081 -94.781547) (xy 119.774004 -94.729456)
			(xy 119.8013 -94.680821) (xy 119.835386 -94.636678) (xy 119.875535 -94.597969) (xy 119.920893 -94.565518)
			(xy 119.970493 -94.540017) (xy 120.023277 -94.52201) (xy 120.07812 -94.51188) (xy 120.133854 -94.509843)
			(xy 120.189291 -94.515943) (xy 120.243248 -94.530049) (xy 120.294577 -94.551861) (xy 120.342183 -94.580915)
			(xy 120.385051 -94.61659) (xy 120.422268 -94.658127) (xy 120.453041 -94.70464) (xy 120.476713 -94.755137)
			(xy 120.492781 -94.808544) (xy 120.500901 -94.86372) (xy 120.50141 -94.891606) (xy 121.975878 -94.891606)
			(xy 121.979949 -94.835984) (xy 121.992075 -94.781547) (xy 122.011998 -94.729456) (xy 122.039294 -94.680821)
			(xy 122.07338 -94.636678) (xy 122.113529 -94.597969) (xy 122.158887 -94.565518) (xy 122.208487 -94.540017)
			(xy 122.261271 -94.52201) (xy 122.316114 -94.51188) (xy 122.371848 -94.509843) (xy 122.427285 -94.515943)
			(xy 122.481242 -94.530049) (xy 122.532571 -94.551861) (xy 122.580177 -94.580915) (xy 122.623045 -94.61659)
			(xy 122.660262 -94.658127) (xy 122.691035 -94.70464) (xy 122.714707 -94.755137) (xy 122.730775 -94.808544)
			(xy 122.738895 -94.86372) (xy 122.739404 -94.891606) (xy 124.302772 -94.891606) (xy 124.306843 -94.835984)
			(xy 124.318969 -94.781547) (xy 124.338892 -94.729456) (xy 124.366188 -94.680821) (xy 124.400274 -94.636678)
			(xy 124.440423 -94.597969) (xy 124.485781 -94.565518) (xy 124.535381 -94.540017) (xy 124.588165 -94.52201)
			(xy 124.643008 -94.51188) (xy 124.698742 -94.509843) (xy 124.754179 -94.515943) (xy 124.808136 -94.530049)
			(xy 124.859465 -94.551861) (xy 124.907071 -94.580915) (xy 124.949939 -94.61659) (xy 124.987156 -94.658127)
			(xy 125.017929 -94.70464) (xy 125.041601 -94.755137) (xy 125.057669 -94.808544) (xy 125.065789 -94.86372)
			(xy 125.066298 -94.891606) (xy 125.065789 -94.919492) (xy 125.057669 -94.974668) (xy 125.041601 -95.028075)
			(xy 125.017929 -95.078572) (xy 124.987156 -95.125085) (xy 124.949939 -95.166622) (xy 124.907071 -95.202297)
			(xy 124.859465 -95.231351) (xy 124.808136 -95.253163) (xy 124.754179 -95.267269) (xy 124.698742 -95.273369)
			(xy 124.643008 -95.271332) (xy 124.588165 -95.261202) (xy 124.535381 -95.243195) (xy 124.485781 -95.217694)
			(xy 124.440423 -95.185243) (xy 124.400274 -95.146534) (xy 124.366188 -95.102391) (xy 124.338892 -95.053756)
			(xy 124.318969 -95.001665) (xy 124.306843 -94.947228) (xy 124.302772 -94.891606) (xy 122.739404 -94.891606)
			(xy 122.738895 -94.919492) (xy 122.730775 -94.974668) (xy 122.714707 -95.028075) (xy 122.691035 -95.078572)
			(xy 122.660262 -95.125085) (xy 122.623045 -95.166622) (xy 122.580177 -95.202297) (xy 122.532571 -95.231351)
			(xy 122.481242 -95.253163) (xy 122.427285 -95.267269) (xy 122.371848 -95.273369) (xy 122.316114 -95.271332)
			(xy 122.261271 -95.261202) (xy 122.208487 -95.243195) (xy 122.158887 -95.217694) (xy 122.113529 -95.185243)
			(xy 122.07338 -95.146534) (xy 122.039294 -95.102391) (xy 122.011998 -95.053756) (xy 121.992075 -95.001665)
			(xy 121.979949 -94.947228) (xy 121.975878 -94.891606) (xy 120.50141 -94.891606) (xy 120.500901 -94.919492)
			(xy 120.492781 -94.974668) (xy 120.476713 -95.028075) (xy 120.453041 -95.078572) (xy 120.422268 -95.125085)
			(xy 120.385051 -95.166622) (xy 120.342183 -95.202297) (xy 120.294577 -95.231351) (xy 120.243248 -95.253163)
			(xy 120.189291 -95.267269) (xy 120.133854 -95.273369) (xy 120.07812 -95.271332) (xy 120.023277 -95.261202)
			(xy 119.970493 -95.243195) (xy 119.920893 -95.217694) (xy 119.875535 -95.185243) (xy 119.835386 -95.146534)
			(xy 119.8013 -95.102391) (xy 119.774004 -95.053756) (xy 119.754081 -95.001665) (xy 119.741955 -94.947228)
			(xy 119.737884 -94.891606) (xy 116.380768 -94.891606) (xy 116.380768 -96.034606) (xy 119.737884 -96.034606)
			(xy 119.741955 -95.978984) (xy 119.754081 -95.924547) (xy 119.774004 -95.872456) (xy 119.8013 -95.823821)
			(xy 119.835386 -95.779678) (xy 119.875535 -95.740969) (xy 119.920893 -95.708518) (xy 119.970493 -95.683017)
			(xy 120.023277 -95.66501) (xy 120.07812 -95.65488) (xy 120.133854 -95.652843) (xy 120.189291 -95.658943)
			(xy 120.243248 -95.673049) (xy 120.294577 -95.694861) (xy 120.342183 -95.723915) (xy 120.385051 -95.75959)
			(xy 120.422268 -95.801127) (xy 120.453041 -95.84764) (xy 120.476713 -95.898137) (xy 120.492781 -95.951544)
			(xy 120.500901 -96.00672) (xy 120.50141 -96.034606) (xy 121.975878 -96.034606) (xy 121.979949 -95.978984)
			(xy 121.992075 -95.924547) (xy 122.011998 -95.872456) (xy 122.039294 -95.823821) (xy 122.07338 -95.779678)
			(xy 122.113529 -95.740969) (xy 122.158887 -95.708518) (xy 122.208487 -95.683017) (xy 122.261271 -95.66501)
			(xy 122.316114 -95.65488) (xy 122.371848 -95.652843) (xy 122.427285 -95.658943) (xy 122.481242 -95.673049)
			(xy 122.532571 -95.694861) (xy 122.580177 -95.723915) (xy 122.623045 -95.75959) (xy 122.660262 -95.801127)
			(xy 122.691035 -95.84764) (xy 122.71224 -95.892874) (xy 125.538482 -95.892874) (xy 125.542553 -95.837252)
			(xy 125.554679 -95.782815) (xy 125.574602 -95.730724) (xy 125.601898 -95.682089) (xy 125.635984 -95.637946)
			(xy 125.676133 -95.599237) (xy 125.721491 -95.566786) (xy 125.771091 -95.541285) (xy 125.823875 -95.523278)
			(xy 125.878718 -95.513148) (xy 125.934452 -95.511111) (xy 125.989889 -95.517211) (xy 126.043846 -95.531317)
			(xy 126.095175 -95.553129) (xy 126.142781 -95.582183) (xy 126.185649 -95.617858) (xy 126.222866 -95.659395)
			(xy 126.253639 -95.705908) (xy 126.277311 -95.756405) (xy 126.293379 -95.809812) (xy 126.301499 -95.864988)
			(xy 126.302008 -95.892874) (xy 126.301499 -95.92076) (xy 126.293379 -95.975936) (xy 126.277311 -96.029343)
			(xy 126.253639 -96.07984) (xy 126.222866 -96.126353) (xy 126.185649 -96.16789) (xy 126.142781 -96.203565)
			(xy 126.095175 -96.232619) (xy 126.043846 -96.254431) (xy 125.989889 -96.268537) (xy 125.934452 -96.274637)
			(xy 125.878718 -96.2726) (xy 125.823875 -96.26247) (xy 125.771091 -96.244463) (xy 125.721491 -96.218962)
			(xy 125.676133 -96.186511) (xy 125.635984 -96.147802) (xy 125.601898 -96.103659) (xy 125.574602 -96.055024)
			(xy 125.554679 -96.002933) (xy 125.542553 -95.948496) (xy 125.538482 -95.892874) (xy 122.71224 -95.892874)
			(xy 122.714707 -95.898137) (xy 122.730775 -95.951544) (xy 122.738895 -96.00672) (xy 122.739404 -96.034606)
			(xy 122.738895 -96.062492) (xy 122.730775 -96.117668) (xy 122.714707 -96.171075) (xy 122.691035 -96.221572)
			(xy 122.660262 -96.268085) (xy 122.623045 -96.309622) (xy 122.580177 -96.345297) (xy 122.532571 -96.374351)
			(xy 122.481242 -96.396163) (xy 122.427285 -96.410269) (xy 122.371848 -96.416369) (xy 122.316114 -96.414332)
			(xy 122.261271 -96.404202) (xy 122.208487 -96.386195) (xy 122.158887 -96.360694) (xy 122.113529 -96.328243)
			(xy 122.07338 -96.289534) (xy 122.039294 -96.245391) (xy 122.011998 -96.196756) (xy 121.992075 -96.144665)
			(xy 121.979949 -96.090228) (xy 121.975878 -96.034606) (xy 120.50141 -96.034606) (xy 120.500901 -96.062492)
			(xy 120.492781 -96.117668) (xy 120.476713 -96.171075) (xy 120.453041 -96.221572) (xy 120.422268 -96.268085)
			(xy 120.385051 -96.309622) (xy 120.342183 -96.345297) (xy 120.294577 -96.374351) (xy 120.243248 -96.396163)
			(xy 120.189291 -96.410269) (xy 120.133854 -96.416369) (xy 120.07812 -96.414332) (xy 120.023277 -96.404202)
			(xy 119.970493 -96.386195) (xy 119.920893 -96.360694) (xy 119.875535 -96.328243) (xy 119.835386 -96.289534)
			(xy 119.8013 -96.245391) (xy 119.774004 -96.196756) (xy 119.754081 -96.144665) (xy 119.741955 -96.090228)
			(xy 119.737884 -96.034606) (xy 116.380768 -96.034606) (xy 116.380768 -97.177606) (xy 119.737884 -97.177606)
			(xy 119.741955 -97.121984) (xy 119.754081 -97.067547) (xy 119.774004 -97.015456) (xy 119.8013 -96.966821)
			(xy 119.835386 -96.922678) (xy 119.875535 -96.883969) (xy 119.920893 -96.851518) (xy 119.970493 -96.826017)
			(xy 120.023277 -96.80801) (xy 120.07812 -96.79788) (xy 120.133854 -96.795843) (xy 120.189291 -96.801943)
			(xy 120.243248 -96.816049) (xy 120.294577 -96.837861) (xy 120.342183 -96.866915) (xy 120.385051 -96.90259)
			(xy 120.422268 -96.944127) (xy 120.453041 -96.99064) (xy 120.476713 -97.041137) (xy 120.492781 -97.094544)
			(xy 120.500901 -97.14972) (xy 120.50141 -97.177606) (xy 121.975878 -97.177606) (xy 121.979949 -97.121984)
			(xy 121.992075 -97.067547) (xy 122.011998 -97.015456) (xy 122.039294 -96.966821) (xy 122.07338 -96.922678)
			(xy 122.113529 -96.883969) (xy 122.158887 -96.851518) (xy 122.208487 -96.826017) (xy 122.261271 -96.80801)
			(xy 122.316114 -96.79788) (xy 122.371848 -96.795843) (xy 122.427285 -96.801943) (xy 122.481242 -96.816049)
			(xy 122.532571 -96.837861) (xy 122.580177 -96.866915) (xy 122.623045 -96.90259) (xy 122.660262 -96.944127)
			(xy 122.691035 -96.99064) (xy 122.714707 -97.041137) (xy 122.730775 -97.094544) (xy 122.738895 -97.14972)
			(xy 122.739316 -97.17278) (xy 124.302772 -97.17278) (xy 124.306843 -97.117158) (xy 124.318969 -97.062721)
			(xy 124.338892 -97.01063) (xy 124.366188 -96.961995) (xy 124.400274 -96.917852) (xy 124.440423 -96.879143)
			(xy 124.485781 -96.846692) (xy 124.535381 -96.821191) (xy 124.588165 -96.803184) (xy 124.643008 -96.793054)
			(xy 124.698742 -96.791017) (xy 124.754179 -96.797117) (xy 124.808136 -96.811223) (xy 124.859465 -96.833035)
			(xy 124.907071 -96.862089) (xy 124.949939 -96.897764) (xy 124.987156 -96.939301) (xy 125.017929 -96.985814)
			(xy 125.041601 -97.036311) (xy 125.057669 -97.089718) (xy 125.065789 -97.144894) (xy 125.066298 -97.17278)
			(xy 125.065789 -97.200666) (xy 125.057669 -97.255842) (xy 125.041601 -97.309249) (xy 125.017929 -97.359746)
			(xy 124.987156 -97.406259) (xy 124.949939 -97.447796) (xy 124.907071 -97.483471) (xy 124.859465 -97.512525)
			(xy 124.808136 -97.534337) (xy 124.754179 -97.548443) (xy 124.698742 -97.554543) (xy 124.643008 -97.552506)
			(xy 124.588165 -97.542376) (xy 124.535381 -97.524369) (xy 124.485781 -97.498868) (xy 124.440423 -97.466417)
			(xy 124.400274 -97.427708) (xy 124.366188 -97.383565) (xy 124.338892 -97.33493) (xy 124.318969 -97.282839)
			(xy 124.306843 -97.228402) (xy 124.302772 -97.17278) (xy 122.739316 -97.17278) (xy 122.739404 -97.177606)
			(xy 122.738895 -97.205492) (xy 122.730775 -97.260668) (xy 122.714707 -97.314075) (xy 122.691035 -97.364572)
			(xy 122.660262 -97.411085) (xy 122.623045 -97.452622) (xy 122.580177 -97.488297) (xy 122.532571 -97.517351)
			(xy 122.481242 -97.539163) (xy 122.427285 -97.553269) (xy 122.371848 -97.559369) (xy 122.316114 -97.557332)
			(xy 122.261271 -97.547202) (xy 122.208487 -97.529195) (xy 122.158887 -97.503694) (xy 122.113529 -97.471243)
			(xy 122.07338 -97.432534) (xy 122.039294 -97.388391) (xy 122.011998 -97.339756) (xy 121.992075 -97.287665)
			(xy 121.979949 -97.233228) (xy 121.975878 -97.177606) (xy 120.50141 -97.177606) (xy 120.500901 -97.205492)
			(xy 120.492781 -97.260668) (xy 120.476713 -97.314075) (xy 120.453041 -97.364572) (xy 120.422268 -97.411085)
			(xy 120.385051 -97.452622) (xy 120.342183 -97.488297) (xy 120.294577 -97.517351) (xy 120.243248 -97.539163)
			(xy 120.189291 -97.553269) (xy 120.133854 -97.559369) (xy 120.07812 -97.557332) (xy 120.023277 -97.547202)
			(xy 119.970493 -97.529195) (xy 119.920893 -97.503694) (xy 119.875535 -97.471243) (xy 119.835386 -97.432534)
			(xy 119.8013 -97.388391) (xy 119.774004 -97.339756) (xy 119.754081 -97.287665) (xy 119.741955 -97.233228)
			(xy 119.737884 -97.177606) (xy 116.380768 -97.177606) (xy 116.380768 -98.152966) (xy 116.381193 -98.163036)
			(xy 116.388912 -98.181635) (xy 116.395754 -98.189034) (xy 116.527326 -98.320606) (xy 119.737884 -98.320606)
			(xy 119.741955 -98.264984) (xy 119.754081 -98.210547) (xy 119.774004 -98.158456) (xy 119.8013 -98.109821)
			(xy 119.835386 -98.065678) (xy 119.875535 -98.026969) (xy 119.920893 -97.994518) (xy 119.970493 -97.969017)
			(xy 120.023277 -97.95101) (xy 120.07812 -97.94088) (xy 120.133854 -97.938843) (xy 120.189291 -97.944943)
			(xy 120.243248 -97.959049) (xy 120.294577 -97.980861) (xy 120.342183 -98.009915) (xy 120.385051 -98.04559)
			(xy 120.422268 -98.087127) (xy 120.453041 -98.13364) (xy 120.476713 -98.184137) (xy 120.492781 -98.237544)
			(xy 120.497566 -98.27006) (xy 125.399544 -98.27006) (xy 125.403615 -98.214438) (xy 125.415741 -98.160001)
			(xy 125.435664 -98.10791) (xy 125.46296 -98.059275) (xy 125.497046 -98.015132) (xy 125.537195 -97.976423)
			(xy 125.582553 -97.943972) (xy 125.632153 -97.918471) (xy 125.684937 -97.900464) (xy 125.73978 -97.890334)
			(xy 125.795514 -97.888297) (xy 125.850951 -97.894397) (xy 125.904908 -97.908503) (xy 125.956237 -97.930315)
			(xy 126.003843 -97.959369) (xy 126.046711 -97.995044) (xy 126.083928 -98.036581) (xy 126.114701 -98.083094)
			(xy 126.138373 -98.133591) (xy 126.154441 -98.186998) (xy 126.162561 -98.242174) (xy 126.16307 -98.27006)
			(xy 126.162561 -98.297946) (xy 126.154441 -98.353122) (xy 126.138373 -98.406529) (xy 126.114701 -98.457026)
			(xy 126.083928 -98.503539) (xy 126.046711 -98.545076) (xy 126.003843 -98.580751) (xy 125.956237 -98.609805)
			(xy 125.904908 -98.631617) (xy 125.850951 -98.645723) (xy 125.795514 -98.651823) (xy 125.73978 -98.649786)
			(xy 125.684937 -98.639656) (xy 125.632153 -98.621649) (xy 125.582553 -98.596148) (xy 125.537195 -98.563697)
			(xy 125.497046 -98.524988) (xy 125.46296 -98.480845) (xy 125.435664 -98.43221) (xy 125.415741 -98.380119)
			(xy 125.403615 -98.325682) (xy 125.399544 -98.27006) (xy 120.497566 -98.27006) (xy 120.500901 -98.29272)
			(xy 120.50141 -98.320606) (xy 120.500901 -98.348492) (xy 120.492781 -98.403668) (xy 120.476713 -98.457075)
			(xy 120.453041 -98.507572) (xy 120.422268 -98.554085) (xy 120.385051 -98.595622) (xy 120.342183 -98.631297)
			(xy 120.294577 -98.660351) (xy 120.243248 -98.682163) (xy 120.189291 -98.696269) (xy 120.133854 -98.702369)
			(xy 120.07812 -98.700332) (xy 120.023277 -98.690202) (xy 119.970493 -98.672195) (xy 119.920893 -98.646694)
			(xy 119.875535 -98.614243) (xy 119.835386 -98.575534) (xy 119.8013 -98.531391) (xy 119.774004 -98.482756)
			(xy 119.754081 -98.430665) (xy 119.741955 -98.376228) (xy 119.737884 -98.320606) (xy 116.527326 -98.320606)
			(xy 117.670326 -99.463606) (xy 119.737884 -99.463606) (xy 119.741955 -99.407984) (xy 119.754081 -99.353547)
			(xy 119.774004 -99.301456) (xy 119.8013 -99.252821) (xy 119.835386 -99.208678) (xy 119.875535 -99.169969)
			(xy 119.920893 -99.137518) (xy 119.970493 -99.112017) (xy 120.023277 -99.09401) (xy 120.07812 -99.08388)
			(xy 120.133854 -99.081843) (xy 120.189291 -99.087943) (xy 120.243248 -99.102049) (xy 120.294577 -99.123861)
			(xy 120.342183 -99.152915) (xy 120.385051 -99.18859) (xy 120.422268 -99.230127) (xy 120.453041 -99.27664)
			(xy 120.476713 -99.327137) (xy 120.492781 -99.380544) (xy 120.500901 -99.43572) (xy 120.50141 -99.463606)
			(xy 124.405388 -99.463606) (xy 124.409459 -99.407984) (xy 124.421585 -99.353547) (xy 124.441508 -99.301456)
			(xy 124.468804 -99.252821) (xy 124.50289 -99.208678) (xy 124.543039 -99.169969) (xy 124.588397 -99.137518)
			(xy 124.637997 -99.112017) (xy 124.690781 -99.09401) (xy 124.745624 -99.08388) (xy 124.801358 -99.081843)
			(xy 124.856795 -99.087943) (xy 124.910752 -99.102049) (xy 124.962081 -99.123861) (xy 125.009687 -99.152915)
			(xy 125.052555 -99.18859) (xy 125.089772 -99.230127) (xy 125.120545 -99.27664) (xy 125.144217 -99.327137)
			(xy 125.160285 -99.380544) (xy 125.168405 -99.43572) (xy 125.168914 -99.463606) (xy 125.168405 -99.491492)
			(xy 125.160285 -99.546668) (xy 125.144217 -99.600075) (xy 125.120545 -99.650572) (xy 125.089772 -99.697085)
			(xy 125.052555 -99.738622) (xy 125.009687 -99.774297) (xy 124.962081 -99.803351) (xy 124.910752 -99.825163)
			(xy 124.856795 -99.839269) (xy 124.801358 -99.845369) (xy 124.745624 -99.843332) (xy 124.690781 -99.833202)
			(xy 124.637997 -99.815195) (xy 124.588397 -99.789694) (xy 124.543039 -99.757243) (xy 124.50289 -99.718534)
			(xy 124.468804 -99.674391) (xy 124.441508 -99.625756) (xy 124.421585 -99.573665) (xy 124.409459 -99.519228)
			(xy 124.405388 -99.463606) (xy 120.50141 -99.463606) (xy 120.500901 -99.491492) (xy 120.492781 -99.546668)
			(xy 120.476713 -99.600075) (xy 120.453041 -99.650572) (xy 120.422268 -99.697085) (xy 120.385051 -99.738622)
			(xy 120.342183 -99.774297) (xy 120.294577 -99.803351) (xy 120.243248 -99.825163) (xy 120.189291 -99.839269)
			(xy 120.133854 -99.845369) (xy 120.07812 -99.843332) (xy 120.023277 -99.833202) (xy 119.970493 -99.815195)
			(xy 119.920893 -99.789694) (xy 119.875535 -99.757243) (xy 119.835386 -99.718534) (xy 119.8013 -99.674391)
			(xy 119.774004 -99.625756) (xy 119.754081 -99.573665) (xy 119.741955 -99.519228) (xy 119.737884 -99.463606)
			(xy 117.670326 -99.463606) (xy 118.433088 -100.226368) (xy 119.200166 -100.226368) (xy 119.204237 -100.170746)
			(xy 119.216363 -100.116309) (xy 119.236286 -100.064218) (xy 119.263582 -100.015583) (xy 119.297668 -99.97144)
			(xy 119.337817 -99.932731) (xy 119.383175 -99.90028) (xy 119.432775 -99.874779) (xy 119.485559 -99.856772)
			(xy 119.540402 -99.846642) (xy 119.596136 -99.844605) (xy 119.651573 -99.850705) (xy 119.70553 -99.864811)
			(xy 119.756859 -99.886623) (xy 119.804465 -99.915677) (xy 119.847333 -99.951352) (xy 119.88455 -99.992889)
			(xy 119.915323 -100.039402) (xy 119.938995 -100.089899) (xy 119.955063 -100.143306) (xy 119.963183 -100.198482)
			(xy 119.963692 -100.226368) (xy 119.963183 -100.254254) (xy 119.955063 -100.30943) (xy 119.938995 -100.362837)
			(xy 119.915323 -100.413334) (xy 119.88455 -100.459847) (xy 119.847333 -100.501384) (xy 119.804465 -100.537059)
			(xy 119.756859 -100.566113) (xy 119.70553 -100.587925) (xy 119.651573 -100.602031) (xy 119.596136 -100.608131)
			(xy 119.540402 -100.606094) (xy 119.485559 -100.595964) (xy 119.432775 -100.577957) (xy 119.383175 -100.552456)
			(xy 119.337817 -100.520005) (xy 119.297668 -100.481296) (xy 119.263582 -100.437153) (xy 119.236286 -100.388518)
			(xy 119.216363 -100.336427) (xy 119.204237 -100.28199) (xy 119.200166 -100.226368) (xy 118.433088 -100.226368)
			(xy 118.590314 -100.383594) (xy 118.613207 -100.407164) (xy 118.654176 -100.458538) (xy 118.689134 -100.514176)
			(xy 118.717644 -100.573379) (xy 118.739345 -100.635401) (xy 118.753965 -100.699463) (xy 118.761321 -100.764759)
			(xy 118.761764 -100.797614) (xy 118.761764 -104.734868) (xy 124.328172 -104.734868) (xy 124.332243 -104.679246)
			(xy 124.344369 -104.624809) (xy 124.364292 -104.572718) (xy 124.391588 -104.524083) (xy 124.425674 -104.47994)
			(xy 124.465823 -104.441231) (xy 124.511181 -104.40878) (xy 124.560781 -104.383279) (xy 124.613565 -104.365272)
			(xy 124.668408 -104.355142) (xy 124.724142 -104.353105) (xy 124.779579 -104.359205) (xy 124.833536 -104.373311)
			(xy 124.884865 -104.395123) (xy 124.932471 -104.424177) (xy 124.975339 -104.459852) (xy 125.012556 -104.501389)
			(xy 125.043329 -104.547902) (xy 125.067001 -104.598399) (xy 125.083069 -104.651806) (xy 125.091189 -104.706982)
			(xy 125.091698 -104.734868) (xy 125.091189 -104.762754) (xy 125.083069 -104.81793) (xy 125.067001 -104.871337)
			(xy 125.043329 -104.921834) (xy 125.012556 -104.968347) (xy 124.975339 -105.009884) (xy 124.932471 -105.045559)
			(xy 124.884865 -105.074613) (xy 124.833536 -105.096425) (xy 124.779579 -105.110531) (xy 124.724142 -105.116631)
			(xy 124.668408 -105.114594) (xy 124.613565 -105.104464) (xy 124.560781 -105.086457) (xy 124.511181 -105.060956)
			(xy 124.465823 -105.028505) (xy 124.425674 -104.989796) (xy 124.391588 -104.945653) (xy 124.364292 -104.897018)
			(xy 124.344369 -104.844927) (xy 124.332243 -104.79049) (xy 124.328172 -104.734868) (xy 118.761764 -104.734868)
			(xy 118.761764 -106.277918) (xy 123.681234 -106.277918) (xy 123.685305 -106.222296) (xy 123.697431 -106.167859)
			(xy 123.717354 -106.115768) (xy 123.74465 -106.067133) (xy 123.778736 -106.02299) (xy 123.818885 -105.984281)
			(xy 123.864243 -105.95183) (xy 123.913843 -105.926329) (xy 123.966627 -105.908322) (xy 124.02147 -105.898192)
			(xy 124.077204 -105.896155) (xy 124.132641 -105.902255) (xy 124.186598 -105.916361) (xy 124.237927 -105.938173)
			(xy 124.285533 -105.967227) (xy 124.328401 -106.002902) (xy 124.365618 -106.044439) (xy 124.396391 -106.090952)
			(xy 124.420063 -106.141449) (xy 124.436131 -106.194856) (xy 124.444251 -106.250032) (xy 124.44476 -106.277918)
			(xy 124.444251 -106.305804) (xy 124.436131 -106.36098) (xy 124.420063 -106.414387) (xy 124.396391 -106.464884)
			(xy 124.365618 -106.511397) (xy 124.328401 -106.552934) (xy 124.285533 -106.588609) (xy 124.237927 -106.617663)
			(xy 124.186598 -106.639475) (xy 124.132641 -106.653581) (xy 124.077204 -106.659681) (xy 124.02147 -106.657644)
			(xy 123.966627 -106.647514) (xy 123.913843 -106.629507) (xy 123.864243 -106.604006) (xy 123.818885 -106.571555)
			(xy 123.778736 -106.532846) (xy 123.74465 -106.488703) (xy 123.717354 -106.440068) (xy 123.697431 -106.387977)
			(xy 123.685305 -106.33354) (xy 123.681234 -106.277918) (xy 118.761764 -106.277918) (xy 118.761764 -109.706918)
			(xy 121.915172 -109.706918) (xy 121.919243 -109.651296) (xy 121.931369 -109.596859) (xy 121.951292 -109.544768)
			(xy 121.978588 -109.496133) (xy 122.012674 -109.45199) (xy 122.052823 -109.413281) (xy 122.098181 -109.38083)
			(xy 122.147781 -109.355329) (xy 122.200565 -109.337322) (xy 122.255408 -109.327192) (xy 122.311142 -109.325155)
			(xy 122.366579 -109.331255) (xy 122.420536 -109.345361) (xy 122.471865 -109.367173) (xy 122.519471 -109.396227)
			(xy 122.562339 -109.431902) (xy 122.599556 -109.473439) (xy 122.630329 -109.519952) (xy 122.654001 -109.570449)
			(xy 122.65685 -109.579918) (xy 123.947172 -109.579918) (xy 123.951243 -109.524296) (xy 123.963369 -109.469859)
			(xy 123.983292 -109.417768) (xy 124.010588 -109.369133) (xy 124.044674 -109.32499) (xy 124.084823 -109.286281)
			(xy 124.130181 -109.25383) (xy 124.179781 -109.228329) (xy 124.232565 -109.210322) (xy 124.287408 -109.200192)
			(xy 124.343142 -109.198155) (xy 124.398579 -109.204255) (xy 124.452536 -109.218361) (xy 124.503865 -109.240173)
			(xy 124.551471 -109.269227) (xy 124.594339 -109.304902) (xy 124.631556 -109.346439) (xy 124.662329 -109.392952)
			(xy 124.686001 -109.443449) (xy 124.702069 -109.496856) (xy 124.710189 -109.552032) (xy 124.710698 -109.579918)
			(xy 124.710189 -109.607804) (xy 124.702069 -109.66298) (xy 124.686001 -109.716387) (xy 124.662329 -109.766884)
			(xy 124.631556 -109.813397) (xy 124.594339 -109.854934) (xy 124.551471 -109.890609) (xy 124.503865 -109.919663)
			(xy 124.452536 -109.941475) (xy 124.398579 -109.955581) (xy 124.343142 -109.961681) (xy 124.287408 -109.959644)
			(xy 124.232565 -109.949514) (xy 124.179781 -109.931507) (xy 124.130181 -109.906006) (xy 124.084823 -109.873555)
			(xy 124.044674 -109.834846) (xy 124.010588 -109.790703) (xy 123.983292 -109.742068) (xy 123.963369 -109.689977)
			(xy 123.951243 -109.63554) (xy 123.947172 -109.579918) (xy 122.65685 -109.579918) (xy 122.670069 -109.623856)
			(xy 122.678189 -109.679032) (xy 122.678698 -109.706918) (xy 122.678189 -109.734804) (xy 122.670069 -109.78998)
			(xy 122.654001 -109.843387) (xy 122.630329 -109.893884) (xy 122.599556 -109.940397) (xy 122.562339 -109.981934)
			(xy 122.519471 -110.017609) (xy 122.471865 -110.046663) (xy 122.420536 -110.068475) (xy 122.366579 -110.082581)
			(xy 122.311142 -110.088681) (xy 122.255408 -110.086644) (xy 122.200565 -110.076514) (xy 122.147781 -110.058507)
			(xy 122.098181 -110.033006) (xy 122.052823 -110.000555) (xy 122.012674 -109.961846) (xy 121.978588 -109.917703)
			(xy 121.951292 -109.869068) (xy 121.931369 -109.816977) (xy 121.919243 -109.76254) (xy 121.915172 -109.706918)
			(xy 118.761764 -109.706918) (xy 118.761764 -111.613188) (xy 118.762179 -111.623259) (xy 118.769905 -111.641857)
			(xy 118.77675 -111.649256) (xy 118.862098 -111.7346) (xy 121.915172 -111.7346) (xy 121.919243 -111.678978)
			(xy 121.931369 -111.624541) (xy 121.951292 -111.57245) (xy 121.978588 -111.523815) (xy 122.012674 -111.479672)
			(xy 122.052823 -111.440963) (xy 122.098181 -111.408512) (xy 122.147781 -111.383011) (xy 122.200565 -111.365004)
			(xy 122.255408 -111.354874) (xy 122.311142 -111.352837) (xy 122.366579 -111.358937) (xy 122.420536 -111.373043)
			(xy 122.471865 -111.394855) (xy 122.519471 -111.423909) (xy 122.562339 -111.459584) (xy 122.599556 -111.501121)
			(xy 122.630329 -111.547634) (xy 122.654001 -111.598131) (xy 122.670069 -111.651538) (xy 122.678189 -111.706714)
			(xy 122.678698 -111.7346) (xy 122.678684 -111.735362) (xy 122.931172 -111.735362) (xy 122.935243 -111.67974)
			(xy 122.947369 -111.625303) (xy 122.967292 -111.573212) (xy 122.994588 -111.524577) (xy 123.028674 -111.480434)
			(xy 123.068823 -111.441725) (xy 123.114181 -111.409274) (xy 123.163781 -111.383773) (xy 123.216565 -111.365766)
			(xy 123.271408 -111.355636) (xy 123.327142 -111.353599) (xy 123.382579 -111.359699) (xy 123.436536 -111.373805)
			(xy 123.487865 -111.395617) (xy 123.535471 -111.424671) (xy 123.578339 -111.460346) (xy 123.615556 -111.501883)
			(xy 123.646329 -111.548396) (xy 123.670001 -111.598893) (xy 123.686069 -111.6523) (xy 123.694189 -111.707476)
			(xy 123.694698 -111.735362) (xy 123.947172 -111.735362) (xy 123.951243 -111.67974) (xy 123.963369 -111.625303)
			(xy 123.983292 -111.573212) (xy 124.010588 -111.524577) (xy 124.044674 -111.480434) (xy 124.084823 -111.441725)
			(xy 124.130181 -111.409274) (xy 124.179781 -111.383773) (xy 124.232565 -111.365766) (xy 124.287408 -111.355636)
			(xy 124.343142 -111.353599) (xy 124.398579 -111.359699) (xy 124.452536 -111.373805) (xy 124.503865 -111.395617)
			(xy 124.551471 -111.424671) (xy 124.594339 -111.460346) (xy 124.631556 -111.501883) (xy 124.662329 -111.548396)
			(xy 124.686001 -111.598893) (xy 124.702069 -111.6523) (xy 124.710189 -111.707476) (xy 124.710698 -111.735362)
			(xy 124.710624 -111.739426) (xy 127.565148 -111.739426) (xy 127.569219 -111.683804) (xy 127.581345 -111.629367)
			(xy 127.601268 -111.577276) (xy 127.628564 -111.528641) (xy 127.66265 -111.484498) (xy 127.702799 -111.445789)
			(xy 127.748157 -111.413338) (xy 127.797757 -111.387837) (xy 127.850541 -111.36983) (xy 127.905384 -111.3597)
			(xy 127.961118 -111.357663) (xy 128.016555 -111.363763) (xy 128.070512 -111.377869) (xy 128.121841 -111.399681)
			(xy 128.169447 -111.428735) (xy 128.212315 -111.46441) (xy 128.249532 -111.505947) (xy 128.280305 -111.55246)
			(xy 128.303977 -111.602957) (xy 128.320045 -111.656364) (xy 128.328165 -111.71154) (xy 128.328674 -111.739426)
			(xy 128.328165 -111.767312) (xy 128.320045 -111.822488) (xy 128.303977 -111.875895) (xy 128.280305 -111.926392)
			(xy 128.249532 -111.972905) (xy 128.212315 -112.014442) (xy 128.169447 -112.050117) (xy 128.121841 -112.079171)
			(xy 128.070512 -112.100983) (xy 128.016555 -112.115089) (xy 127.961118 -112.121189) (xy 127.905384 -112.119152)
			(xy 127.850541 -112.109022) (xy 127.797757 -112.091015) (xy 127.748157 -112.065514) (xy 127.702799 -112.033063)
			(xy 127.66265 -111.994354) (xy 127.628564 -111.950211) (xy 127.601268 -111.901576) (xy 127.581345 -111.849485)
			(xy 127.569219 -111.795048) (xy 127.565148 -111.739426) (xy 124.710624 -111.739426) (xy 124.710189 -111.763248)
			(xy 124.702069 -111.818424) (xy 124.686001 -111.871831) (xy 124.662329 -111.922328) (xy 124.631556 -111.968841)
			(xy 124.594339 -112.010378) (xy 124.551471 -112.046053) (xy 124.503865 -112.075107) (xy 124.452536 -112.096919)
			(xy 124.398579 -112.111025) (xy 124.343142 -112.117125) (xy 124.287408 -112.115088) (xy 124.232565 -112.104958)
			(xy 124.179781 -112.086951) (xy 124.130181 -112.06145) (xy 124.084823 -112.028999) (xy 124.044674 -111.99029)
			(xy 124.010588 -111.946147) (xy 123.983292 -111.897512) (xy 123.963369 -111.845421) (xy 123.951243 -111.790984)
			(xy 123.947172 -111.735362) (xy 123.694698 -111.735362) (xy 123.694189 -111.763248) (xy 123.686069 -111.818424)
			(xy 123.670001 -111.871831) (xy 123.646329 -111.922328) (xy 123.615556 -111.968841) (xy 123.578339 -112.010378)
			(xy 123.535471 -112.046053) (xy 123.487865 -112.075107) (xy 123.436536 -112.096919) (xy 123.382579 -112.111025)
			(xy 123.327142 -112.117125) (xy 123.271408 -112.115088) (xy 123.216565 -112.104958) (xy 123.163781 -112.086951)
			(xy 123.114181 -112.06145) (xy 123.068823 -112.028999) (xy 123.028674 -111.99029) (xy 122.994588 -111.946147)
			(xy 122.967292 -111.897512) (xy 122.947369 -111.845421) (xy 122.935243 -111.790984) (xy 122.931172 -111.735362)
			(xy 122.678684 -111.735362) (xy 122.678189 -111.762486) (xy 122.670069 -111.817662) (xy 122.654001 -111.871069)
			(xy 122.630329 -111.921566) (xy 122.599556 -111.968079) (xy 122.562339 -112.009616) (xy 122.519471 -112.045291)
			(xy 122.471865 -112.074345) (xy 122.420536 -112.096157) (xy 122.366579 -112.110263) (xy 122.311142 -112.116363)
			(xy 122.255408 -112.114326) (xy 122.200565 -112.104196) (xy 122.147781 -112.086189) (xy 122.098181 -112.060688)
			(xy 122.052823 -112.028237) (xy 122.012674 -111.989528) (xy 121.978588 -111.945385) (xy 121.951292 -111.89675)
			(xy 121.931369 -111.844659) (xy 121.919243 -111.790222) (xy 121.915172 -111.7346) (xy 118.862098 -111.7346)
			(xy 119.667568 -112.540034) (xy 129.905504 -112.540034) (xy 129.909575 -112.484412) (xy 129.921701 -112.429975)
			(xy 129.941624 -112.377884) (xy 129.96892 -112.329249) (xy 130.003006 -112.285106) (xy 130.043155 -112.246397)
			(xy 130.088513 -112.213946) (xy 130.138113 -112.188445) (xy 130.190897 -112.170438) (xy 130.24574 -112.160308)
			(xy 130.301474 -112.158271) (xy 130.356911 -112.164371) (xy 130.410868 -112.178477) (xy 130.462197 -112.200289)
			(xy 130.509803 -112.229343) (xy 130.552671 -112.265018) (xy 130.589888 -112.306555) (xy 130.620661 -112.353068)
			(xy 130.644333 -112.403565) (xy 130.649627 -112.421162) (xy 131.907024 -112.421162) (xy 131.911095 -112.36554)
			(xy 131.923221 -112.311103) (xy 131.943144 -112.259012) (xy 131.97044 -112.210377) (xy 132.004526 -112.166234)
			(xy 132.044675 -112.127525) (xy 132.090033 -112.095074) (xy 132.139633 -112.069573) (xy 132.192417 -112.051566)
			(xy 132.24726 -112.041436) (xy 132.302994 -112.039399) (xy 132.358431 -112.045499) (xy 132.412388 -112.059605)
			(xy 132.463717 -112.081417) (xy 132.511323 -112.110471) (xy 132.554191 -112.146146) (xy 132.591408 -112.187683)
			(xy 132.622181 -112.234196) (xy 132.645853 -112.284693) (xy 132.661921 -112.3381) (xy 132.670041 -112.393276)
			(xy 132.67055 -112.421162) (xy 132.670041 -112.449048) (xy 132.661921 -112.504224) (xy 132.645853 -112.557631)
			(xy 132.622181 -112.608128) (xy 132.591408 -112.654641) (xy 132.554191 -112.696178) (xy 132.511323 -112.731853)
			(xy 132.463717 -112.760907) (xy 132.412388 -112.782719) (xy 132.358431 -112.796825) (xy 132.302994 -112.802925)
			(xy 132.24726 -112.800888) (xy 132.192417 -112.790758) (xy 132.139633 -112.772751) (xy 132.090033 -112.74725)
			(xy 132.044675 -112.714799) (xy 132.004526 -112.67609) (xy 131.97044 -112.631947) (xy 131.943144 -112.583312)
			(xy 131.923221 -112.531221) (xy 131.911095 -112.476784) (xy 131.907024 -112.421162) (xy 130.649627 -112.421162)
			(xy 130.660401 -112.456972) (xy 130.668521 -112.512148) (xy 130.66903 -112.540034) (xy 130.668521 -112.56792)
			(xy 130.660401 -112.623096) (xy 130.644333 -112.676503) (xy 130.620661 -112.727) (xy 130.589888 -112.773513)
			(xy 130.552671 -112.81505) (xy 130.509803 -112.850725) (xy 130.462197 -112.879779) (xy 130.410868 -112.901591)
			(xy 130.356911 -112.915697) (xy 130.301474 -112.921797) (xy 130.24574 -112.91976) (xy 130.190897 -112.90963)
			(xy 130.138113 -112.891623) (xy 130.088513 -112.866122) (xy 130.043155 -112.833671) (xy 130.003006 -112.794962)
			(xy 129.96892 -112.750819) (xy 129.941624 -112.702184) (xy 129.921701 -112.650093) (xy 129.909575 -112.595656)
			(xy 129.905504 -112.540034) (xy 119.667568 -112.540034) (xy 121.02602 -113.898426) (xy 127.55321 -113.898426)
			(xy 127.557281 -113.842804) (xy 127.569407 -113.788367) (xy 127.58933 -113.736276) (xy 127.616626 -113.687641)
			(xy 127.650712 -113.643498) (xy 127.690861 -113.604789) (xy 127.736219 -113.572338) (xy 127.785819 -113.546837)
			(xy 127.838603 -113.52883) (xy 127.893446 -113.5187) (xy 127.94918 -113.516663) (xy 128.004617 -113.522763)
			(xy 128.058574 -113.536869) (xy 128.109903 -113.558681) (xy 128.157509 -113.587735) (xy 128.200377 -113.62341)
			(xy 128.237594 -113.664947) (xy 128.268367 -113.71146) (xy 128.292039 -113.761957) (xy 128.308107 -113.815364)
			(xy 128.316227 -113.87054) (xy 128.316736 -113.898426) (xy 128.316227 -113.926312) (xy 128.308107 -113.981488)
			(xy 128.292039 -114.034895) (xy 128.268367 -114.085392) (xy 128.237594 -114.131905) (xy 128.200377 -114.173442)
			(xy 128.157509 -114.209117) (xy 128.109903 -114.238171) (xy 128.058574 -114.259983) (xy 128.004617 -114.274089)
			(xy 127.94918 -114.280189) (xy 127.893446 -114.278152) (xy 127.838603 -114.268022) (xy 127.785819 -114.250015)
			(xy 127.736219 -114.224514) (xy 127.690861 -114.192063) (xy 127.650712 -114.153354) (xy 127.616626 -114.109211)
			(xy 127.58933 -114.060576) (xy 127.569407 -114.008485) (xy 127.557281 -113.954048) (xy 127.55321 -113.898426)
			(xy 121.02602 -113.898426) (xy 123.799823 -116.672106) (xy 128.968754 -116.672106) (xy 128.96921 -116.644735)
			(xy 128.977029 -116.590555) (xy 128.992519 -116.538052) (xy 129.015363 -116.488305) (xy 129.045091 -116.442339)
			(xy 129.062734 -116.421408) (xy 129.062988 -116.421154) (xy 129.068557 -116.414055) (xy 129.074815 -116.397148)
			(xy 129.07518 -116.388134) (xy 129.07518 -116.321078) (xy 129.074838 -116.31206) (xy 129.06858 -116.295142)
			(xy 129.062988 -116.288058) (xy 129.062734 -116.288058) (xy 129.062734 -116.287804) (xy 129.045099 -116.266867)
			(xy 129.015373 -116.2209) (xy 128.992527 -116.171154) (xy 128.97703 -116.118653) (xy 128.969201 -116.064475)
			(xy 128.9692 -116.009734) (xy 128.977028 -115.955556) (xy 128.992524 -115.903054) (xy 129.015369 -115.853308)
			(xy 129.045093 -115.807341) (xy 129.062734 -115.786408) (xy 129.062988 -115.786154) (xy 129.068557 -115.779055)
			(xy 129.074815 -115.762148) (xy 129.07518 -115.753134) (xy 129.07518 -115.686078) (xy 129.074838 -115.67706)
			(xy 129.06858 -115.660142) (xy 129.062988 -115.653058) (xy 129.062734 -115.653058) (xy 129.062734 -115.652804)
			(xy 129.045089 -115.631877) (xy 129.015377 -115.585903) (xy 128.992541 -115.536155) (xy 128.977052 -115.483653)
			(xy 128.969226 -115.429476) (xy 128.968754 -115.402106) (xy 128.969283 -115.374857) (xy 128.977038 -115.320912)
			(xy 128.99239 -115.268621) (xy 129.015028 -115.219046) (xy 129.04449 -115.173198) (xy 129.080177 -115.132008)
			(xy 129.121362 -115.096317) (xy 129.167207 -115.066849) (xy 129.21678 -115.044206) (xy 129.269069 -115.028847)
			(xy 129.323013 -115.021086) (xy 129.350262 -115.020598) (xy 129.377631 -115.021087) (xy 129.431809 -115.028899)
			(xy 129.484312 -115.044383) (xy 129.53406 -115.06722) (xy 129.580027 -115.096939) (xy 129.60096 -115.114578)
			(xy 129.601214 -115.114832) (xy 129.60829 -115.120434) (xy 129.625215 -115.12667) (xy 129.634234 -115.127024)
			(xy 129.70129 -115.127024) (xy 129.710306 -115.126657) (xy 129.727222 -115.120416) (xy 129.73431 -115.114832)
			(xy 129.73431 -115.114578) (xy 129.734564 -115.114578) (xy 129.755496 -115.096939) (xy 129.801469 -115.067228)
			(xy 129.851217 -115.044392) (xy 129.903717 -115.028901) (xy 129.957893 -115.021072) (xy 129.985262 -115.020598)
			(xy 130.012514 -115.021091) (xy 130.066464 -115.028843) (xy 130.118762 -115.044194) (xy 130.168342 -115.066833)
			(xy 130.214196 -115.096297) (xy 130.255389 -115.131988) (xy 130.291084 -115.173178) (xy 130.320552 -115.219029)
			(xy 130.343195 -115.268608) (xy 130.358551 -115.320904) (xy 130.366307 -115.374854) (xy 130.36677 -115.402106)
			(xy 130.366315 -115.429477) (xy 130.358495 -115.483657) (xy 130.343004 -115.53616) (xy 130.32016 -115.585907)
			(xy 130.290433 -115.631873) (xy 130.27279 -115.652804) (xy 130.272536 -115.653058) (xy 130.266953 -115.660147)
			(xy 130.260706 -115.677062) (xy 130.260344 -115.686078) (xy 130.260344 -115.753134) (xy 130.260675 -115.762154)
			(xy 130.26694 -115.779071) (xy 130.272536 -115.786154) (xy 130.27279 -115.786154) (xy 130.27279 -115.786408)
			(xy 130.290436 -115.807336) (xy 130.320159 -115.853305) (xy 130.343003 -115.903052) (xy 130.358498 -115.955555)
			(xy 130.366326 -116.009734) (xy 130.366325 -116.064475) (xy 130.358496 -116.118654) (xy 130.343 -116.171156)
			(xy 130.320155 -116.220903) (xy 130.29043 -116.266871) (xy 130.27279 -116.287804) (xy 130.272536 -116.288058)
			(xy 130.266953 -116.295147) (xy 130.260706 -116.312062) (xy 130.260344 -116.321078) (xy 130.260344 -116.388134)
			(xy 130.260675 -116.397154) (xy 130.26694 -116.414071) (xy 130.272536 -116.421154) (xy 130.27279 -116.421154)
			(xy 130.27279 -116.421408) (xy 130.290445 -116.442327) (xy 130.320155 -116.488304) (xy 130.342988 -116.538054)
			(xy 130.358475 -116.590558) (xy 130.366299 -116.644736) (xy 130.36677 -116.672106) (xy 130.366631 -116.680234)
			(xy 131.250942 -116.680234) (xy 131.255013 -116.624612) (xy 131.267139 -116.570175) (xy 131.287062 -116.518084)
			(xy 131.314358 -116.469449) (xy 131.348444 -116.425306) (xy 131.388593 -116.386597) (xy 131.433951 -116.354146)
			(xy 131.483551 -116.328645) (xy 131.536335 -116.310638) (xy 131.591178 -116.300508) (xy 131.646912 -116.298471)
			(xy 131.702349 -116.304571) (xy 131.756306 -116.318677) (xy 131.807635 -116.340489) (xy 131.855241 -116.369543)
			(xy 131.898109 -116.405218) (xy 131.935326 -116.446755) (xy 131.966099 -116.493268) (xy 131.989771 -116.543765)
			(xy 132.005839 -116.597172) (xy 132.013959 -116.652348) (xy 132.014468 -116.680234) (xy 132.013959 -116.70812)
			(xy 132.005839 -116.763296) (xy 131.989771 -116.816703) (xy 131.966099 -116.8672) (xy 131.935326 -116.913713)
			(xy 131.898109 -116.95525) (xy 131.855241 -116.990925) (xy 131.807635 -117.019979) (xy 131.756306 -117.041791)
			(xy 131.702349 -117.055897) (xy 131.646912 -117.061997) (xy 131.591178 -117.05996) (xy 131.536335 -117.04983)
			(xy 131.483551 -117.031823) (xy 131.433951 -117.006322) (xy 131.388593 -116.973871) (xy 131.348444 -116.935162)
			(xy 131.314358 -116.891019) (xy 131.287062 -116.842384) (xy 131.267139 -116.790293) (xy 131.255013 -116.735856)
			(xy 131.250942 -116.680234) (xy 130.366631 -116.680234) (xy 130.366317 -116.698663) (xy 130.358948 -116.751262)
			(xy 130.344354 -116.802331) (xy 130.334004 -116.826792) (xy 130.329655 -116.83816) (xy 130.331003 -116.862434)
			(xy 130.336544 -116.873274) (xy 130.377946 -116.944394) (xy 130.38471 -116.95444) (xy 130.405096 -116.967442)
			(xy 130.417062 -116.969286) (xy 130.445045 -116.972458) (xy 130.499709 -116.985996) (xy 130.551788 -117.007424)
			(xy 130.600151 -117.036276) (xy 130.643746 -117.071926) (xy 130.681627 -117.113597) (xy 130.712968 -117.160385)
			(xy 130.73709 -117.211273) (xy 130.753467 -117.265155) (xy 130.758909 -117.301772) (xy 132.398006 -117.301772)
			(xy 132.402077 -117.24615) (xy 132.414203 -117.191713) (xy 132.434126 -117.139622) (xy 132.461422 -117.090987)
			(xy 132.495508 -117.046844) (xy 132.535657 -117.008135) (xy 132.581015 -116.975684) (xy 132.630615 -116.950183)
			(xy 132.683399 -116.932176) (xy 132.738242 -116.922046) (xy 132.793976 -116.920009) (xy 132.849413 -116.926109)
			(xy 132.90337 -116.940215) (xy 132.954699 -116.962027) (xy 133.002305 -116.991081) (xy 133.045173 -117.026756)
			(xy 133.08239 -117.068293) (xy 133.113163 -117.114806) (xy 133.136835 -117.165303) (xy 133.152903 -117.21871)
			(xy 133.161023 -117.273886) (xy 133.161532 -117.301772) (xy 133.161023 -117.329658) (xy 133.152903 -117.384834)
			(xy 133.136835 -117.438241) (xy 133.113163 -117.488738) (xy 133.08239 -117.535251) (xy 133.045173 -117.576788)
			(xy 133.002305 -117.612463) (xy 132.954699 -117.641517) (xy 132.90337 -117.663329) (xy 132.849413 -117.677435)
			(xy 132.793976 -117.683535) (xy 132.738242 -117.681498) (xy 132.683399 -117.671368) (xy 132.630615 -117.653361)
			(xy 132.581015 -117.62786) (xy 132.535657 -117.595409) (xy 132.495508 -117.5567) (xy 132.461422 -117.512557)
			(xy 132.434126 -117.463922) (xy 132.414203 -117.411831) (xy 132.402077 -117.357394) (xy 132.398006 -117.301772)
			(xy 130.758909 -117.301772) (xy 130.761745 -117.320858) (xy 130.762248 -117.349016) (xy 130.761762 -117.376267)
			(xy 130.754006 -117.430215) (xy 130.738651 -117.48251) (xy 130.716009 -117.532087) (xy 130.686543 -117.577937)
			(xy 130.650852 -117.619128) (xy 130.609661 -117.654819) (xy 130.563811 -117.684285) (xy 130.514234 -117.706927)
			(xy 130.461939 -117.722282) (xy 130.407991 -117.730038) (xy 130.353489 -117.730038) (xy 130.299541 -117.722282)
			(xy 130.247246 -117.706927) (xy 130.197669 -117.684285) (xy 130.151819 -117.654819) (xy 130.110628 -117.619128)
			(xy 130.074937 -117.577937) (xy 130.045471 -117.532087) (xy 130.022829 -117.48251) (xy 130.007474 -117.430215)
			(xy 129.999718 -117.376267) (xy 129.999232 -117.349016) (xy 129.999692 -117.32246) (xy 130.007058 -117.26986)
			(xy 130.02165 -117.218791) (xy 130.031998 -117.19433) (xy 130.036333 -117.182957) (xy 130.034994 -117.158688)
			(xy 130.029458 -117.147848) (xy 129.988056 -117.076728) (xy 129.981359 -117.066629) (xy 129.960923 -117.053657)
			(xy 129.94894 -117.051836) (xy 129.919467 -117.048452) (xy 129.861998 -117.033735) (xy 129.807501 -117.010297)
			(xy 129.757291 -116.978703) (xy 129.734564 -116.959634) (xy 129.73431 -116.95938) (xy 129.727226 -116.953789)
			(xy 129.710307 -116.947546) (xy 129.70129 -116.947188) (xy 129.634234 -116.947188) (xy 129.625219 -116.947564)
			(xy 129.608302 -116.953799) (xy 129.601214 -116.95938) (xy 129.601214 -116.959634) (xy 129.60096 -116.959634)
			(xy 129.58002 -116.977264) (xy 129.534049 -117.006976) (xy 129.484304 -117.029813) (xy 129.431805 -117.045306)
			(xy 129.377631 -117.053138) (xy 129.350262 -117.053614) (xy 129.32301 -117.053158) (xy 129.269062 -117.045396)
			(xy 129.216767 -117.030036) (xy 129.16719 -117.007391) (xy 129.12134 -116.977922) (xy 129.08015 -116.942227)
			(xy 129.044459 -116.901035) (xy 129.014993 -116.855182) (xy 128.992352 -116.805603) (xy 128.976997 -116.753307)
			(xy 128.96924 -116.699358) (xy 128.968754 -116.672106) (xy 123.799823 -116.672106) (xy 124.455172 -117.327426)
			(xy 125.787148 -117.327426) (xy 125.791219 -117.271804) (xy 125.803345 -117.217367) (xy 125.823268 -117.165276)
			(xy 125.850564 -117.116641) (xy 125.88465 -117.072498) (xy 125.924799 -117.033789) (xy 125.970157 -117.001338)
			(xy 126.019757 -116.975837) (xy 126.072541 -116.95783) (xy 126.127384 -116.9477) (xy 126.183118 -116.945663)
			(xy 126.238555 -116.951763) (xy 126.292512 -116.965869) (xy 126.343841 -116.987681) (xy 126.391447 -117.016735)
			(xy 126.434315 -117.05241) (xy 126.471532 -117.093947) (xy 126.502305 -117.14046) (xy 126.525977 -117.190957)
			(xy 126.528826 -117.200426) (xy 127.819148 -117.200426) (xy 127.823219 -117.144804) (xy 127.835345 -117.090367)
			(xy 127.855268 -117.038276) (xy 127.882564 -116.989641) (xy 127.91665 -116.945498) (xy 127.956799 -116.906789)
			(xy 128.002157 -116.874338) (xy 128.051757 -116.848837) (xy 128.104541 -116.83083) (xy 128.159384 -116.8207)
			(xy 128.215118 -116.818663) (xy 128.270555 -116.824763) (xy 128.324512 -116.838869) (xy 128.375841 -116.860681)
			(xy 128.423447 -116.889735) (xy 128.466315 -116.92541) (xy 128.503532 -116.966947) (xy 128.534305 -117.01346)
			(xy 128.557977 -117.063957) (xy 128.574045 -117.117364) (xy 128.582165 -117.17254) (xy 128.582674 -117.200426)
			(xy 128.582165 -117.228312) (xy 128.574045 -117.283488) (xy 128.557977 -117.336895) (xy 128.534305 -117.387392)
			(xy 128.503532 -117.433905) (xy 128.466315 -117.475442) (xy 128.423447 -117.511117) (xy 128.375841 -117.540171)
			(xy 128.324512 -117.561983) (xy 128.270555 -117.576089) (xy 128.215118 -117.582189) (xy 128.159384 -117.580152)
			(xy 128.104541 -117.570022) (xy 128.051757 -117.552015) (xy 128.002157 -117.526514) (xy 127.956799 -117.494063)
			(xy 127.91665 -117.455354) (xy 127.882564 -117.411211) (xy 127.855268 -117.362576) (xy 127.835345 -117.310485)
			(xy 127.823219 -117.256048) (xy 127.819148 -117.200426) (xy 126.528826 -117.200426) (xy 126.542045 -117.244364)
			(xy 126.550165 -117.29954) (xy 126.550674 -117.327426) (xy 126.550165 -117.355312) (xy 126.542045 -117.410488)
			(xy 126.525977 -117.463895) (xy 126.502305 -117.514392) (xy 126.471532 -117.560905) (xy 126.434315 -117.602442)
			(xy 126.391447 -117.638117) (xy 126.343841 -117.667171) (xy 126.292512 -117.688983) (xy 126.238555 -117.703089)
			(xy 126.183118 -117.709189) (xy 126.127384 -117.707152) (xy 126.072541 -117.697022) (xy 126.019757 -117.679015)
			(xy 125.970157 -117.653514) (xy 125.924799 -117.621063) (xy 125.88465 -117.582354) (xy 125.850564 -117.538211)
			(xy 125.823268 -117.489576) (xy 125.803345 -117.437485) (xy 125.791219 -117.383048) (xy 125.787148 -117.327426)
			(xy 124.455172 -117.327426) (xy 124.493274 -117.365526) (xy 124.516181 -117.389082) (xy 124.557145 -117.44046)
			(xy 124.592098 -117.496102) (xy 124.620602 -117.555307) (xy 124.642299 -117.617331) (xy 124.656915 -117.681394)
			(xy 124.664266 -117.746691) (xy 124.664724 -117.779546) (xy 124.664724 -119.486426) (xy 125.787148 -119.486426)
			(xy 125.791219 -119.430804) (xy 125.803345 -119.376367) (xy 125.823268 -119.324276) (xy 125.850564 -119.275641)
			(xy 125.88465 -119.231498) (xy 125.924799 -119.192789) (xy 125.970157 -119.160338) (xy 126.019757 -119.134837)
			(xy 126.072541 -119.11683) (xy 126.127384 -119.1067) (xy 126.183118 -119.104663) (xy 126.238555 -119.110763)
			(xy 126.292512 -119.124869) (xy 126.343841 -119.146681) (xy 126.391447 -119.175735) (xy 126.434315 -119.21141)
			(xy 126.471532 -119.252947) (xy 126.502305 -119.29946) (xy 126.525977 -119.349957) (xy 126.527756 -119.35587)
			(xy 126.803148 -119.35587) (xy 126.807219 -119.300248) (xy 126.819345 -119.245811) (xy 126.839268 -119.19372)
			(xy 126.866564 -119.145085) (xy 126.90065 -119.100942) (xy 126.940799 -119.062233) (xy 126.986157 -119.029782)
			(xy 127.035757 -119.004281) (xy 127.088541 -118.986274) (xy 127.143384 -118.976144) (xy 127.199118 -118.974107)
			(xy 127.254555 -118.980207) (xy 127.308512 -118.994313) (xy 127.359841 -119.016125) (xy 127.407447 -119.045179)
			(xy 127.450315 -119.080854) (xy 127.487532 -119.122391) (xy 127.518305 -119.168904) (xy 127.541977 -119.219401)
			(xy 127.558045 -119.272808) (xy 127.566165 -119.327984) (xy 127.566674 -119.35587) (xy 127.819148 -119.35587)
			(xy 127.823219 -119.300248) (xy 127.835345 -119.245811) (xy 127.855268 -119.19372) (xy 127.882564 -119.145085)
			(xy 127.91665 -119.100942) (xy 127.956799 -119.062233) (xy 128.002157 -119.029782) (xy 128.051757 -119.004281)
			(xy 128.104541 -118.986274) (xy 128.159384 -118.976144) (xy 128.215118 -118.974107) (xy 128.270555 -118.980207)
			(xy 128.324512 -118.994313) (xy 128.375841 -119.016125) (xy 128.423447 -119.045179) (xy 128.466315 -119.080854)
			(xy 128.503532 -119.122391) (xy 128.534305 -119.168904) (xy 128.557977 -119.219401) (xy 128.574045 -119.272808)
			(xy 128.582165 -119.327984) (xy 128.582674 -119.35587) (xy 128.582165 -119.383756) (xy 128.581036 -119.39143)
			(xy 131.014722 -119.39143) (xy 131.018793 -119.335808) (xy 131.030919 -119.281371) (xy 131.050842 -119.22928)
			(xy 131.078138 -119.180645) (xy 131.112224 -119.136502) (xy 131.152373 -119.097793) (xy 131.197731 -119.065342)
			(xy 131.247331 -119.039841) (xy 131.300115 -119.021834) (xy 131.354958 -119.011704) (xy 131.410692 -119.009667)
			(xy 131.466129 -119.015767) (xy 131.520086 -119.029873) (xy 131.571415 -119.051685) (xy 131.619021 -119.080739)
			(xy 131.661889 -119.116414) (xy 131.699106 -119.157951) (xy 131.729879 -119.204464) (xy 131.753551 -119.254961)
			(xy 131.769619 -119.308368) (xy 131.777739 -119.363544) (xy 131.778248 -119.39143) (xy 131.777739 -119.419316)
			(xy 131.769619 -119.474492) (xy 131.753551 -119.527899) (xy 131.729879 -119.578396) (xy 131.699106 -119.624909)
			(xy 131.661889 -119.666446) (xy 131.619021 -119.702121) (xy 131.571415 -119.731175) (xy 131.520086 -119.752987)
			(xy 131.466129 -119.767093) (xy 131.410692 -119.773193) (xy 131.354958 -119.771156) (xy 131.300115 -119.761026)
			(xy 131.247331 -119.743019) (xy 131.197731 -119.717518) (xy 131.152373 -119.685067) (xy 131.112224 -119.646358)
			(xy 131.078138 -119.602215) (xy 131.050842 -119.55358) (xy 131.030919 -119.501489) (xy 131.018793 -119.447052)
			(xy 131.014722 -119.39143) (xy 128.581036 -119.39143) (xy 128.574045 -119.438932) (xy 128.557977 -119.492339)
			(xy 128.534305 -119.542836) (xy 128.503532 -119.589349) (xy 128.466315 -119.630886) (xy 128.423447 -119.666561)
			(xy 128.375841 -119.695615) (xy 128.324512 -119.717427) (xy 128.270555 -119.731533) (xy 128.215118 -119.737633)
			(xy 128.159384 -119.735596) (xy 128.104541 -119.725466) (xy 128.051757 -119.707459) (xy 128.002157 -119.681958)
			(xy 127.956799 -119.649507) (xy 127.91665 -119.610798) (xy 127.882564 -119.566655) (xy 127.855268 -119.51802)
			(xy 127.835345 -119.465929) (xy 127.823219 -119.411492) (xy 127.819148 -119.35587) (xy 127.566674 -119.35587)
			(xy 127.566165 -119.383756) (xy 127.558045 -119.438932) (xy 127.541977 -119.492339) (xy 127.518305 -119.542836)
			(xy 127.487532 -119.589349) (xy 127.450315 -119.630886) (xy 127.407447 -119.666561) (xy 127.359841 -119.695615)
			(xy 127.308512 -119.717427) (xy 127.254555 -119.731533) (xy 127.199118 -119.737633) (xy 127.143384 -119.735596)
			(xy 127.088541 -119.725466) (xy 127.035757 -119.707459) (xy 126.986157 -119.681958) (xy 126.940799 -119.649507)
			(xy 126.90065 -119.610798) (xy 126.866564 -119.566655) (xy 126.839268 -119.51802) (xy 126.819345 -119.465929)
			(xy 126.807219 -119.411492) (xy 126.803148 -119.35587) (xy 126.527756 -119.35587) (xy 126.542045 -119.403364)
			(xy 126.550165 -119.45854) (xy 126.550674 -119.486426) (xy 126.550165 -119.514312) (xy 126.542045 -119.569488)
			(xy 126.525977 -119.622895) (xy 126.502305 -119.673392) (xy 126.471532 -119.719905) (xy 126.434315 -119.761442)
			(xy 126.391447 -119.797117) (xy 126.343841 -119.826171) (xy 126.292512 -119.847983) (xy 126.238555 -119.862089)
			(xy 126.183118 -119.868189) (xy 126.127384 -119.866152) (xy 126.072541 -119.856022) (xy 126.019757 -119.838015)
			(xy 125.970157 -119.812514) (xy 125.924799 -119.780063) (xy 125.88465 -119.741354) (xy 125.850564 -119.697211)
			(xy 125.823268 -119.648576) (xy 125.803345 -119.596485) (xy 125.791219 -119.542048) (xy 125.787148 -119.486426)
			(xy 124.664724 -119.486426) (xy 124.664724 -121.57075) (xy 129.719832 -121.57075) (xy 129.720256 -121.544434)
			(xy 129.727498 -121.492304) (xy 129.741825 -121.44166) (xy 129.762966 -121.393461) (xy 129.79052 -121.348618)
			(xy 129.823967 -121.307981) (xy 129.843022 -121.289826) (xy 129.850417 -121.2823) (xy 129.858945 -121.263023)
			(xy 129.859532 -121.252488) (xy 129.859532 -121.177812) (xy 129.859001 -121.167263) (xy 129.850466 -121.147968)
			(xy 129.843022 -121.140474) (xy 129.823965 -121.12232) (xy 129.790507 -121.08169) (xy 129.762948 -121.03685)
			(xy 129.741809 -120.988649) (xy 129.727493 -120.938001) (xy 129.72027 -120.885866) (xy 129.719832 -120.85955)
			(xy 129.720318 -120.832299) (xy 129.728074 -120.778351) (xy 129.743429 -120.726056) (xy 129.766071 -120.676479)
			(xy 129.795537 -120.630629) (xy 129.831228 -120.589438) (xy 129.872419 -120.553747) (xy 129.918269 -120.524281)
			(xy 129.967846 -120.501639) (xy 130.020141 -120.486284) (xy 130.074089 -120.478528) (xy 130.128591 -120.478528)
			(xy 130.182539 -120.486284) (xy 130.234834 -120.501639) (xy 130.284411 -120.524281) (xy 130.330261 -120.553747)
			(xy 130.371452 -120.589438) (xy 130.407143 -120.630629) (xy 130.436609 -120.676479) (xy 130.459251 -120.726056)
			(xy 130.474606 -120.778351) (xy 130.482362 -120.832299) (xy 130.482848 -120.85955) (xy 130.482431 -120.885866)
			(xy 130.475188 -120.937997) (xy 130.46086 -120.988642) (xy 130.439718 -121.036841) (xy 130.412163 -121.081683)
			(xy 130.378714 -121.12232) (xy 130.359658 -121.140474) (xy 130.352274 -121.148011) (xy 130.343738 -121.167279)
			(xy 130.343148 -121.177812) (xy 130.343148 -121.252488) (xy 130.343656 -121.263041) (xy 130.352204 -121.282337)
			(xy 130.359658 -121.289826) (xy 130.37873 -121.307965) (xy 130.412184 -121.348599) (xy 130.439739 -121.393443)
			(xy 130.460874 -121.441647) (xy 130.475188 -121.492297) (xy 130.482411 -121.544433) (xy 130.482848 -121.57075)
			(xy 130.482362 -121.598001) (xy 130.474606 -121.651949) (xy 130.459251 -121.704244) (xy 130.436609 -121.753821)
			(xy 130.407143 -121.799671) (xy 130.371452 -121.840862) (xy 130.330261 -121.876553) (xy 130.284411 -121.906019)
			(xy 130.234834 -121.928661) (xy 130.182539 -121.944016) (xy 130.128591 -121.951772) (xy 130.074089 -121.951772)
			(xy 130.020141 -121.944016) (xy 129.967846 -121.928661) (xy 129.918269 -121.906019) (xy 129.872419 -121.876553)
			(xy 129.831228 -121.840862) (xy 129.795537 -121.799671) (xy 129.766071 -121.753821) (xy 129.743429 -121.704244)
			(xy 129.728074 -121.651949) (xy 129.720318 -121.598001) (xy 129.719832 -121.57075) (xy 124.664724 -121.57075)
			(xy 124.664724 -122.292618) (xy 125.880112 -122.292618) (xy 125.884183 -122.236996) (xy 125.896309 -122.182559)
			(xy 125.916232 -122.130468) (xy 125.943528 -122.081833) (xy 125.977614 -122.03769) (xy 126.017763 -121.998981)
			(xy 126.063121 -121.96653) (xy 126.112721 -121.941029) (xy 126.165505 -121.923022) (xy 126.220348 -121.912892)
			(xy 126.276082 -121.910855) (xy 126.331519 -121.916955) (xy 126.385476 -121.931061) (xy 126.436805 -121.952873)
			(xy 126.484411 -121.981927) (xy 126.527279 -122.017602) (xy 126.564496 -122.059139) (xy 126.595269 -122.105652)
			(xy 126.618941 -122.156149) (xy 126.635009 -122.209556) (xy 126.643129 -122.264732) (xy 126.643638 -122.292618)
			(xy 126.643129 -122.320504) (xy 126.635009 -122.37568) (xy 126.618941 -122.429087) (xy 126.599804 -122.46991)
			(xy 127.036828 -122.46991) (xy 127.040899 -122.414288) (xy 127.053025 -122.359851) (xy 127.072948 -122.30776)
			(xy 127.100244 -122.259125) (xy 127.13433 -122.214982) (xy 127.174479 -122.176273) (xy 127.219837 -122.143822)
			(xy 127.269437 -122.118321) (xy 127.322221 -122.100314) (xy 127.377064 -122.090184) (xy 127.432798 -122.088147)
			(xy 127.488235 -122.094247) (xy 127.542192 -122.108353) (xy 127.593521 -122.130165) (xy 127.641127 -122.159219)
			(xy 127.683995 -122.194894) (xy 127.721212 -122.236431) (xy 127.751985 -122.282944) (xy 127.775657 -122.333441)
			(xy 127.791725 -122.386848) (xy 127.799845 -122.442024) (xy 127.800354 -122.46991) (xy 127.799845 -122.497796)
			(xy 127.791725 -122.552972) (xy 127.775657 -122.606379) (xy 127.751985 -122.656876) (xy 127.721212 -122.703389)
			(xy 127.683995 -122.744926) (xy 127.641127 -122.780601) (xy 127.593521 -122.809655) (xy 127.542192 -122.831467)
			(xy 127.488235 -122.845573) (xy 127.432798 -122.851673) (xy 127.377064 -122.849636) (xy 127.322221 -122.839506)
			(xy 127.269437 -122.821499) (xy 127.219837 -122.795998) (xy 127.174479 -122.763547) (xy 127.13433 -122.724838)
			(xy 127.100244 -122.680695) (xy 127.072948 -122.63206) (xy 127.053025 -122.579969) (xy 127.040899 -122.525532)
			(xy 127.036828 -122.46991) (xy 126.599804 -122.46991) (xy 126.595269 -122.479584) (xy 126.564496 -122.526097)
			(xy 126.527279 -122.567634) (xy 126.484411 -122.603309) (xy 126.436805 -122.632363) (xy 126.385476 -122.654175)
			(xy 126.331519 -122.668281) (xy 126.276082 -122.674381) (xy 126.220348 -122.672344) (xy 126.165505 -122.662214)
			(xy 126.112721 -122.644207) (xy 126.063121 -122.618706) (xy 126.017763 -122.586255) (xy 125.977614 -122.547546)
			(xy 125.943528 -122.503403) (xy 125.916232 -122.454768) (xy 125.896309 -122.402677) (xy 125.884183 -122.34824)
			(xy 125.880112 -122.292618) (xy 124.664724 -122.292618) (xy 124.664724 -123.249752) (xy 128.009867 -123.249752)
			(xy 128.009867 -123.195248) (xy 128.017624 -123.141298) (xy 128.03298 -123.089002) (xy 128.055622 -123.039423)
			(xy 128.085089 -122.993571) (xy 128.120782 -122.95238) (xy 128.161974 -122.916687) (xy 128.207826 -122.88722)
			(xy 128.257405 -122.864579) (xy 128.309702 -122.849223) (xy 128.363652 -122.841467) (xy 128.390904 -122.841004)
			(xy 128.417934 -122.841497) (xy 128.471452 -122.849135) (xy 128.523353 -122.864259) (xy 128.572597 -122.886563)
			(xy 128.618196 -122.915602) (xy 128.659234 -122.950791) (xy 128.677416 -122.970798) (xy 128.67767 -122.971052)
			(xy 128.685148 -122.978659) (xy 128.704606 -122.98735) (xy 128.715262 -122.987816) (xy 128.802892 -122.988324)
			(xy 128.82245 -122.979688) (xy 128.829816 -122.971306) (xy 128.847975 -122.951581) (xy 128.888876 -122.916917)
			(xy 128.934232 -122.888329) (xy 128.983148 -122.86638) (xy 129.034657 -122.851505) (xy 129.087743 -122.843997)
			(xy 129.11455 -122.843544) (xy 129.14192 -122.844029) (xy 129.196098 -122.85184) (xy 129.248602 -122.867324)
			(xy 129.298349 -122.890162) (xy 129.344316 -122.919884) (xy 129.365248 -122.937524) (xy 129.365502 -122.937778)
			(xy 129.372577 -122.943381) (xy 129.389503 -122.949616) (xy 129.398522 -122.94997) (xy 129.465578 -122.94997)
			(xy 129.474595 -122.949609) (xy 129.491512 -122.943365) (xy 129.498598 -122.937778) (xy 129.498598 -122.937524)
			(xy 129.498852 -122.937524) (xy 129.519785 -122.919883) (xy 129.565753 -122.890159) (xy 129.615499 -122.867313)
			(xy 129.668001 -122.851817) (xy 129.722179 -122.843988) (xy 129.776921 -122.843988) (xy 129.831099 -122.851817)
			(xy 129.883601 -122.867313) (xy 129.933347 -122.890159) (xy 129.979315 -122.919883) (xy 130.000248 -122.937524)
			(xy 130.000502 -122.937778) (xy 130.007577 -122.943381) (xy 130.024503 -122.949616) (xy 130.033522 -122.94997)
			(xy 130.100578 -122.94997) (xy 130.109595 -122.949609) (xy 130.126512 -122.943365) (xy 130.133598 -122.937778)
			(xy 130.134106 -122.937524) (xy 130.14684 -122.926579) (xy 130.173931 -122.906738) (xy 130.188208 -122.8979)
			(xy 130.197098 -122.892566) (xy 130.20929 -122.875548) (xy 130.22961 -122.78233) (xy 130.225292 -122.761756)
			(xy 130.21945 -122.75312) (xy 130.203451 -122.729056) (xy 130.178109 -122.677124) (xy 130.160884 -122.621966)
			(xy 130.152168 -122.564842) (xy 130.151632 -122.53595) (xy 130.152118 -122.508699) (xy 130.159874 -122.454751)
			(xy 130.175229 -122.402456) (xy 130.197871 -122.352879) (xy 130.227337 -122.307029) (xy 130.263028 -122.265838)
			(xy 130.304219 -122.230147) (xy 130.350069 -122.200681) (xy 130.399646 -122.178039) (xy 130.451941 -122.162684)
			(xy 130.505889 -122.154928) (xy 130.560391 -122.154928) (xy 130.614339 -122.162684) (xy 130.666634 -122.178039)
			(xy 130.716211 -122.200681) (xy 130.762061 -122.230147) (xy 130.803252 -122.265838) (xy 130.838943 -122.307029)
			(xy 130.868409 -122.352879) (xy 130.891051 -122.402456) (xy 130.906406 -122.454751) (xy 130.914162 -122.508699)
			(xy 130.914648 -122.53595) (xy 130.914099 -122.564039) (xy 130.90588 -122.619613) (xy 130.889597 -122.673381)
			(xy 130.865603 -122.724177) (xy 130.834417 -122.770905) (xy 130.796714 -122.812552) (xy 130.753308 -122.848217)
			(xy 130.729482 -122.863102) (xy 130.720592 -122.868436) (xy 130.7084 -122.885454) (xy 130.68808 -122.978672)
			(xy 130.692398 -122.999246) (xy 130.69824 -123.007882) (xy 130.714239 -123.031946) (xy 130.739581 -123.083878)
			(xy 130.756807 -123.139036) (xy 130.765523 -123.19616) (xy 130.766058 -123.225052) (xy 130.7656 -123.252306)
			(xy 130.757848 -123.30626) (xy 130.742496 -123.358561) (xy 130.719855 -123.408144) (xy 130.690387 -123.454)
			(xy 130.654693 -123.495194) (xy 130.613498 -123.530889) (xy 130.567642 -123.560356) (xy 130.518059 -123.582996)
			(xy 130.465758 -123.598349) (xy 130.411804 -123.6061) (xy 130.38455 -123.60656) (xy 130.35718 -123.606074)
			(xy 130.303002 -123.598263) (xy 130.250498 -123.582779) (xy 130.200751 -123.559941) (xy 130.154784 -123.53022)
			(xy 130.133852 -123.51258) (xy 130.133598 -123.512326) (xy 130.126522 -123.506724) (xy 130.109597 -123.500488)
			(xy 130.100578 -123.500134) (xy 130.033522 -123.500134) (xy 130.024505 -123.500494) (xy 130.007588 -123.506739)
			(xy 130.000502 -123.512326) (xy 130.000248 -123.51258) (xy 129.979315 -123.530221) (xy 129.933347 -123.559945)
			(xy 129.883601 -123.582791) (xy 129.831099 -123.598287) (xy 129.776921 -123.606116) (xy 129.722179 -123.606116)
			(xy 129.668001 -123.598287) (xy 129.615499 -123.582791) (xy 129.565753 -123.559945) (xy 129.519785 -123.530221)
			(xy 129.498852 -123.51258) (xy 129.498598 -123.512326) (xy 129.491522 -123.506724) (xy 129.474597 -123.500488)
			(xy 129.465578 -123.500134) (xy 129.398522 -123.500134) (xy 129.389505 -123.500494) (xy 129.372588 -123.506739)
			(xy 129.365502 -123.512326) (xy 129.365502 -123.51258) (xy 129.365248 -123.51258) (xy 129.344306 -123.530207)
			(xy 129.298336 -123.559921) (xy 129.248591 -123.58276) (xy 129.196093 -123.598254) (xy 129.141919 -123.606085)
			(xy 129.11455 -123.60656) (xy 129.08752 -123.606077) (xy 129.034003 -123.598433) (xy 128.982102 -123.583307)
			(xy 128.932859 -123.561) (xy 128.88726 -123.531961) (xy 128.846221 -123.496772) (xy 128.828038 -123.476766)
			(xy 128.827784 -123.476512) (xy 128.820315 -123.468894) (xy 128.80085 -123.460207) (xy 128.790192 -123.459748)
			(xy 128.702562 -123.45924) (xy 128.683004 -123.467876) (xy 128.675638 -123.476258) (xy 128.657465 -123.495969)
			(xy 128.616566 -123.530632) (xy 128.571212 -123.559221) (xy 128.522299 -123.581171) (xy 128.470793 -123.59605)
			(xy 128.41771 -123.603564) (xy 128.390904 -123.60402) (xy 128.363652 -123.603533) (xy 128.309702 -123.595777)
			(xy 128.257405 -123.580421) (xy 128.207826 -123.55778) (xy 128.161974 -123.528313) (xy 128.120782 -123.49262)
			(xy 128.085089 -123.451429) (xy 128.055622 -123.405577) (xy 128.03298 -123.355998) (xy 128.017624 -123.303702)
			(xy 128.009867 -123.249752) (xy 124.664724 -123.249752) (xy 124.664724 -124.963428) (xy 124.772926 -124.963428)
			(xy 124.776997 -124.907806) (xy 124.789123 -124.853369) (xy 124.809046 -124.801278) (xy 124.836342 -124.752643)
			(xy 124.870428 -124.7085) (xy 124.910577 -124.669791) (xy 124.955935 -124.63734) (xy 125.005535 -124.611839)
			(xy 125.058319 -124.593832) (xy 125.113162 -124.583702) (xy 125.168896 -124.581665) (xy 125.224333 -124.587765)
			(xy 125.27829 -124.601871) (xy 125.329619 -124.623683) (xy 125.377225 -124.652737) (xy 125.420093 -124.688412)
			(xy 125.45731 -124.729949) (xy 125.488083 -124.776462) (xy 125.511755 -124.826959) (xy 125.527823 -124.880366)
			(xy 125.535943 -124.935542) (xy 125.536452 -124.963428) (xy 125.536137 -124.9807) (xy 126.928878 -124.9807)
			(xy 126.932949 -124.925078) (xy 126.945075 -124.870641) (xy 126.964998 -124.81855) (xy 126.992294 -124.769915)
			(xy 127.02638 -124.725772) (xy 127.066529 -124.687063) (xy 127.111887 -124.654612) (xy 127.161487 -124.629111)
			(xy 127.214271 -124.611104) (xy 127.269114 -124.600974) (xy 127.324848 -124.598937) (xy 127.380285 -124.605037)
			(xy 127.434242 -124.619143) (xy 127.485571 -124.640955) (xy 127.533177 -124.670009) (xy 127.576045 -124.705684)
			(xy 127.613262 -124.747221) (xy 127.644035 -124.793734) (xy 127.667707 -124.844231) (xy 127.683775 -124.897638)
			(xy 127.691895 -124.952814) (xy 127.692404 -124.9807) (xy 127.691895 -125.008586) (xy 127.683775 -125.063762)
			(xy 127.667707 -125.117169) (xy 127.644035 -125.167666) (xy 127.613262 -125.214179) (xy 127.576045 -125.255716)
			(xy 127.533177 -125.291391) (xy 127.485571 -125.320445) (xy 127.434242 -125.342257) (xy 127.380285 -125.356363)
			(xy 127.324848 -125.362463) (xy 127.269114 -125.360426) (xy 127.214271 -125.350296) (xy 127.161487 -125.332289)
			(xy 127.111887 -125.306788) (xy 127.066529 -125.274337) (xy 127.02638 -125.235628) (xy 126.992294 -125.191485)
			(xy 126.964998 -125.14285) (xy 126.945075 -125.090759) (xy 126.932949 -125.036322) (xy 126.928878 -124.9807)
			(xy 125.536137 -124.9807) (xy 125.535943 -124.991314) (xy 125.527823 -125.04649) (xy 125.511755 -125.099897)
			(xy 125.488083 -125.150394) (xy 125.45731 -125.196907) (xy 125.420093 -125.238444) (xy 125.377225 -125.274119)
			(xy 125.329619 -125.303173) (xy 125.27829 -125.324985) (xy 125.224333 -125.339091) (xy 125.168896 -125.345191)
			(xy 125.113162 -125.343154) (xy 125.058319 -125.333024) (xy 125.005535 -125.315017) (xy 124.955935 -125.289516)
			(xy 124.910577 -125.257065) (xy 124.870428 -125.218356) (xy 124.836342 -125.174213) (xy 124.809046 -125.125578)
			(xy 124.789123 -125.073487) (xy 124.776997 -125.01905) (xy 124.772926 -124.963428) (xy 124.664724 -124.963428)
			(xy 124.664724 -125.403356) (xy 131.644136 -125.403356) (xy 131.644626 -125.375987) (xy 131.652437 -125.321808)
			(xy 131.66792 -125.269305) (xy 131.690756 -125.219558) (xy 131.720477 -125.17359) (xy 131.738116 -125.152658)
			(xy 131.73837 -125.152404) (xy 131.743969 -125.145326) (xy 131.750206 -125.128402) (xy 131.750562 -125.119384)
			(xy 131.750562 -125.052328) (xy 131.7502 -125.043312) (xy 131.743957 -125.026394) (xy 131.73837 -125.019308)
			(xy 131.738116 -125.019308) (xy 131.738116 -125.019054) (xy 131.720491 -124.99811) (xy 131.690777 -124.952141)
			(xy 131.667938 -124.902396) (xy 131.652443 -124.849898) (xy 131.644612 -124.795724) (xy 131.644136 -124.768356)
			(xy 131.644622 -124.741105) (xy 131.652378 -124.687157) (xy 131.667733 -124.634862) (xy 131.690375 -124.585285)
			(xy 131.719841 -124.539435) (xy 131.755532 -124.498244) (xy 131.796723 -124.462553) (xy 131.842573 -124.433087)
			(xy 131.89215 -124.410445) (xy 131.944445 -124.39509) (xy 131.998393 -124.387334) (xy 132.052895 -124.387334)
			(xy 132.106843 -124.39509) (xy 132.159138 -124.410445) (xy 132.208715 -124.433087) (xy 132.254565 -124.462553)
			(xy 132.295756 -124.498244) (xy 132.331447 -124.539435) (xy 132.360913 -124.585285) (xy 132.383555 -124.634862)
			(xy 132.39891 -124.687157) (xy 132.406666 -124.741105) (xy 132.407152 -124.768356) (xy 132.406672 -124.795726)
			(xy 132.398859 -124.849905) (xy 132.383374 -124.902408) (xy 132.360535 -124.952155) (xy 132.330813 -124.998122)
			(xy 132.313172 -125.019054) (xy 132.312918 -125.019308) (xy 132.307324 -125.02639) (xy 132.301082 -125.04331)
			(xy 132.300726 -125.052328) (xy 132.300726 -125.119384) (xy 132.301085 -125.128401) (xy 132.307331 -125.145318)
			(xy 132.312918 -125.152404) (xy 132.313172 -125.152404) (xy 132.313172 -125.152658) (xy 132.330801 -125.173599)
			(xy 132.360515 -125.219569) (xy 132.383353 -125.269314) (xy 132.398847 -125.321813) (xy 132.406677 -125.375987)
			(xy 132.407152 -125.403356) (xy 132.406666 -125.430607) (xy 132.39891 -125.484555) (xy 132.383555 -125.53685)
			(xy 132.360913 -125.586427) (xy 132.331447 -125.632277) (xy 132.295756 -125.673468) (xy 132.254565 -125.709159)
			(xy 132.208715 -125.738625) (xy 132.159138 -125.761267) (xy 132.106843 -125.776622) (xy 132.052895 -125.784378)
			(xy 131.998393 -125.784378) (xy 131.944445 -125.776622) (xy 131.89215 -125.761267) (xy 131.842573 -125.738625)
			(xy 131.796723 -125.709159) (xy 131.755532 -125.673468) (xy 131.719841 -125.632277) (xy 131.690375 -125.586427)
			(xy 131.667733 -125.53685) (xy 131.652378 -125.484555) (xy 131.644622 -125.430607) (xy 131.644136 -125.403356)
			(xy 124.664724 -125.403356) (xy 124.664724 -125.979428) (xy 124.772926 -125.979428) (xy 124.776997 -125.923806)
			(xy 124.789123 -125.869369) (xy 124.809046 -125.817278) (xy 124.836342 -125.768643) (xy 124.870428 -125.7245)
			(xy 124.910577 -125.685791) (xy 124.955935 -125.65334) (xy 125.005535 -125.627839) (xy 125.058319 -125.609832)
			(xy 125.113162 -125.599702) (xy 125.168896 -125.597665) (xy 125.224333 -125.603765) (xy 125.27829 -125.617871)
			(xy 125.329619 -125.639683) (xy 125.377225 -125.668737) (xy 125.420093 -125.704412) (xy 125.45731 -125.745949)
			(xy 125.488083 -125.792462) (xy 125.511755 -125.842959) (xy 125.527823 -125.896366) (xy 125.535943 -125.951542)
			(xy 125.536151 -125.962918) (xy 127.251204 -125.962918) (xy 127.255275 -125.907296) (xy 127.267401 -125.852859)
			(xy 127.287324 -125.800768) (xy 127.31462 -125.752133) (xy 127.348706 -125.70799) (xy 127.388855 -125.669281)
			(xy 127.434213 -125.63683) (xy 127.483813 -125.611329) (xy 127.536597 -125.593322) (xy 127.59144 -125.583192)
			(xy 127.647174 -125.581155) (xy 127.702611 -125.587255) (xy 127.756568 -125.601361) (xy 127.807897 -125.623173)
			(xy 127.855503 -125.652227) (xy 127.898371 -125.687902) (xy 127.935588 -125.729439) (xy 127.966361 -125.775952)
			(xy 127.990033 -125.826449) (xy 127.998231 -125.853698) (xy 132.584698 -125.853698) (xy 132.585163 -125.826328)
			(xy 132.592981 -125.772149) (xy 132.608471 -125.719646) (xy 132.631313 -125.669899) (xy 132.661037 -125.623932)
			(xy 132.678678 -125.603) (xy 132.678932 -125.602746) (xy 132.684509 -125.595653) (xy 132.69076 -125.578741)
			(xy 132.691124 -125.569726) (xy 132.691124 -125.50267) (xy 132.690776 -125.493652) (xy 132.684522 -125.476736)
			(xy 132.678932 -125.46965) (xy 132.678678 -125.46965) (xy 132.678678 -125.469396) (xy 132.66102 -125.448479)
			(xy 132.631312 -125.402502) (xy 132.60848 -125.35275) (xy 132.592993 -125.300246) (xy 132.58517 -125.246068)
			(xy 132.584698 -125.218698) (xy 132.585184 -125.191447) (xy 132.59294 -125.137499) (xy 132.608295 -125.085204)
			(xy 132.630937 -125.035627) (xy 132.660403 -124.989777) (xy 132.696094 -124.948586) (xy 132.737285 -124.912895)
			(xy 132.783135 -124.883429) (xy 132.832712 -124.860787) (xy 132.885007 -124.845432) (xy 132.938955 -124.837676)
			(xy 132.993457 -124.837676) (xy 133.047405 -124.845432) (xy 133.0997 -124.860787) (xy 133.149277 -124.883429)
			(xy 133.195127 -124.912895) (xy 133.236318 -124.948586) (xy 133.272009 -124.989777) (xy 133.301475 -125.035627)
			(xy 133.324117 -125.085204) (xy 133.339472 -125.137499) (xy 133.347228 -125.191447) (xy 133.347714 -125.218698)
			(xy 133.347243 -125.246068) (xy 133.339426 -125.300247) (xy 133.323938 -125.35275) (xy 133.301097 -125.402497)
			(xy 133.271374 -125.448464) (xy 133.253734 -125.469396) (xy 133.25348 -125.46965) (xy 133.247906 -125.476745)
			(xy 133.241652 -125.493655) (xy 133.241288 -125.50267) (xy 133.241288 -125.569726) (xy 133.241635 -125.578744)
			(xy 133.24789 -125.59566) (xy 133.25348 -125.602746) (xy 133.253734 -125.602746) (xy 133.253734 -125.603)
			(xy 133.271392 -125.623917) (xy 133.3011 -125.669894) (xy 133.323931 -125.719646) (xy 133.339418 -125.77215)
			(xy 133.347242 -125.826328) (xy 133.347714 -125.853698) (xy 133.347228 -125.880949) (xy 133.339472 -125.934897)
			(xy 133.324117 -125.987192) (xy 133.301475 -126.036769) (xy 133.272009 -126.082619) (xy 133.236318 -126.12381)
			(xy 133.195127 -126.159501) (xy 133.149277 -126.188967) (xy 133.0997 -126.211609) (xy 133.047405 -126.226964)
			(xy 132.993457 -126.23472) (xy 132.938955 -126.23472) (xy 132.885007 -126.226964) (xy 132.832712 -126.211609)
			(xy 132.783135 -126.188967) (xy 132.737285 -126.159501) (xy 132.696094 -126.12381) (xy 132.660403 -126.082619)
			(xy 132.630937 -126.036769) (xy 132.608295 -125.987192) (xy 132.59294 -125.934897) (xy 132.585184 -125.880949)
			(xy 132.584698 -125.853698) (xy 127.998231 -125.853698) (xy 128.006101 -125.879856) (xy 128.014221 -125.935032)
			(xy 128.01473 -125.962918) (xy 128.014221 -125.990804) (xy 128.006101 -126.04598) (xy 127.990033 -126.099387)
			(xy 127.966361 -126.149884) (xy 127.935588 -126.196397) (xy 127.898371 -126.237934) (xy 127.855503 -126.273609)
			(xy 127.807897 -126.302663) (xy 127.756568 -126.324475) (xy 127.702611 -126.338581) (xy 127.647174 -126.344681)
			(xy 127.59144 -126.342644) (xy 127.536597 -126.332514) (xy 127.483813 -126.314507) (xy 127.434213 -126.289006)
			(xy 127.388855 -126.256555) (xy 127.348706 -126.217846) (xy 127.31462 -126.173703) (xy 127.287324 -126.125068)
			(xy 127.267401 -126.072977) (xy 127.255275 -126.01854) (xy 127.251204 -125.962918) (xy 125.536151 -125.962918)
			(xy 125.536452 -125.979428) (xy 125.535943 -126.007314) (xy 125.527823 -126.06249) (xy 125.511755 -126.115897)
			(xy 125.488083 -126.166394) (xy 125.45731 -126.212907) (xy 125.420093 -126.254444) (xy 125.377225 -126.290119)
			(xy 125.329619 -126.319173) (xy 125.27829 -126.340985) (xy 125.224333 -126.355091) (xy 125.168896 -126.361191)
			(xy 125.113162 -126.359154) (xy 125.058319 -126.349024) (xy 125.005535 -126.331017) (xy 124.955935 -126.305516)
			(xy 124.910577 -126.273065) (xy 124.870428 -126.234356) (xy 124.836342 -126.190213) (xy 124.809046 -126.141578)
			(xy 124.789123 -126.089487) (xy 124.776997 -126.03505) (xy 124.772926 -125.979428) (xy 124.664724 -125.979428)
			(xy 124.664724 -126.530354) (xy 133.79323 -126.530354) (xy 133.79377 -126.50269) (xy 133.801763 -126.447941)
			(xy 133.817574 -126.39492) (xy 133.840871 -126.344735) (xy 133.871169 -126.298439) (xy 133.907831 -126.257)
			(xy 133.95009 -126.221287) (xy 133.973316 -126.20625) (xy 133.982968 -126.199582) (xy 133.995426 -126.179744)
			(xy 133.997192 -126.16815) (xy 134.005066 -126.08814) (xy 134.005661 -126.076503) (xy 133.997606 -126.054668)
			(xy 133.989572 -126.04623) (xy 133.989318 -126.045976) (xy 133.970746 -126.027885) (xy 133.938166 -125.987556)
			(xy 133.911352 -125.943184) (xy 133.890797 -125.895587) (xy 133.876882 -125.845644) (xy 133.869863 -125.794277)
			(xy 133.86943 -125.768354) (xy 133.869835 -125.7411) (xy 133.877599 -125.687147) (xy 133.892962 -125.634849)
			(xy 133.915611 -125.585269) (xy 133.945086 -125.539417) (xy 133.980786 -125.498226) (xy 134.021984 -125.462535)
			(xy 134.067843 -125.433071) (xy 134.117428 -125.410432) (xy 134.169729 -125.395081) (xy 134.223684 -125.387329)
			(xy 134.250938 -125.386846) (xy 134.278307 -125.387337) (xy 134.332486 -125.395147) (xy 134.384989 -125.41063)
			(xy 134.434737 -125.433466) (xy 134.480704 -125.463187) (xy 134.501636 -125.480826) (xy 134.50189 -125.48108)
			(xy 134.508968 -125.486678) (xy 134.525892 -125.492916) (xy 134.53491 -125.493272) (xy 134.601966 -125.493272)
			(xy 134.610982 -125.492905) (xy 134.627899 -125.486665) (xy 134.634986 -125.48108) (xy 134.634986 -125.480826)
			(xy 134.63524 -125.480826) (xy 134.656187 -125.463206) (xy 134.702155 -125.43349) (xy 134.751899 -125.41065)
			(xy 134.804397 -125.395155) (xy 134.85857 -125.387322) (xy 134.885938 -125.386846) (xy 134.913188 -125.387342)
			(xy 134.967133 -125.395103) (xy 135.019425 -125.41046) (xy 135.068999 -125.433103) (xy 135.114847 -125.462569)
			(xy 135.156036 -125.498259) (xy 135.191727 -125.539447) (xy 135.221194 -125.585294) (xy 135.243837 -125.634868)
			(xy 135.259195 -125.687159) (xy 135.266957 -125.741104) (xy 135.267446 -125.768354) (xy 135.266915 -125.797271)
			(xy 135.258192 -125.854442) (xy 135.240938 -125.909642) (xy 135.215548 -125.961604) (xy 135.182606 -126.009138)
			(xy 135.142865 -126.051154) (xy 135.12038 -126.069344) (xy 135.111559 -126.076938) (xy 135.101384 -126.097849)
			(xy 135.100822 -126.109476) (xy 135.100822 -126.189232) (xy 135.101349 -126.200866) (xy 135.111546 -126.221775)
			(xy 135.12038 -126.229364) (xy 135.142842 -126.24758) (xy 135.18258 -126.289594) (xy 135.215522 -126.337124)
			(xy 135.240914 -126.38908) (xy 135.258175 -126.444273) (xy 135.266908 -126.501439) (xy 135.267446 -126.530354)
			(xy 135.266902 -126.557604) (xy 135.259152 -126.61155) (xy 135.243804 -126.663844) (xy 135.22117 -126.713422)
			(xy 135.19171 -126.759273) (xy 135.156025 -126.800465) (xy 135.11484 -126.83616) (xy 135.068995 -126.865629)
			(xy 135.019423 -126.888275) (xy 134.967132 -126.903634) (xy 134.913188 -126.911396) (xy 134.885938 -126.911862)
			(xy 134.859622 -126.911448) (xy 134.807491 -126.904204) (xy 134.756847 -126.889875) (xy 134.708647 -126.868733)
			(xy 134.663805 -126.841177) (xy 134.623169 -126.807728) (xy 134.605014 -126.788672) (xy 134.59748 -126.781285)
			(xy 134.57821 -126.77275) (xy 134.567676 -126.772162) (xy 134.493 -126.772162) (xy 134.48245 -126.772689)
			(xy 134.463156 -126.781227) (xy 134.455662 -126.788672) (xy 134.437512 -126.807734) (xy 134.396882 -126.841191)
			(xy 134.352041 -126.86875) (xy 134.303839 -126.889888) (xy 134.25319 -126.904203) (xy 134.201055 -126.911425)
			(xy 134.174738 -126.911862) (xy 134.147484 -126.911409) (xy 134.09353 -126.903656) (xy 134.041229 -126.888303)
			(xy 133.991646 -126.865661) (xy 133.945791 -126.836193) (xy 133.904597 -126.800498) (xy 133.868902 -126.759303)
			(xy 133.839435 -126.713447) (xy 133.816795 -126.663863) (xy 133.801442 -126.611562) (xy 133.79369 -126.557608)
			(xy 133.79323 -126.530354) (xy 124.664724 -126.530354) (xy 124.664724 -127.051308) (xy 126.844042 -127.051308)
			(xy 126.848113 -126.995686) (xy 126.860239 -126.941249) (xy 126.880162 -126.889158) (xy 126.907458 -126.840523)
			(xy 126.941544 -126.79638) (xy 126.981693 -126.757671) (xy 127.027051 -126.72522) (xy 127.076651 -126.699719)
			(xy 127.129435 -126.681712) (xy 127.184278 -126.671582) (xy 127.240012 -126.669545) (xy 127.295449 -126.675645)
			(xy 127.349406 -126.689751) (xy 127.400735 -126.711563) (xy 127.448341 -126.740617) (xy 127.491209 -126.776292)
			(xy 127.528426 -126.817829) (xy 127.559199 -126.864342) (xy 127.582871 -126.914839) (xy 127.598939 -126.968246)
			(xy 127.607059 -127.023422) (xy 127.607568 -127.051308) (xy 127.607059 -127.079194) (xy 127.598939 -127.13437)
			(xy 127.582871 -127.187777) (xy 127.559199 -127.238274) (xy 127.528426 -127.284787) (xy 127.491209 -127.326324)
			(xy 127.448341 -127.361999) (xy 127.400735 -127.391053) (xy 127.349406 -127.412865) (xy 127.295449 -127.426971)
			(xy 127.240012 -127.433071) (xy 127.184278 -127.431034) (xy 127.129435 -127.420904) (xy 127.076651 -127.402897)
			(xy 127.027051 -127.377396) (xy 126.981693 -127.344945) (xy 126.941544 -127.306236) (xy 126.907458 -127.262093)
			(xy 126.880162 -127.213458) (xy 126.860239 -127.161367) (xy 126.848113 -127.10693) (xy 126.844042 -127.051308)
			(xy 124.664724 -127.051308) (xy 124.664724 -128.252748) (xy 125.828328 -128.252748) (xy 125.828328 -128.198252)
			(xy 125.836084 -128.144312) (xy 125.851437 -128.092024) (xy 125.874075 -128.042454) (xy 125.903537 -127.99661)
			(xy 125.939223 -127.955425) (xy 125.980408 -127.919738) (xy 126.026252 -127.890276) (xy 126.075822 -127.867637)
			(xy 126.12811 -127.852284) (xy 126.18205 -127.844528) (xy 126.209298 -127.844042) (xy 126.236669 -127.844499)
			(xy 126.290849 -127.852317) (xy 126.343352 -127.867808) (xy 126.393099 -127.890652) (xy 126.439065 -127.920379)
			(xy 126.459996 -127.938022) (xy 126.46025 -127.938276) (xy 126.46734 -127.943857) (xy 126.484254 -127.950105)
			(xy 126.49327 -127.950468) (xy 126.560326 -127.950468) (xy 126.569345 -127.95013) (xy 126.586262 -127.94387)
			(xy 126.593346 -127.938276) (xy 126.593346 -127.938022) (xy 126.5936 -127.938022) (xy 126.614533 -127.920381)
			(xy 126.660501 -127.890657) (xy 126.710247 -127.867811) (xy 126.762749 -127.852315) (xy 126.816927 -127.844486)
			(xy 126.871669 -127.844486) (xy 126.925847 -127.852315) (xy 126.978349 -127.867811) (xy 127.028095 -127.890657)
			(xy 127.074063 -127.920381) (xy 127.094996 -127.938022) (xy 127.09525 -127.938276) (xy 127.10234 -127.943857)
			(xy 127.119254 -127.950105) (xy 127.12827 -127.950468) (xy 127.195326 -127.950468) (xy 127.204345 -127.95013)
			(xy 127.221262 -127.94387) (xy 127.228346 -127.938276) (xy 127.228346 -127.938022) (xy 127.2286 -127.938022)
			(xy 127.249524 -127.920373) (xy 127.295499 -127.890662) (xy 127.345248 -127.867827) (xy 127.397751 -127.852339)
			(xy 127.451928 -127.844514) (xy 127.479298 -127.844042) (xy 127.506555 -127.844405) (xy 127.560513 -127.852163)
			(xy 127.612818 -127.86752) (xy 127.662405 -127.890166) (xy 127.708264 -127.919638) (xy 127.749463 -127.955336)
			(xy 127.785161 -127.996534) (xy 127.814633 -128.042393) (xy 127.837279 -128.09198) (xy 127.852637 -128.144285)
			(xy 127.860395 -128.198243) (xy 127.860395 -128.252757) (xy 127.852637 -128.306715) (xy 127.837279 -128.35902)
			(xy 127.814633 -128.408607) (xy 127.785161 -128.454466) (xy 127.749463 -128.495664) (xy 127.708264 -128.531362)
			(xy 127.662405 -128.560834) (xy 127.612818 -128.58348) (xy 127.560513 -128.598837) (xy 127.506555 -128.606595)
			(xy 127.479298 -128.607058) (xy 127.451927 -128.606603) (xy 127.397747 -128.598784) (xy 127.345244 -128.583293)
			(xy 127.295497 -128.560449) (xy 127.249531 -128.530721) (xy 127.2286 -128.513078) (xy 127.228346 -128.512824)
			(xy 127.221257 -128.507242) (xy 127.204342 -128.500994) (xy 127.195326 -128.500632) (xy 127.12827 -128.500632)
			(xy 127.119251 -128.500968) (xy 127.102334 -128.507229) (xy 127.09525 -128.512824) (xy 127.094996 -128.513078)
			(xy 127.074063 -128.530719) (xy 127.028095 -128.560443) (xy 126.978349 -128.583289) (xy 126.925847 -128.598785)
			(xy 126.871669 -128.606614) (xy 126.816927 -128.606614) (xy 126.762749 -128.598785) (xy 126.710247 -128.583289)
			(xy 126.660501 -128.560443) (xy 126.614533 -128.530719) (xy 126.5936 -128.513078) (xy 126.593346 -128.512824)
			(xy 126.586257 -128.507242) (xy 126.569342 -128.500994) (xy 126.560326 -128.500632) (xy 126.49327 -128.500632)
			(xy 126.484251 -128.500968) (xy 126.467334 -128.507229) (xy 126.46025 -128.512824) (xy 126.46025 -128.513078)
			(xy 126.459996 -128.513078) (xy 126.439073 -128.530729) (xy 126.393098 -128.56044) (xy 126.343348 -128.583274)
			(xy 126.290846 -128.598762) (xy 126.236668 -128.606586) (xy 126.209298 -128.607058) (xy 126.18205 -128.606472)
			(xy 126.12811 -128.598716) (xy 126.075822 -128.583363) (xy 126.026252 -128.560724) (xy 125.980408 -128.531262)
			(xy 125.939223 -128.495575) (xy 125.903537 -128.45439) (xy 125.874075 -128.408546) (xy 125.851437 -128.358976)
			(xy 125.836084 -128.306688) (xy 125.828328 -128.252748) (xy 124.664724 -128.252748) (xy 124.664724 -131.447157)
			(xy 125.813209 -131.447157) (xy 125.813209 -131.392643) (xy 125.820967 -131.338685) (xy 125.836326 -131.28638)
			(xy 125.858972 -131.236793) (xy 125.888445 -131.190933) (xy 125.924144 -131.149735) (xy 125.965343 -131.114037)
			(xy 126.011203 -131.084566) (xy 126.060791 -131.061922) (xy 126.113096 -131.046565) (xy 126.167055 -131.038808)
			(xy 126.194312 -131.038346) (xy 126.221683 -131.038794) (xy 126.275863 -131.046614) (xy 126.328367 -131.062107)
			(xy 126.378114 -131.084953) (xy 126.424079 -131.114682) (xy 126.44501 -131.132326) (xy 126.445264 -131.13258)
			(xy 126.45235 -131.138167) (xy 126.469268 -131.144411) (xy 126.478284 -131.144772) (xy 126.54534 -131.144772)
			(xy 126.55436 -131.14444) (xy 126.571277 -131.138176) (xy 126.57836 -131.13258) (xy 126.57836 -131.132326)
			(xy 126.578614 -131.132326) (xy 126.599547 -131.114685) (xy 126.645515 -131.084961) (xy 126.695261 -131.062115)
			(xy 126.747763 -131.046619) (xy 126.801941 -131.03879) (xy 126.856683 -131.03879) (xy 126.910861 -131.046619)
			(xy 126.963363 -131.062115) (xy 127.013109 -131.084961) (xy 127.059077 -131.114685) (xy 127.08001 -131.132326)
			(xy 127.080264 -131.13258) (xy 127.08735 -131.138167) (xy 127.104268 -131.144411) (xy 127.113284 -131.144772)
			(xy 127.18034 -131.144772) (xy 127.18936 -131.14444) (xy 127.206277 -131.138176) (xy 127.21336 -131.13258)
			(xy 127.21336 -131.132326) (xy 127.213614 -131.132326) (xy 127.234571 -131.114718) (xy 127.280537 -131.085)
			(xy 127.330278 -131.062158) (xy 127.382773 -131.04666) (xy 127.436944 -131.038824) (xy 127.464312 -131.038346)
			(xy 127.491559 -131.038925) (xy 127.545499 -131.046682) (xy 127.597786 -131.062036) (xy 127.647356 -131.084675)
			(xy 127.693199 -131.114138) (xy 127.734383 -131.149826) (xy 127.770069 -131.19101) (xy 127.79953 -131.236855)
			(xy 127.822168 -131.286425) (xy 127.837521 -131.338712) (xy 127.845276 -131.392653) (xy 127.845276 -131.447147)
			(xy 127.837521 -131.501087) (xy 127.822168 -131.553375) (xy 127.79953 -131.602945) (xy 127.770069 -131.64879)
			(xy 127.734383 -131.689974) (xy 127.693199 -131.725662) (xy 127.647356 -131.755125) (xy 127.597786 -131.777764)
			(xy 127.545499 -131.793118) (xy 127.491559 -131.800875) (xy 127.464312 -131.801362) (xy 127.436942 -131.800898)
			(xy 127.382762 -131.793081) (xy 127.330259 -131.777592) (xy 127.280512 -131.75475) (xy 127.234545 -131.725024)
			(xy 127.213614 -131.707382) (xy 127.21336 -131.707128) (xy 127.206267 -131.701552) (xy 127.189355 -131.695301)
			(xy 127.18034 -131.694936) (xy 127.113284 -131.694936) (xy 127.104265 -131.695277) (xy 127.087348 -131.701535)
			(xy 127.080264 -131.707128) (xy 127.08001 -131.707382) (xy 127.059077 -131.725023) (xy 127.013109 -131.754747)
			(xy 126.963363 -131.777593) (xy 126.910861 -131.793089) (xy 126.856683 -131.800918) (xy 126.801941 -131.800918)
			(xy 126.747763 -131.793089) (xy 126.695261 -131.777593) (xy 126.645515 -131.754747) (xy 126.599547 -131.725023)
			(xy 126.578614 -131.707382) (xy 126.57836 -131.707128) (xy 126.571267 -131.701552) (xy 126.554355 -131.695301)
			(xy 126.54534 -131.694936) (xy 126.478284 -131.694936) (xy 126.469265 -131.695277) (xy 126.452348 -131.701535)
			(xy 126.445264 -131.707128) (xy 126.445264 -131.707382) (xy 126.44501 -131.707382) (xy 126.424083 -131.725027)
			(xy 126.378109 -131.754739) (xy 126.32836 -131.777574) (xy 126.275858 -131.793063) (xy 126.221682 -131.800889)
			(xy 126.194312 -131.801362) (xy 126.167055 -131.800992) (xy 126.113096 -131.793235) (xy 126.060791 -131.777878)
			(xy 126.011203 -131.755234) (xy 125.965343 -131.725763) (xy 125.924144 -131.690065) (xy 125.888445 -131.648867)
			(xy 125.858972 -131.603007) (xy 125.836326 -131.55342) (xy 125.820967 -131.501115) (xy 125.813209 -131.447157)
			(xy 124.664724 -131.447157) (xy 124.664724 -133.443726) (xy 127.222758 -133.443726) (xy 127.223224 -133.417412)
			(xy 127.230457 -133.365282) (xy 127.244775 -133.314639) (xy 127.265907 -133.26644) (xy 127.293455 -133.221596)
			(xy 127.326895 -133.180958) (xy 127.345948 -133.162802) (xy 127.353343 -133.155275) (xy 127.361873 -133.135999)
			(xy 127.362458 -133.125464) (xy 127.362458 -133.050788) (xy 127.361961 -133.040234) (xy 127.353405 -133.020938)
			(xy 127.345948 -133.01345) (xy 127.326865 -132.995322) (xy 127.293413 -132.954685) (xy 127.265858 -132.909839)
			(xy 127.244725 -132.861633) (xy 127.230413 -132.810981) (xy 127.223194 -132.758844) (xy 127.222758 -132.732526)
			(xy 127.223244 -132.705275) (xy 127.231 -132.651327) (xy 127.246355 -132.599032) (xy 127.268997 -132.549455)
			(xy 127.298463 -132.503605) (xy 127.334154 -132.462414) (xy 127.375345 -132.426723) (xy 127.421195 -132.397257)
			(xy 127.470772 -132.374615) (xy 127.523067 -132.35926) (xy 127.577015 -132.351504) (xy 127.631517 -132.351504)
			(xy 127.685465 -132.35926) (xy 127.73776 -132.374615) (xy 127.787337 -132.397257) (xy 127.833187 -132.426723)
			(xy 127.874378 -132.462414) (xy 127.910069 -132.503605) (xy 127.939535 -132.549455) (xy 127.962177 -132.599032)
			(xy 127.977532 -132.651327) (xy 127.985288 -132.705275) (xy 127.985774 -132.732526) (xy 127.985332 -132.758841)
			(xy 127.978093 -132.810971) (xy 127.96377 -132.861614) (xy 127.942633 -132.909814) (xy 127.915082 -132.954656)
			(xy 127.881638 -132.995294) (xy 127.862584 -133.01345) (xy 127.855156 -133.020949) (xy 127.846647 -133.040246)
			(xy 127.846074 -133.050788) (xy 127.846074 -133.125464) (xy 127.846617 -133.136012) (xy 127.855143 -133.155307)
			(xy 127.862584 -133.162802) (xy 127.88163 -133.180967) (xy 127.915089 -133.221594) (xy 127.94265 -133.266432)
			(xy 127.96379 -133.314631) (xy 127.978109 -133.365277) (xy 127.985335 -133.41741) (xy 127.985774 -133.443726)
			(xy 127.985288 -133.470977) (xy 127.977532 -133.524925) (xy 127.962177 -133.57722) (xy 127.939535 -133.626797)
			(xy 127.910069 -133.672647) (xy 127.874378 -133.713838) (xy 127.833187 -133.749529) (xy 127.787337 -133.778995)
			(xy 127.73776 -133.801637) (xy 127.685465 -133.816992) (xy 127.631517 -133.824748) (xy 127.577015 -133.824748)
			(xy 127.523067 -133.816992) (xy 127.470772 -133.801637) (xy 127.421195 -133.778995) (xy 127.375345 -133.749529)
			(xy 127.334154 -133.713838) (xy 127.298463 -133.672647) (xy 127.268997 -133.626797) (xy 127.246355 -133.57722)
			(xy 127.231 -133.524925) (xy 127.223244 -133.470977) (xy 127.222758 -133.443726) (xy 124.664724 -133.443726)
			(xy 124.664724 -135.142051) (xy 125.46177 -135.142051) (xy 125.46177 -135.087549) (xy 125.469526 -135.033603)
			(xy 125.48488 -134.981309) (xy 125.50752 -134.931732) (xy 125.536985 -134.885882) (xy 125.572674 -134.844691)
			(xy 125.613862 -134.808999) (xy 125.659711 -134.779531) (xy 125.709286 -134.756888) (xy 125.761579 -134.741531)
			(xy 125.815525 -134.733771) (xy 125.842776 -134.733284) (xy 125.871694 -134.733788) (xy 125.928867 -134.742515)
			(xy 125.984068 -134.759774) (xy 126.03603 -134.785168) (xy 126.083563 -134.818116) (xy 126.125578 -134.857862)
			(xy 126.143766 -134.88035) (xy 126.151557 -134.889338) (xy 126.173023 -134.899526) (xy 126.184914 -134.899908)
			(xy 126.278386 -134.897876) (xy 126.299722 -134.8867) (xy 126.30658 -134.876794) (xy 126.321977 -134.855883)
			(xy 126.357555 -134.818056) (xy 126.397935 -134.785404) (xy 126.442369 -134.75853) (xy 126.490038 -134.737929)
			(xy 126.54006 -134.723985) (xy 126.591511 -134.716952) (xy 126.617476 -134.71652) (xy 126.644846 -134.716995)
			(xy 126.699025 -134.72481) (xy 126.751528 -134.740297) (xy 126.801275 -134.763137) (xy 126.847242 -134.792859)
			(xy 126.868174 -134.8105) (xy 126.868428 -134.810754) (xy 126.875526 -134.816323) (xy 126.892434 -134.822579)
			(xy 126.901448 -134.822946) (xy 126.968504 -134.822946) (xy 126.977522 -134.822602) (xy 126.99444 -134.816347)
			(xy 127.001524 -134.810754) (xy 127.001524 -134.8105) (xy 127.001778 -134.8105) (xy 127.022711 -134.792859)
			(xy 127.068679 -134.763135) (xy 127.118425 -134.740289) (xy 127.170927 -134.724793) (xy 127.225105 -134.716964)
			(xy 127.279847 -134.716964) (xy 127.334025 -134.724793) (xy 127.386527 -134.740289) (xy 127.436273 -134.763135)
			(xy 127.482241 -134.792859) (xy 127.503174 -134.8105) (xy 127.503428 -134.810754) (xy 127.510526 -134.816323)
			(xy 127.527434 -134.822579) (xy 127.536448 -134.822946) (xy 127.603504 -134.822946) (xy 127.612522 -134.822602)
			(xy 127.62944 -134.816347) (xy 127.636524 -134.810754) (xy 127.637032 -134.8105) (xy 127.64977 -134.79956)
			(xy 127.676859 -134.779716) (xy 127.691134 -134.770876) (xy 127.700024 -134.765542) (xy 127.712216 -134.748524)
			(xy 127.732536 -134.655306) (xy 127.728218 -134.634732) (xy 127.722376 -134.626096) (xy 127.706369 -134.602036)
			(xy 127.681029 -134.550103) (xy 127.663805 -134.494944) (xy 127.655092 -134.437819) (xy 127.654558 -134.408926)
			(xy 127.655044 -134.381675) (xy 127.6628 -134.327727) (xy 127.678155 -134.275432) (xy 127.700797 -134.225855)
			(xy 127.730263 -134.180005) (xy 127.765954 -134.138814) (xy 127.807145 -134.103123) (xy 127.852995 -134.073657)
			(xy 127.902572 -134.051015) (xy 127.954867 -134.03566) (xy 128.008815 -134.027904) (xy 128.063317 -134.027904)
			(xy 128.117265 -134.03566) (xy 128.16956 -134.051015) (xy 128.219137 -134.073657) (xy 128.264987 -134.103123)
			(xy 128.306178 -134.138814) (xy 128.341869 -134.180005) (xy 128.371335 -134.225855) (xy 128.393977 -134.275432)
			(xy 128.409332 -134.327727) (xy 128.417088 -134.381675) (xy 128.417574 -134.408926) (xy 128.417121 -134.437019)
			(xy 128.408889 -134.492599) (xy 128.392592 -134.54637) (xy 128.368583 -134.597169) (xy 128.337381 -134.643895)
			(xy 128.299662 -134.685539) (xy 128.256242 -134.721198) (xy 128.232408 -134.736078) (xy 128.223518 -134.741412)
			(xy 128.211326 -134.75843) (xy 128.191006 -134.851648) (xy 128.195324 -134.872222) (xy 128.201166 -134.880858)
			(xy 128.217146 -134.904934) (xy 128.242495 -134.956861) (xy 128.259726 -135.012015) (xy 128.268447 -135.069136)
			(xy 128.268984 -135.098028) (xy 128.268548 -135.125281) (xy 128.260787 -135.179232) (xy 128.245427 -135.231529)
			(xy 128.222781 -135.281108) (xy 128.19331 -135.326959) (xy 128.157613 -135.36815) (xy 128.116418 -135.403841)
			(xy 128.070562 -135.433306) (xy 128.02098 -135.455946) (xy 127.968681 -135.471298) (xy 127.914729 -135.479052)
			(xy 127.887476 -135.479536) (xy 127.860105 -135.4791) (xy 127.805924 -135.471277) (xy 127.753419 -135.455782)
			(xy 127.703673 -135.432933) (xy 127.657708 -135.403201) (xy 127.636778 -135.385556) (xy 127.636524 -135.385302)
			(xy 127.629435 -135.37972) (xy 127.61252 -135.37347) (xy 127.603504 -135.37311) (xy 127.536448 -135.37311)
			(xy 127.527433 -135.373488) (xy 127.510516 -135.379721) (xy 127.503428 -135.385302) (xy 127.503428 -135.385556)
			(xy 127.503174 -135.385556) (xy 127.482241 -135.403197) (xy 127.436273 -135.432921) (xy 127.386527 -135.455767)
			(xy 127.334025 -135.471263) (xy 127.279847 -135.479092) (xy 127.225105 -135.479092) (xy 127.170927 -135.471263)
			(xy 127.118425 -135.455767) (xy 127.068679 -135.432921) (xy 127.022711 -135.403197) (xy 127.001778 -135.385556)
			(xy 127.001524 -135.385302) (xy 126.994435 -135.37972) (xy 126.97752 -135.37347) (xy 126.968504 -135.37311)
			(xy 126.901448 -135.37311) (xy 126.892433 -135.373488) (xy 126.875516 -135.379721) (xy 126.868428 -135.385302)
			(xy 126.868428 -135.385556) (xy 126.868174 -135.385556) (xy 126.847219 -135.403167) (xy 126.801253 -135.432885)
			(xy 126.751512 -135.455727) (xy 126.699016 -135.471224) (xy 126.644844 -135.479059) (xy 126.617476 -135.479536)
			(xy 126.58856 -135.478987) (xy 126.531389 -135.470268) (xy 126.47619 -135.453018) (xy 126.424227 -135.427632)
			(xy 126.376693 -135.394692) (xy 126.334676 -135.354954) (xy 126.316486 -135.33247) (xy 126.308668 -135.323509)
			(xy 126.287222 -135.313305) (xy 126.275338 -135.312912) (xy 126.181866 -135.314944) (xy 126.16053 -135.32612)
			(xy 126.153672 -135.336026) (xy 126.138249 -135.356917) (xy 126.102675 -135.394743) (xy 126.062299 -135.427397)
			(xy 126.017869 -135.454273) (xy 125.970205 -135.474877) (xy 125.920187 -135.488826) (xy 125.868739 -135.495864)
			(xy 125.842776 -135.4963) (xy 125.815525 -135.495829) (xy 125.761579 -135.488069) (xy 125.709286 -135.472712)
			(xy 125.659711 -135.450069) (xy 125.613862 -135.420601) (xy 125.572674 -135.384909) (xy 125.536985 -135.343718)
			(xy 125.50752 -135.297868) (xy 125.48488 -135.248291) (xy 125.469526 -135.195997) (xy 125.46177 -135.142051)
			(xy 124.664724 -135.142051) (xy 124.664724 -135.409432) (xy 124.665433 -135.421591) (xy 124.676561 -135.443213)
			(xy 124.68606 -135.450834) (xy 124.763276 -135.506206) (xy 124.787406 -135.509762) (xy 124.79909 -135.505698)
			(xy 124.828874 -135.496233) (xy 124.890527 -135.486025) (xy 124.921772 -135.485378) (xy 124.949025 -135.485867)
			(xy 125.002977 -135.493621) (xy 125.055276 -135.508974) (xy 125.104858 -135.531614) (xy 125.150713 -135.56108)
			(xy 125.191908 -135.596772) (xy 125.227603 -135.637964) (xy 125.257073 -135.683817) (xy 125.279716 -135.733397)
			(xy 125.295073 -135.785695) (xy 125.302831 -135.839647) (xy 125.302831 -135.894153) (xy 125.295073 -135.948105)
			(xy 125.279716 -136.000403) (xy 125.257073 -136.049983) (xy 125.227603 -136.095836) (xy 125.191908 -136.137028)
			(xy 125.150713 -136.17272) (xy 125.104858 -136.202186) (xy 125.055276 -136.224826) (xy 125.002977 -136.240179)
			(xy 124.949025 -136.247933) (xy 124.921772 -136.248394) (xy 124.890525 -136.24777) (xy 124.828871 -136.237554)
			(xy 124.79909 -136.228074) (xy 124.787406 -136.22401) (xy 124.763276 -136.227566) (xy 124.68606 -136.282938)
			(xy 124.676579 -136.29058) (xy 124.665428 -136.312185) (xy 124.664724 -136.32434) (xy 124.664724 -136.968992)
			(xy 124.665222 -136.979828) (xy 124.674187 -136.999561) (xy 124.681996 -137.007092) (xy 124.7394 -137.057638)
			(xy 124.747853 -137.064238) (xy 124.768324 -137.070546) (xy 124.779024 -137.06983) (xy 124.779278 -137.06983)
			(xy 124.791165 -137.06841) (xy 124.815059 -137.066882) (xy 124.82703 -137.066782) (xy 124.854279 -137.06729)
			(xy 124.908222 -137.07505) (xy 124.960512 -137.090407) (xy 125.010084 -137.11305) (xy 125.055929 -137.142516)
			(xy 125.097115 -137.178206) (xy 125.132802 -137.219395) (xy 125.162265 -137.265242) (xy 125.167329 -137.276332)
			(xy 129.147062 -137.276332) (xy 129.147532 -137.248962) (xy 129.155346 -137.194782) (xy 129.170834 -137.142279)
			(xy 129.193675 -137.092532) (xy 129.2234 -137.046565) (xy 129.241042 -137.025634) (xy 129.241296 -137.02538)
			(xy 129.246897 -137.018303) (xy 129.253135 -137.001379) (xy 129.253488 -136.99236) (xy 129.253488 -136.925304)
			(xy 129.253132 -136.916287) (xy 129.246884 -136.89937) (xy 129.241296 -136.892284) (xy 129.241042 -136.892284)
			(xy 129.241042 -136.89203) (xy 129.22341 -136.871092) (xy 129.193696 -136.825122) (xy 129.170858 -136.775376)
			(xy 129.155365 -136.722876) (xy 129.147536 -136.668701) (xy 129.147062 -136.641332) (xy 129.147548 -136.614081)
			(xy 129.155304 -136.560133) (xy 129.170659 -136.507838) (xy 129.193301 -136.458261) (xy 129.222767 -136.412411)
			(xy 129.258458 -136.37122) (xy 129.299649 -136.335529) (xy 129.345499 -136.306063) (xy 129.395076 -136.283421)
			(xy 129.447371 -136.268066) (xy 129.501319 -136.26031) (xy 129.555821 -136.26031) (xy 129.609769 -136.268066)
			(xy 129.662064 -136.283421) (xy 129.711641 -136.306063) (xy 129.757491 -136.335529) (xy 129.798682 -136.37122)
			(xy 129.834373 -136.412411) (xy 129.863839 -136.458261) (xy 129.886481 -136.507838) (xy 129.901836 -136.560133)
			(xy 129.909592 -136.614081) (xy 129.910078 -136.641332) (xy 129.909636 -136.668703) (xy 129.901813 -136.722883)
			(xy 129.886319 -136.775387) (xy 129.863472 -136.825134) (xy 129.833742 -136.871099) (xy 129.816098 -136.89203)
			(xy 129.815844 -136.892284) (xy 129.810251 -136.899366) (xy 129.80401 -136.916287) (xy 129.803652 -136.925304)
			(xy 129.803652 -136.99236) (xy 129.804017 -137.001376) (xy 129.810258 -137.018294) (xy 129.815844 -137.02538)
			(xy 129.816098 -137.02538) (xy 129.816098 -137.025634) (xy 129.833719 -137.04658) (xy 129.863434 -137.092549)
			(xy 129.886273 -137.142293) (xy 129.901769 -137.194791) (xy 129.909601 -137.248964) (xy 129.910078 -137.276332)
			(xy 129.909592 -137.303583) (xy 129.901836 -137.357531) (xy 129.886481 -137.409826) (xy 129.863839 -137.459403)
			(xy 129.834373 -137.505253) (xy 129.798682 -137.546444) (xy 129.757491 -137.582135) (xy 129.711641 -137.611601)
			(xy 129.662064 -137.634243) (xy 129.609769 -137.649598) (xy 129.555821 -137.657354) (xy 129.501319 -137.657354)
			(xy 129.447371 -137.649598) (xy 129.395076 -137.634243) (xy 129.345499 -137.611601) (xy 129.299649 -137.582135)
			(xy 129.258458 -137.546444) (xy 129.222767 -137.505253) (xy 129.193301 -137.459403) (xy 129.170659 -137.409826)
			(xy 129.155304 -137.357531) (xy 129.147548 -137.303583) (xy 129.147062 -137.276332) (xy 125.167329 -137.276332)
			(xy 125.184903 -137.314816) (xy 125.200256 -137.367107) (xy 125.208012 -137.421051) (xy 125.208012 -137.475549)
			(xy 125.200256 -137.529493) (xy 125.184903 -137.581784) (xy 125.162265 -137.631358) (xy 125.132802 -137.677205)
			(xy 125.097115 -137.718394) (xy 125.08756 -137.726674) (xy 130.087624 -137.726674) (xy 130.088069 -137.699303)
			(xy 130.095891 -137.645123) (xy 130.111385 -137.592619) (xy 130.134231 -137.542873) (xy 130.16396 -137.496907)
			(xy 130.181604 -137.475976) (xy 130.181858 -137.475722) (xy 130.187448 -137.468638) (xy 130.193691 -137.451719)
			(xy 130.19405 -137.442702) (xy 130.19405 -137.375646) (xy 130.193682 -137.36663) (xy 130.187443 -137.349712)
			(xy 130.181858 -137.342626) (xy 130.181604 -137.342626) (xy 130.181604 -137.342372) (xy 130.163986 -137.321423)
			(xy 130.134271 -137.275455) (xy 130.111431 -137.225712) (xy 130.095935 -137.173215) (xy 130.088101 -137.119042)
			(xy 130.087624 -137.091674) (xy 130.08811 -137.064423) (xy 130.095866 -137.010475) (xy 130.111221 -136.95818)
			(xy 130.133863 -136.908603) (xy 130.163329 -136.862753) (xy 130.19902 -136.821562) (xy 130.240211 -136.785871)
			(xy 130.286061 -136.756405) (xy 130.335638 -136.733763) (xy 130.387933 -136.718408) (xy 130.441881 -136.710652)
			(xy 130.496383 -136.710652) (xy 130.550331 -136.718408) (xy 130.602626 -136.733763) (xy 130.652203 -136.756405)
			(xy 130.698053 -136.785871) (xy 130.739244 -136.821562) (xy 130.774935 -136.862753) (xy 130.804401 -136.908603)
			(xy 130.827043 -136.95818) (xy 130.842398 -137.010475) (xy 130.850154 -137.064423) (xy 130.85064 -137.091674)
			(xy 130.850173 -137.119044) (xy 130.842358 -137.173224) (xy 130.82687 -137.225728) (xy 130.804028 -137.275475)
			(xy 130.774302 -137.321441) (xy 130.75666 -137.342372) (xy 130.756406 -137.342626) (xy 130.750845 -137.34973)
			(xy 130.744583 -137.366633) (xy 130.744214 -137.375646) (xy 130.744214 -137.442702) (xy 130.744567 -137.451719)
			(xy 130.750817 -137.468636) (xy 130.756406 -137.475722) (xy 130.75666 -137.475722) (xy 130.75666 -137.475976)
			(xy 130.774295 -137.496911) (xy 130.804009 -137.542883) (xy 130.826846 -137.592629) (xy 130.842338 -137.645129)
			(xy 130.850166 -137.699305) (xy 130.85064 -137.726674) (xy 130.850154 -137.753925) (xy 130.842398 -137.807873)
			(xy 130.827043 -137.860168) (xy 130.804401 -137.909745) (xy 130.774935 -137.955595) (xy 130.739244 -137.996786)
			(xy 130.698053 -138.032477) (xy 130.652203 -138.061943) (xy 130.602626 -138.084585) (xy 130.550331 -138.09994)
			(xy 130.496383 -138.107696) (xy 130.441881 -138.107696) (xy 130.387933 -138.09994) (xy 130.335638 -138.084585)
			(xy 130.286061 -138.061943) (xy 130.240211 -138.032477) (xy 130.19902 -137.996786) (xy 130.163329 -137.955595)
			(xy 130.133863 -137.909745) (xy 130.111221 -137.860168) (xy 130.095866 -137.807873) (xy 130.08811 -137.753925)
			(xy 130.087624 -137.726674) (xy 125.08756 -137.726674) (xy 125.055929 -137.754084) (xy 125.010084 -137.78355)
			(xy 124.960512 -137.806193) (xy 124.908222 -137.82155) (xy 124.854279 -137.82931) (xy 124.82703 -137.829798)
			(xy 124.815059 -137.829681) (xy 124.791166 -137.828159) (xy 124.779278 -137.82675) (xy 124.779024 -137.82675)
			(xy 124.768308 -137.825874) (xy 124.747777 -137.832201) (xy 124.7394 -137.838942) (xy 124.681996 -137.889488)
			(xy 124.674152 -137.896988) (xy 124.665215 -137.916745) (xy 124.664724 -137.927588) (xy 124.664724 -138.347704)
			(xy 124.665252 -138.358724) (xy 124.674478 -138.378741) (xy 124.682504 -138.386312) (xy 124.702632 -138.40333)
			(xy 131.296156 -138.40333) (xy 131.296666 -138.375664) (xy 131.304662 -138.320914) (xy 131.320477 -138.267891)
			(xy 131.34378 -138.217706) (xy 131.374082 -138.17141) (xy 131.41075 -138.129973) (xy 131.453014 -138.094262)
			(xy 131.476242 -138.079226) (xy 131.485908 -138.072576) (xy 131.498358 -138.052725) (xy 131.500118 -138.041126)
			(xy 131.507992 -137.961116) (xy 131.508594 -137.949479) (xy 131.500533 -137.927644) (xy 131.492498 -137.919206)
			(xy 131.492244 -137.918952) (xy 131.473666 -137.900868) (xy 131.441085 -137.860538) (xy 131.414271 -137.816164)
			(xy 131.393717 -137.768566) (xy 131.379804 -137.718622) (xy 131.372787 -137.667253) (xy 131.372356 -137.64133)
			(xy 131.372906 -137.614081) (xy 131.380658 -137.560138) (xy 131.396007 -137.507846) (xy 131.418642 -137.458272)
			(xy 131.448102 -137.412423) (xy 131.483787 -137.371233) (xy 131.52497 -137.335541) (xy 131.570814 -137.306074)
			(xy 131.620384 -137.28343) (xy 131.672673 -137.268072) (xy 131.726615 -137.260311) (xy 131.753864 -137.259822)
			(xy 131.781234 -137.260304) (xy 131.835412 -137.268117) (xy 131.887915 -137.283602) (xy 131.937663 -137.30644)
			(xy 131.98363 -137.336162) (xy 132.004562 -137.353802) (xy 132.004816 -137.354056) (xy 132.011889 -137.359662)
			(xy 132.028816 -137.365896) (xy 132.037836 -137.366248) (xy 132.104892 -137.366248) (xy 132.11391 -137.365898)
			(xy 132.130827 -137.359647) (xy 132.137912 -137.354056) (xy 132.137912 -137.353802) (xy 132.138166 -137.353802)
			(xy 132.1591 -137.336166) (xy 132.205072 -137.306453) (xy 132.254819 -137.283617) (xy 132.30732 -137.268125)
			(xy 132.361495 -137.260296) (xy 132.388864 -137.259822) (xy 132.416117 -137.260289) (xy 132.47007 -137.268042)
			(xy 132.522369 -137.283395) (xy 132.571951 -137.306035) (xy 132.617806 -137.335502) (xy 132.659 -137.371196)
			(xy 132.694694 -137.412389) (xy 132.724162 -137.458243) (xy 132.746803 -137.507825) (xy 132.762157 -137.560124)
			(xy 132.769911 -137.614077) (xy 132.770372 -137.64133) (xy 132.769814 -137.670246) (xy 132.761095 -137.727415)
			(xy 132.743846 -137.782614) (xy 132.718461 -137.834576) (xy 132.685524 -137.882111) (xy 132.645789 -137.924129)
			(xy 132.623306 -137.94232) (xy 132.614501 -137.949929) (xy 132.604316 -137.970828) (xy 132.603748 -137.982452)
			(xy 132.603748 -138.062208) (xy 132.60428 -138.073841) (xy 132.614472 -138.094752) (xy 132.623306 -138.10234)
			(xy 132.64581 -138.120507) (xy 132.685544 -138.162532) (xy 132.71848 -138.210072) (xy 132.743865 -138.262038)
			(xy 132.761117 -138.31724) (xy 132.76984 -138.374413) (xy 132.770372 -138.40333) (xy 132.769973 -138.430585)
			(xy 132.762211 -138.48454) (xy 132.750105 -138.525758) (xy 133.041644 -138.525758) (xy 133.042133 -138.498388)
			(xy 133.049944 -138.44421) (xy 133.065427 -138.391707) (xy 133.088264 -138.341959) (xy 133.117984 -138.295992)
			(xy 133.135624 -138.27506) (xy 133.135878 -138.274806) (xy 133.141477 -138.267729) (xy 133.147714 -138.250804)
			(xy 133.14807 -138.241786) (xy 133.14807 -138.17473) (xy 133.147705 -138.165714) (xy 133.141464 -138.148797)
			(xy 133.135878 -138.14171) (xy 133.135624 -138.14171) (xy 133.135624 -138.141456) (xy 133.117942 -138.120557)
			(xy 133.088219 -138.074583) (xy 133.065377 -138.024831) (xy 133.049884 -137.972324) (xy 133.042059 -137.918141)
			(xy 133.042064 -137.863396) (xy 133.049897 -137.809214) (xy 133.065399 -137.75671) (xy 133.08825 -137.706962)
			(xy 133.11798 -137.660993) (xy 133.135624 -137.64006) (xy 133.135878 -137.639806) (xy 133.141477 -137.632729)
			(xy 133.147714 -137.615804) (xy 133.14807 -137.606786) (xy 133.14807 -137.53973) (xy 133.147705 -137.530714)
			(xy 133.141464 -137.513797) (xy 133.135878 -137.50671) (xy 133.135624 -137.50671) (xy 133.135624 -137.506456)
			(xy 133.117942 -137.485557) (xy 133.088219 -137.439583) (xy 133.065377 -137.389831) (xy 133.049884 -137.337324)
			(xy 133.042059 -137.283141) (xy 133.042064 -137.228396) (xy 133.049897 -137.174214) (xy 133.065399 -137.12171)
			(xy 133.08825 -137.071962) (xy 133.11798 -137.025993) (xy 133.135624 -137.00506) (xy 133.135878 -137.004806)
			(xy 133.141477 -136.997729) (xy 133.147714 -136.980804) (xy 133.14807 -136.971786) (xy 133.14807 -136.90473)
			(xy 133.147705 -136.895714) (xy 133.141464 -136.878797) (xy 133.135878 -136.87171) (xy 133.135624 -136.87171)
			(xy 133.135624 -136.871456) (xy 133.118001 -136.850511) (xy 133.088286 -136.804542) (xy 133.065447 -136.754798)
			(xy 133.049952 -136.7023) (xy 133.04212 -136.648126) (xy 133.041644 -136.620758) (xy 133.04213 -136.593507)
			(xy 133.049886 -136.539559) (xy 133.065241 -136.487264) (xy 133.087883 -136.437687) (xy 133.117349 -136.391837)
			(xy 133.15304 -136.350646) (xy 133.194231 -136.314955) (xy 133.240081 -136.285489) (xy 133.289658 -136.262847)
			(xy 133.341953 -136.247492) (xy 133.395901 -136.239736) (xy 133.450403 -136.239736) (xy 133.504351 -136.247492)
			(xy 133.556646 -136.262847) (xy 133.606223 -136.285489) (xy 133.652073 -136.314955) (xy 133.693264 -136.350646)
			(xy 133.728955 -136.391837) (xy 133.758421 -136.437687) (xy 133.781063 -136.487264) (xy 133.796418 -136.539559)
			(xy 133.804174 -136.593507) (xy 133.80466 -136.620758) (xy 133.804179 -136.648128) (xy 133.796366 -136.702307)
			(xy 133.780881 -136.75481) (xy 133.758043 -136.804557) (xy 133.72832 -136.850524) (xy 133.71068 -136.871456)
			(xy 133.710426 -136.87171) (xy 133.70482 -136.878783) (xy 133.698587 -136.895711) (xy 133.698234 -136.90473)
			(xy 133.698234 -136.971786) (xy 133.698591 -136.980803) (xy 133.704838 -136.99772) (xy 133.710426 -137.004806)
			(xy 133.71068 -137.004806) (xy 133.71068 -137.00506) (xy 133.728279 -137.026026) (xy 133.758005 -137.071988)
			(xy 133.780853 -137.121729) (xy 133.796352 -137.174226) (xy 133.804184 -137.2284) (xy 133.804189 -137.283137)
			(xy 133.796365 -137.337312) (xy 133.780875 -137.389812) (xy 133.758036 -137.439556) (xy 133.728317 -137.485523)
			(xy 133.71068 -137.506456) (xy 133.710426 -137.50671) (xy 133.70482 -137.513783) (xy 133.698587 -137.530711)
			(xy 133.698234 -137.53973) (xy 133.698234 -137.606786) (xy 133.698591 -137.615803) (xy 133.704838 -137.63272)
			(xy 133.710426 -137.639806) (xy 133.71068 -137.639806) (xy 133.71068 -137.64006) (xy 133.728279 -137.661026)
			(xy 133.758005 -137.706988) (xy 133.780853 -137.756729) (xy 133.796352 -137.809226) (xy 133.804184 -137.8634)
			(xy 133.804189 -137.918137) (xy 133.796365 -137.972312) (xy 133.780875 -138.024812) (xy 133.758036 -138.074556)
			(xy 133.728317 -138.120523) (xy 133.71068 -138.141456) (xy 133.710426 -138.14171) (xy 133.70482 -138.148783)
			(xy 133.698587 -138.165711) (xy 133.698234 -138.17473) (xy 133.698234 -138.241786) (xy 133.698591 -138.250803)
			(xy 133.704838 -138.26772) (xy 133.710426 -138.274806) (xy 133.71068 -138.274806) (xy 133.71068 -138.27506)
			(xy 133.728311 -138.295999) (xy 133.758024 -138.34197) (xy 133.780862 -138.391715) (xy 133.796355 -138.444215)
			(xy 133.804185 -138.498389) (xy 133.80466 -138.525758) (xy 133.804185 -138.552387) (xy 133.796782 -138.605129)
			(xy 133.782114 -138.656328) (xy 133.760466 -138.704988) (xy 133.732259 -138.750164) (xy 133.715506 -138.770868)
			(xy 133.707632 -138.780266) (xy 133.702044 -138.803634) (xy 133.723634 -138.894566) (xy 133.726994 -138.90594)
			(xy 133.742225 -138.924083) (xy 133.752844 -138.929364) (xy 133.779561 -138.941549) (xy 133.829186 -138.972936)
			(xy 133.85165 -138.991848) (xy 133.851904 -138.992102) (xy 133.858985 -138.997697) (xy 133.875906 -139.003938)
			(xy 133.884924 -139.004294) (xy 133.95198 -139.004294) (xy 133.960996 -139.003929) (xy 133.977913 -138.997687)
			(xy 133.985 -138.992102) (xy 133.985 -138.991848) (xy 133.985254 -138.991848) (xy 134.006187 -138.974207)
			(xy 134.052155 -138.944483) (xy 134.101901 -138.921637) (xy 134.154403 -138.906141) (xy 134.208581 -138.898312)
			(xy 134.263323 -138.898312) (xy 134.317501 -138.906141) (xy 134.370003 -138.921637) (xy 134.419749 -138.944483)
			(xy 134.465717 -138.974207) (xy 134.48665 -138.991848) (xy 134.486904 -138.992102) (xy 134.493985 -138.997697)
			(xy 134.510906 -139.003938) (xy 134.519924 -139.004294) (xy 134.58698 -139.004294) (xy 134.595996 -139.003929)
			(xy 134.612913 -138.997687) (xy 134.62 -138.992102) (xy 134.62 -138.991848) (xy 134.620254 -138.991848)
			(xy 134.641187 -138.974207) (xy 134.687155 -138.944483) (xy 134.736901 -138.921637) (xy 134.789403 -138.906141)
			(xy 134.843581 -138.898312) (xy 134.898323 -138.898312) (xy 134.952501 -138.906141) (xy 135.005003 -138.921637)
			(xy 135.054749 -138.944483) (xy 135.100717 -138.974207) (xy 135.12165 -138.991848) (xy 135.121904 -138.992102)
			(xy 135.128985 -138.997697) (xy 135.145906 -139.003938) (xy 135.154924 -139.004294) (xy 135.22198 -139.004294)
			(xy 135.230996 -139.003929) (xy 135.247913 -138.997687) (xy 135.255 -138.992102) (xy 135.255 -138.991848)
			(xy 135.255254 -138.991848) (xy 135.276199 -138.974224) (xy 135.322167 -138.944509) (xy 135.371912 -138.921669)
			(xy 135.42441 -138.906174) (xy 135.478584 -138.898343) (xy 135.505952 -138.897868) (xy 135.533205 -138.898376)
			(xy 135.587158 -138.906127) (xy 135.639458 -138.921478) (xy 135.689041 -138.944116) (xy 135.734898 -138.973581)
			(xy 135.776094 -139.009272) (xy 135.81179 -139.050464) (xy 135.841261 -139.096316) (xy 135.863905 -139.145897)
			(xy 135.879263 -139.198195) (xy 135.887021 -139.252147) (xy 135.887021 -139.306653) (xy 135.879263 -139.360605)
			(xy 135.863905 -139.412903) (xy 135.841261 -139.462484) (xy 135.81179 -139.508336) (xy 135.776094 -139.549528)
			(xy 135.734898 -139.585219) (xy 135.689041 -139.614684) (xy 135.639458 -139.637322) (xy 135.587158 -139.652673)
			(xy 135.533205 -139.660424) (xy 135.505952 -139.660884) (xy 135.478583 -139.660391) (xy 135.424405 -139.652581)
			(xy 135.371902 -139.637098) (xy 135.322154 -139.614262) (xy 135.276186 -139.584543) (xy 135.255254 -139.566904)
			(xy 135.255 -139.56665) (xy 135.247922 -139.561051) (xy 135.230998 -139.554813) (xy 135.22198 -139.554458)
			(xy 135.154924 -139.554458) (xy 135.145907 -139.554814) (xy 135.128989 -139.561061) (xy 135.121904 -139.56665)
			(xy 135.121904 -139.566904) (xy 135.12165 -139.566904) (xy 135.100717 -139.584545) (xy 135.054749 -139.614269)
			(xy 135.005003 -139.637115) (xy 134.952501 -139.652611) (xy 134.898323 -139.66044) (xy 134.843581 -139.66044)
			(xy 134.789403 -139.652611) (xy 134.736901 -139.637115) (xy 134.687155 -139.614269) (xy 134.641187 -139.584545)
			(xy 134.620254 -139.566904) (xy 134.62 -139.56665) (xy 134.612922 -139.561051) (xy 134.595998 -139.554813)
			(xy 134.58698 -139.554458) (xy 134.519924 -139.554458) (xy 134.510907 -139.554814) (xy 134.493989 -139.561061)
			(xy 134.486904 -139.56665) (xy 134.486904 -139.566904) (xy 134.48665 -139.566904) (xy 134.465717 -139.584545)
			(xy 134.419749 -139.614269) (xy 134.370003 -139.637115) (xy 134.317501 -139.652611) (xy 134.263323 -139.66044)
			(xy 134.208581 -139.66044) (xy 134.154403 -139.652611) (xy 134.101901 -139.637115) (xy 134.052155 -139.614269)
			(xy 134.006187 -139.584545) (xy 133.985254 -139.566904) (xy 133.985 -139.56665) (xy 133.977922 -139.561051)
			(xy 133.960998 -139.554813) (xy 133.95198 -139.554458) (xy 133.884924 -139.554458) (xy 133.875907 -139.554814)
			(xy 133.858989 -139.561061) (xy 133.851904 -139.56665) (xy 133.851904 -139.566904) (xy 133.85165 -139.566904)
			(xy 133.83071 -139.584534) (xy 133.78474 -139.614247) (xy 133.734994 -139.637085) (xy 133.682495 -139.652578)
			(xy 133.628321 -139.660409) (xy 133.600952 -139.660884) (xy 133.573698 -139.660467) (xy 133.519747 -139.652703)
			(xy 133.46745 -139.637341) (xy 133.417871 -139.614692) (xy 133.372019 -139.585219) (xy 133.330829 -139.54952)
			(xy 133.295138 -139.508323) (xy 133.265673 -139.462466) (xy 133.243034 -139.412883) (xy 133.227682 -139.360583)
			(xy 133.219928 -139.30663) (xy 133.219444 -139.279376) (xy 133.21988 -139.252745) (xy 133.227292 -139.200002)
			(xy 133.241969 -139.148803) (xy 133.263626 -139.100143) (xy 133.291841 -139.054969) (xy 133.308598 -139.034266)
			(xy 133.316472 -139.024868) (xy 133.32206 -139.0015) (xy 133.30047 -138.910568) (xy 133.297138 -138.899183)
			(xy 133.281886 -138.881047) (xy 133.27126 -138.87577) (xy 133.246048 -138.864275) (xy 133.198951 -138.835085)
			(xy 133.156571 -138.799391) (xy 133.119797 -138.757944) (xy 133.089403 -138.711615) (xy 133.066029 -138.661377)
			(xy 133.050164 -138.608288) (xy 133.042143 -138.553462) (xy 133.041644 -138.525758) (xy 132.750105 -138.525758)
			(xy 132.746849 -138.536842) (xy 132.724201 -138.586424) (xy 132.694726 -138.632279) (xy 132.659026 -138.673472)
			(xy 132.617826 -138.709166) (xy 132.571966 -138.738632) (xy 132.52238 -138.761272) (xy 132.470076 -138.776625)
			(xy 132.416119 -138.784378) (xy 132.388864 -138.784838) (xy 132.362548 -138.784414) (xy 132.310417 -138.777173)
			(xy 132.259773 -138.762847) (xy 132.211573 -138.741706) (xy 132.166731 -138.714152) (xy 132.126094 -138.680704)
			(xy 132.10794 -138.661648) (xy 132.100399 -138.654269) (xy 132.081134 -138.64573) (xy 132.070602 -138.645138)
			(xy 131.995926 -138.645138) (xy 131.985375 -138.645657) (xy 131.966079 -138.654198) (xy 131.958588 -138.661648)
			(xy 131.940441 -138.680712) (xy 131.899808 -138.714166) (xy 131.854966 -138.741723) (xy 131.806764 -138.76286)
			(xy 131.756115 -138.777176) (xy 131.70398 -138.7844) (xy 131.677664 -138.784838) (xy 131.650413 -138.784356)
			(xy 131.596467 -138.776595) (xy 131.544174 -138.761237) (xy 131.494599 -138.738594) (xy 131.44875 -138.709127)
			(xy 131.407561 -138.673435) (xy 131.37187 -138.632245) (xy 131.342403 -138.586396) (xy 131.319761 -138.53682)
			(xy 131.304404 -138.484527) (xy 131.296644 -138.430581) (xy 131.296156 -138.40333) (xy 124.702632 -138.40333)
			(xy 124.741686 -138.43635) (xy 124.750406 -138.443099) (xy 124.771622 -138.449021) (xy 124.78258 -138.44778)
			(xy 124.782834 -138.44778) (xy 124.79797 -138.445497) (xy 124.828487 -138.443084) (xy 124.843794 -138.442954)
			(xy 124.871044 -138.443493) (xy 124.924991 -138.451248) (xy 124.977284 -138.466602) (xy 125.02686 -138.489242)
			(xy 125.072709 -138.518707) (xy 125.113899 -138.554397) (xy 125.149589 -138.595586) (xy 125.179055 -138.641435)
			(xy 125.201696 -138.69101) (xy 125.21705 -138.743304) (xy 125.224807 -138.79725) (xy 125.224807 -138.85175)
			(xy 125.21705 -138.905696) (xy 125.201696 -138.95799) (xy 125.179055 -139.007565) (xy 125.149589 -139.053414)
			(xy 125.113899 -139.094603) (xy 125.072709 -139.130293) (xy 125.02686 -139.159758) (xy 124.977284 -139.182398)
			(xy 124.924991 -139.197752) (xy 124.871044 -139.205507) (xy 124.843794 -139.20597) (xy 124.828488 -139.205834)
			(xy 124.797971 -139.203418) (xy 124.782834 -139.201144) (xy 124.78258 -139.201144) (xy 124.771628 -139.199954)
			(xy 124.750431 -139.205874) (xy 124.741686 -139.212574) (xy 124.682504 -139.262612) (xy 124.674478 -139.270182)
			(xy 124.665261 -139.2902) (xy 124.664724 -139.30122) (xy 124.664724 -139.916662) (xy 124.665317 -139.927803)
			(xy 124.674804 -139.947967) (xy 124.683012 -139.955524) (xy 124.751338 -140.012674) (xy 124.772674 -140.018516)
			(xy 124.78385 -140.016484) (xy 124.800166 -140.013832) (xy 124.833106 -140.011037) (xy 124.849636 -140.010896)
			(xy 124.876886 -140.011376) (xy 124.93083 -140.019137) (xy 124.983121 -140.034495) (xy 125.032694 -140.057139)
			(xy 125.078541 -140.086606) (xy 125.119727 -140.122298) (xy 125.155415 -140.163488) (xy 125.184878 -140.209337)
			(xy 125.207517 -140.258913) (xy 125.222871 -140.311205) (xy 125.230626 -140.36515) (xy 125.230626 -140.41965)
			(xy 125.222871 -140.473595) (xy 125.207517 -140.525887) (xy 125.184878 -140.575463) (xy 125.155415 -140.621312)
			(xy 125.119727 -140.662502) (xy 125.078541 -140.698194) (xy 125.032694 -140.727661) (xy 124.983121 -140.750305)
			(xy 124.93083 -140.765663) (xy 124.876886 -140.773424) (xy 124.849636 -140.773912) (xy 124.833107 -140.773769)
			(xy 124.800167 -140.770969) (xy 124.78385 -140.768324) (xy 124.772674 -140.766292) (xy 124.751338 -140.772134)
			(xy 124.683012 -140.829284) (xy 124.674837 -140.836865) (xy 124.665353 -140.857015) (xy 124.664724 -140.868146)
			(xy 124.664724 -141.046551) (xy 126.854954 -141.046551) (xy 126.854954 -140.992049) (xy 126.86271 -140.9381)
			(xy 126.878064 -140.885805) (xy 126.900704 -140.836227) (xy 126.930169 -140.790375) (xy 126.965859 -140.749183)
			(xy 127.007048 -140.71349) (xy 127.052897 -140.684021) (xy 127.102473 -140.661376) (xy 127.154767 -140.646017)
			(xy 127.208715 -140.638256) (xy 127.235966 -140.637768) (xy 127.262281 -140.638202) (xy 127.314411 -140.645445)
			(xy 127.365054 -140.659771) (xy 127.413252 -140.68091) (xy 127.458095 -140.708462) (xy 127.498734 -140.741905)
			(xy 127.51689 -140.760958) (xy 127.524419 -140.768351) (xy 127.543693 -140.776882) (xy 127.554228 -140.777468)
			(xy 127.628904 -140.777468) (xy 127.639457 -140.776964) (xy 127.658752 -140.768412) (xy 127.666242 -140.760958)
			(xy 127.684376 -140.741881) (xy 127.725011 -140.708427) (xy 127.769856 -140.680872) (xy 127.818061 -140.659738)
			(xy 127.868712 -140.645425) (xy 127.920849 -140.638204) (xy 127.947166 -140.637768) (xy 127.974419 -140.638277)
			(xy 128.02837 -140.64603) (xy 128.080669 -140.661382) (xy 128.13025 -140.684021) (xy 128.176104 -140.713486)
			(xy 128.217299 -140.749177) (xy 128.252994 -140.790368) (xy 128.282463 -140.83622) (xy 128.305106 -140.8858)
			(xy 128.320463 -140.938097) (xy 128.328221 -140.992047) (xy 128.328221 -141.046553) (xy 128.320463 -141.100503)
			(xy 128.305106 -141.1528) (xy 128.282463 -141.20238) (xy 128.252994 -141.248232) (xy 128.217299 -141.289423)
			(xy 128.176104 -141.325114) (xy 128.13025 -141.354579) (xy 128.080669 -141.377218) (xy 128.02837 -141.39257)
			(xy 127.974419 -141.400323) (xy 127.947166 -141.400784) (xy 127.920851 -141.400344) (xy 127.868721 -141.393105)
			(xy 127.818078 -141.37878) (xy 127.769879 -141.357643) (xy 127.725036 -141.330092) (xy 127.684398 -141.296648)
			(xy 127.666242 -141.277594) (xy 127.658707 -141.270208) (xy 127.639437 -141.261675) (xy 127.628904 -141.261084)
			(xy 127.554228 -141.261084) (xy 127.543679 -141.26162) (xy 127.524384 -141.270151) (xy 127.51689 -141.277594)
			(xy 127.498731 -141.296646) (xy 127.458102 -141.330104) (xy 127.413263 -141.357664) (xy 127.365063 -141.378803)
			(xy 127.314416 -141.39312) (xy 127.262282 -141.400345) (xy 127.235966 -141.400784) (xy 127.208715 -141.400344)
			(xy 127.154767 -141.392583) (xy 127.102473 -141.377224) (xy 127.052897 -141.354579) (xy 127.007048 -141.32511)
			(xy 126.965859 -141.289417) (xy 126.930169 -141.248225) (xy 126.900704 -141.202373) (xy 126.878064 -141.152795)
			(xy 126.86271 -141.1005) (xy 126.854954 -141.046551) (xy 124.664724 -141.046551) (xy 124.664724 -143.078551)
			(xy 126.854954 -143.078551) (xy 126.854954 -143.024049) (xy 126.86271 -142.9701) (xy 126.878064 -142.917805)
			(xy 126.900704 -142.868227) (xy 126.930169 -142.822375) (xy 126.965859 -142.781183) (xy 127.007048 -142.74549)
			(xy 127.052897 -142.716021) (xy 127.102473 -142.693376) (xy 127.154767 -142.678017) (xy 127.208715 -142.670256)
			(xy 127.235966 -142.669768) (xy 127.262281 -142.670202) (xy 127.314411 -142.677445) (xy 127.365054 -142.691771)
			(xy 127.413252 -142.71291) (xy 127.458095 -142.740462) (xy 127.498734 -142.773905) (xy 127.51689 -142.792958)
			(xy 127.524419 -142.800351) (xy 127.543693 -142.808882) (xy 127.554228 -142.809468) (xy 127.628904 -142.809468)
			(xy 127.639457 -142.808964) (xy 127.658752 -142.800412) (xy 127.666242 -142.792958) (xy 127.684376 -142.773881)
			(xy 127.725011 -142.740427) (xy 127.769856 -142.712872) (xy 127.818061 -142.691738) (xy 127.868712 -142.677425)
			(xy 127.920849 -142.670204) (xy 127.947166 -142.669768) (xy 127.974419 -142.670277) (xy 128.02837 -142.67803)
			(xy 128.080669 -142.693382) (xy 128.13025 -142.716021) (xy 128.176104 -142.745486) (xy 128.217299 -142.781177)
			(xy 128.252994 -142.822368) (xy 128.282463 -142.86822) (xy 128.305106 -142.9178) (xy 128.320463 -142.970097)
			(xy 128.328221 -143.024047) (xy 128.328221 -143.078553) (xy 128.320463 -143.132503) (xy 128.305106 -143.1848)
			(xy 128.282463 -143.23438) (xy 128.252994 -143.280232) (xy 128.217299 -143.321423) (xy 128.176104 -143.357114)
			(xy 128.13025 -143.386579) (xy 128.080669 -143.409218) (xy 128.02837 -143.42457) (xy 127.974419 -143.432323)
			(xy 127.947166 -143.432784) (xy 127.920851 -143.432344) (xy 127.868721 -143.425105) (xy 127.818078 -143.41078)
			(xy 127.769879 -143.389643) (xy 127.725036 -143.362092) (xy 127.684398 -143.328648) (xy 127.666242 -143.309594)
			(xy 127.658707 -143.302208) (xy 127.639437 -143.293675) (xy 127.628904 -143.293084) (xy 127.554228 -143.293084)
			(xy 127.543679 -143.29362) (xy 127.524384 -143.302151) (xy 127.51689 -143.309594) (xy 127.498731 -143.328646)
			(xy 127.458102 -143.362104) (xy 127.413263 -143.389664) (xy 127.365063 -143.410803) (xy 127.314416 -143.42512)
			(xy 127.262282 -143.432345) (xy 127.235966 -143.432784) (xy 127.208715 -143.432344) (xy 127.154767 -143.424583)
			(xy 127.102473 -143.409224) (xy 127.052897 -143.386579) (xy 127.007048 -143.35711) (xy 126.965859 -143.321417)
			(xy 126.930169 -143.280225) (xy 126.900704 -143.234373) (xy 126.878064 -143.184795) (xy 126.86271 -143.1325)
			(xy 126.854954 -143.078551) (xy 124.664724 -143.078551) (xy 124.664724 -143.966438) (xy 135.564118 -143.966438)
			(xy 135.564527 -143.940462) (xy 135.571578 -143.88899) (xy 135.585553 -143.838952) (xy 135.606195 -143.791276)
			(xy 135.63312 -143.746845) (xy 135.66583 -143.706483) (xy 135.703718 -143.670936) (xy 135.724646 -143.655542)
			(xy 135.734137 -143.64791) (xy 135.745282 -143.626298) (xy 135.745982 -143.61414) (xy 135.745982 -143.531336)
			(xy 135.745289 -143.519174) (xy 135.73415 -143.497553) (xy 135.724646 -143.489934) (xy 135.703727 -143.474531)
			(xy 135.665851 -143.438978) (xy 135.633151 -143.398613) (xy 135.606232 -143.354184) (xy 135.585593 -143.306511)
			(xy 135.571616 -143.256479) (xy 135.56456 -143.205012) (xy 135.564118 -143.179038) (xy 135.564626 -143.150299)
			(xy 135.573256 -143.093472) (xy 135.590311 -143.038582) (xy 135.615405 -142.98687) (xy 135.647971 -142.939507)
			(xy 135.667242 -142.91818) (xy 135.673846 -142.911322) (xy 135.680958 -142.893288) (xy 135.680958 -142.804388)
			(xy 135.673846 -142.786354) (xy 135.667242 -142.779496) (xy 135.648008 -142.758137) (xy 135.61544 -142.710781)
			(xy 135.590345 -142.659074) (xy 135.573292 -142.604188) (xy 135.564665 -142.547365) (xy 135.564661 -142.489891)
			(xy 135.573279 -142.433066) (xy 135.590325 -142.378177) (xy 135.615412 -142.326467) (xy 135.647973 -142.279106)
			(xy 135.667242 -142.25778) (xy 135.673846 -142.250922) (xy 135.680958 -142.232888) (xy 135.680958 -142.143988)
			(xy 135.673846 -142.125954) (xy 135.667242 -142.119096) (xy 135.648008 -142.097737) (xy 135.61544 -142.050381)
			(xy 135.590345 -141.998674) (xy 135.573292 -141.943788) (xy 135.564665 -141.886965) (xy 135.564661 -141.829491)
			(xy 135.573279 -141.772666) (xy 135.590325 -141.717777) (xy 135.615412 -141.666067) (xy 135.647973 -141.618706)
			(xy 135.667242 -141.59738) (xy 135.673846 -141.590522) (xy 135.680958 -141.572488) (xy 135.680958 -141.483588)
			(xy 135.673846 -141.465554) (xy 135.667242 -141.458696) (xy 135.648008 -141.437337) (xy 135.61544 -141.389981)
			(xy 135.590345 -141.338274) (xy 135.573292 -141.283388) (xy 135.564665 -141.226565) (xy 135.564661 -141.169091)
			(xy 135.573279 -141.112266) (xy 135.590325 -141.057377) (xy 135.615412 -141.005667) (xy 135.647973 -140.958306)
			(xy 135.667242 -140.93698) (xy 135.673846 -140.930122) (xy 135.680958 -140.912088) (xy 135.680958 -140.823188)
			(xy 135.673846 -140.805154) (xy 135.667242 -140.798296) (xy 135.64799 -140.776953) (xy 135.615421 -140.729595)
			(xy 135.590325 -140.677888) (xy 135.57327 -140.623001) (xy 135.564642 -140.566176) (xy 135.564118 -140.537438)
			(xy 135.564604 -140.510187) (xy 135.57236 -140.456239) (xy 135.587715 -140.403944) (xy 135.610357 -140.354367)
			(xy 135.639823 -140.308517) (xy 135.675514 -140.267326) (xy 135.716705 -140.231635) (xy 135.762555 -140.202169)
			(xy 135.812132 -140.179527) (xy 135.864427 -140.164172) (xy 135.918375 -140.156416) (xy 135.972877 -140.156416)
			(xy 136.026825 -140.164172) (xy 136.07912 -140.179527) (xy 136.128697 -140.202169) (xy 136.174547 -140.231635)
			(xy 136.215738 -140.267326) (xy 136.251429 -140.308517) (xy 136.280895 -140.354367) (xy 136.303537 -140.403944)
			(xy 136.318892 -140.456239) (xy 136.326648 -140.510187) (xy 136.327134 -140.537438) (xy 136.326624 -140.566177)
			(xy 136.317997 -140.623005) (xy 136.300943 -140.677895) (xy 136.275849 -140.729607) (xy 136.243281 -140.776969)
			(xy 136.22401 -140.798296) (xy 136.217406 -140.805154) (xy 136.210294 -140.823188) (xy 136.210294 -140.912088)
			(xy 136.217406 -140.930122) (xy 136.22401 -140.93698) (xy 136.243317 -140.958275) (xy 136.275878 -141.005644)
			(xy 136.300965 -141.057361) (xy 136.318011 -141.112256) (xy 136.326629 -141.169087) (xy 136.326625 -141.226568)
			(xy 136.317999 -141.283398) (xy 136.300945 -141.338291) (xy 136.27585 -141.390004) (xy 136.243282 -141.437368)
			(xy 136.22401 -141.458696) (xy 136.217406 -141.465554) (xy 136.210294 -141.483588) (xy 136.210294 -141.572488)
			(xy 136.217406 -141.590522) (xy 136.22401 -141.59738) (xy 136.243317 -141.618675) (xy 136.275878 -141.666044)
			(xy 136.300965 -141.717761) (xy 136.318011 -141.772656) (xy 136.326629 -141.829487) (xy 136.326625 -141.886968)
			(xy 136.317999 -141.943798) (xy 136.300945 -141.998691) (xy 136.27585 -142.050404) (xy 136.243282 -142.097768)
			(xy 136.22401 -142.119096) (xy 136.217406 -142.125954) (xy 136.210294 -142.143988) (xy 136.210294 -142.232888)
			(xy 136.217406 -142.250922) (xy 136.22401 -142.25778) (xy 136.243317 -142.279075) (xy 136.275878 -142.326444)
			(xy 136.300965 -142.378161) (xy 136.318011 -142.433056) (xy 136.326629 -142.489887) (xy 136.326625 -142.547368)
			(xy 136.317999 -142.604198) (xy 136.300945 -142.659091) (xy 136.27585 -142.710804) (xy 136.243282 -142.758168)
			(xy 136.22401 -142.779496) (xy 136.217406 -142.786354) (xy 136.210294 -142.804388) (xy 136.210294 -142.893288)
			(xy 136.217406 -142.911322) (xy 136.22401 -142.91818) (xy 136.24329 -142.939499) (xy 136.275857 -142.986863)
			(xy 136.300948 -143.038576) (xy 136.317996 -143.093469) (xy 136.326615 -143.150298) (xy 136.327134 -143.179038)
			(xy 136.326727 -143.205015) (xy 136.319679 -143.256488) (xy 136.305704 -143.306526) (xy 136.285063 -143.354203)
			(xy 136.258137 -143.398634) (xy 136.225426 -143.438996) (xy 136.187535 -143.474541) (xy 136.166606 -143.489934)
			(xy 136.157135 -143.497587) (xy 136.145977 -143.519183) (xy 136.14527 -143.531336) (xy 136.14527 -143.61414)
			(xy 136.145957 -143.626303) (xy 136.157098 -143.647926) (xy 136.166606 -143.655542) (xy 136.187525 -143.670945)
			(xy 136.225399 -143.706499) (xy 136.258098 -143.746865) (xy 136.285015 -143.791294) (xy 136.305654 -143.838966)
			(xy 136.319632 -143.888998) (xy 136.326691 -143.940464) (xy 136.327134 -143.966438) (xy 136.326648 -143.993689)
			(xy 136.318892 -144.047637) (xy 136.303537 -144.099932) (xy 136.280895 -144.149509) (xy 136.251429 -144.195359)
			(xy 136.215738 -144.23655) (xy 136.174547 -144.272241) (xy 136.128697 -144.301707) (xy 136.07912 -144.324349)
			(xy 136.026825 -144.339704) (xy 135.972877 -144.34746) (xy 135.918375 -144.34746) (xy 135.864427 -144.339704)
			(xy 135.812132 -144.324349) (xy 135.762555 -144.301707) (xy 135.716705 -144.272241) (xy 135.675514 -144.23655)
			(xy 135.639823 -144.195359) (xy 135.610357 -144.149509) (xy 135.587715 -144.099932) (xy 135.57236 -144.047637)
			(xy 135.564604 -143.993689) (xy 135.564118 -143.966438) (xy 124.664724 -143.966438) (xy 124.664724 -145.110551)
			(xy 126.854954 -145.110551) (xy 126.854954 -145.056049) (xy 126.86271 -145.0021) (xy 126.878064 -144.949805)
			(xy 126.900704 -144.900227) (xy 126.930169 -144.854375) (xy 126.965859 -144.813183) (xy 127.007048 -144.77749)
			(xy 127.052897 -144.748021) (xy 127.102473 -144.725376) (xy 127.154767 -144.710017) (xy 127.208715 -144.702256)
			(xy 127.235966 -144.701768) (xy 127.262281 -144.702202) (xy 127.314411 -144.709445) (xy 127.365054 -144.723771)
			(xy 127.413252 -144.74491) (xy 127.458095 -144.772462) (xy 127.498734 -144.805905) (xy 127.51689 -144.824958)
			(xy 127.524419 -144.832351) (xy 127.543693 -144.840882) (xy 127.554228 -144.841468) (xy 127.628904 -144.841468)
			(xy 127.639457 -144.840964) (xy 127.658752 -144.832412) (xy 127.666242 -144.824958) (xy 127.684376 -144.805881)
			(xy 127.725011 -144.772427) (xy 127.769856 -144.744872) (xy 127.818061 -144.723738) (xy 127.868712 -144.709425)
			(xy 127.920849 -144.702204) (xy 127.947166 -144.701768) (xy 127.974419 -144.702277) (xy 128.02837 -144.71003)
			(xy 128.080669 -144.725382) (xy 128.13025 -144.748021) (xy 128.176104 -144.777486) (xy 128.217299 -144.813177)
			(xy 128.252994 -144.854368) (xy 128.282463 -144.90022) (xy 128.305106 -144.9498) (xy 128.306411 -144.954244)
			(xy 134.038848 -144.954244) (xy 134.039419 -144.926996) (xy 134.047168 -144.873054) (xy 134.062516 -144.820763)
			(xy 134.085149 -144.771189) (xy 134.114606 -144.725341) (xy 134.150289 -144.684151) (xy 134.19147 -144.648459)
			(xy 134.237312 -144.618991) (xy 134.286881 -144.596347) (xy 134.339167 -144.580987) (xy 134.393108 -144.573225)
			(xy 134.420356 -144.572736) (xy 134.44913 -144.573257) (xy 134.506025 -144.581907) (xy 134.560976 -144.599004)
			(xy 134.612736 -144.624159) (xy 134.660132 -144.656801) (xy 134.681468 -144.676114) (xy 134.689342 -144.68348)
			(xy 134.709154 -144.690592) (xy 134.80542 -144.683226) (xy 134.824216 -144.67332) (xy 134.83082 -144.664938)
			(xy 134.849055 -144.642762) (xy 134.890987 -144.603551) (xy 134.938321 -144.571063) (xy 134.989987 -144.546033)
			(xy 135.04482 -144.529025) (xy 135.101581 -144.520423) (xy 135.130286 -144.519904) (xy 135.157539 -144.520368)
			(xy 135.211491 -144.528124) (xy 135.263789 -144.543479) (xy 135.31337 -144.56612) (xy 135.359224 -144.595588)
			(xy 135.400417 -144.631282) (xy 135.436111 -144.672475) (xy 135.465579 -144.718328) (xy 135.488221 -144.767909)
			(xy 135.503576 -144.820207) (xy 135.511331 -144.874159) (xy 135.511794 -144.901412) (xy 135.511345 -144.928315)
			(xy 135.503772 -144.981586) (xy 135.48879 -145.033265) (xy 135.466698 -145.082327) (xy 135.437933 -145.127799)
			(xy 135.403067 -145.16878) (xy 135.362789 -145.204457) (xy 135.340598 -145.219674) (xy 135.329676 -145.226786)
			(xy 135.317738 -145.249646) (xy 135.31977 -145.361914) (xy 135.332724 -145.384266) (xy 135.3439 -145.391124)
			(xy 135.367501 -145.406046) (xy 135.410453 -145.441725) (xy 135.447747 -145.483283) (xy 135.478584 -145.529833)
			(xy 135.502308 -145.58038) (xy 135.51841 -145.633846) (xy 135.526548 -145.689087) (xy 135.527034 -145.717006)
			(xy 135.526579 -145.744) (xy 135.518972 -145.797448) (xy 135.50391 -145.849292) (xy 135.481695 -145.898496)
			(xy 135.452769 -145.94408) (xy 135.435594 -145.96491) (xy 135.428482 -145.973038) (xy 135.422386 -145.993612)
			(xy 135.433308 -146.078956) (xy 135.435097 -146.089497) (xy 135.446141 -146.107781) (xy 135.454644 -146.114262)
			(xy 135.47585 -146.129648) (xy 135.514304 -146.16523) (xy 135.547524 -146.205741) (xy 135.574886 -146.250418)
			(xy 135.595874 -146.298421) (xy 135.610092 -146.348845) (xy 135.617273 -146.400741) (xy 135.617712 -146.426936)
			(xy 135.617226 -146.454187) (xy 135.60947 -146.508135) (xy 135.594115 -146.56043) (xy 135.571473 -146.610007)
			(xy 135.542007 -146.655857) (xy 135.506316 -146.697048) (xy 135.465125 -146.732739) (xy 135.419275 -146.762205)
			(xy 135.369698 -146.784847) (xy 135.317403 -146.800202) (xy 135.263455 -146.807958) (xy 135.208953 -146.807958)
			(xy 135.155005 -146.800202) (xy 135.10271 -146.784847) (xy 135.053133 -146.762205) (xy 135.007283 -146.732739)
			(xy 134.966092 -146.697048) (xy 134.930401 -146.655857) (xy 134.900935 -146.610007) (xy 134.878293 -146.56043)
			(xy 134.862938 -146.508135) (xy 134.855182 -146.454187) (xy 134.854696 -146.426936) (xy 134.855192 -146.399944)
			(xy 134.862792 -146.346498) (xy 134.877845 -146.294656) (xy 134.90005 -146.24545) (xy 134.928966 -146.199864)
			(xy 134.946136 -146.179032) (xy 134.953248 -146.170904) (xy 134.959344 -146.15033) (xy 134.948422 -146.064986)
			(xy 134.94665 -146.054441) (xy 134.935593 -146.036159) (xy 134.927086 -146.02968) (xy 134.902785 -146.012068)
			(xy 134.859526 -145.970472) (xy 134.84098 -145.946876) (xy 134.835138 -145.939002) (xy 134.817612 -145.928588)
			(xy 134.727188 -145.91538) (xy 134.707884 -145.920206) (xy 134.70001 -145.926048) (xy 134.699756 -145.926048)
			(xy 134.675012 -145.943552) (xy 134.62116 -145.971355) (xy 134.563588 -145.990291) (xy 134.503745 -145.999883)
			(xy 134.473442 -146.00047) (xy 134.446188 -146.000006) (xy 134.392236 -145.992253) (xy 134.339935 -145.976901)
			(xy 134.290353 -145.95426) (xy 134.244498 -145.924793) (xy 134.203304 -145.889099) (xy 134.167609 -145.847905)
			(xy 134.138142 -145.802051) (xy 134.115501 -145.752468) (xy 134.100148 -145.700168) (xy 134.092395 -145.646216)
			(xy 134.091934 -145.618962) (xy 134.092369 -145.592928) (xy 134.09946 -145.541345) (xy 134.113493 -145.491203)
			(xy 134.134206 -145.443432) (xy 134.161217 -145.398918) (xy 134.177278 -145.378424) (xy 134.183019 -145.370666)
			(xy 134.18876 -145.352256) (xy 134.188454 -145.34261) (xy 134.182104 -145.262854) (xy 134.173468 -145.245074)
			(xy 134.166102 -145.238724) (xy 134.146463 -145.220535) (xy 134.111937 -145.179632) (xy 134.083465 -145.134305)
			(xy 134.061605 -145.085444) (xy 134.046787 -145.034009) (xy 134.039302 -144.981008) (xy 134.038848 -144.954244)
			(xy 128.306411 -144.954244) (xy 128.320463 -145.002097) (xy 128.328221 -145.056047) (xy 128.328221 -145.110553)
			(xy 128.320463 -145.164503) (xy 128.305106 -145.2168) (xy 128.282463 -145.26638) (xy 128.252994 -145.312232)
			(xy 128.217299 -145.353423) (xy 128.176104 -145.389114) (xy 128.13025 -145.418579) (xy 128.080669 -145.441218)
			(xy 128.02837 -145.45657) (xy 127.974419 -145.464323) (xy 127.947166 -145.464784) (xy 127.920851 -145.464344)
			(xy 127.868721 -145.457105) (xy 127.818078 -145.44278) (xy 127.769879 -145.421643) (xy 127.725036 -145.394092)
			(xy 127.684398 -145.360648) (xy 127.666242 -145.341594) (xy 127.658707 -145.334208) (xy 127.639437 -145.325675)
			(xy 127.628904 -145.325084) (xy 127.554228 -145.325084) (xy 127.543679 -145.32562) (xy 127.524384 -145.334151)
			(xy 127.51689 -145.341594) (xy 127.498731 -145.360646) (xy 127.458102 -145.394104) (xy 127.413263 -145.421664)
			(xy 127.365063 -145.442803) (xy 127.314416 -145.45712) (xy 127.262282 -145.464345) (xy 127.235966 -145.464784)
			(xy 127.208715 -145.464344) (xy 127.154767 -145.456583) (xy 127.102473 -145.441224) (xy 127.052897 -145.418579)
			(xy 127.007048 -145.38911) (xy 126.965859 -145.353417) (xy 126.930169 -145.312225) (xy 126.900704 -145.266373)
			(xy 126.878064 -145.216795) (xy 126.86271 -145.1645) (xy 126.854954 -145.110551) (xy 124.664724 -145.110551)
			(xy 124.664724 -146.202654) (xy 124.664274 -146.235508) (xy 124.656906 -146.300801) (xy 124.642279 -146.36486)
			(xy 124.620578 -146.42688) (xy 124.592074 -146.486083) (xy 124.557126 -146.541726) (xy 124.516172 -146.59311)
			(xy 124.493274 -146.616674) (xy 124.195001 -146.91487) (xy 135.716008 -146.91487) (xy 135.720079 -146.859248)
			(xy 135.732205 -146.804811) (xy 135.752128 -146.75272) (xy 135.779424 -146.704085) (xy 135.81351 -146.659942)
			(xy 135.853659 -146.621233) (xy 135.899017 -146.588782) (xy 135.948617 -146.563281) (xy 136.001401 -146.545274)
			(xy 136.056244 -146.535144) (xy 136.111978 -146.533107) (xy 136.167415 -146.539207) (xy 136.221372 -146.553313)
			(xy 136.272701 -146.575125) (xy 136.320307 -146.604179) (xy 136.363175 -146.639854) (xy 136.400392 -146.681391)
			(xy 136.431165 -146.727904) (xy 136.454837 -146.778401) (xy 136.470905 -146.831808) (xy 136.479025 -146.886984)
			(xy 136.479534 -146.91487) (xy 136.479025 -146.942756) (xy 136.470905 -146.997932) (xy 136.454837 -147.051339)
			(xy 136.449631 -147.062444) (xy 137.094212 -147.062444) (xy 137.098283 -147.006822) (xy 137.110409 -146.952385)
			(xy 137.130332 -146.900294) (xy 137.157628 -146.851659) (xy 137.191714 -146.807516) (xy 137.231863 -146.768807)
			(xy 137.277221 -146.736356) (xy 137.326821 -146.710855) (xy 137.379605 -146.692848) (xy 137.434448 -146.682718)
			(xy 137.490182 -146.680681) (xy 137.545619 -146.686781) (xy 137.599576 -146.700887) (xy 137.650905 -146.722699)
			(xy 137.698511 -146.751753) (xy 137.741379 -146.787428) (xy 137.778596 -146.828965) (xy 137.809369 -146.875478)
			(xy 137.833041 -146.925975) (xy 137.849109 -146.979382) (xy 137.857229 -147.034558) (xy 137.857738 -147.062444)
			(xy 137.857229 -147.09033) (xy 137.849109 -147.145506) (xy 137.833041 -147.198913) (xy 137.809369 -147.24941)
			(xy 137.778596 -147.295923) (xy 137.741379 -147.33746) (xy 137.698511 -147.373135) (xy 137.650905 -147.402189)
			(xy 137.599576 -147.424001) (xy 137.545619 -147.438107) (xy 137.490182 -147.444207) (xy 137.434448 -147.44217)
			(xy 137.379605 -147.43204) (xy 137.326821 -147.414033) (xy 137.277221 -147.388532) (xy 137.231863 -147.356081)
			(xy 137.191714 -147.317372) (xy 137.157628 -147.273229) (xy 137.130332 -147.224594) (xy 137.110409 -147.172503)
			(xy 137.098283 -147.118066) (xy 137.094212 -147.062444) (xy 136.449631 -147.062444) (xy 136.431165 -147.101836)
			(xy 136.400392 -147.148349) (xy 136.363175 -147.189886) (xy 136.320307 -147.225561) (xy 136.272701 -147.254615)
			(xy 136.221372 -147.276427) (xy 136.167415 -147.290533) (xy 136.111978 -147.296633) (xy 136.056244 -147.294596)
			(xy 136.001401 -147.284466) (xy 135.948617 -147.266459) (xy 135.899017 -147.240958) (xy 135.853659 -147.208507)
			(xy 135.81351 -147.169798) (xy 135.779424 -147.125655) (xy 135.752128 -147.07702) (xy 135.732205 -147.024929)
			(xy 135.720079 -146.970492) (xy 135.716008 -146.91487) (xy 124.195001 -146.91487) (xy 123.51131 -147.598384)
			(xy 123.504486 -147.605797) (xy 123.496756 -147.624386) (xy 123.496324 -147.634452) (xy 123.496324 -147.657656)
			(xy 127.250343 -147.657656) (xy 127.250343 -147.603144) (xy 127.258101 -147.549188) (xy 127.27346 -147.496885)
			(xy 127.296107 -147.4473) (xy 127.32558 -147.401443) (xy 127.361279 -147.360248) (xy 127.402478 -147.324553)
			(xy 127.448339 -147.295085) (xy 127.497926 -147.272445) (xy 127.550231 -147.257092) (xy 127.604188 -147.24934)
			(xy 127.631444 -147.24888) (xy 127.657759 -147.249324) (xy 127.709888 -147.256565) (xy 127.760531 -147.270889)
			(xy 127.80873 -147.292026) (xy 127.853573 -147.319576) (xy 127.894212 -147.353017) (xy 127.912368 -147.37207)
			(xy 127.919904 -147.379455) (xy 127.939173 -147.38799) (xy 127.949706 -147.38858) (xy 128.024382 -147.38858)
			(xy 128.034933 -147.388061) (xy 128.054229 -147.379519) (xy 128.06172 -147.37207) (xy 128.08154 -147.351282)
			(xy 128.126312 -147.315307) (xy 128.17597 -147.286447) (xy 128.229392 -147.265354) (xy 128.285371 -147.252505)
			(xy 128.342644 -147.24819) (xy 128.399917 -147.252505) (xy 128.455896 -147.265354) (xy 128.509318 -147.286447)
			(xy 128.558976 -147.315307) (xy 128.603748 -147.351282) (xy 128.623568 -147.37207) (xy 128.631104 -147.379455)
			(xy 128.650373 -147.38799) (xy 128.660906 -147.38858) (xy 128.735582 -147.38858) (xy 128.746133 -147.388061)
			(xy 128.765429 -147.379519) (xy 128.77292 -147.37207) (xy 128.791067 -147.353006) (xy 128.831699 -147.319551)
			(xy 128.876541 -147.291994) (xy 128.924744 -147.270857) (xy 128.975393 -147.256541) (xy 129.027527 -147.249318)
			(xy 129.053844 -147.24888) (xy 129.081092 -147.249393) (xy 129.135034 -147.257155) (xy 129.187321 -147.272513)
			(xy 129.236891 -147.295156) (xy 129.282735 -147.324622) (xy 129.323918 -147.360313) (xy 129.359604 -147.401501)
			(xy 129.389065 -147.447347) (xy 129.411702 -147.49692) (xy 129.427055 -147.54921) (xy 129.43481 -147.603152)
			(xy 129.43481 -147.657648) (xy 129.427055 -147.71159) (xy 129.411702 -147.76388) (xy 129.389065 -147.813453)
			(xy 129.359604 -147.859299) (xy 129.323918 -147.900487) (xy 129.282735 -147.936178) (xy 129.236891 -147.965644)
			(xy 129.187321 -147.988287) (xy 129.135034 -148.003645) (xy 129.081092 -148.011407) (xy 129.053844 -148.011896)
			(xy 129.027529 -148.011467) (xy 128.975398 -148.004225) (xy 128.924755 -147.989898) (xy 128.876556 -147.968758)
			(xy 128.831714 -147.941205) (xy 128.791076 -147.90776) (xy 128.77292 -147.888706) (xy 128.765392 -147.881312)
			(xy 128.746117 -147.872783) (xy 128.735582 -147.872196) (xy 128.660906 -147.872196) (xy 128.650355 -147.872716)
			(xy 128.63106 -147.881258) (xy 128.623568 -147.888706) (xy 128.603748 -147.909494) (xy 128.558976 -147.945469)
			(xy 128.509318 -147.974329) (xy 128.455896 -147.995422) (xy 128.399917 -148.008271) (xy 128.342644 -148.012586)
			(xy 128.285371 -148.008271) (xy 128.229392 -147.995422) (xy 128.17597 -147.974329) (xy 128.126312 -147.945469)
			(xy 128.08154 -147.909494) (xy 128.06172 -147.888706) (xy 128.054192 -147.881312) (xy 128.034917 -147.872783)
			(xy 128.024382 -147.872196) (xy 127.949706 -147.872196) (xy 127.939155 -147.872716) (xy 127.91986 -147.881258)
			(xy 127.912368 -147.888706) (xy 127.894222 -147.907771) (xy 127.85359 -147.941227) (xy 127.808748 -147.968785)
			(xy 127.760545 -147.989922) (xy 127.709896 -148.004237) (xy 127.657761 -148.011459) (xy 127.631444 -148.011896)
			(xy 127.604188 -148.01146) (xy 127.550231 -148.003708) (xy 127.497926 -147.988355) (xy 127.448339 -147.965715)
			(xy 127.402478 -147.936247) (xy 127.361279 -147.900552) (xy 127.32558 -147.859357) (xy 127.296107 -147.8135)
			(xy 127.27346 -147.763915) (xy 127.258101 -147.711612) (xy 127.250343 -147.657656) (xy 123.496324 -147.657656)
			(xy 123.496324 -148.017738) (xy 132.077458 -148.017738) (xy 132.081529 -147.962116) (xy 132.093655 -147.907679)
			(xy 132.113578 -147.855588) (xy 132.140874 -147.806953) (xy 132.17496 -147.76281) (xy 132.215109 -147.724101)
			(xy 132.260467 -147.69165) (xy 132.310067 -147.666149) (xy 132.362851 -147.648142) (xy 132.417694 -147.638012)
			(xy 132.473428 -147.635975) (xy 132.528865 -147.642075) (xy 132.582822 -147.656181) (xy 132.634151 -147.677993)
			(xy 132.681757 -147.707047) (xy 132.72302 -147.741386) (xy 137.981434 -147.741386) (xy 137.985505 -147.685764)
			(xy 137.997631 -147.631327) (xy 138.017554 -147.579236) (xy 138.04485 -147.530601) (xy 138.078936 -147.486458)
			(xy 138.119085 -147.447749) (xy 138.164443 -147.415298) (xy 138.214043 -147.389797) (xy 138.266827 -147.37179)
			(xy 138.32167 -147.36166) (xy 138.377404 -147.359623) (xy 138.432841 -147.365723) (xy 138.486798 -147.379829)
			(xy 138.538127 -147.401641) (xy 138.585733 -147.430695) (xy 138.628601 -147.46637) (xy 138.665818 -147.507907)
			(xy 138.696591 -147.55442) (xy 138.720263 -147.604917) (xy 138.736331 -147.658324) (xy 138.744451 -147.7135)
			(xy 138.74496 -147.741386) (xy 138.744451 -147.769272) (xy 138.736331 -147.824448) (xy 138.720263 -147.877855)
			(xy 138.696591 -147.928352) (xy 138.665818 -147.974865) (xy 138.628601 -148.016402) (xy 138.585733 -148.052077)
			(xy 138.538127 -148.081131) (xy 138.486798 -148.102943) (xy 138.432841 -148.117049) (xy 138.377404 -148.123149)
			(xy 138.32167 -148.121112) (xy 138.266827 -148.110982) (xy 138.214043 -148.092975) (xy 138.164443 -148.067474)
			(xy 138.119085 -148.035023) (xy 138.078936 -147.996314) (xy 138.04485 -147.952171) (xy 138.017554 -147.903536)
			(xy 137.997631 -147.851445) (xy 137.985505 -147.797008) (xy 137.981434 -147.741386) (xy 132.72302 -147.741386)
			(xy 132.724625 -147.742722) (xy 132.761842 -147.784259) (xy 132.792615 -147.830772) (xy 132.816287 -147.881269)
			(xy 132.832355 -147.934676) (xy 132.840475 -147.989852) (xy 132.840984 -148.017738) (xy 132.840475 -148.045624)
			(xy 132.832355 -148.1008) (xy 132.816287 -148.154207) (xy 132.792615 -148.204704) (xy 132.761842 -148.251217)
			(xy 132.724625 -148.292754) (xy 132.681757 -148.328429) (xy 132.634151 -148.357483) (xy 132.582822 -148.379295)
			(xy 132.528865 -148.393401) (xy 132.473428 -148.399501) (xy 132.417694 -148.397464) (xy 132.362851 -148.387334)
			(xy 132.310067 -148.369327) (xy 132.260467 -148.343826) (xy 132.215109 -148.311375) (xy 132.17496 -148.272666)
			(xy 132.140874 -148.228523) (xy 132.113578 -148.179888) (xy 132.093655 -148.127797) (xy 132.081529 -148.07336)
			(xy 132.077458 -148.017738) (xy 123.496324 -148.017738) (xy 123.496324 -150.069804) (xy 123.496741 -150.079874)
			(xy 123.504467 -150.098472) (xy 123.51131 -150.105872) (xy 123.601332 -150.195854) (xy 127.250365 -150.195854)
			(xy 127.250365 -150.141346) (xy 127.258123 -150.087392) (xy 127.273481 -150.035093) (xy 127.296126 -149.985511)
			(xy 127.325598 -149.939657) (xy 127.361295 -149.898464) (xy 127.402492 -149.862771) (xy 127.448349 -149.833305)
			(xy 127.497934 -149.810666) (xy 127.550236 -149.795314) (xy 127.60419 -149.787562) (xy 127.631444 -149.787102)
			(xy 127.657759 -149.787539) (xy 127.709889 -149.79478) (xy 127.760532 -149.809105) (xy 127.808731 -149.830243)
			(xy 127.853574 -149.857795) (xy 127.894212 -149.891238) (xy 127.912368 -149.910292) (xy 127.919901 -149.91768)
			(xy 127.939172 -149.926212) (xy 127.949706 -149.926802) (xy 128.024382 -149.926802) (xy 128.034932 -149.926276)
			(xy 128.054227 -149.917738) (xy 128.06172 -149.910292) (xy 128.08154 -149.889504) (xy 128.126312 -149.853529)
			(xy 128.17597 -149.824669) (xy 128.229392 -149.803576) (xy 128.285371 -149.790727) (xy 128.342644 -149.786412)
			(xy 128.399917 -149.790727) (xy 128.455896 -149.803576) (xy 128.509318 -149.824669) (xy 128.558976 -149.853529)
			(xy 128.603748 -149.889504) (xy 128.623568 -149.910292) (xy 128.631101 -149.91768) (xy 128.650372 -149.926212)
			(xy 128.660906 -149.926802) (xy 128.735582 -149.926802) (xy 128.746132 -149.926276) (xy 128.765427 -149.917738)
			(xy 128.77292 -149.910292) (xy 128.791071 -149.891232) (xy 128.831702 -149.857776) (xy 128.876543 -149.830218)
			(xy 128.924745 -149.80908) (xy 128.975393 -149.794764) (xy 129.027528 -149.78754) (xy 129.053844 -149.787102)
			(xy 129.081094 -149.787571) (xy 129.135038 -149.795333) (xy 129.187329 -149.810692) (xy 129.236902 -149.833336)
			(xy 129.282748 -149.862804) (xy 129.323934 -149.898497) (xy 129.359622 -149.939687) (xy 129.389085 -149.985537)
			(xy 129.411723 -150.035112) (xy 129.420045 -150.063454) (xy 131.938012 -150.063454) (xy 131.942083 -150.007832)
			(xy 131.954209 -149.953395) (xy 131.974132 -149.901304) (xy 132.001428 -149.852669) (xy 132.035514 -149.808526)
			(xy 132.075663 -149.769817) (xy 132.121021 -149.737366) (xy 132.170621 -149.711865) (xy 132.223405 -149.693858)
			(xy 132.278248 -149.683728) (xy 132.333982 -149.681691) (xy 132.389419 -149.687791) (xy 132.443376 -149.701897)
			(xy 132.494705 -149.723709) (xy 132.542311 -149.752763) (xy 132.585179 -149.788438) (xy 132.622396 -149.829975)
			(xy 132.653169 -149.876488) (xy 132.676841 -149.926985) (xy 132.692909 -149.980392) (xy 132.701029 -150.035568)
			(xy 132.701538 -150.063454) (xy 132.701029 -150.09134) (xy 132.692909 -150.146516) (xy 132.676841 -150.199923)
			(xy 132.653169 -150.25042) (xy 132.622396 -150.296933) (xy 132.585179 -150.33847) (xy 132.542311 -150.374145)
			(xy 132.494705 -150.403199) (xy 132.443376 -150.425011) (xy 132.389419 -150.439117) (xy 132.333982 -150.445217)
			(xy 132.278248 -150.44318) (xy 132.223405 -150.43305) (xy 132.170621 -150.415043) (xy 132.121021 -150.389542)
			(xy 132.075663 -150.357091) (xy 132.035514 -150.318382) (xy 132.001428 -150.274239) (xy 131.974132 -150.225604)
			(xy 131.954209 -150.173513) (xy 131.942083 -150.119076) (xy 131.938012 -150.063454) (xy 129.420045 -150.063454)
			(xy 129.427077 -150.087405) (xy 129.434832 -150.14135) (xy 129.434832 -150.19585) (xy 129.427077 -150.249795)
			(xy 129.411723 -150.302088) (xy 129.389085 -150.351663) (xy 129.359622 -150.397513) (xy 129.323934 -150.438703)
			(xy 129.282748 -150.474396) (xy 129.236902 -150.503864) (xy 129.187329 -150.526508) (xy 129.135038 -150.541867)
			(xy 129.081094 -150.549629) (xy 129.053844 -150.550118) (xy 129.027529 -150.549682) (xy 128.975399 -150.54244)
			(xy 128.924756 -150.528114) (xy 128.876558 -150.506976) (xy 128.831715 -150.479425) (xy 128.791076 -150.445982)
			(xy 128.77292 -150.426928) (xy 128.765389 -150.419537) (xy 128.746116 -150.411006) (xy 128.735582 -150.410418)
			(xy 128.660906 -150.410418) (xy 128.650354 -150.410932) (xy 128.631059 -150.419477) (xy 128.623568 -150.426928)
			(xy 128.603748 -150.447716) (xy 128.558976 -150.483691) (xy 128.509318 -150.512551) (xy 128.455896 -150.533644)
			(xy 128.399917 -150.546493) (xy 128.342644 -150.550808) (xy 128.285371 -150.546493) (xy 128.229392 -150.533644)
			(xy 128.17597 -150.512551) (xy 128.126312 -150.483691) (xy 128.08154 -150.447716) (xy 128.06172 -150.426928)
			(xy 128.054189 -150.419537) (xy 128.034916 -150.411006) (xy 128.024382 -150.410418) (xy 127.949706 -150.410418)
			(xy 127.939154 -150.410932) (xy 127.919859 -150.419477) (xy 127.912368 -150.426928) (xy 127.894226 -150.445997)
			(xy 127.853593 -150.479452) (xy 127.80875 -150.507009) (xy 127.760546 -150.528145) (xy 127.709897 -150.542459)
			(xy 127.657761 -150.549681) (xy 127.631444 -150.550118) (xy 127.60419 -150.549638) (xy 127.550236 -150.541886)
			(xy 127.497934 -150.526534) (xy 127.448349 -150.503895) (xy 127.402492 -150.474429) (xy 127.361295 -150.438736)
			(xy 127.325598 -150.397543) (xy 127.296126 -150.351689) (xy 127.273481 -150.302107) (xy 127.258123 -150.249808)
			(xy 127.250365 -150.195854) (xy 123.601332 -150.195854) (xy 124.076714 -150.671022) (xy 124.084112 -150.677864)
			(xy 124.102713 -150.685582) (xy 124.112782 -150.686008) (xy 128.749044 -150.686008) (xy 128.781924 -150.686482)
			(xy 128.847271 -150.693843) (xy 128.911382 -150.708479) (xy 128.973449 -150.730206) (xy 129.032691 -150.758749)
			(xy 129.088363 -150.79375) (xy 129.139763 -150.834767) (xy 129.163318 -150.857712) (xy 129.976626 -151.67102)
			(xy 131.893562 -151.67102) (xy 131.897633 -151.615398) (xy 131.909759 -151.560961) (xy 131.929682 -151.50887)
			(xy 131.956978 -151.460235) (xy 131.991064 -151.416092) (xy 132.031213 -151.377383) (xy 132.076571 -151.344932)
			(xy 132.126171 -151.319431) (xy 132.178955 -151.301424) (xy 132.233798 -151.291294) (xy 132.289532 -151.289257)
			(xy 132.344969 -151.295357) (xy 132.398926 -151.309463) (xy 132.450255 -151.331275) (xy 132.497861 -151.360329)
			(xy 132.540729 -151.396004) (xy 132.577946 -151.437541) (xy 132.608719 -151.484054) (xy 132.632391 -151.534551)
			(xy 132.648459 -151.587958) (xy 132.656579 -151.643134) (xy 132.657088 -151.67102) (xy 132.656615 -151.696928)
			(xy 132.909562 -151.696928) (xy 132.913633 -151.641306) (xy 132.925759 -151.586869) (xy 132.945682 -151.534778)
			(xy 132.972978 -151.486143) (xy 133.007064 -151.442) (xy 133.047213 -151.403291) (xy 133.092571 -151.37084)
			(xy 133.142171 -151.345339) (xy 133.194955 -151.327332) (xy 133.249798 -151.317202) (xy 133.305532 -151.315165)
			(xy 133.360969 -151.321265) (xy 133.414926 -151.335371) (xy 133.466255 -151.357183) (xy 133.513861 -151.386237)
			(xy 133.538337 -151.406606) (xy 134.136636 -151.406606) (xy 134.140707 -151.350984) (xy 134.152833 -151.296547)
			(xy 134.172756 -151.244456) (xy 134.200052 -151.195821) (xy 134.234138 -151.151678) (xy 134.274287 -151.112969)
			(xy 134.319645 -151.080518) (xy 134.369245 -151.055017) (xy 134.422029 -151.03701) (xy 134.476872 -151.02688)
			(xy 134.532606 -151.024843) (xy 134.588043 -151.030943) (xy 134.642 -151.045049) (xy 134.693329 -151.066861)
			(xy 134.740935 -151.095915) (xy 134.783803 -151.13159) (xy 134.82102 -151.173127) (xy 134.851793 -151.21964)
			(xy 134.875465 -151.270137) (xy 134.891533 -151.323544) (xy 134.899653 -151.37872) (xy 134.900162 -151.406606)
			(xy 134.899653 -151.434492) (xy 134.891533 -151.489668) (xy 134.875465 -151.543075) (xy 134.856923 -151.582628)
			(xy 135.462262 -151.582628) (xy 135.466333 -151.527006) (xy 135.478459 -151.472569) (xy 135.498382 -151.420478)
			(xy 135.525678 -151.371843) (xy 135.559764 -151.3277) (xy 135.599913 -151.288991) (xy 135.645271 -151.25654)
			(xy 135.694871 -151.231039) (xy 135.747655 -151.213032) (xy 135.802498 -151.202902) (xy 135.858232 -151.200865)
			(xy 135.913669 -151.206965) (xy 135.967626 -151.221071) (xy 136.018955 -151.242883) (xy 136.066561 -151.271937)
			(xy 136.109429 -151.307612) (xy 136.146646 -151.349149) (xy 136.177419 -151.395662) (xy 136.201091 -151.446159)
			(xy 136.217159 -151.499566) (xy 136.225279 -151.554742) (xy 136.225542 -151.569166) (xy 136.973562 -151.569166)
			(xy 136.977633 -151.513544) (xy 136.989759 -151.459107) (xy 137.009682 -151.407016) (xy 137.036978 -151.358381)
			(xy 137.071064 -151.314238) (xy 137.111213 -151.275529) (xy 137.156571 -151.243078) (xy 137.206171 -151.217577)
			(xy 137.258955 -151.19957) (xy 137.313798 -151.18944) (xy 137.369532 -151.187403) (xy 137.424969 -151.193503)
			(xy 137.478926 -151.207609) (xy 137.530255 -151.229421) (xy 137.577861 -151.258475) (xy 137.620729 -151.29415)
			(xy 137.657946 -151.335687) (xy 137.688719 -151.3822) (xy 137.712391 -151.432697) (xy 137.728459 -151.486104)
			(xy 137.736579 -151.54128) (xy 137.737088 -151.569166) (xy 137.736579 -151.597052) (xy 137.728459 -151.652228)
			(xy 137.712391 -151.705635) (xy 137.688719 -151.756132) (xy 137.657946 -151.802645) (xy 137.620729 -151.844182)
			(xy 137.577861 -151.879857) (xy 137.530255 -151.908911) (xy 137.478926 -151.930723) (xy 137.424969 -151.944829)
			(xy 137.369532 -151.950929) (xy 137.313798 -151.948892) (xy 137.258955 -151.938762) (xy 137.206171 -151.920755)
			(xy 137.156571 -151.895254) (xy 137.111213 -151.862803) (xy 137.071064 -151.824094) (xy 137.036978 -151.779951)
			(xy 137.009682 -151.731316) (xy 136.989759 -151.679225) (xy 136.977633 -151.624788) (xy 136.973562 -151.569166)
			(xy 136.225542 -151.569166) (xy 136.225788 -151.582628) (xy 136.225279 -151.610514) (xy 136.217159 -151.66569)
			(xy 136.201091 -151.719097) (xy 136.177419 -151.769594) (xy 136.146646 -151.816107) (xy 136.109429 -151.857644)
			(xy 136.066561 -151.893319) (xy 136.018955 -151.922373) (xy 135.967626 -151.944185) (xy 135.913669 -151.958291)
			(xy 135.858232 -151.964391) (xy 135.802498 -151.962354) (xy 135.747655 -151.952224) (xy 135.694871 -151.934217)
			(xy 135.645271 -151.908716) (xy 135.599913 -151.876265) (xy 135.559764 -151.837556) (xy 135.525678 -151.793413)
			(xy 135.498382 -151.744778) (xy 135.478459 -151.692687) (xy 135.466333 -151.63825) (xy 135.462262 -151.582628)
			(xy 134.856923 -151.582628) (xy 134.851793 -151.593572) (xy 134.82102 -151.640085) (xy 134.783803 -151.681622)
			(xy 134.740935 -151.717297) (xy 134.693329 -151.746351) (xy 134.642 -151.768163) (xy 134.588043 -151.782269)
			(xy 134.532606 -151.788369) (xy 134.476872 -151.786332) (xy 134.422029 -151.776202) (xy 134.369245 -151.758195)
			(xy 134.319645 -151.732694) (xy 134.274287 -151.700243) (xy 134.234138 -151.661534) (xy 134.200052 -151.617391)
			(xy 134.172756 -151.568756) (xy 134.152833 -151.516665) (xy 134.140707 -151.462228) (xy 134.136636 -151.406606)
			(xy 133.538337 -151.406606) (xy 133.556729 -151.421912) (xy 133.593946 -151.463449) (xy 133.624719 -151.509962)
			(xy 133.648391 -151.560459) (xy 133.664459 -151.613866) (xy 133.672579 -151.669042) (xy 133.673088 -151.696928)
			(xy 133.672579 -151.724814) (xy 133.664459 -151.77999) (xy 133.648391 -151.833397) (xy 133.624719 -151.883894)
			(xy 133.593946 -151.930407) (xy 133.556729 -151.971944) (xy 133.513861 -152.007619) (xy 133.466255 -152.036673)
			(xy 133.414926 -152.058485) (xy 133.360969 -152.072591) (xy 133.305532 -152.078691) (xy 133.249798 -152.076654)
			(xy 133.194955 -152.066524) (xy 133.142171 -152.048517) (xy 133.092571 -152.023016) (xy 133.047213 -151.990565)
			(xy 133.007064 -151.951856) (xy 132.972978 -151.907713) (xy 132.945682 -151.859078) (xy 132.925759 -151.806987)
			(xy 132.913633 -151.75255) (xy 132.909562 -151.696928) (xy 132.656615 -151.696928) (xy 132.656579 -151.698906)
			(xy 132.648459 -151.754082) (xy 132.632391 -151.807489) (xy 132.608719 -151.857986) (xy 132.577946 -151.904499)
			(xy 132.540729 -151.946036) (xy 132.497861 -151.981711) (xy 132.450255 -152.010765) (xy 132.398926 -152.032577)
			(xy 132.344969 -152.046683) (xy 132.289532 -152.052783) (xy 132.233798 -152.050746) (xy 132.178955 -152.040616)
			(xy 132.126171 -152.022609) (xy 132.076571 -151.997108) (xy 132.031213 -151.964657) (xy 131.991064 -151.925948)
			(xy 131.956978 -151.881805) (xy 131.929682 -151.83317) (xy 131.909759 -151.781079) (xy 131.897633 -151.726642)
			(xy 131.893562 -151.67102) (xy 129.976626 -151.67102) (xy 131.673854 -153.368248) (xy 131.703826 -153.400506)
			(xy 131.703826 -153.40076) (xy 131.710149 -153.407517) (xy 131.726416 -153.416316) (xy 131.744748 -153.41875)
			(xy 131.762747 -153.414503) (xy 131.770628 -153.40965) (xy 131.928108 -153.304494) (xy 131.952226 -153.288799)
			(xy 132.002993 -153.2617) (xy 132.029454 -153.250392) (xy 132.051552 -153.241248) (xy 132.087198 -153.227136)
			(xy 132.161243 -153.20726) (xy 132.237247 -153.197202) (xy 132.27558 -153.196544) (xy 132.31057 -153.197056)
			(xy 132.380051 -153.205399) (xy 132.448044 -153.221957) (xy 132.513582 -153.246495) (xy 132.57573 -153.278662)
			(xy 132.633606 -153.318002) (xy 132.686386 -153.363954) (xy 132.733317 -153.415864) (xy 132.773733 -153.472994)
			(xy 132.807057 -153.53453) (xy 132.82041 -153.566876) (xy 132.82549 -153.579576) (xy 132.846318 -153.59634)
			(xy 132.960364 -153.613612) (xy 132.985256 -153.603706) (xy 132.993892 -153.593038) (xy 133.012125 -153.571175)
			(xy 133.053965 -153.532571) (xy 133.101072 -153.500608) (xy 133.152403 -153.475993) (xy 133.20682 -153.459272)
			(xy 133.263116 -153.450817) (xy 133.29158 -153.45029) (xy 133.318832 -153.450774) (xy 133.372782 -153.458528)
			(xy 133.42508 -153.473882) (xy 133.47466 -153.496522) (xy 133.520513 -153.525987) (xy 133.561706 -153.561679)
			(xy 133.5974 -153.60287) (xy 133.626868 -153.648721) (xy 133.649511 -153.6983) (xy 133.664867 -153.750596)
			(xy 133.669458 -153.782522) (xy 135.957562 -153.782522) (xy 135.961633 -153.7269) (xy 135.973759 -153.672463)
			(xy 135.993682 -153.620372) (xy 136.020978 -153.571737) (xy 136.055064 -153.527594) (xy 136.095213 -153.488885)
			(xy 136.140571 -153.456434) (xy 136.190171 -153.430933) (xy 136.242955 -153.412926) (xy 136.297798 -153.402796)
			(xy 136.353532 -153.400759) (xy 136.408969 -153.406859) (xy 136.462926 -153.420965) (xy 136.514255 -153.442777)
			(xy 136.561861 -153.471831) (xy 136.604729 -153.507506) (xy 136.641946 -153.549043) (xy 136.672719 -153.595556)
			(xy 136.696391 -153.646053) (xy 136.712459 -153.69946) (xy 136.720579 -153.754636) (xy 136.721088 -153.782522)
			(xy 137.989562 -153.782522) (xy 137.993633 -153.7269) (xy 138.005759 -153.672463) (xy 138.025682 -153.620372)
			(xy 138.052978 -153.571737) (xy 138.087064 -153.527594) (xy 138.127213 -153.488885) (xy 138.172571 -153.456434)
			(xy 138.222171 -153.430933) (xy 138.274955 -153.412926) (xy 138.329798 -153.402796) (xy 138.385532 -153.400759)
			(xy 138.440969 -153.406859) (xy 138.494926 -153.420965) (xy 138.546255 -153.442777) (xy 138.593861 -153.471831)
			(xy 138.636729 -153.507506) (xy 138.673946 -153.549043) (xy 138.704719 -153.595556) (xy 138.728391 -153.646053)
			(xy 138.744459 -153.69946) (xy 138.752579 -153.754636) (xy 138.753088 -153.782522) (xy 138.752579 -153.810408)
			(xy 138.744459 -153.865584) (xy 138.728391 -153.918991) (xy 138.704719 -153.969488) (xy 138.673946 -154.016001)
			(xy 138.636729 -154.057538) (xy 138.593861 -154.093213) (xy 138.546255 -154.122267) (xy 138.494926 -154.144079)
			(xy 138.440969 -154.158185) (xy 138.385532 -154.164285) (xy 138.329798 -154.162248) (xy 138.274955 -154.152118)
			(xy 138.222171 -154.134111) (xy 138.172571 -154.10861) (xy 138.127213 -154.076159) (xy 138.087064 -154.03745)
			(xy 138.052978 -153.993307) (xy 138.025682 -153.944672) (xy 138.005759 -153.892581) (xy 137.993633 -153.838144)
			(xy 137.989562 -153.782522) (xy 136.721088 -153.782522) (xy 136.720579 -153.810408) (xy 136.712459 -153.865584)
			(xy 136.696391 -153.918991) (xy 136.672719 -153.969488) (xy 136.641946 -154.016001) (xy 136.604729 -154.057538)
			(xy 136.561861 -154.093213) (xy 136.514255 -154.122267) (xy 136.462926 -154.144079) (xy 136.408969 -154.158185)
			(xy 136.353532 -154.164285) (xy 136.297798 -154.162248) (xy 136.242955 -154.152118) (xy 136.190171 -154.134111)
			(xy 136.140571 -154.10861) (xy 136.095213 -154.076159) (xy 136.055064 -154.03745) (xy 136.020978 -153.993307)
			(xy 135.993682 -153.944672) (xy 135.973759 -153.892581) (xy 135.961633 -153.838144) (xy 135.957562 -153.782522)
			(xy 133.669458 -153.782522) (xy 133.672625 -153.804546) (xy 133.673088 -153.831798) (xy 133.672473 -153.862601)
			(xy 133.66255 -153.923402) (xy 133.642978 -153.981815) (xy 133.629146 -154.009344) (xy 133.626414 -154.014861)
			(xy 133.623469 -154.026812) (xy 133.623304 -154.032966) (xy 133.623304 -154.280616) (xy 133.622765 -154.306639)
			(xy 133.614602 -154.358042) (xy 133.598511 -154.407539) (xy 133.574886 -154.453916) (xy 133.544307 -154.496033)
			(xy 133.526276 -154.514804) (xy 132.81152 -155.22956) (xy 132.792765 -155.247609) (xy 132.750643 -155.278185)
			(xy 132.704262 -155.301808) (xy 132.654762 -155.317898) (xy 132.603357 -155.326062) (xy 132.577332 -155.326588)
			(xy 131.136644 -155.326588) (xy 131.11062 -155.326079) (xy 131.059215 -155.317909) (xy 131.009717 -155.301811)
			(xy 130.963341 -155.27818) (xy 130.921226 -155.247595) (xy 130.902456 -155.22956) (xy 130.26517 -154.59202)
			(xy 130.257106 -154.584676) (xy 130.236703 -154.577036) (xy 130.2258 -154.577288) (xy 130.138424 -154.583384)
			(xy 130.11912 -154.593544) (xy 130.112516 -154.602434) (xy 130.102144 -154.615813) (xy 130.079376 -154.640869)
			(xy 130.06705 -154.652472) (xy 130.059666 -154.660009) (xy 130.05113 -154.679277) (xy 130.05054 -154.68981)
			(xy 130.05054 -154.764486) (xy 130.051051 -154.775038) (xy 130.059598 -154.794334) (xy 130.06705 -154.801824)
			(xy 130.08612 -154.819965) (xy 130.119574 -154.860599) (xy 130.14713 -154.905443) (xy 130.168265 -154.953646)
			(xy 130.18258 -155.004296) (xy 130.189802 -155.056431) (xy 130.19024 -155.082748) (xy 130.189767 -155.109999)
			(xy 130.182005 -155.163945) (xy 130.166645 -155.216238) (xy 130.144001 -155.265814) (xy 130.114532 -155.311662)
			(xy 130.07884 -155.352851) (xy 130.03765 -155.388542) (xy 129.9918 -155.418008) (xy 129.942223 -155.440651)
			(xy 129.88993 -155.456008) (xy 129.835983 -155.463768) (xy 129.808732 -155.464256) (xy 129.782416 -155.463848)
			(xy 129.730284 -155.456603) (xy 129.67964 -155.442273) (xy 129.631441 -155.42113) (xy 129.586599 -155.393572)
			(xy 129.545962 -155.360123) (xy 129.527808 -155.341066) (xy 129.520277 -155.333676) (xy 129.501004 -155.325143)
			(xy 129.49047 -155.324556) (xy 129.415794 -155.324556) (xy 129.405244 -155.325082) (xy 129.38595 -155.333621)
			(xy 129.378456 -155.341066) (xy 129.358636 -155.361854) (xy 129.313864 -155.397829) (xy 129.264206 -155.426689)
			(xy 129.210784 -155.447782) (xy 129.154805 -155.460631) (xy 129.097532 -155.464946) (xy 129.040259 -155.460631)
			(xy 128.98428 -155.447782) (xy 128.930858 -155.426689) (xy 128.8812 -155.397829) (xy 128.836428 -155.361854)
			(xy 128.816608 -155.341066) (xy 128.809077 -155.333676) (xy 128.789804 -155.325143) (xy 128.77927 -155.324556)
			(xy 128.704594 -155.324556) (xy 128.694044 -155.325082) (xy 128.67475 -155.333621) (xy 128.667256 -155.341066)
			(xy 128.647436 -155.361854) (xy 128.602664 -155.397829) (xy 128.553006 -155.426689) (xy 128.499584 -155.447782)
			(xy 128.443605 -155.460631) (xy 128.386332 -155.464946) (xy 128.329059 -155.460631) (xy 128.27308 -155.447782)
			(xy 128.219658 -155.426689) (xy 128.17 -155.397829) (xy 128.125228 -155.361854) (xy 128.105408 -155.341066)
			(xy 128.097877 -155.333676) (xy 128.078604 -155.325143) (xy 128.06807 -155.324556) (xy 127.993394 -155.324556)
			(xy 127.982844 -155.325082) (xy 127.96355 -155.333621) (xy 127.956056 -155.341066) (xy 127.937928 -155.360148)
			(xy 127.897291 -155.393601) (xy 127.852444 -155.421154) (xy 127.804238 -155.442288) (xy 127.753587 -155.4566)
			(xy 127.701449 -155.46382) (xy 127.675132 -155.464256) (xy 127.647884 -155.463692) (xy 127.593941 -155.455941)
			(xy 127.541651 -155.440593) (xy 127.492077 -155.417959) (xy 127.446229 -155.3885) (xy 127.40504 -155.352817)
			(xy 127.369348 -155.311635) (xy 127.33988 -155.265793) (xy 127.317235 -155.216224) (xy 127.301876 -155.163937)
			(xy 127.294114 -155.109996) (xy 127.293624 -155.082748) (xy 127.294049 -155.056433) (xy 127.301292 -155.004302)
			(xy 127.315618 -154.953658) (xy 127.336759 -154.905459) (xy 127.364313 -154.860617) (xy 127.397759 -154.819979)
			(xy 127.416814 -154.801824) (xy 127.424209 -154.794297) (xy 127.432737 -154.775021) (xy 127.433324 -154.764486)
			(xy 127.433324 -154.68981) (xy 127.432796 -154.67926) (xy 127.424259 -154.659965) (xy 127.416814 -154.652472)
			(xy 127.397755 -154.63432) (xy 127.364297 -154.59369) (xy 127.336738 -154.548849) (xy 127.3156 -154.500648)
			(xy 127.301284 -154.449999) (xy 127.294061 -154.397864) (xy 127.293624 -154.371548) (xy 127.2941 -154.344295)
			(xy 127.301851 -154.290343) (xy 127.317203 -154.238043) (xy 127.339842 -154.188461) (xy 127.369308 -154.142606)
			(xy 127.405001 -154.101412) (xy 127.446193 -154.065718) (xy 127.492047 -154.03625) (xy 127.541628 -154.013608)
			(xy 127.593927 -153.998255) (xy 127.647879 -153.990501) (xy 127.675132 -153.99004) (xy 127.701447 -153.990473)
			(xy 127.753578 -153.997713) (xy 127.804222 -154.012038) (xy 127.852421 -154.033177) (xy 127.897263 -154.06073)
			(xy 127.937901 -154.094175) (xy 127.956056 -154.11323) (xy 127.963601 -154.120604) (xy 127.982863 -154.129147)
			(xy 127.993394 -154.12974) (xy 128.06807 -154.12974) (xy 128.078618 -154.129197) (xy 128.097913 -154.12067)
			(xy 128.105408 -154.11323) (xy 128.125228 -154.092442) (xy 128.17 -154.056467) (xy 128.219658 -154.027607)
			(xy 128.27308 -154.006514) (xy 128.329059 -153.993665) (xy 128.386332 -153.98935) (xy 128.443605 -153.993665)
			(xy 128.499584 -154.006514) (xy 128.553006 -154.027607) (xy 128.602664 -154.056467) (xy 128.647436 -154.092442)
			(xy 128.667256 -154.11323) (xy 128.674801 -154.120604) (xy 128.694063 -154.129147) (xy 128.704594 -154.12974)
			(xy 128.77927 -154.12974) (xy 128.789818 -154.129197) (xy 128.809113 -154.12067) (xy 128.816608 -154.11323)
			(xy 128.836428 -154.092442) (xy 128.8812 -154.056467) (xy 128.930858 -154.027607) (xy 128.98428 -154.006514)
			(xy 129.040259 -153.993665) (xy 129.097532 -153.98935) (xy 129.154805 -153.993665) (xy 129.210784 -154.006514)
			(xy 129.264206 -154.027607) (xy 129.313864 -154.056467) (xy 129.358636 -154.092442) (xy 129.378456 -154.11323)
			(xy 129.386001 -154.120604) (xy 129.405263 -154.129147) (xy 129.415794 -154.12974) (xy 129.49047 -154.12974)
			(xy 129.501018 -154.129197) (xy 129.520313 -154.12067) (xy 129.527808 -154.11323) (xy 129.539417 -154.100909)
			(xy 129.564471 -154.078141) (xy 129.577846 -154.067764) (xy 129.586146 -154.060788) (xy 129.596399 -154.041704)
			(xy 129.597658 -154.030934) (xy 129.602992 -153.95448) (xy 129.603173 -153.943587) (xy 129.595556 -153.923199)
			(xy 129.58826 -153.91511) (xy 128.211326 -152.53843) (xy 128.203907 -152.531613) (xy 128.185323 -152.523879)
			(xy 128.175258 -152.523444) (xy 123.467622 -152.523444) (xy 123.441534 -152.522974) (xy 123.39 -152.514808)
			(xy 123.340381 -152.498673) (xy 123.293901 -152.474968) (xy 123.251705 -152.444278) (xy 123.232926 -152.426162)
			(xy 122.040396 -151.233632) (xy 122.010424 -151.227536) (xy 121.9962 -151.233632) (xy 121.987061 -151.237828)
			(xy 121.972827 -151.252013) (xy 121.965125 -151.270574) (xy 121.964704 -151.280622) (xy 121.964704 -155.212034)
			(xy 123.369068 -155.212034) (xy 123.373139 -155.156412) (xy 123.385265 -155.101975) (xy 123.405188 -155.049884)
			(xy 123.432484 -155.001249) (xy 123.46657 -154.957106) (xy 123.506719 -154.918397) (xy 123.552077 -154.885946)
			(xy 123.601677 -154.860445) (xy 123.654461 -154.842438) (xy 123.709304 -154.832308) (xy 123.765038 -154.830271)
			(xy 123.820475 -154.836371) (xy 123.874432 -154.850477) (xy 123.925761 -154.872289) (xy 123.973367 -154.901343)
			(xy 124.016235 -154.937018) (xy 124.053452 -154.978555) (xy 124.084225 -155.025068) (xy 124.107897 -155.075565)
			(xy 124.108988 -155.079192) (xy 125.969774 -155.079192) (xy 125.973845 -155.02357) (xy 125.985971 -154.969133)
			(xy 126.005894 -154.917042) (xy 126.03319 -154.868407) (xy 126.067276 -154.824264) (xy 126.107425 -154.785555)
			(xy 126.152783 -154.753104) (xy 126.202383 -154.727603) (xy 126.255167 -154.709596) (xy 126.31001 -154.699466)
			(xy 126.365744 -154.697429) (xy 126.421181 -154.703529) (xy 126.475138 -154.717635) (xy 126.526467 -154.739447)
			(xy 126.574073 -154.768501) (xy 126.616941 -154.804176) (xy 126.654158 -154.845713) (xy 126.684931 -154.892226)
			(xy 126.708603 -154.942723) (xy 126.724671 -154.99613) (xy 126.732791 -155.051306) (xy 126.7333 -155.079192)
			(xy 126.732791 -155.107078) (xy 126.724671 -155.162254) (xy 126.708603 -155.215661) (xy 126.684931 -155.266158)
			(xy 126.654158 -155.312671) (xy 126.616941 -155.354208) (xy 126.574073 -155.389883) (xy 126.526467 -155.418937)
			(xy 126.475138 -155.440749) (xy 126.421181 -155.454855) (xy 126.365744 -155.460955) (xy 126.31001 -155.458918)
			(xy 126.255167 -155.448788) (xy 126.202383 -155.430781) (xy 126.152783 -155.40528) (xy 126.107425 -155.372829)
			(xy 126.067276 -155.33412) (xy 126.03319 -155.289977) (xy 126.005894 -155.241342) (xy 125.985971 -155.189251)
			(xy 125.973845 -155.134814) (xy 125.969774 -155.079192) (xy 124.108988 -155.079192) (xy 124.123965 -155.128972)
			(xy 124.132085 -155.184148) (xy 124.132594 -155.212034) (xy 124.132085 -155.23992) (xy 124.123965 -155.295096)
			(xy 124.107897 -155.348503) (xy 124.084225 -155.399) (xy 124.053452 -155.445513) (xy 124.016235 -155.48705)
			(xy 123.973367 -155.522725) (xy 123.925761 -155.551779) (xy 123.874432 -155.573591) (xy 123.820475 -155.587697)
			(xy 123.765038 -155.593797) (xy 123.709304 -155.59176) (xy 123.654461 -155.58163) (xy 123.601677 -155.563623)
			(xy 123.552077 -155.538122) (xy 123.506719 -155.505671) (xy 123.46657 -155.466962) (xy 123.432484 -155.422819)
			(xy 123.405188 -155.374184) (xy 123.385265 -155.322093) (xy 123.373139 -155.267656) (xy 123.369068 -155.212034)
			(xy 121.964704 -155.212034) (xy 121.964704 -156.69387) (xy 124.987302 -156.69387) (xy 124.991373 -156.638248)
			(xy 125.003499 -156.583811) (xy 125.023422 -156.53172) (xy 125.050718 -156.483085) (xy 125.084804 -156.438942)
			(xy 125.124953 -156.400233) (xy 125.170311 -156.367782) (xy 125.219911 -156.342281) (xy 125.272695 -156.324274)
			(xy 125.327538 -156.314144) (xy 125.383272 -156.312107) (xy 125.438709 -156.318207) (xy 125.492666 -156.332313)
			(xy 125.543995 -156.354125) (xy 125.591601 -156.383179) (xy 125.634469 -156.418854) (xy 125.671686 -156.460391)
			(xy 125.702459 -156.506904) (xy 125.726131 -156.557401) (xy 125.742199 -156.610808) (xy 125.750319 -156.665984)
			(xy 125.750828 -156.69387) (xy 125.750319 -156.721756) (xy 125.742199 -156.776932) (xy 125.726131 -156.830339)
			(xy 125.702459 -156.880836) (xy 125.671686 -156.927349) (xy 125.634469 -156.968886) (xy 125.591601 -157.004561)
			(xy 125.543995 -157.033615) (xy 125.492666 -157.055427) (xy 125.438709 -157.069533) (xy 125.383272 -157.075633)
			(xy 125.327538 -157.073596) (xy 125.272695 -157.063466) (xy 125.219911 -157.045459) (xy 125.170311 -157.019958)
			(xy 125.124953 -156.987507) (xy 125.084804 -156.948798) (xy 125.050718 -156.904655) (xy 125.023422 -156.85602)
			(xy 125.003499 -156.803929) (xy 124.991373 -156.749492) (xy 124.987302 -156.69387) (xy 121.964704 -156.69387)
			(xy 121.964704 -157.812994) (xy 122.75007 -157.812994) (xy 122.754141 -157.757372) (xy 122.766267 -157.702935)
			(xy 122.78619 -157.650844) (xy 122.813486 -157.602209) (xy 122.847572 -157.558066) (xy 122.887721 -157.519357)
			(xy 122.933079 -157.486906) (xy 122.982679 -157.461405) (xy 123.035463 -157.443398) (xy 123.090306 -157.433268)
			(xy 123.14604 -157.431231) (xy 123.201477 -157.437331) (xy 123.255434 -157.451437) (xy 123.306763 -157.473249)
			(xy 123.354369 -157.502303) (xy 123.397237 -157.537978) (xy 123.434454 -157.579515) (xy 123.465227 -157.626028)
			(xy 123.475477 -157.647894) (xy 127.113792 -157.647894) (xy 127.114327 -157.621251) (xy 127.12285 -157.568653)
			(xy 127.139707 -157.518105) (xy 127.164461 -157.470918) (xy 127.196468 -157.428318) (xy 127.2349 -157.391409)
			(xy 127.25654 -157.37586) (xy 127.267829 -157.367502) (xy 127.28568 -157.345826) (xy 127.296959 -157.320111)
			(xy 127.300815 -157.292297) (xy 127.296957 -157.264483) (xy 127.285677 -157.238768) (xy 127.267824 -157.217094)
			(xy 127.25654 -157.208728) (xy 127.234939 -157.193131) (xy 127.196524 -157.156217) (xy 127.164523 -157.113623)
			(xy 127.139765 -157.066449) (xy 127.12289 -157.015916) (xy 127.114334 -156.963332) (xy 127.113792 -156.936694)
			(xy 127.114302 -156.910707) (xy 127.122432 -156.859372) (xy 127.138493 -156.809942) (xy 127.162089 -156.763632)
			(xy 127.192639 -156.721584) (xy 127.22939 -156.684833) (xy 127.271438 -156.654283) (xy 127.317748 -156.630687)
			(xy 127.367178 -156.614626) (xy 127.418513 -156.606496) (xy 127.470487 -156.606496) (xy 127.521822 -156.614626)
			(xy 127.571252 -156.630687) (xy 127.617562 -156.654283) (xy 127.65961 -156.684833) (xy 127.696361 -156.721584)
			(xy 127.726911 -156.763632) (xy 127.750507 -156.809942) (xy 127.766568 -156.859372) (xy 127.774698 -156.910707)
			(xy 127.775208 -156.936694) (xy 127.774664 -156.963336) (xy 127.766143 -157.015935) (xy 127.749288 -157.066482)
			(xy 127.724536 -157.113669) (xy 127.69253 -157.156269) (xy 127.6541 -157.193179) (xy 127.63246 -157.208728)
			(xy 127.621182 -157.217101) (xy 127.603332 -157.238773) (xy 127.592052 -157.264485) (xy 127.588195 -157.292297)
			(xy 127.59205 -157.320108) (xy 127.603328 -157.345821) (xy 127.621177 -157.367494) (xy 127.63246 -157.37586)
			(xy 127.654056 -157.391465) (xy 127.692471 -157.428377) (xy 127.724472 -157.47097) (xy 127.749231 -157.518142)
			(xy 127.766107 -157.568673) (xy 127.774665 -157.621257) (xy 127.775208 -157.647894) (xy 128.013714 -157.647894)
			(xy 128.014239 -157.621251) (xy 128.022763 -157.568651) (xy 128.039622 -157.518103) (xy 128.064377 -157.470916)
			(xy 128.096387 -157.428316) (xy 128.13482 -157.391408) (xy 128.156462 -157.37586) (xy 128.167749 -157.3675)
			(xy 128.185596 -157.345824) (xy 128.196873 -157.320109) (xy 128.200728 -157.292297) (xy 128.196871 -157.264484)
			(xy 128.185593 -157.238771) (xy 128.167744 -157.217095) (xy 128.156462 -157.208728) (xy 128.134866 -157.193124)
			(xy 128.096449 -157.156213) (xy 128.064448 -157.11362) (xy 128.039689 -157.066447) (xy 128.022813 -157.015915)
			(xy 128.014256 -156.963332) (xy 128.013714 -156.936694) (xy 128.014224 -156.910707) (xy 128.022354 -156.859372)
			(xy 128.038415 -156.809942) (xy 128.062011 -156.763632) (xy 128.092561 -156.721584) (xy 128.129312 -156.684833)
			(xy 128.17136 -156.654283) (xy 128.21767 -156.630687) (xy 128.2671 -156.614626) (xy 128.318435 -156.606496)
			(xy 128.370409 -156.606496) (xy 128.421744 -156.614626) (xy 128.471174 -156.630687) (xy 128.517484 -156.654283)
			(xy 128.559532 -156.684833) (xy 128.596283 -156.721584) (xy 128.626833 -156.763632) (xy 128.650429 -156.809942)
			(xy 128.66649 -156.859372) (xy 128.67462 -156.910707) (xy 128.67513 -156.936694) (xy 128.67462 -156.963338)
			(xy 128.666096 -157.01594) (xy 128.649236 -157.06649) (xy 128.624478 -157.113677) (xy 128.592465 -157.156276)
			(xy 128.554026 -157.193182) (xy 128.532382 -157.208728) (xy 128.521103 -157.2171) (xy 128.503248 -157.238771)
			(xy 128.491966 -157.264484) (xy 128.488108 -157.292297) (xy 128.491964 -157.320109) (xy 128.503245 -157.345823)
			(xy 128.521098 -157.367495) (xy 128.532382 -157.37586) (xy 128.553982 -157.391458) (xy 128.592396 -157.428372)
			(xy 128.624396 -157.470967) (xy 128.649154 -157.51814) (xy 128.66603 -157.568673) (xy 128.674587 -157.621256)
			(xy 128.67513 -157.647894) (xy 128.913636 -157.647894) (xy 128.914152 -157.62125) (xy 128.922677 -157.56865)
			(xy 128.939536 -157.5181) (xy 128.964293 -157.470914) (xy 128.996305 -157.428314) (xy 129.034741 -157.391407)
			(xy 129.056384 -157.37586) (xy 129.067678 -157.367505) (xy 129.085539 -157.345831) (xy 129.096824 -157.320115)
			(xy 129.100683 -157.292297) (xy 129.096823 -157.264479) (xy 129.085535 -157.238763) (xy 129.067673 -157.217091)
			(xy 129.056384 -157.208728) (xy 129.034792 -157.193118) (xy 128.996375 -157.156208) (xy 128.964372 -157.113617)
			(xy 128.939612 -157.066446) (xy 128.922735 -157.015914) (xy 128.914178 -156.963331) (xy 128.913636 -156.936694)
			(xy 128.914146 -156.910707) (xy 128.922276 -156.859372) (xy 128.938337 -156.809942) (xy 128.961933 -156.763632)
			(xy 128.992483 -156.721584) (xy 129.029234 -156.684833) (xy 129.071282 -156.654283) (xy 129.117592 -156.630687)
			(xy 129.167022 -156.614626) (xy 129.218357 -156.606496) (xy 129.270331 -156.606496) (xy 129.321666 -156.614626)
			(xy 129.371096 -156.630687) (xy 129.417406 -156.654283) (xy 129.459454 -156.684833) (xy 129.496205 -156.721584)
			(xy 129.526755 -156.763632) (xy 129.550351 -156.809942) (xy 129.566412 -156.859372) (xy 129.574542 -156.910707)
			(xy 129.575052 -156.936694) (xy 129.574532 -156.963338) (xy 129.566009 -157.015938) (xy 129.549151 -157.066488)
			(xy 129.524395 -157.113674) (xy 129.492383 -157.156274) (xy 129.453947 -157.193181) (xy 129.432304 -157.208728)
			(xy 129.421023 -157.217099) (xy 129.403164 -157.238769) (xy 129.39188 -157.264482) (xy 129.38802 -157.292297)
			(xy 129.391878 -157.320111) (xy 129.403161 -157.345825) (xy 129.421018 -157.367497) (xy 129.432304 -157.37586)
			(xy 129.453887 -157.391481) (xy 129.492306 -157.428388) (xy 129.52431 -157.470977) (xy 129.549072 -157.518146)
			(xy 129.56595 -157.568676) (xy 129.574509 -157.621257) (xy 129.575052 -157.647894) (xy 129.813812 -157.647894)
			(xy 129.814338 -157.621251) (xy 129.822862 -157.568651) (xy 129.83972 -157.518103) (xy 129.864475 -157.470916)
			(xy 129.896485 -157.428316) (xy 129.934919 -157.391408) (xy 129.95656 -157.37586) (xy 129.967847 -157.3675)
			(xy 129.985695 -157.345824) (xy 129.996971 -157.320109) (xy 130.000827 -157.292297) (xy 129.99697 -157.264484)
			(xy 129.985691 -157.23877) (xy 129.967842 -157.217095) (xy 129.95656 -157.208728) (xy 129.934963 -157.193125)
			(xy 129.896547 -157.156213) (xy 129.864545 -157.11362) (xy 129.839786 -157.066447) (xy 129.822911 -157.015915)
			(xy 129.814354 -156.963332) (xy 129.813812 -156.936694) (xy 129.814322 -156.910707) (xy 129.822452 -156.859372)
			(xy 129.838513 -156.809942) (xy 129.862109 -156.763632) (xy 129.892659 -156.721584) (xy 129.92941 -156.684833)
			(xy 129.971458 -156.654283) (xy 130.017768 -156.630687) (xy 130.067198 -156.614626) (xy 130.118533 -156.606496)
			(xy 130.170507 -156.606496) (xy 130.221842 -156.614626) (xy 130.271272 -156.630687) (xy 130.317582 -156.654283)
			(xy 130.35963 -156.684833) (xy 130.396381 -156.721584) (xy 130.426931 -156.763632) (xy 130.450527 -156.809942)
			(xy 130.466588 -156.859372) (xy 130.474718 -156.910707) (xy 130.475228 -156.936694) (xy 130.474719 -156.963338)
			(xy 130.466195 -157.01594) (xy 130.449335 -157.06649) (xy 130.424577 -157.113677) (xy 130.392563 -157.156276)
			(xy 130.354124 -157.193182) (xy 130.33248 -157.208728) (xy 130.321201 -157.2171) (xy 130.303346 -157.238771)
			(xy 130.292064 -157.264484) (xy 130.288206 -157.292297) (xy 130.292063 -157.320109) (xy 130.303343 -157.345823)
			(xy 130.321196 -157.367495) (xy 130.33248 -157.37586) (xy 130.35408 -157.391459) (xy 130.392494 -157.428373)
			(xy 130.424494 -157.470967) (xy 130.449252 -157.518141) (xy 130.466128 -157.568673) (xy 130.474685 -157.621256)
			(xy 130.475187 -157.645862) (xy 131.429252 -157.645862) (xy 131.429677 -157.619546) (xy 131.436919 -157.567415)
			(xy 131.451245 -157.516771) (xy 131.472385 -157.468572) (xy 131.499939 -157.42373) (xy 131.533386 -157.383093)
			(xy 131.552442 -157.364938) (xy 131.55982 -157.357396) (xy 131.56836 -157.338132) (xy 131.568952 -157.3276)
			(xy 131.568952 -157.252924) (xy 131.568437 -157.242372) (xy 131.559893 -157.223076) (xy 131.552442 -157.215586)
			(xy 131.533376 -157.197442) (xy 131.499922 -157.156808) (xy 131.472366 -157.111965) (xy 131.451229 -157.063762)
			(xy 131.436914 -157.013114) (xy 131.42969 -156.960979) (xy 131.429252 -156.934662) (xy 131.429738 -156.907411)
			(xy 131.437494 -156.853463) (xy 131.452849 -156.801168) (xy 131.475491 -156.751591) (xy 131.504957 -156.705741)
			(xy 131.540648 -156.66455) (xy 131.581839 -156.628859) (xy 131.627689 -156.599393) (xy 131.677266 -156.576751)
			(xy 131.729561 -156.561396) (xy 131.783509 -156.55364) (xy 131.838011 -156.55364) (xy 131.891959 -156.561396)
			(xy 131.944254 -156.576751) (xy 131.993831 -156.599393) (xy 132.039681 -156.628859) (xy 132.058426 -156.645101)
			(xy 133.41382 -156.645101) (xy 133.418135 -156.587828) (xy 133.430985 -156.531848) (xy 133.452079 -156.478427)
			(xy 133.48094 -156.428769) (xy 133.516917 -156.383997) (xy 133.537706 -156.364178) (xy 133.54512 -156.356667)
			(xy 133.553637 -156.337379) (xy 133.554216 -156.32684) (xy 133.554216 -156.252164) (xy 133.553661 -156.241617)
			(xy 133.545144 -156.222322) (xy 133.537706 -156.214826) (xy 133.518671 -156.196649) (xy 133.485212 -156.156024)
			(xy 133.45765 -156.111189) (xy 133.436508 -156.062992) (xy 133.422186 -156.012348) (xy 133.414957 -155.960217)
			(xy 133.414516 -155.933902) (xy 133.415002 -155.906651) (xy 133.422758 -155.852703) (xy 133.438113 -155.800408)
			(xy 133.460755 -155.750831) (xy 133.490221 -155.704981) (xy 133.525912 -155.66379) (xy 133.567103 -155.628099)
			(xy 133.612953 -155.598633) (xy 133.66253 -155.575991) (xy 133.714825 -155.560636) (xy 133.768773 -155.55288)
			(xy 133.823275 -155.55288) (xy 133.877223 -155.560636) (xy 133.929518 -155.575991) (xy 133.979095 -155.598633)
			(xy 134.024945 -155.628099) (xy 134.066136 -155.66379) (xy 134.101827 -155.704981) (xy 134.131293 -155.750831)
			(xy 134.153935 -155.800408) (xy 134.16929 -155.852703) (xy 134.177046 -155.906651) (xy 134.177532 -155.933902)
			(xy 134.177056 -155.960216) (xy 134.169821 -156.012343) (xy 134.155503 -156.062985) (xy 134.134372 -156.111184)
			(xy 134.106828 -156.156028) (xy 134.073392 -156.196669) (xy 134.054342 -156.214826) (xy 134.046933 -156.222342)
			(xy 134.038412 -156.241626) (xy 134.037832 -156.252164) (xy 134.037832 -156.32684) (xy 134.038371 -156.337389)
			(xy 134.046898 -156.356685) (xy 134.054342 -156.364178) (xy 134.075131 -156.383997) (xy 134.111104 -156.42877)
			(xy 134.139961 -156.478428) (xy 134.161053 -156.53185) (xy 134.173901 -156.587829) (xy 134.178216 -156.645101)
			(xy 134.1739 -156.702373) (xy 134.172764 -156.707322) (xy 136.479628 -156.707322) (xy 136.48394 -156.650052)
			(xy 136.496786 -156.594075) (xy 136.517874 -156.540656) (xy 136.54673 -156.490999) (xy 136.5827 -156.446228)
			(xy 136.603486 -156.426408) (xy 136.610884 -156.418883) (xy 136.619411 -156.399606) (xy 136.619996 -156.38907)
			(xy 136.619996 -156.314394) (xy 136.619485 -156.303842) (xy 136.610937 -156.284547) (xy 136.603486 -156.277056)
			(xy 136.584413 -156.258918) (xy 136.550958 -156.218284) (xy 136.523402 -156.17344) (xy 136.502267 -156.125236)
			(xy 136.487953 -156.074585) (xy 136.480732 -156.022449) (xy 136.480296 -155.996132) (xy 136.480782 -155.968881)
			(xy 136.488538 -155.914933) (xy 136.503893 -155.862638) (xy 136.526535 -155.813061) (xy 136.556001 -155.767211)
			(xy 136.591692 -155.72602) (xy 136.632883 -155.690329) (xy 136.678733 -155.660863) (xy 136.72831 -155.638221)
			(xy 136.780605 -155.622866) (xy 136.834553 -155.61511) (xy 136.889055 -155.61511) (xy 136.943003 -155.622866)
			(xy 136.995298 -155.638221) (xy 137.044875 -155.660863) (xy 137.090725 -155.690329) (xy 137.131916 -155.72602)
			(xy 137.167607 -155.767211) (xy 137.197073 -155.813061) (xy 137.219715 -155.862638) (xy 137.23507 -155.914933)
			(xy 137.242826 -155.968881) (xy 137.243312 -155.996132) (xy 137.242862 -156.022447) (xy 137.235623 -156.074576)
			(xy 137.2213 -156.125219) (xy 137.200165 -156.173417) (xy 137.172616 -156.21826) (xy 137.139175 -156.2589)
			(xy 137.120122 -156.277056) (xy 137.112741 -156.284595) (xy 137.104204 -156.303862) (xy 137.103612 -156.314394)
			(xy 137.103612 -156.38907) (xy 137.10414 -156.39962) (xy 137.112676 -156.418915) (xy 137.120122 -156.426408)
			(xy 137.140942 -156.446196) (xy 137.176916 -156.490973) (xy 137.205775 -156.540636) (xy 137.226865 -156.594062)
			(xy 137.239712 -156.650045) (xy 137.244024 -156.707322) (xy 137.239705 -156.764598) (xy 137.226852 -156.820579)
			(xy 137.205756 -156.874003) (xy 137.176892 -156.923663) (xy 137.140912 -156.968436) (xy 137.120122 -156.988256)
			(xy 137.112741 -156.995795) (xy 137.104204 -157.015062) (xy 137.103612 -157.025594) (xy 137.103612 -157.10027)
			(xy 137.10414 -157.11082) (xy 137.112676 -157.130115) (xy 137.120122 -157.137608) (xy 137.139179 -157.155762)
			(xy 137.172635 -157.196393) (xy 137.200193 -157.241234) (xy 137.221331 -157.289434) (xy 137.235648 -157.340082)
			(xy 137.242873 -157.392216) (xy 137.243312 -157.418532) (xy 137.242826 -157.445783) (xy 137.23507 -157.499731)
			(xy 137.219715 -157.552026) (xy 137.197073 -157.601603) (xy 137.167607 -157.647453) (xy 137.131916 -157.688644)
			(xy 137.090725 -157.724335) (xy 137.044875 -157.753801) (xy 136.995298 -157.776443) (xy 136.943003 -157.791798)
			(xy 136.889055 -157.799554) (xy 136.834553 -157.799554) (xy 136.780605 -157.791798) (xy 136.72831 -157.776443)
			(xy 136.678733 -157.753801) (xy 136.632883 -157.724335) (xy 136.591692 -157.688644) (xy 136.556001 -157.647453)
			(xy 136.526535 -157.601603) (xy 136.503893 -157.552026) (xy 136.488538 -157.499731) (xy 136.480782 -157.445783)
			(xy 136.480296 -157.418532) (xy 136.480719 -157.392217) (xy 136.487963 -157.340086) (xy 136.502291 -157.289443)
			(xy 136.523432 -157.241244) (xy 136.550986 -157.196401) (xy 136.584431 -157.155764) (xy 136.603486 -157.137608)
			(xy 136.610884 -157.130083) (xy 136.619411 -157.110806) (xy 136.619996 -157.10027) (xy 136.619996 -157.025594)
			(xy 136.619485 -157.015042) (xy 136.610937 -156.995747) (xy 136.603486 -156.988256) (xy 136.58273 -156.968404)
			(xy 136.546754 -156.923636) (xy 136.517893 -156.873983) (xy 136.496798 -156.820566) (xy 136.483947 -156.764591)
			(xy 136.479628 -156.707322) (xy 134.172764 -156.707322) (xy 134.161052 -156.758352) (xy 134.13996 -156.811774)
			(xy 134.111102 -156.861432) (xy 134.075129 -156.906205) (xy 134.054342 -156.926026) (xy 134.046933 -156.933542)
			(xy 134.038412 -156.952826) (xy 134.037832 -156.963364) (xy 134.037832 -157.03804) (xy 134.038371 -157.048589)
			(xy 134.046898 -157.067885) (xy 134.054342 -157.075378) (xy 134.073388 -157.093543) (xy 134.106844 -157.134172)
			(xy 134.134404 -157.17901) (xy 134.155543 -157.227209) (xy 134.169863 -157.277854) (xy 134.177091 -157.329987)
			(xy 134.177532 -157.356302) (xy 134.177046 -157.383553) (xy 134.16929 -157.437501) (xy 134.153935 -157.489796)
			(xy 134.131293 -157.539373) (xy 134.101827 -157.585223) (xy 134.066136 -157.626414) (xy 134.024945 -157.662105)
			(xy 133.979095 -157.691571) (xy 133.929518 -157.714213) (xy 133.877223 -157.729568) (xy 133.823275 -157.737324)
			(xy 133.768773 -157.737324) (xy 133.714825 -157.729568) (xy 133.66253 -157.714213) (xy 133.612953 -157.691571)
			(xy 133.567103 -157.662105) (xy 133.525912 -157.626414) (xy 133.490221 -157.585223) (xy 133.460755 -157.539373)
			(xy 133.438113 -157.489796) (xy 133.422758 -157.437501) (xy 133.415002 -157.383553) (xy 133.414516 -157.356302)
			(xy 133.41498 -157.329988) (xy 133.422215 -157.277859) (xy 133.436534 -157.227216) (xy 133.457667 -157.179017)
			(xy 133.485214 -157.134174) (xy 133.518654 -157.093534) (xy 133.537706 -157.075378) (xy 133.54512 -157.067867)
			(xy 133.553637 -157.048579) (xy 133.554216 -157.03804) (xy 133.554216 -156.963364) (xy 133.553661 -156.952817)
			(xy 133.545144 -156.933522) (xy 133.537706 -156.926026) (xy 133.516919 -156.906205) (xy 133.480942 -156.861433)
			(xy 133.45208 -156.811776) (xy 133.430986 -156.758354) (xy 133.418136 -156.702375) (xy 133.41382 -156.645101)
			(xy 132.058426 -156.645101) (xy 132.080872 -156.66455) (xy 132.116563 -156.705741) (xy 132.146029 -156.751591)
			(xy 132.168671 -156.801168) (xy 132.184026 -156.853463) (xy 132.191782 -156.907411) (xy 132.192268 -156.934662)
			(xy 132.191852 -156.960978) (xy 132.184608 -157.013109) (xy 132.17028 -157.063753) (xy 132.149138 -157.111952)
			(xy 132.121582 -157.156794) (xy 132.088134 -157.197431) (xy 132.069078 -157.215586) (xy 132.061677 -157.223108)
			(xy 132.053153 -157.242388) (xy 132.052568 -157.252924) (xy 132.052568 -157.3276) (xy 132.053093 -157.33815)
			(xy 132.061632 -157.357445) (xy 132.069078 -157.364938) (xy 132.088141 -157.383086) (xy 132.121598 -157.423717)
			(xy 132.149157 -157.468559) (xy 132.170294 -157.516761) (xy 132.184609 -157.56741) (xy 132.191831 -157.619545)
			(xy 132.192268 -157.645862) (xy 132.191782 -157.673113) (xy 132.184026 -157.727061) (xy 132.168671 -157.779356)
			(xy 132.146029 -157.828933) (xy 132.116563 -157.874783) (xy 132.080872 -157.915974) (xy 132.039681 -157.951665)
			(xy 131.993831 -157.981131) (xy 131.944254 -158.003773) (xy 131.891959 -158.019128) (xy 131.838011 -158.026884)
			(xy 131.783509 -158.026884) (xy 131.729561 -158.019128) (xy 131.677266 -158.003773) (xy 131.627689 -157.981131)
			(xy 131.581839 -157.951665) (xy 131.540648 -157.915974) (xy 131.504957 -157.874783) (xy 131.475491 -157.828933)
			(xy 131.452849 -157.779356) (xy 131.437494 -157.727061) (xy 131.429738 -157.673113) (xy 131.429252 -157.645862)
			(xy 130.475187 -157.645862) (xy 130.475228 -157.647894) (xy 130.474718 -157.673881) (xy 130.466588 -157.725216)
			(xy 130.450527 -157.774646) (xy 130.426931 -157.820956) (xy 130.396381 -157.863004) (xy 130.35963 -157.899755)
			(xy 130.317582 -157.930305) (xy 130.271272 -157.953901) (xy 130.221842 -157.969962) (xy 130.170507 -157.978092)
			(xy 130.118533 -157.978092) (xy 130.067198 -157.969962) (xy 130.017768 -157.953901) (xy 129.971458 -157.930305)
			(xy 129.92941 -157.899755) (xy 129.892659 -157.863004) (xy 129.862109 -157.820956) (xy 129.838513 -157.774646)
			(xy 129.822452 -157.725216) (xy 129.814322 -157.673881) (xy 129.813812 -157.647894) (xy 129.575052 -157.647894)
			(xy 129.574542 -157.673881) (xy 129.566412 -157.725216) (xy 129.550351 -157.774646) (xy 129.526755 -157.820956)
			(xy 129.496205 -157.863004) (xy 129.459454 -157.899755) (xy 129.417406 -157.930305) (xy 129.371096 -157.953901)
			(xy 129.321666 -157.969962) (xy 129.270331 -157.978092) (xy 129.218357 -157.978092) (xy 129.167022 -157.969962)
			(xy 129.117592 -157.953901) (xy 129.071282 -157.930305) (xy 129.029234 -157.899755) (xy 128.992483 -157.863004)
			(xy 128.961933 -157.820956) (xy 128.938337 -157.774646) (xy 128.922276 -157.725216) (xy 128.914146 -157.673881)
			(xy 128.913636 -157.647894) (xy 128.67513 -157.647894) (xy 128.67462 -157.673881) (xy 128.66649 -157.725216)
			(xy 128.650429 -157.774646) (xy 128.626833 -157.820956) (xy 128.596283 -157.863004) (xy 128.559532 -157.899755)
			(xy 128.517484 -157.930305) (xy 128.471174 -157.953901) (xy 128.421744 -157.969962) (xy 128.370409 -157.978092)
			(xy 128.318435 -157.978092) (xy 128.2671 -157.969962) (xy 128.21767 -157.953901) (xy 128.17136 -157.930305)
			(xy 128.129312 -157.899755) (xy 128.092561 -157.863004) (xy 128.062011 -157.820956) (xy 128.038415 -157.774646)
			(xy 128.022354 -157.725216) (xy 128.014224 -157.673881) (xy 128.013714 -157.647894) (xy 127.775208 -157.647894)
			(xy 127.774698 -157.673881) (xy 127.766568 -157.725216) (xy 127.750507 -157.774646) (xy 127.726911 -157.820956)
			(xy 127.696361 -157.863004) (xy 127.65961 -157.899755) (xy 127.617562 -157.930305) (xy 127.571252 -157.953901)
			(xy 127.521822 -157.969962) (xy 127.470487 -157.978092) (xy 127.418513 -157.978092) (xy 127.367178 -157.969962)
			(xy 127.317748 -157.953901) (xy 127.271438 -157.930305) (xy 127.22939 -157.899755) (xy 127.192639 -157.863004)
			(xy 127.162089 -157.820956) (xy 127.138493 -157.774646) (xy 127.122432 -157.725216) (xy 127.114302 -157.673881)
			(xy 127.113792 -157.647894) (xy 123.475477 -157.647894) (xy 123.488899 -157.676525) (xy 123.504967 -157.729932)
			(xy 123.513087 -157.785108) (xy 123.513596 -157.812994) (xy 123.513087 -157.84088) (xy 123.504967 -157.896056)
			(xy 123.488899 -157.949463) (xy 123.465227 -157.99996) (xy 123.434454 -158.046473) (xy 123.421984 -158.06039)
			(xy 124.93955 -158.06039) (xy 124.943621 -158.004768) (xy 124.955747 -157.950331) (xy 124.97567 -157.89824)
			(xy 125.002966 -157.849605) (xy 125.037052 -157.805462) (xy 125.077201 -157.766753) (xy 125.122559 -157.734302)
			(xy 125.172159 -157.708801) (xy 125.224943 -157.690794) (xy 125.279786 -157.680664) (xy 125.33552 -157.678627)
			(xy 125.390957 -157.684727) (xy 125.444914 -157.698833) (xy 125.496243 -157.720645) (xy 125.543849 -157.749699)
			(xy 125.586717 -157.785374) (xy 125.623934 -157.826911) (xy 125.654707 -157.873424) (xy 125.678379 -157.923921)
			(xy 125.694447 -157.977328) (xy 125.702567 -158.032504) (xy 125.703076 -158.06039) (xy 125.702567 -158.088276)
			(xy 125.694447 -158.143452) (xy 125.678379 -158.196859) (xy 125.654707 -158.247356) (xy 125.623934 -158.293869)
			(xy 125.586717 -158.335406) (xy 125.543849 -158.371081) (xy 125.496243 -158.400135) (xy 125.444914 -158.421947)
			(xy 125.390957 -158.436053) (xy 125.33552 -158.442153) (xy 125.279786 -158.440116) (xy 125.224943 -158.429986)
			(xy 125.172159 -158.411979) (xy 125.122559 -158.386478) (xy 125.077201 -158.354027) (xy 125.037052 -158.315318)
			(xy 125.002966 -158.271175) (xy 124.97567 -158.22254) (xy 124.955747 -158.170449) (xy 124.943621 -158.116012)
			(xy 124.93955 -158.06039) (xy 123.421984 -158.06039) (xy 123.397237 -158.08801) (xy 123.354369 -158.123685)
			(xy 123.306763 -158.152739) (xy 123.255434 -158.174551) (xy 123.201477 -158.188657) (xy 123.14604 -158.194757)
			(xy 123.090306 -158.19272) (xy 123.035463 -158.18259) (xy 122.982679 -158.164583) (xy 122.933079 -158.139082)
			(xy 122.887721 -158.106631) (xy 122.847572 -158.067922) (xy 122.813486 -158.023779) (xy 122.78619 -157.975144)
			(xy 122.766267 -157.923053) (xy 122.754141 -157.868616) (xy 122.75007 -157.812994) (xy 121.964704 -157.812994)
			(xy 121.964704 -158.828994) (xy 122.75007 -158.828994) (xy 122.754141 -158.773372) (xy 122.766267 -158.718935)
			(xy 122.78619 -158.666844) (xy 122.813486 -158.618209) (xy 122.847572 -158.574066) (xy 122.887721 -158.535357)
			(xy 122.933079 -158.502906) (xy 122.982679 -158.477405) (xy 123.035463 -158.459398) (xy 123.090306 -158.449268)
			(xy 123.14604 -158.447231) (xy 123.201477 -158.453331) (xy 123.255434 -158.467437) (xy 123.306763 -158.489249)
			(xy 123.354369 -158.518303) (xy 123.397237 -158.553978) (xy 123.434454 -158.595515) (xy 123.465227 -158.642028)
			(xy 123.488899 -158.692525) (xy 123.504967 -158.745932) (xy 123.506052 -158.753302) (xy 132.616446 -158.753302)
			(xy 132.620517 -158.69768) (xy 132.632643 -158.643243) (xy 132.652566 -158.591152) (xy 132.679862 -158.542517)
			(xy 132.713948 -158.498374) (xy 132.754097 -158.459665) (xy 132.799455 -158.427214) (xy 132.849055 -158.401713)
			(xy 132.901839 -158.383706) (xy 132.956682 -158.373576) (xy 133.012416 -158.371539) (xy 133.067853 -158.377639)
			(xy 133.12181 -158.391745) (xy 133.173139 -158.413557) (xy 133.220745 -158.442611) (xy 133.263613 -158.478286)
			(xy 133.30083 -158.519823) (xy 133.331603 -158.566336) (xy 133.355275 -158.616833) (xy 133.371343 -158.67024)
			(xy 133.379463 -158.725416) (xy 133.379972 -158.753302) (xy 133.379463 -158.781188) (xy 133.371343 -158.836364)
			(xy 133.355275 -158.889771) (xy 133.331603 -158.940268) (xy 133.30083 -158.986781) (xy 133.263613 -159.028318)
			(xy 133.220745 -159.063993) (xy 133.173139 -159.093047) (xy 133.12181 -159.114859) (xy 133.067853 -159.128965)
			(xy 133.012416 -159.135065) (xy 132.956682 -159.133028) (xy 132.901839 -159.122898) (xy 132.849055 -159.104891)
			(xy 132.799455 -159.07939) (xy 132.754097 -159.046939) (xy 132.713948 -159.00823) (xy 132.679862 -158.964087)
			(xy 132.652566 -158.915452) (xy 132.632643 -158.863361) (xy 132.620517 -158.808924) (xy 132.616446 -158.753302)
			(xy 123.506052 -158.753302) (xy 123.513087 -158.801108) (xy 123.513596 -158.828994) (xy 123.513087 -158.85688)
			(xy 123.504967 -158.912056) (xy 123.488899 -158.965463) (xy 123.465227 -159.01596) (xy 123.434454 -159.062473)
			(xy 123.397237 -159.10401) (xy 123.354369 -159.139685) (xy 123.306763 -159.168739) (xy 123.255434 -159.190551)
			(xy 123.201477 -159.204657) (xy 123.14604 -159.210757) (xy 123.090306 -159.20872) (xy 123.035463 -159.19859)
			(xy 122.982679 -159.180583) (xy 122.933079 -159.155082) (xy 122.887721 -159.122631) (xy 122.847572 -159.083922)
			(xy 122.813486 -159.039779) (xy 122.78619 -158.991144) (xy 122.766267 -158.939053) (xy 122.754141 -158.884616)
			(xy 122.75007 -158.828994) (xy 121.964704 -158.828994) (xy 121.964704 -159.439102) (xy 125.007876 -159.439102)
			(xy 125.011947 -159.38348) (xy 125.024073 -159.329043) (xy 125.043996 -159.276952) (xy 125.071292 -159.228317)
			(xy 125.105378 -159.184174) (xy 125.145527 -159.145465) (xy 125.190885 -159.113014) (xy 125.240485 -159.087513)
			(xy 125.293269 -159.069506) (xy 125.348112 -159.059376) (xy 125.403846 -159.057339) (xy 125.459283 -159.063439)
			(xy 125.51324 -159.077545) (xy 125.564569 -159.099357) (xy 125.612175 -159.128411) (xy 125.655043 -159.164086)
			(xy 125.69226 -159.205623) (xy 125.723033 -159.252136) (xy 125.746705 -159.302633) (xy 125.762773 -159.35604)
			(xy 125.770893 -159.411216) (xy 125.771402 -159.439102) (xy 125.770893 -159.466988) (xy 125.762773 -159.522164)
			(xy 125.75987 -159.531812) (xy 128.212594 -159.531812) (xy 128.216665 -159.47619) (xy 128.228791 -159.421753)
			(xy 128.248714 -159.369662) (xy 128.27601 -159.321027) (xy 128.310096 -159.276884) (xy 128.350245 -159.238175)
			(xy 128.395603 -159.205724) (xy 128.445203 -159.180223) (xy 128.497987 -159.162216) (xy 128.55283 -159.152086)
			(xy 128.608564 -159.150049) (xy 128.664001 -159.156149) (xy 128.717958 -159.170255) (xy 128.769287 -159.192067)
			(xy 128.816893 -159.221121) (xy 128.859761 -159.256796) (xy 128.896978 -159.298333) (xy 128.927751 -159.344846)
			(xy 128.951423 -159.395343) (xy 128.967491 -159.44875) (xy 128.97336 -159.488632) (xy 130.4958 -159.488632)
			(xy 130.499871 -159.43301) (xy 130.511997 -159.378573) (xy 130.53192 -159.326482) (xy 130.559216 -159.277847)
			(xy 130.593302 -159.233704) (xy 130.633451 -159.194995) (xy 130.678809 -159.162544) (xy 130.728409 -159.137043)
			(xy 130.781193 -159.119036) (xy 130.836036 -159.108906) (xy 130.89177 -159.106869) (xy 130.947207 -159.112969)
			(xy 131.001164 -159.127075) (xy 131.052493 -159.148887) (xy 131.100099 -159.177941) (xy 131.142967 -159.213616)
			(xy 131.180184 -159.255153) (xy 131.210957 -159.301666) (xy 131.234629 -159.352163) (xy 131.250697 -159.40557)
			(xy 131.258817 -159.460746) (xy 131.259326 -159.488632) (xy 131.258817 -159.516518) (xy 131.250697 -159.571694)
			(xy 131.234629 -159.625101) (xy 131.210957 -159.675598) (xy 131.180184 -159.722111) (xy 131.142967 -159.763648)
			(xy 131.100099 -159.799323) (xy 131.052493 -159.828377) (xy 131.001164 -159.850189) (xy 130.947207 -159.864295)
			(xy 130.89177 -159.870395) (xy 130.836036 -159.868358) (xy 130.781193 -159.858228) (xy 130.728409 -159.840221)
			(xy 130.678809 -159.81472) (xy 130.633451 -159.782269) (xy 130.593302 -159.74356) (xy 130.559216 -159.699417)
			(xy 130.53192 -159.650782) (xy 130.511997 -159.598691) (xy 130.499871 -159.544254) (xy 130.4958 -159.488632)
			(xy 128.97336 -159.488632) (xy 128.975611 -159.503926) (xy 128.97612 -159.531812) (xy 128.975611 -159.559698)
			(xy 128.967491 -159.614874) (xy 128.951423 -159.668281) (xy 128.927751 -159.718778) (xy 128.896978 -159.765291)
			(xy 128.859761 -159.806828) (xy 128.816893 -159.842503) (xy 128.769287 -159.871557) (xy 128.717958 -159.893369)
			(xy 128.664001 -159.907475) (xy 128.608564 -159.913575) (xy 128.55283 -159.911538) (xy 128.497987 -159.901408)
			(xy 128.445203 -159.883401) (xy 128.395603 -159.8579) (xy 128.350245 -159.825449) (xy 128.310096 -159.78674)
			(xy 128.27601 -159.742597) (xy 128.248714 -159.693962) (xy 128.228791 -159.641871) (xy 128.216665 -159.587434)
			(xy 128.212594 -159.531812) (xy 125.75987 -159.531812) (xy 125.746705 -159.575571) (xy 125.723033 -159.626068)
			(xy 125.69226 -159.672581) (xy 125.655043 -159.714118) (xy 125.612175 -159.749793) (xy 125.564569 -159.778847)
			(xy 125.51324 -159.800659) (xy 125.459283 -159.814765) (xy 125.403846 -159.820865) (xy 125.348112 -159.818828)
			(xy 125.293269 -159.808698) (xy 125.240485 -159.790691) (xy 125.190885 -159.76519) (xy 125.145527 -159.732739)
			(xy 125.105378 -159.69403) (xy 125.071292 -159.649887) (xy 125.043996 -159.601252) (xy 125.024073 -159.549161)
			(xy 125.011947 -159.494724) (xy 125.007876 -159.439102) (xy 121.964704 -159.439102) (xy 121.964704 -159.844994)
			(xy 122.75007 -159.844994) (xy 122.754141 -159.789372) (xy 122.766267 -159.734935) (xy 122.78619 -159.682844)
			(xy 122.813486 -159.634209) (xy 122.847572 -159.590066) (xy 122.887721 -159.551357) (xy 122.933079 -159.518906)
			(xy 122.982679 -159.493405) (xy 123.035463 -159.475398) (xy 123.090306 -159.465268) (xy 123.14604 -159.463231)
			(xy 123.201477 -159.469331) (xy 123.255434 -159.483437) (xy 123.306763 -159.505249) (xy 123.354369 -159.534303)
			(xy 123.397237 -159.569978) (xy 123.434454 -159.611515) (xy 123.465227 -159.658028) (xy 123.488899 -159.708525)
			(xy 123.504967 -159.761932) (xy 123.513087 -159.817108) (xy 123.513596 -159.844994) (xy 123.513087 -159.87288)
			(xy 123.504967 -159.928056) (xy 123.488899 -159.981463) (xy 123.465227 -160.03196) (xy 123.434454 -160.078473)
			(xy 123.397237 -160.12001) (xy 123.354369 -160.155685) (xy 123.306763 -160.184739) (xy 123.255434 -160.206551)
			(xy 123.201477 -160.220657) (xy 123.14604 -160.226757) (xy 123.090306 -160.22472) (xy 123.035463 -160.21459)
			(xy 122.982679 -160.196583) (xy 122.933079 -160.171082) (xy 122.887721 -160.138631) (xy 122.847572 -160.099922)
			(xy 122.813486 -160.055779) (xy 122.78619 -160.007144) (xy 122.766267 -159.955053) (xy 122.754141 -159.900616)
			(xy 122.75007 -159.844994) (xy 121.964704 -159.844994) (xy 121.964704 -160.06699) (xy 121.965107 -160.077062)
			(xy 121.97284 -160.095662) (xy 121.97969 -160.103058) (xy 122.842528 -160.965896) (xy 125.037594 -160.965896)
			(xy 125.041665 -160.910274) (xy 125.053791 -160.855837) (xy 125.073714 -160.803746) (xy 125.10101 -160.755111)
			(xy 125.135096 -160.710968) (xy 125.175245 -160.672259) (xy 125.220603 -160.639808) (xy 125.270203 -160.614307)
			(xy 125.322987 -160.5963) (xy 125.37783 -160.58617) (xy 125.433564 -160.584133) (xy 125.489001 -160.590233)
			(xy 125.542958 -160.604339) (xy 125.594287 -160.626151) (xy 125.641893 -160.655205) (xy 125.684761 -160.69088)
			(xy 125.721978 -160.732417) (xy 125.752751 -160.77893) (xy 125.776423 -160.829427) (xy 125.792491 -160.882834)
			(xy 125.800611 -160.93801) (xy 125.801083 -160.963864) (xy 126.429514 -160.963864) (xy 126.433585 -160.908242)
			(xy 126.445711 -160.853805) (xy 126.465634 -160.801714) (xy 126.49293 -160.753079) (xy 126.527016 -160.708936)
			(xy 126.567165 -160.670227) (xy 126.612523 -160.637776) (xy 126.662123 -160.612275) (xy 126.714907 -160.594268)
			(xy 126.76975 -160.584138) (xy 126.825484 -160.582101) (xy 126.880921 -160.588201) (xy 126.934878 -160.602307)
			(xy 126.986207 -160.624119) (xy 127.033813 -160.653173) (xy 127.076681 -160.688848) (xy 127.113898 -160.730385)
			(xy 127.144671 -160.776898) (xy 127.168343 -160.827395) (xy 127.184411 -160.880802) (xy 127.192531 -160.935978)
			(xy 127.19304 -160.963864) (xy 127.192947 -160.968944) (xy 127.701292 -160.968944) (xy 127.705363 -160.913322)
			(xy 127.717489 -160.858885) (xy 127.737412 -160.806794) (xy 127.764708 -160.758159) (xy 127.798794 -160.714016)
			(xy 127.838943 -160.675307) (xy 127.884301 -160.642856) (xy 127.933901 -160.617355) (xy 127.986685 -160.599348)
			(xy 128.041528 -160.589218) (xy 128.097262 -160.587181) (xy 128.152699 -160.593281) (xy 128.206656 -160.607387)
			(xy 128.257985 -160.629199) (xy 128.305591 -160.658253) (xy 128.348459 -160.693928) (xy 128.385676 -160.735465)
			(xy 128.416449 -160.781978) (xy 128.440121 -160.832475) (xy 128.456189 -160.885882) (xy 128.458582 -160.902142)
			(xy 129.482594 -160.902142) (xy 129.486665 -160.84652) (xy 129.498791 -160.792083) (xy 129.518714 -160.739992)
			(xy 129.54601 -160.691357) (xy 129.580096 -160.647214) (xy 129.620245 -160.608505) (xy 129.665603 -160.576054)
			(xy 129.715203 -160.550553) (xy 129.767987 -160.532546) (xy 129.82283 -160.522416) (xy 129.878564 -160.520379)
			(xy 129.934001 -160.526479) (xy 129.987958 -160.540585) (xy 130.039287 -160.562397) (xy 130.086893 -160.591451)
			(xy 130.129761 -160.627126) (xy 130.166978 -160.668663) (xy 130.197751 -160.715176) (xy 130.221423 -160.765673)
			(xy 130.237491 -160.81908) (xy 130.245611 -160.874256) (xy 130.24612 -160.902142) (xy 130.245611 -160.930028)
			(xy 130.237491 -160.985204) (xy 130.221423 -161.038611) (xy 130.197751 -161.089108) (xy 130.166978 -161.135621)
			(xy 130.129761 -161.177158) (xy 130.086893 -161.212833) (xy 130.039287 -161.241887) (xy 129.987958 -161.263699)
			(xy 129.934001 -161.277805) (xy 129.878564 -161.283905) (xy 129.82283 -161.281868) (xy 129.767987 -161.271738)
			(xy 129.715203 -161.253731) (xy 129.665603 -161.22823) (xy 129.620245 -161.195779) (xy 129.580096 -161.15707)
			(xy 129.54601 -161.112927) (xy 129.518714 -161.064292) (xy 129.498791 -161.012201) (xy 129.486665 -160.957764)
			(xy 129.482594 -160.902142) (xy 128.458582 -160.902142) (xy 128.464309 -160.941058) (xy 128.464818 -160.968944)
			(xy 128.464309 -160.99683) (xy 128.456189 -161.052006) (xy 128.440121 -161.105413) (xy 128.416449 -161.15591)
			(xy 128.385676 -161.202423) (xy 128.348459 -161.24396) (xy 128.305591 -161.279635) (xy 128.257985 -161.308689)
			(xy 128.206656 -161.330501) (xy 128.152699 -161.344607) (xy 128.097262 -161.350707) (xy 128.041528 -161.34867)
			(xy 127.986685 -161.33854) (xy 127.933901 -161.320533) (xy 127.884301 -161.295032) (xy 127.838943 -161.262581)
			(xy 127.798794 -161.223872) (xy 127.764708 -161.179729) (xy 127.737412 -161.131094) (xy 127.717489 -161.079003)
			(xy 127.705363 -161.024566) (xy 127.701292 -160.968944) (xy 127.192947 -160.968944) (xy 127.192531 -160.99175)
			(xy 127.184411 -161.046926) (xy 127.168343 -161.100333) (xy 127.144671 -161.15083) (xy 127.113898 -161.197343)
			(xy 127.076681 -161.23888) (xy 127.033813 -161.274555) (xy 126.986207 -161.303609) (xy 126.934878 -161.325421)
			(xy 126.880921 -161.339527) (xy 126.825484 -161.345627) (xy 126.76975 -161.34359) (xy 126.714907 -161.33346)
			(xy 126.662123 -161.315453) (xy 126.612523 -161.289952) (xy 126.567165 -161.257501) (xy 126.527016 -161.218792)
			(xy 126.49293 -161.174649) (xy 126.465634 -161.126014) (xy 126.445711 -161.073923) (xy 126.433585 -161.019486)
			(xy 126.429514 -160.963864) (xy 125.801083 -160.963864) (xy 125.80112 -160.965896) (xy 125.800611 -160.993782)
			(xy 125.792491 -161.048958) (xy 125.776423 -161.102365) (xy 125.752751 -161.152862) (xy 125.721978 -161.199375)
			(xy 125.684761 -161.240912) (xy 125.641893 -161.276587) (xy 125.594287 -161.305641) (xy 125.542958 -161.327453)
			(xy 125.489001 -161.341559) (xy 125.433564 -161.347659) (xy 125.37783 -161.345622) (xy 125.322987 -161.335492)
			(xy 125.270203 -161.317485) (xy 125.220603 -161.291984) (xy 125.175245 -161.259533) (xy 125.135096 -161.220824)
			(xy 125.10101 -161.176681) (xy 125.073714 -161.128046) (xy 125.053791 -161.075955) (xy 125.041665 -161.021518)
			(xy 125.037594 -160.965896) (xy 122.842528 -160.965896) (xy 125.207522 -163.33089) (xy 125.214922 -163.337731)
			(xy 125.233521 -163.345451) (xy 125.24359 -163.345876) (xy 131.810252 -163.345876) (xy 131.820319 -163.345432)
			(xy 131.838918 -163.337725) (xy 131.84632 -163.33089) (xy 132.15493 -163.022026) (xy 132.159059 -163.017644)
			(xy 132.165336 -163.007371) (xy 132.167376 -163.001706) (xy 132.167376 -163.001198) (xy 132.175785 -162.975641)
			(xy 132.198862 -162.927037) (xy 132.228538 -162.882157) (xy 132.264224 -162.84189) (xy 132.305213 -162.807036)
			(xy 132.350692 -162.778286) (xy 132.399758 -162.756209) (xy 132.451439 -162.741245) (xy 132.50471 -162.733688)
			(xy 132.531612 -162.733228) (xy 132.558867 -162.733644) (xy 132.612821 -162.741403) (xy 132.665122 -162.756763)
			(xy 132.714705 -162.779409) (xy 132.76056 -162.808882) (xy 132.801753 -162.844581) (xy 132.837447 -162.885779)
			(xy 132.866914 -162.931637) (xy 132.889554 -162.981223) (xy 132.904907 -163.033526) (xy 132.91266 -163.087481)
			(xy 132.91312 -163.114736) (xy 132.912638 -163.141646) (xy 132.905058 -163.194929) (xy 132.890065 -163.246618)
			(xy 132.867959 -163.295688) (xy 132.839178 -163.341166) (xy 132.804293 -163.382148) (xy 132.763995 -163.417822)
			(xy 132.719085 -163.447481) (xy 132.670453 -163.470535) (xy 132.644896 -163.478972) (xy 132.644642 -163.478972)
			(xy 132.638945 -163.480943) (xy 132.628672 -163.487245) (xy 132.624322 -163.491418) (xy 132.203444 -163.912296)
			(xy 132.184668 -163.930323) (xy 132.142552 -163.960904) (xy 132.096178 -163.984532) (xy 132.046682 -164.000628)
			(xy 131.995279 -164.008796) (xy 131.969256 -164.009324) (xy 128.68656 -164.009324) (xy 128.660906 -164.026342)
			(xy 128.655064 -164.04082) (xy 128.651748 -164.050219) (xy 128.651737 -164.070127) (xy 128.659315 -164.088535)
			(xy 128.665986 -164.095938) (xy 132.634984 -168.065164) (xy 135.245906 -168.065164) (xy 135.245906 -168.005236)
			(xy 135.253728 -167.94582) (xy 135.269237 -167.887933) (xy 135.29217 -167.832566) (xy 135.322132 -167.780665)
			(xy 135.358612 -167.733119) (xy 135.400986 -167.690742) (xy 135.448529 -167.654257) (xy 135.500426 -167.624289)
			(xy 135.555791 -167.601351) (xy 135.613677 -167.585836) (xy 135.673092 -167.578009) (xy 135.703056 -167.577516)
			(xy 136.566656 -167.577516) (xy 136.596628 -167.577934) (xy 136.656061 -167.585754) (xy 136.713965 -167.601264)
			(xy 136.769348 -167.6242) (xy 136.821264 -167.654169) (xy 136.868823 -167.690658) (xy 136.911213 -167.733044)
			(xy 136.947707 -167.7806) (xy 136.977681 -167.832512) (xy 137.000622 -167.887894) (xy 137.016138 -167.945796)
			(xy 137.023963 -168.005228) (xy 137.023963 -168.022016) (xy 139.692632 -168.022016) (xy 139.696703 -167.966394)
			(xy 139.708829 -167.911957) (xy 139.728752 -167.859866) (xy 139.756048 -167.811231) (xy 139.790134 -167.767088)
			(xy 139.830283 -167.728379) (xy 139.875641 -167.695928) (xy 139.925241 -167.670427) (xy 139.978025 -167.65242)
			(xy 140.032868 -167.64229) (xy 140.088602 -167.640253) (xy 140.144039 -167.646353) (xy 140.197996 -167.660459)
			(xy 140.249325 -167.682271) (xy 140.296931 -167.711325) (xy 140.339799 -167.747) (xy 140.377016 -167.788537)
			(xy 140.407789 -167.83505) (xy 140.431461 -167.885547) (xy 140.447529 -167.938954) (xy 140.455649 -167.99413)
			(xy 140.456158 -168.022016) (xy 140.455649 -168.049902) (xy 140.447529 -168.105078) (xy 140.431461 -168.158485)
			(xy 140.407789 -168.208982) (xy 140.377016 -168.255495) (xy 140.339799 -168.297032) (xy 140.296931 -168.332707)
			(xy 140.249325 -168.361761) (xy 140.197996 -168.383573) (xy 140.144039 -168.397679) (xy 140.088602 -168.403779)
			(xy 140.032868 -168.401742) (xy 139.978025 -168.391612) (xy 139.925241 -168.373605) (xy 139.875641 -168.348104)
			(xy 139.830283 -168.315653) (xy 139.790134 -168.276944) (xy 139.756048 -168.232801) (xy 139.728752 -168.184166)
			(xy 139.708829 -168.132075) (xy 139.696703 -168.077638) (xy 139.692632 -168.022016) (xy 137.023963 -168.022016)
			(xy 137.023963 -168.065172) (xy 137.016138 -168.124604) (xy 137.000622 -168.182506) (xy 136.977681 -168.237888)
			(xy 136.947707 -168.2898) (xy 136.911213 -168.337356) (xy 136.868823 -168.379742) (xy 136.821264 -168.416231)
			(xy 136.769348 -168.4462) (xy 136.713965 -168.469136) (xy 136.656061 -168.484646) (xy 136.596628 -168.492466)
			(xy 136.566656 -168.492932) (xy 135.703056 -168.492932) (xy 135.673092 -168.492391) (xy 135.613677 -168.484564)
			(xy 135.555791 -168.469049) (xy 135.500426 -168.446111) (xy 135.448529 -168.416143) (xy 135.400986 -168.379658)
			(xy 135.358612 -168.337281) (xy 135.322132 -168.289735) (xy 135.29217 -168.237834) (xy 135.269237 -168.182467)
			(xy 135.253728 -168.12458) (xy 135.245906 -168.065164) (xy 132.634984 -168.065164) (xy 133.086856 -168.517062)
			(xy 133.096075 -168.525519) (xy 133.119926 -168.532977) (xy 133.132322 -168.531286) (xy 133.214872 -168.515538)
			(xy 133.226919 -168.512672) (xy 133.246354 -168.497371) (xy 133.251956 -168.486328) (xy 133.251956 -168.486074)
			(xy 133.264218 -168.459319) (xy 133.294619 -168.408924) (xy 133.331227 -168.362839) (xy 133.373437 -168.321825)
			(xy 133.420555 -168.286557) (xy 133.471804 -168.257618) (xy 133.526339 -168.235484) (xy 133.583259 -168.22052)
			(xy 133.641629 -168.212973) (xy 133.671056 -168.212516) (xy 134.534656 -168.212516) (xy 134.564628 -168.212934)
			(xy 134.624061 -168.220754) (xy 134.681965 -168.236264) (xy 134.737348 -168.2592) (xy 134.789264 -168.289169)
			(xy 134.836823 -168.325658) (xy 134.879213 -168.368044) (xy 134.915707 -168.4156) (xy 134.945681 -168.467512)
			(xy 134.968622 -168.522894) (xy 134.984138 -168.580796) (xy 134.991963 -168.640228) (xy 134.991963 -168.700172)
			(xy 134.984138 -168.759604) (xy 134.968622 -168.817506) (xy 134.945681 -168.872888) (xy 134.915707 -168.9248)
			(xy 134.879213 -168.972356) (xy 134.836823 -169.014742) (xy 134.789264 -169.051231) (xy 134.737348 -169.0812)
			(xy 134.681965 -169.104136) (xy 134.624061 -169.119646) (xy 134.564628 -169.127466) (xy 134.534656 -169.127932)
			(xy 133.852412 -169.127932) (xy 133.840875 -169.128458) (xy 133.820111 -169.138519) (xy 133.812534 -169.147236)
			(xy 133.755892 -169.219118) (xy 133.750812 -169.241978) (xy 133.753606 -169.253154) (xy 133.757804 -169.272116)
			(xy 133.762264 -169.310697) (xy 133.762496 -169.330116) (xy 133.762496 -172.287946) (xy 138.61415 -172.287946)
			(xy 138.614589 -172.261333) (xy 138.621988 -172.208624) (xy 138.636648 -172.157457) (xy 138.658284 -172.108828)
			(xy 138.686476 -172.063681) (xy 138.720674 -172.022896) (xy 138.740134 -172.004736) (xy 138.748008 -171.997624)
			(xy 138.756644 -171.978574) (xy 138.758168 -171.88307) (xy 138.750294 -171.863766) (xy 138.742674 -171.8564)
			(xy 138.724675 -171.838349) (xy 138.693109 -171.798322) (xy 138.667154 -171.754449) (xy 138.647271 -171.707511)
			(xy 138.633814 -171.658343) (xy 138.627022 -171.607822) (xy 138.626596 -171.582334) (xy 138.627082 -171.555083)
			(xy 138.634838 -171.501135) (xy 138.650193 -171.44884) (xy 138.672835 -171.399263) (xy 138.702301 -171.353413)
			(xy 138.737992 -171.312222) (xy 138.779183 -171.276531) (xy 138.825033 -171.247065) (xy 138.87461 -171.224423)
			(xy 138.926905 -171.209068) (xy 138.980853 -171.201312) (xy 139.035355 -171.201312) (xy 139.089303 -171.209068)
			(xy 139.141598 -171.224423) (xy 139.191175 -171.247065) (xy 139.237025 -171.276531) (xy 139.278216 -171.312222)
			(xy 139.313907 -171.353413) (xy 139.343373 -171.399263) (xy 139.366015 -171.44884) (xy 139.38137 -171.501135)
			(xy 139.389126 -171.555083) (xy 139.389612 -171.582334) (xy 139.389172 -171.608947) (xy 139.381775 -171.661656)
			(xy 139.367116 -171.712824) (xy 139.34548 -171.761454) (xy 139.317288 -171.8066) (xy 139.283089 -171.847385)
			(xy 139.263628 -171.865544) (xy 139.255754 -171.872656) (xy 139.247118 -171.891706) (xy 139.245594 -171.98721)
			(xy 139.253468 -172.006514) (xy 139.261088 -172.01388) (xy 139.279089 -172.031929) (xy 139.310652 -172.071958)
			(xy 139.336606 -172.115832) (xy 139.356488 -172.16277) (xy 139.369946 -172.211937) (xy 139.376738 -172.262458)
			(xy 139.377166 -172.287946) (xy 139.37668 -172.315197) (xy 139.368924 -172.369145) (xy 139.353569 -172.42144)
			(xy 139.330927 -172.471017) (xy 139.301461 -172.516867) (xy 139.26577 -172.558058) (xy 139.224579 -172.593749)
			(xy 139.178729 -172.623215) (xy 139.129152 -172.645857) (xy 139.076857 -172.661212) (xy 139.022909 -172.668968)
			(xy 138.968407 -172.668968) (xy 138.914459 -172.661212) (xy 138.862164 -172.645857) (xy 138.812587 -172.623215)
			(xy 138.766737 -172.593749) (xy 138.725546 -172.558058) (xy 138.689855 -172.516867) (xy 138.660389 -172.471017)
			(xy 138.637747 -172.42144) (xy 138.622392 -172.369145) (xy 138.614636 -172.315197) (xy 138.61415 -172.287946)
			(xy 133.762496 -172.287946) (xy 133.762496 -173.365922) (xy 133.761963 -173.391945) (xy 133.753799 -173.443349)
			(xy 133.737706 -173.492846) (xy 133.71408 -173.539223) (xy 133.6835 -173.581339) (xy 133.665468 -173.60011)
			(xy 132.847842 -174.417736) (xy 132.843731 -174.422134) (xy 132.837443 -174.432395) (xy 132.835396 -174.438056)
			(xy 132.835396 -174.438564) (xy 132.826901 -174.464091) (xy 132.803834 -174.512692) (xy 132.774169 -174.557571)
			(xy 132.738494 -174.597838) (xy 132.697517 -174.632695) (xy 132.671024 -174.649449) (xy 135.696484 -174.649449)
			(xy 135.696484 -174.594951) (xy 135.704239 -174.541009) (xy 135.719591 -174.488719) (xy 135.742229 -174.439145)
			(xy 135.77169 -174.393298) (xy 135.807376 -174.35211) (xy 135.848559 -174.316419) (xy 135.894403 -174.286952)
			(xy 135.943974 -174.264308) (xy 135.996262 -174.248949) (xy 136.050203 -174.241187) (xy 136.077452 -174.240698)
			(xy 136.077706 -174.240698) (xy 136.104205 -174.241155) (xy 136.15669 -174.248524) (xy 136.207652 -174.263076)
			(xy 136.256114 -174.284534) (xy 136.301143 -174.312484) (xy 136.3218 -174.32909) (xy 136.329166 -174.335186)
			(xy 136.3472 -174.341282) (xy 136.425686 -174.337218) (xy 136.435172 -174.336332) (xy 136.452526 -174.328503)
			(xy 136.459468 -174.321978) (xy 136.477489 -174.304161) (xy 136.517399 -174.272933) (xy 136.561092 -174.247263)
			(xy 136.607799 -174.227604) (xy 136.656697 -174.2143) (xy 136.706926 -174.207587) (xy 136.732264 -174.20717)
			(xy 136.759517 -174.207675) (xy 136.813469 -174.215427) (xy 136.865768 -174.230779) (xy 136.91535 -174.253418)
			(xy 136.961205 -174.282884) (xy 137.002399 -174.318575) (xy 137.038095 -174.359767) (xy 137.067564 -174.405619)
			(xy 137.090208 -174.455198) (xy 137.105565 -174.507496) (xy 137.113323 -174.561447) (xy 137.113323 -174.615953)
			(xy 137.105565 -174.669904) (xy 137.090208 -174.722202) (xy 137.067564 -174.771781) (xy 137.046159 -174.805086)
			(xy 141.546072 -174.805086) (xy 141.546072 -173.941486) (xy 141.546562 -173.911518) (xy 141.554385 -173.852096)
			(xy 141.569898 -173.794203) (xy 141.592834 -173.73883) (xy 141.622801 -173.686924) (xy 141.659288 -173.639374)
			(xy 141.701668 -173.596994) (xy 141.749218 -173.560507) (xy 141.801124 -173.53054) (xy 141.856497 -173.507604)
			(xy 141.91439 -173.492091) (xy 141.973812 -173.484268) (xy 142.033748 -173.484268) (xy 142.09317 -173.492091)
			(xy 142.151063 -173.507604) (xy 142.206436 -173.53054) (xy 142.258342 -173.560507) (xy 142.305892 -173.596994)
			(xy 142.348272 -173.639374) (xy 142.384759 -173.686924) (xy 142.414726 -173.73883) (xy 142.437662 -173.794203)
			(xy 142.453175 -173.852096) (xy 142.460998 -173.911518) (xy 142.461488 -173.941486) (xy 142.461488 -174.805086)
			(xy 142.460998 -174.835054) (xy 142.453175 -174.894476) (xy 142.437662 -174.952369) (xy 142.414726 -175.007742)
			(xy 142.384759 -175.059648) (xy 142.348272 -175.107198) (xy 142.305892 -175.149578) (xy 142.258342 -175.186065)
			(xy 142.206436 -175.216032) (xy 142.151063 -175.238968) (xy 142.09317 -175.254481) (xy 142.033748 -175.262304)
			(xy 141.973812 -175.262304) (xy 141.91439 -175.254481) (xy 141.856497 -175.238968) (xy 141.801124 -175.216032)
			(xy 141.749218 -175.186065) (xy 141.701668 -175.149578) (xy 141.659288 -175.107198) (xy 141.622801 -175.059648)
			(xy 141.592834 -175.007742) (xy 141.569898 -174.952369) (xy 141.554385 -174.894476) (xy 141.546562 -174.835054)
			(xy 141.546072 -174.805086) (xy 137.046159 -174.805086) (xy 137.038095 -174.817633) (xy 137.002399 -174.858825)
			(xy 136.961205 -174.894516) (xy 136.91535 -174.923982) (xy 136.865768 -174.946621) (xy 136.813469 -174.961973)
			(xy 136.759517 -174.969725) (xy 136.732264 -174.970186) (xy 136.73201 -174.970186) (xy 136.705511 -174.969723)
			(xy 136.653026 -174.962357) (xy 136.602064 -174.947806) (xy 136.553603 -174.926349) (xy 136.508573 -174.898399)
			(xy 136.487916 -174.881794) (xy 136.48055 -174.875698) (xy 136.462516 -174.869602) (xy 136.38403 -174.873666)
			(xy 136.374546 -174.874564) (xy 136.357191 -174.882385) (xy 136.350248 -174.888906) (xy 136.332263 -174.906761)
			(xy 136.292345 -174.937986) (xy 136.248645 -174.963651) (xy 136.201931 -174.983304) (xy 136.153026 -174.996599)
			(xy 136.102792 -175.003303) (xy 136.077452 -175.003714) (xy 136.050203 -175.003213) (xy 135.996262 -174.995451)
			(xy 135.943974 -174.980092) (xy 135.894403 -174.957448) (xy 135.848559 -174.927981) (xy 135.807376 -174.89229)
			(xy 135.77169 -174.851102) (xy 135.742229 -174.805255) (xy 135.719591 -174.755681) (xy 135.704239 -174.703391)
			(xy 135.696484 -174.649449) (xy 132.671024 -174.649449) (xy 132.652049 -174.661449) (xy 132.602993 -174.683531)
			(xy 132.551321 -174.698504) (xy 132.498059 -174.706069) (xy 132.47116 -174.706534) (xy 132.443909 -174.706059)
			(xy 132.389962 -174.698298) (xy 132.337669 -174.682939) (xy 132.288093 -174.660295) (xy 132.242244 -174.630827)
			(xy 132.201055 -174.595135) (xy 132.165364 -174.553945) (xy 132.135898 -174.508095) (xy 132.113256 -174.458518)
			(xy 132.097899 -174.406224) (xy 132.09014 -174.352277) (xy 132.089652 -174.325026) (xy 132.09012 -174.298116)
			(xy 132.097705 -174.244833) (xy 132.112701 -174.193145) (xy 132.134809 -174.144075) (xy 132.163593 -174.098599)
			(xy 132.198479 -174.057617) (xy 132.238777 -174.021942) (xy 132.283687 -173.992283) (xy 132.332319 -173.969228)
			(xy 132.357876 -173.96079) (xy 132.35813 -173.96079) (xy 132.363819 -173.958799) (xy 132.374096 -173.952511)
			(xy 132.37845 -173.948344) (xy 133.084062 -173.242986) (xy 133.090895 -173.23558) (xy 133.09862 -173.216986)
			(xy 133.099048 -173.206918) (xy 133.099048 -172.437552) (xy 133.098587 -172.427306) (xy 133.090645 -172.40842)
			(xy 133.075931 -172.394164) (xy 133.066536 -172.390054) (xy 132.97789 -172.356018) (xy 132.968168 -172.3528)
			(xy 132.947722 -172.353516) (xy 132.929189 -172.362178) (xy 132.92201 -172.36948) (xy 132.903843 -172.388916)
			(xy 132.863024 -172.423035) (xy 132.817864 -172.451158) (xy 132.769238 -172.472741) (xy 132.718086 -172.487366)
			(xy 132.6654 -172.49475) (xy 132.6388 -172.49521) (xy 132.611549 -172.49472) (xy 132.557601 -172.486964)
			(xy 132.505307 -172.471609) (xy 132.45573 -172.448968) (xy 132.40988 -172.419502) (xy 132.36869 -172.38381)
			(xy 132.332998 -172.34262) (xy 132.303532 -172.29677) (xy 132.280891 -172.247193) (xy 132.265536 -172.194899)
			(xy 132.25778 -172.140951) (xy 132.25778 -172.086449) (xy 132.265536 -172.032501) (xy 132.280891 -171.980207)
			(xy 132.303532 -171.93063) (xy 132.332998 -171.88478) (xy 132.36869 -171.84359) (xy 132.40988 -171.807898)
			(xy 132.45573 -171.778432) (xy 132.505307 -171.755791) (xy 132.557601 -171.740436) (xy 132.611549 -171.73268)
			(xy 132.6388 -171.732194) (xy 132.665401 -171.732647) (xy 132.718089 -171.740024) (xy 132.769241 -171.754647)
			(xy 132.817866 -171.776234) (xy 132.863022 -171.804366) (xy 132.903831 -171.838498) (xy 132.92201 -171.857924)
			(xy 132.929186 -171.865219) (xy 132.947731 -171.873837) (xy 132.968168 -171.874584) (xy 132.97789 -171.871386)
			(xy 133.066536 -171.83735) (xy 133.075915 -171.833219) (xy 133.090601 -171.818948) (xy 133.098582 -171.80009)
			(xy 133.099048 -171.789852) (xy 133.099048 -169.748454) (xy 133.098528 -169.738027) (xy 133.090168 -169.718915)
			(xy 133.074919 -169.704682) (xy 133.065266 -169.700702) (xy 133.04139 -169.69232) (xy 133.031856 -169.689375)
			(xy 133.011941 -169.690323) (xy 132.993879 -169.698767) (xy 132.98678 -169.705782) (xy 132.968746 -169.724832)
			(xy 132.444236 -170.249342) (xy 132.420703 -170.272274) (xy 132.369321 -170.313239) (xy 132.313676 -170.348193)
			(xy 132.254468 -170.376696) (xy 132.19244 -170.398391) (xy 132.128373 -170.413005) (xy 132.063072 -170.420353)
			(xy 132.030216 -170.420792) (xy 131.423918 -170.420792) (xy 131.391065 -170.420305) (xy 131.325773 -170.412944)
			(xy 131.261715 -170.398324) (xy 131.199694 -170.376629) (xy 131.140491 -170.348131) (xy 131.084847 -170.313188)
			(xy 131.033463 -170.272238) (xy 131.009898 -170.249342) (xy 130.519424 -169.758868) (xy 130.496523 -169.735275)
			(xy 130.455527 -169.683867) (xy 130.420539 -169.628195) (xy 130.391997 -169.56896) (xy 130.37026 -169.506904)
			(xy 130.3556 -169.442806) (xy 130.348202 -169.37747) (xy 130.34772 -169.344594) (xy 130.34772 -168.687496)
			(xy 130.347318 -168.677424) (xy 130.339583 -168.658825) (xy 130.332734 -168.651428) (xy 127.376682 -165.695122)
			(xy 127.36928 -165.688284) (xy 127.350682 -165.680562) (xy 127.340614 -165.680136) (xy 124.621036 -165.680136)
			(xy 124.588182 -165.679689) (xy 124.522889 -165.67232) (xy 124.45883 -165.657693) (xy 124.39681 -165.635991)
			(xy 124.337607 -165.607486) (xy 124.281964 -165.572538) (xy 124.23058 -165.531584) (xy 124.207016 -165.508686)
			(xy 122.76836 -164.07003) (xy 122.761303 -164.063566) (xy 122.743778 -164.055924) (xy 122.72467 -164.055267)
			(xy 122.715528 -164.058092) (xy 122.614944 -164.093906) (xy 122.59691 -164.11702) (xy 122.595386 -164.131498)
			(xy 122.592128 -164.159368) (xy 122.578386 -164.213773) (xy 122.55682 -164.265576) (xy 122.527896 -164.313659)
			(xy 122.492238 -164.356986) (xy 122.450615 -164.394619) (xy 122.403928 -164.425746) (xy 122.353183 -164.449696)
			(xy 122.299476 -164.465951) (xy 122.243967 -164.474161) (xy 122.21591 -164.474652) (xy 122.188661 -164.474113)
			(xy 122.134718 -164.466359) (xy 122.082427 -164.451007) (xy 122.032852 -164.42837) (xy 121.987004 -164.398909)
			(xy 121.945815 -164.363223) (xy 121.910123 -164.322039) (xy 121.880656 -164.276195) (xy 121.858012 -164.226624)
			(xy 121.842653 -164.174335) (xy 121.834891 -164.120393) (xy 121.834402 -164.093144) (xy 121.834934 -164.065095)
			(xy 121.84317 -164.009604) (xy 121.859443 -163.955917) (xy 121.883401 -163.905191) (xy 121.914528 -163.85852)
			(xy 121.952154 -163.816909) (xy 121.995466 -163.781256) (xy 122.043532 -163.752328) (xy 122.095315 -163.730751)
			(xy 122.149699 -163.716987) (xy 122.177556 -163.713668) (xy 122.192034 -163.712144) (xy 122.215148 -163.69411)
			(xy 122.250962 -163.593526) (xy 122.253744 -163.584381) (xy 122.253044 -163.565292) (xy 122.245463 -163.547759)
			(xy 122.239024 -163.540694) (xy 120.221756 -161.523426) (xy 120.191784 -161.51733) (xy 120.17756 -161.523426)
			(xy 120.168415 -161.52761) (xy 120.154185 -161.541803) (xy 120.146485 -161.560367) (xy 120.146064 -161.570416)
			(xy 120.146064 -166.974266) (xy 120.14649 -166.984336) (xy 120.152641 -166.999158) (xy 121.98045 -166.999158)
			(xy 121.984521 -166.943536) (xy 121.996647 -166.889099) (xy 122.01657 -166.837008) (xy 122.043866 -166.788373)
			(xy 122.077952 -166.74423) (xy 122.118101 -166.705521) (xy 122.163459 -166.67307) (xy 122.213059 -166.647569)
			(xy 122.265843 -166.629562) (xy 122.320686 -166.619432) (xy 122.37642 -166.617395) (xy 122.431857 -166.623495)
			(xy 122.485814 -166.637601) (xy 122.537143 -166.659413) (xy 122.584749 -166.688467) (xy 122.627617 -166.724142)
			(xy 122.664834 -166.765679) (xy 122.695607 -166.812192) (xy 122.719279 -166.862689) (xy 122.735347 -166.916096)
			(xy 122.743467 -166.971272) (xy 122.743976 -166.999158) (xy 122.743467 -167.027044) (xy 122.736544 -167.074088)
			(xy 125.212092 -167.074088) (xy 125.216163 -167.018466) (xy 125.228289 -166.964029) (xy 125.248212 -166.911938)
			(xy 125.275508 -166.863303) (xy 125.309594 -166.81916) (xy 125.349743 -166.780451) (xy 125.395101 -166.748)
			(xy 125.444701 -166.722499) (xy 125.497485 -166.704492) (xy 125.552328 -166.694362) (xy 125.608062 -166.692325)
			(xy 125.663499 -166.698425) (xy 125.717456 -166.712531) (xy 125.768785 -166.734343) (xy 125.816391 -166.763397)
			(xy 125.859259 -166.799072) (xy 125.896476 -166.840609) (xy 125.927249 -166.887122) (xy 125.950921 -166.937619)
			(xy 125.966989 -166.991026) (xy 125.975109 -167.046202) (xy 125.975618 -167.074088) (xy 125.975109 -167.101974)
			(xy 125.972552 -167.119352) (xy 126.499077 -167.119352) (xy 126.499077 -167.064848) (xy 126.506834 -167.010899)
			(xy 126.52219 -166.958604) (xy 126.544832 -166.909025) (xy 126.574299 -166.863174) (xy 126.609992 -166.821984)
			(xy 126.651184 -166.786292) (xy 126.697036 -166.756826) (xy 126.746615 -166.734186) (xy 126.798911 -166.718832)
			(xy 126.85286 -166.711076) (xy 126.880112 -166.710614) (xy 126.906518 -166.711069) (xy 126.958824 -166.718361)
			(xy 127.009626 -166.732791) (xy 127.057955 -166.754084) (xy 127.102889 -166.781833) (xy 127.143571 -166.81551)
			(xy 127.179224 -166.85447) (xy 127.194564 -166.875968) (xy 127.203292 -166.887861) (xy 127.226243 -166.906378)
			(xy 127.25353 -166.917563) (xy 127.282875 -166.920481) (xy 127.31183 -166.91489) (xy 127.337978 -166.901256)
			(xy 127.359139 -166.880717) (xy 127.366776 -166.868094) (xy 127.381373 -166.843114) (xy 127.416906 -166.79746)
			(xy 127.458926 -166.757694) (xy 127.506467 -166.724728) (xy 127.55844 -166.699317) (xy 127.613655 -166.682044)
			(xy 127.670844 -166.673305) (xy 127.69977 -166.672768) (xy 127.727023 -166.673277) (xy 127.780973 -166.68103)
			(xy 127.833271 -166.696383) (xy 127.882852 -166.719022) (xy 127.928706 -166.748487) (xy 127.9699 -166.784179)
			(xy 128.005595 -166.82537) (xy 128.035064 -166.871221) (xy 128.057707 -166.9208) (xy 128.073063 -166.973097)
			(xy 128.080821 -167.027047) (xy 128.080821 -167.081553) (xy 128.073063 -167.135503) (xy 128.057707 -167.1878)
			(xy 128.035064 -167.237379) (xy 128.005595 -167.28323) (xy 127.9699 -167.324421) (xy 127.928706 -167.360113)
			(xy 127.882852 -167.389578) (xy 127.833271 -167.412217) (xy 127.780973 -167.42757) (xy 127.727023 -167.435323)
			(xy 127.69977 -167.435784) (xy 127.673364 -167.435344) (xy 127.621057 -167.428049) (xy 127.570255 -167.413616)
			(xy 127.521926 -167.392321) (xy 127.476992 -167.364569) (xy 127.43631 -167.330891) (xy 127.400658 -167.291929)
			(xy 127.385318 -167.27043) (xy 127.376612 -167.25852) (xy 127.353656 -167.240002) (xy 127.326364 -167.228819)
			(xy 127.297015 -167.225902) (xy 127.268057 -167.231497) (xy 127.241905 -167.245135) (xy 127.220743 -167.265679)
			(xy 127.213106 -167.278304) (xy 127.198521 -167.303291) (xy 127.162986 -167.348945) (xy 127.120965 -167.388711)
			(xy 127.073421 -167.421677) (xy 127.021446 -167.447086) (xy 126.96623 -167.464357) (xy 126.909039 -167.473094)
			(xy 126.880112 -167.47363) (xy 126.85286 -167.473124) (xy 126.798911 -167.465368) (xy 126.746615 -167.450014)
			(xy 126.697036 -167.427374) (xy 126.651184 -167.397908) (xy 126.609992 -167.362216) (xy 126.574299 -167.321026)
			(xy 126.544832 -167.275175) (xy 126.52219 -167.225596) (xy 126.506834 -167.173301) (xy 126.499077 -167.119352)
			(xy 125.972552 -167.119352) (xy 125.966989 -167.15715) (xy 125.950921 -167.210557) (xy 125.927249 -167.261054)
			(xy 125.896476 -167.307567) (xy 125.859259 -167.349104) (xy 125.816391 -167.384779) (xy 125.768785 -167.413833)
			(xy 125.717456 -167.435645) (xy 125.663499 -167.449751) (xy 125.608062 -167.455851) (xy 125.552328 -167.453814)
			(xy 125.497485 -167.443684) (xy 125.444701 -167.425677) (xy 125.395101 -167.400176) (xy 125.349743 -167.367725)
			(xy 125.309594 -167.329016) (xy 125.275508 -167.284873) (xy 125.248212 -167.236238) (xy 125.228289 -167.184147)
			(xy 125.216163 -167.12971) (xy 125.212092 -167.074088) (xy 122.736544 -167.074088) (xy 122.735347 -167.08222)
			(xy 122.719279 -167.135627) (xy 122.695607 -167.186124) (xy 122.664834 -167.232637) (xy 122.627617 -167.274174)
			(xy 122.584749 -167.309849) (xy 122.537143 -167.338903) (xy 122.485814 -167.360715) (xy 122.431857 -167.374821)
			(xy 122.37642 -167.380921) (xy 122.320686 -167.378884) (xy 122.265843 -167.368754) (xy 122.213059 -167.350747)
			(xy 122.163459 -167.325246) (xy 122.118101 -167.292795) (xy 122.077952 -167.254086) (xy 122.043866 -167.209943)
			(xy 122.01657 -167.161308) (xy 121.996647 -167.109217) (xy 121.984521 -167.05478) (xy 121.98045 -166.999158)
			(xy 120.152641 -166.999158) (xy 120.154208 -167.002934) (xy 120.16105 -167.010334) (xy 121.189496 -168.038526)
			(xy 121.207508 -168.057315) (xy 121.238091 -168.099427) (xy 121.261722 -168.145799) (xy 121.277822 -168.195292)
			(xy 121.285994 -168.246692) (xy 121.286524 -168.272714) (xy 121.286524 -168.312846) (xy 122.314968 -168.312846)
			(xy 122.319039 -168.257224) (xy 122.331165 -168.202787) (xy 122.351088 -168.150696) (xy 122.378384 -168.102061)
			(xy 122.41247 -168.057918) (xy 122.452619 -168.019209) (xy 122.497977 -167.986758) (xy 122.547577 -167.961257)
			(xy 122.600361 -167.94325) (xy 122.655204 -167.93312) (xy 122.710938 -167.931083) (xy 122.766375 -167.937183)
			(xy 122.820332 -167.951289) (xy 122.871661 -167.973101) (xy 122.919267 -168.002155) (xy 122.962135 -168.03783)
			(xy 122.999352 -168.079367) (xy 123.030125 -168.12588) (xy 123.053797 -168.176377) (xy 123.069865 -168.229784)
			(xy 123.077985 -168.28496) (xy 123.078494 -168.312846) (xy 123.077985 -168.340732) (xy 123.069865 -168.395908)
			(xy 123.053797 -168.449315) (xy 123.030125 -168.499812) (xy 122.999352 -168.546325) (xy 122.962135 -168.587862)
			(xy 122.919267 -168.623537) (xy 122.871661 -168.652591) (xy 122.820332 -168.674403) (xy 122.766375 -168.688509)
			(xy 122.710938 -168.694609) (xy 122.655204 -168.692572) (xy 122.600361 -168.682442) (xy 122.547577 -168.664435)
			(xy 122.497977 -168.638934) (xy 122.452619 -168.606483) (xy 122.41247 -168.567774) (xy 122.378384 -168.523631)
			(xy 122.351088 -168.474996) (xy 122.331165 -168.422905) (xy 122.319039 -168.368468) (xy 122.314968 -168.312846)
			(xy 121.286524 -168.312846) (xy 121.286524 -169.474896) (xy 123.764292 -169.474896) (xy 123.768363 -169.419274)
			(xy 123.780489 -169.364837) (xy 123.800412 -169.312746) (xy 123.827708 -169.264111) (xy 123.861794 -169.219968)
			(xy 123.901943 -169.181259) (xy 123.947301 -169.148808) (xy 123.996901 -169.123307) (xy 124.049685 -169.1053)
			(xy 124.104528 -169.09517) (xy 124.160262 -169.093133) (xy 124.215699 -169.099233) (xy 124.269656 -169.113339)
			(xy 124.320985 -169.135151) (xy 124.358267 -169.157904) (xy 125.619762 -169.157904) (xy 125.623833 -169.102282)
			(xy 125.635959 -169.047845) (xy 125.655882 -168.995754) (xy 125.683178 -168.947119) (xy 125.717264 -168.902976)
			(xy 125.757413 -168.864267) (xy 125.802771 -168.831816) (xy 125.852371 -168.806315) (xy 125.905155 -168.788308)
			(xy 125.959998 -168.778178) (xy 126.015732 -168.776141) (xy 126.071169 -168.782241) (xy 126.125126 -168.796347)
			(xy 126.176455 -168.818159) (xy 126.224061 -168.847213) (xy 126.266929 -168.882888) (xy 126.304146 -168.924425)
			(xy 126.334919 -168.970938) (xy 126.358591 -169.021435) (xy 126.374659 -169.074842) (xy 126.382779 -169.130018)
			(xy 126.383288 -169.157904) (xy 126.382779 -169.18579) (xy 126.374659 -169.240966) (xy 126.358591 -169.294373)
			(xy 126.334919 -169.34487) (xy 126.304146 -169.391383) (xy 126.266929 -169.43292) (xy 126.224061 -169.468595)
			(xy 126.176455 -169.497649) (xy 126.125126 -169.519461) (xy 126.071169 -169.533567) (xy 126.015732 -169.539667)
			(xy 125.959998 -169.53763) (xy 125.905155 -169.5275) (xy 125.852371 -169.509493) (xy 125.802771 -169.483992)
			(xy 125.757413 -169.451541) (xy 125.717264 -169.412832) (xy 125.683178 -169.368689) (xy 125.655882 -169.320054)
			(xy 125.635959 -169.267963) (xy 125.623833 -169.213526) (xy 125.619762 -169.157904) (xy 124.358267 -169.157904)
			(xy 124.368591 -169.164205) (xy 124.411459 -169.19988) (xy 124.448676 -169.241417) (xy 124.479449 -169.28793)
			(xy 124.503121 -169.338427) (xy 124.519189 -169.391834) (xy 124.527309 -169.44701) (xy 124.527818 -169.474896)
			(xy 124.527309 -169.502782) (xy 124.519189 -169.557958) (xy 124.503121 -169.611365) (xy 124.479449 -169.661862)
			(xy 124.448676 -169.708375) (xy 124.411459 -169.749912) (xy 124.368591 -169.785587) (xy 124.320985 -169.814641)
			(xy 124.269656 -169.836453) (xy 124.215699 -169.850559) (xy 124.160262 -169.856659) (xy 124.104528 -169.854622)
			(xy 124.049685 -169.844492) (xy 123.996901 -169.826485) (xy 123.947301 -169.800984) (xy 123.901943 -169.768533)
			(xy 123.861794 -169.729824) (xy 123.827708 -169.685681) (xy 123.800412 -169.637046) (xy 123.780489 -169.584955)
			(xy 123.768363 -169.530518) (xy 123.764292 -169.474896) (xy 121.286524 -169.474896) (xy 121.286524 -178.995324)
			(xy 123.198636 -178.995324) (xy 123.198636 -178.131724) (xy 123.199126 -178.10174) (xy 123.206954 -178.042284)
			(xy 123.222475 -177.984359) (xy 123.245424 -177.928955) (xy 123.275408 -177.877021) (xy 123.311914 -177.829445)
			(xy 123.354319 -177.78704) (xy 123.401895 -177.750534) (xy 123.453829 -177.72055) (xy 123.509233 -177.697601)
			(xy 123.567158 -177.68208) (xy 123.626614 -177.674252) (xy 123.686582 -177.674252) (xy 123.746038 -177.68208)
			(xy 123.803963 -177.697601) (xy 123.859367 -177.72055) (xy 123.911301 -177.750534) (xy 123.958877 -177.78704)
			(xy 124.001282 -177.829445) (xy 124.037788 -177.877021) (xy 124.067772 -177.928955) (xy 124.090721 -177.984359)
			(xy 124.106242 -178.042284) (xy 124.11407 -178.10174) (xy 124.11456 -178.131724) (xy 124.11456 -178.995324)
			(xy 124.11407 -179.025308) (xy 124.106242 -179.084764) (xy 124.090721 -179.142689) (xy 124.067772 -179.198093)
			(xy 124.037788 -179.250027) (xy 124.001282 -179.297603) (xy 123.958877 -179.340008) (xy 123.911301 -179.376514)
			(xy 123.859367 -179.406498) (xy 123.803963 -179.429447) (xy 123.746038 -179.444968) (xy 123.686582 -179.452796)
			(xy 123.626614 -179.452796) (xy 123.567158 -179.444968) (xy 123.509233 -179.429447) (xy 123.453829 -179.406498)
			(xy 123.401895 -179.376514) (xy 123.354319 -179.340008) (xy 123.311914 -179.297603) (xy 123.275408 -179.250027)
			(xy 123.245424 -179.198093) (xy 123.222475 -179.142689) (xy 123.206954 -179.084764) (xy 123.199126 -179.025308)
			(xy 123.198636 -178.995324) (xy 121.286524 -178.995324) (xy 121.286524 -181.276244) (xy 124.263912 -181.276244)
			(xy 124.263912 -171.928282) (xy 124.26433 -171.904309) (xy 124.271831 -171.856953) (xy 124.28666 -171.811358)
			(xy 124.308451 -171.768651) (xy 124.336666 -171.729886) (xy 124.35332 -171.712636) (xy 125.095762 -170.970194)
			(xy 125.113028 -170.953514) (xy 125.151845 -170.925266) (xy 125.194603 -170.903438) (xy 125.240249 -170.888568)
			(xy 125.287659 -170.881021) (xy 125.311662 -170.880532) (xy 127.395224 -170.880532) (xy 127.41923 -170.880956)
			(xy 127.466646 -170.888509) (xy 127.512294 -170.903392) (xy 127.555049 -170.925239) (xy 127.593856 -170.95351)
			(xy 127.611124 -170.970194) (xy 127.8128 -171.17187) (xy 127.829408 -171.189153) (xy 127.857572 -171.227937)
			(xy 127.879337 -171.27064) (xy 127.894171 -171.316218) (xy 127.901711 -171.363551) (xy 127.902208 -171.387516)
			(xy 127.902208 -171.828206) (xy 127.902609 -171.837272) (xy 127.908991 -171.854247) (xy 127.920858 -171.867961)
			(xy 127.928624 -171.872656) (xy 128.006602 -171.915582) (xy 128.014698 -171.919655) (xy 128.032605 -171.922349)
			(xy 128.050322 -171.9186) (xy 128.058164 -171.914058) (xy 128.081072 -171.900139) (xy 128.129983 -171.878203)
			(xy 128.181485 -171.863337) (xy 128.234562 -171.855835) (xy 128.261364 -171.855384) (xy 128.288618 -171.855861)
			(xy 128.342572 -171.863614) (xy 128.394873 -171.878966) (xy 128.444456 -171.901606) (xy 128.490313 -171.931072)
			(xy 128.531509 -171.966765) (xy 128.567206 -172.007958) (xy 128.596677 -172.053812) (xy 128.619321 -172.103394)
			(xy 128.634679 -172.155693) (xy 128.642437 -172.209646) (xy 128.642437 -172.264154) (xy 128.634679 -172.318107)
			(xy 128.619321 -172.370406) (xy 128.596677 -172.419988) (xy 128.567206 -172.465842) (xy 128.531509 -172.507035)
			(xy 128.490313 -172.542728) (xy 128.444456 -172.572194) (xy 128.394873 -172.594834) (xy 128.342572 -172.610186)
			(xy 128.288618 -172.617939) (xy 128.261364 -172.6184) (xy 128.234563 -172.617946) (xy 128.181489 -172.610434)
			(xy 128.129991 -172.595563) (xy 128.081083 -172.573626) (xy 128.058164 -172.559726) (xy 128.050315 -172.555218)
			(xy 128.032605 -172.551521) (xy 128.01471 -172.554177) (xy 128.006602 -172.558202) (xy 127.928624 -172.601128)
			(xy 127.920842 -172.605814) (xy 127.908924 -172.619501) (xy 127.902574 -172.636503) (xy 127.902208 -172.645578)
			(xy 127.902208 -173.544484) (xy 129.265932 -173.544484) (xy 129.270003 -173.488862) (xy 129.282129 -173.434425)
			(xy 129.302052 -173.382334) (xy 129.329348 -173.333699) (xy 129.363434 -173.289556) (xy 129.403583 -173.250847)
			(xy 129.448941 -173.218396) (xy 129.498541 -173.192895) (xy 129.551325 -173.174888) (xy 129.606168 -173.164758)
			(xy 129.661902 -173.162721) (xy 129.717339 -173.168821) (xy 129.771296 -173.182927) (xy 129.822625 -173.204739)
			(xy 129.870231 -173.233793) (xy 129.913099 -173.269468) (xy 129.950316 -173.311005) (xy 129.981089 -173.357518)
			(xy 130.004761 -173.408015) (xy 130.020829 -173.461422) (xy 130.028949 -173.516598) (xy 130.029458 -173.544484)
			(xy 130.028949 -173.57237) (xy 130.020829 -173.627546) (xy 130.004761 -173.680953) (xy 129.981089 -173.73145)
			(xy 129.950316 -173.777963) (xy 129.913099 -173.8195) (xy 129.870231 -173.855175) (xy 129.822625 -173.884229)
			(xy 129.771296 -173.906041) (xy 129.717339 -173.920147) (xy 129.661902 -173.926247) (xy 129.606168 -173.92421)
			(xy 129.551325 -173.91408) (xy 129.498541 -173.896073) (xy 129.448941 -173.870572) (xy 129.403583 -173.838121)
			(xy 129.363434 -173.799412) (xy 129.329348 -173.755269) (xy 129.302052 -173.706634) (xy 129.282129 -173.654543)
			(xy 129.270003 -173.600106) (xy 129.265932 -173.544484) (xy 127.902208 -173.544484) (xy 127.902208 -176.722278)
			(xy 130.560318 -176.722278) (xy 130.560719 -176.696161) (xy 130.568017 -176.64444) (xy 130.582466 -176.594244)
			(xy 130.603785 -176.546558) (xy 130.631554 -176.502317) (xy 130.665229 -176.462388) (xy 130.704151 -176.427553)
			(xy 130.747556 -176.398495) (xy 130.770884 -176.386744) (xy 130.783584 -176.380648) (xy 130.799078 -176.357026)
			(xy 130.803142 -176.25314) (xy 130.803054 -176.24395) (xy 130.797134 -176.226565) (xy 130.785492 -176.21236)
			(xy 130.777742 -176.20742) (xy 130.777488 -176.207166) (xy 130.754665 -176.193402) (xy 130.712988 -176.160184)
			(xy 130.67673 -176.121124) (xy 130.6467 -176.077096) (xy 130.623569 -176.029082) (xy 130.607855 -175.978156)
			(xy 130.599908 -175.925457) (xy 130.599434 -175.89881) (xy 130.599922 -175.870823) (xy 130.608677 -175.815538)
			(xy 130.625975 -175.762303) (xy 130.651387 -175.71243) (xy 130.684289 -175.667147) (xy 130.723871 -175.627569)
			(xy 130.769157 -175.59467) (xy 130.819032 -175.569262) (xy 130.872269 -175.55197) (xy 130.927555 -175.543219)
			(xy 130.955542 -175.542702) (xy 130.95605 -175.542702) (xy 130.984909 -175.543265) (xy 131.041862 -175.552626)
			(xy 131.096562 -175.571047) (xy 131.147576 -175.598046) (xy 131.19357 -175.632916) (xy 131.21386 -175.653446)
			(xy 131.22148 -175.661574) (xy 131.242054 -175.669956) (xy 131.329684 -175.665638) (xy 131.340595 -175.664593)
			(xy 131.360076 -175.654597) (xy 131.367276 -175.646334) (xy 131.36753 -175.64608) (xy 131.384499 -175.625173)
			(xy 131.423683 -175.588242) (xy 131.467983 -175.557635) (xy 131.516387 -175.534049) (xy 131.567792 -175.518021)
			(xy 131.621023 -175.509919) (xy 131.647946 -175.509428) (xy 131.6482 -175.509428) (xy 131.675496 -175.509931)
			(xy 131.729445 -175.518299) (xy 131.781487 -175.534795) (xy 131.830405 -175.559033) (xy 131.875057 -175.590445)
			(xy 131.895088 -175.608996) (xy 131.902454 -175.616108) (xy 131.920234 -175.62322) (xy 132.010658 -175.62322)
			(xy 132.028438 -175.616108) (xy 132.035804 -175.608996) (xy 132.055803 -175.590405) (xy 132.100448 -175.558971)
			(xy 132.149374 -175.534729) (xy 132.201429 -175.518249) (xy 132.255391 -175.509919) (xy 132.282692 -175.509428)
			(xy 132.282946 -175.509428) (xy 132.309596 -175.509857) (xy 132.362299 -175.517807) (xy 132.413229 -175.533523)
			(xy 132.461248 -175.556653) (xy 132.505284 -175.586681) (xy 132.544353 -175.622937) (xy 132.577583 -175.66461)
			(xy 132.60423 -175.71077) (xy 132.623701 -175.760386) (xy 132.635561 -175.812349) (xy 132.639544 -175.8655)
			(xy 132.63842 -175.8805) (xy 132.86459 -175.8805) (xy 132.868573 -175.827348) (xy 132.880434 -175.775383)
			(xy 132.899908 -175.725767) (xy 132.92656 -175.679607) (xy 132.959794 -175.637936) (xy 132.998867 -175.601683)
			(xy 133.042908 -175.571659) (xy 133.090931 -175.548535) (xy 133.141865 -175.532827) (xy 133.194571 -175.524886)
			(xy 133.221222 -175.524414) (xy 133.221476 -175.524414) (xy 133.248772 -175.524935) (xy 133.302719 -175.5333)
			(xy 133.354761 -175.549792) (xy 133.40368 -175.574025) (xy 133.448332 -175.605433) (xy 133.468364 -175.623982)
			(xy 133.47573 -175.631094) (xy 133.49351 -175.638206) (xy 133.583934 -175.638206) (xy 133.601714 -175.631094)
			(xy 133.60908 -175.623982) (xy 133.629106 -175.605384) (xy 133.673796 -175.573926) (xy 133.722772 -175.549674)
			(xy 133.77488 -175.533199) (xy 133.828896 -175.524889) (xy 133.856222 -175.524414) (xy 133.883543 -175.524918)
			(xy 133.937546 -175.533259) (xy 133.989643 -175.549744) (xy 134.038614 -175.573986) (xy 134.083312 -175.605417)
			(xy 134.103364 -175.623982) (xy 134.11073 -175.631094) (xy 134.12851 -175.638206) (xy 134.218934 -175.638206)
			(xy 134.236714 -175.631094) (xy 134.24408 -175.623982) (xy 134.264087 -175.6054) (xy 134.308731 -175.573965)
			(xy 134.357654 -175.549722) (xy 134.409707 -175.53324) (xy 134.463668 -175.524906) (xy 134.490968 -175.524414)
			(xy 134.491222 -175.524414) (xy 134.519207 -175.524921) (xy 134.574487 -175.53368) (xy 134.627716 -175.550979)
			(xy 134.677584 -175.576391) (xy 134.722862 -175.609292) (xy 134.762436 -175.648871) (xy 134.795332 -175.694154)
			(xy 134.820738 -175.744025) (xy 134.838031 -175.797256) (xy 134.846783 -175.852537) (xy 134.84733 -175.880522)
			(xy 134.84733 -175.880776) (xy 134.846797 -175.908071) (xy 134.838433 -175.962017) (xy 134.821943 -176.014058)
			(xy 134.797713 -176.062977) (xy 134.766309 -176.107631) (xy 134.747762 -176.127664) (xy 134.74065 -176.13503)
			(xy 134.733538 -176.15281) (xy 134.733538 -176.243234) (xy 134.74065 -176.261014) (xy 134.747762 -176.26838)
			(xy 134.766351 -176.288415) (xy 134.797812 -176.333101) (xy 134.822066 -176.382074) (xy 134.838543 -176.434182)
			(xy 134.846855 -176.488196) (xy 134.84733 -176.515522) (xy 134.846814 -176.542843) (xy 134.838474 -176.596844)
			(xy 134.821991 -176.64894) (xy 134.797752 -176.697912) (xy 134.766325 -176.742611) (xy 134.747762 -176.762664)
			(xy 134.74065 -176.77003) (xy 134.733538 -176.78781) (xy 134.733538 -176.837086) (xy 142.181072 -176.837086)
			(xy 142.181072 -175.973486) (xy 142.181562 -175.943518) (xy 142.189385 -175.884096) (xy 142.204898 -175.826203)
			(xy 142.227834 -175.77083) (xy 142.257801 -175.718924) (xy 142.294288 -175.671374) (xy 142.336668 -175.628994)
			(xy 142.384218 -175.592507) (xy 142.436124 -175.56254) (xy 142.491497 -175.539604) (xy 142.54939 -175.524091)
			(xy 142.608812 -175.516268) (xy 142.668748 -175.516268) (xy 142.72817 -175.524091) (xy 142.786063 -175.539604)
			(xy 142.841436 -175.56254) (xy 142.893342 -175.592507) (xy 142.940892 -175.628994) (xy 142.983272 -175.671374)
			(xy 143.019759 -175.718924) (xy 143.049726 -175.77083) (xy 143.072662 -175.826203) (xy 143.088175 -175.884096)
			(xy 143.095998 -175.943518) (xy 143.096488 -175.973486) (xy 143.096488 -176.837086) (xy 143.095998 -176.867054)
			(xy 143.088175 -176.926476) (xy 143.072662 -176.984369) (xy 143.049726 -177.039742) (xy 143.019759 -177.091648)
			(xy 142.983272 -177.139198) (xy 142.940892 -177.181578) (xy 142.893342 -177.218065) (xy 142.841436 -177.248032)
			(xy 142.786063 -177.270968) (xy 142.72817 -177.286481) (xy 142.668748 -177.294304) (xy 142.608812 -177.294304)
			(xy 142.54939 -177.286481) (xy 142.491497 -177.270968) (xy 142.436124 -177.248032) (xy 142.384218 -177.218065)
			(xy 142.336668 -177.181578) (xy 142.294288 -177.139198) (xy 142.257801 -177.091648) (xy 142.227834 -177.039742)
			(xy 142.204898 -176.984369) (xy 142.189385 -176.926476) (xy 142.181562 -176.867054) (xy 142.181072 -176.837086)
			(xy 134.733538 -176.837086) (xy 134.733538 -176.878234) (xy 134.74065 -176.896014) (xy 134.747762 -176.90338)
			(xy 134.766351 -176.923415) (xy 134.797812 -176.968101) (xy 134.822066 -177.017074) (xy 134.838543 -177.069182)
			(xy 134.846855 -177.123196) (xy 134.84733 -177.150522) (xy 134.846814 -177.177843) (xy 134.838474 -177.231844)
			(xy 134.821991 -177.28394) (xy 134.797752 -177.332912) (xy 134.766325 -177.377611) (xy 134.747762 -177.397664)
			(xy 134.74065 -177.40503) (xy 134.733538 -177.42281) (xy 134.733538 -177.488088) (xy 137.565636 -177.488088)
			(xy 137.569707 -177.432466) (xy 137.581833 -177.378029) (xy 137.601756 -177.325938) (xy 137.629052 -177.277303)
			(xy 137.663138 -177.23316) (xy 137.703287 -177.194451) (xy 137.748645 -177.162) (xy 137.798245 -177.136499)
			(xy 137.851029 -177.118492) (xy 137.905872 -177.108362) (xy 137.961606 -177.106325) (xy 138.017043 -177.112425)
			(xy 138.071 -177.126531) (xy 138.122329 -177.148343) (xy 138.169935 -177.177397) (xy 138.212803 -177.213072)
			(xy 138.25002 -177.254609) (xy 138.280793 -177.301122) (xy 138.304465 -177.351619) (xy 138.320533 -177.405026)
			(xy 138.328653 -177.460202) (xy 138.329162 -177.488088) (xy 138.328653 -177.515974) (xy 138.320533 -177.57115)
			(xy 138.304465 -177.624557) (xy 138.280793 -177.675054) (xy 138.25002 -177.721567) (xy 138.212803 -177.763104)
			(xy 138.169935 -177.798779) (xy 138.122329 -177.827833) (xy 138.071 -177.849645) (xy 138.017043 -177.863751)
			(xy 137.961606 -177.869851) (xy 137.905872 -177.867814) (xy 137.851029 -177.857684) (xy 137.798245 -177.839677)
			(xy 137.748645 -177.814176) (xy 137.703287 -177.781725) (xy 137.663138 -177.743016) (xy 137.629052 -177.698873)
			(xy 137.601756 -177.650238) (xy 137.581833 -177.598147) (xy 137.569707 -177.54371) (xy 137.565636 -177.488088)
			(xy 134.733538 -177.488088) (xy 134.733538 -177.513234) (xy 134.74065 -177.531014) (xy 134.747762 -177.53838)
			(xy 134.766334 -177.558396) (xy 134.797773 -177.603036) (xy 134.822019 -177.651957) (xy 134.838503 -177.704008)
			(xy 134.846837 -177.757968) (xy 134.84733 -177.785268) (xy 134.84733 -177.785522) (xy 134.846919 -177.810307)
			(xy 134.840047 -177.859399) (xy 134.826427 -177.907061) (xy 134.806321 -177.95237) (xy 134.780119 -177.99445)
			(xy 134.74833 -178.032484) (xy 134.730236 -178.049428) (xy 134.722691 -178.057024) (xy 134.714035 -178.076582)
			(xy 134.713472 -178.087274) (xy 134.713726 -178.173634) (xy 134.722616 -178.193446) (xy 134.730744 -178.200558)
			(xy 134.749035 -178.217556) (xy 134.781227 -178.255724) (xy 134.807774 -178.298014) (xy 134.828153 -178.343598)
			(xy 134.841966 -178.391581) (xy 134.843218 -178.400456) (xy 135.78408 -178.400456) (xy 135.788151 -178.344834)
			(xy 135.800277 -178.290397) (xy 135.8202 -178.238306) (xy 135.847496 -178.189671) (xy 135.881582 -178.145528)
			(xy 135.921731 -178.106819) (xy 135.967089 -178.074368) (xy 136.016689 -178.048867) (xy 136.069473 -178.03086)
			(xy 136.124316 -178.02073) (xy 136.18005 -178.018693) (xy 136.235487 -178.024793) (xy 136.289444 -178.038899)
			(xy 136.340773 -178.060711) (xy 136.388379 -178.089765) (xy 136.431247 -178.12544) (xy 136.468464 -178.166977)
			(xy 136.499237 -178.21349) (xy 136.522909 -178.263987) (xy 136.538977 -178.317394) (xy 136.547097 -178.37257)
			(xy 136.547606 -178.400456) (xy 136.547097 -178.428342) (xy 136.538977 -178.483518) (xy 136.522909 -178.536925)
			(xy 136.499237 -178.587422) (xy 136.468464 -178.633935) (xy 136.431247 -178.675472) (xy 136.388379 -178.711147)
			(xy 136.340773 -178.740201) (xy 136.289444 -178.762013) (xy 136.235487 -178.776119) (xy 136.18005 -178.782219)
			(xy 136.124316 -178.780182) (xy 136.069473 -178.770052) (xy 136.016689 -178.752045) (xy 135.967089 -178.726544)
			(xy 135.921731 -178.694093) (xy 135.881582 -178.655384) (xy 135.847496 -178.611241) (xy 135.8202 -178.562606)
			(xy 135.800277 -178.510515) (xy 135.788151 -178.456078) (xy 135.78408 -178.400456) (xy 134.843218 -178.400456)
			(xy 134.848941 -178.441022) (xy 134.849362 -178.465988) (xy 134.848864 -178.492637) (xy 134.840921 -178.545341)
			(xy 134.825211 -178.596271) (xy 134.802085 -178.644292) (xy 134.772061 -178.688329) (xy 134.735809 -178.7274)
			(xy 134.694138 -178.760631) (xy 134.64798 -178.78728) (xy 134.598366 -178.806752) (xy 134.546404 -178.818612)
			(xy 134.493254 -178.822596) (xy 134.440104 -178.818612) (xy 134.388142 -178.806752) (xy 134.338528 -178.78728)
			(xy 134.29237 -178.760631) (xy 134.250699 -178.7274) (xy 134.214447 -178.688329) (xy 134.184423 -178.644292)
			(xy 134.161297 -178.596271) (xy 134.145587 -178.545341) (xy 134.137644 -178.492637) (xy 134.137146 -178.465988)
			(xy 134.137572 -178.441203) (xy 134.144441 -178.392113) (xy 134.15806 -178.344451) (xy 134.178163 -178.299142)
			(xy 134.204361 -178.257062) (xy 134.236148 -178.219027) (xy 134.25424 -178.202082) (xy 134.261777 -178.194479)
			(xy 134.270438 -178.174927) (xy 134.271004 -178.164236) (xy 134.27075 -178.077876) (xy 134.26186 -178.058064)
			(xy 134.253732 -178.050952) (xy 134.235393 -178.034004) (xy 134.203205 -177.995824) (xy 134.176666 -177.953524)
			(xy 134.156295 -177.907931) (xy 134.142493 -177.859939) (xy 134.135529 -177.81049) (xy 134.135114 -177.785522)
			(xy 134.135114 -177.785268) (xy 134.135662 -177.757973) (xy 134.14402 -177.704027) (xy 134.160506 -177.651986)
			(xy 134.184733 -177.603066) (xy 134.216135 -177.558413) (xy 134.234682 -177.53838) (xy 134.241794 -177.531014)
			(xy 134.248906 -177.513234) (xy 134.248906 -177.42281) (xy 134.241794 -177.40503) (xy 134.234682 -177.397664)
			(xy 134.216057 -177.377661) (xy 134.184603 -177.332965) (xy 134.160356 -177.283984) (xy 134.143888 -177.23187)
			(xy 134.135585 -177.17785) (xy 134.135114 -177.150522) (xy 134.135645 -177.123202) (xy 134.14398 -177.0692)
			(xy 134.160458 -177.017104) (xy 134.184694 -176.968132) (xy 134.216119 -176.923432) (xy 134.234682 -176.90338)
			(xy 134.241794 -176.896014) (xy 134.248906 -176.878234) (xy 134.248906 -176.78781) (xy 134.241794 -176.77003)
			(xy 134.234682 -176.762664) (xy 134.216074 -176.742681) (xy 134.184642 -176.698031) (xy 134.160404 -176.649102)
			(xy 134.143928 -176.597043) (xy 134.135602 -176.543078) (xy 134.135114 -176.515776) (xy 134.135114 -176.515522)
			(xy 134.135513 -176.490779) (xy 134.142358 -176.441768) (xy 134.155919 -176.394176) (xy 134.175936 -176.348919)
			(xy 134.202023 -176.306867) (xy 134.233678 -176.268829) (xy 134.2517 -176.25187) (xy 134.259327 -176.244408)
			(xy 134.268008 -176.224938) (xy 134.268464 -176.214278) (xy 134.268464 -176.181766) (xy 134.267871 -176.171138)
			(xy 134.259208 -176.15172) (xy 134.2517 -176.144174) (xy 134.24408 -176.137062) (xy 134.236714 -176.12995)
			(xy 134.218934 -176.122838) (xy 134.12851 -176.122838) (xy 134.11073 -176.12995) (xy 134.103364 -176.137062)
			(xy 134.083353 -176.155677) (xy 134.03866 -176.187135) (xy 133.989681 -176.211384) (xy 133.937568 -176.227855)
			(xy 133.883549 -176.236159) (xy 133.856222 -176.23663) (xy 133.828902 -176.236087) (xy 133.774902 -176.227753)
			(xy 133.722806 -176.211277) (xy 133.673834 -176.187044) (xy 133.629133 -176.155623) (xy 133.60908 -176.137062)
			(xy 133.601714 -176.12995) (xy 133.583934 -176.122838) (xy 133.49351 -176.122838) (xy 133.47573 -176.12995)
			(xy 133.468364 -176.137062) (xy 133.448372 -176.155661) (xy 133.403725 -176.187096) (xy 133.354799 -176.211337)
			(xy 133.302742 -176.227814) (xy 133.248778 -176.236142) (xy 133.221476 -176.23663) (xy 133.221222 -176.23663)
			(xy 133.194571 -176.236114) (xy 133.141865 -176.228173) (xy 133.090931 -176.212465) (xy 133.042908 -176.189341)
			(xy 132.998867 -176.159317) (xy 132.959794 -176.123064) (xy 132.92656 -176.081392) (xy 132.899908 -176.035233)
			(xy 132.880434 -175.985617) (xy 132.868573 -175.933652) (xy 132.86459 -175.8805) (xy 132.63842 -175.8805)
			(xy 132.635561 -175.918651) (xy 132.623701 -175.970614) (xy 132.60423 -176.02023) (xy 132.577583 -176.06639)
			(xy 132.544353 -176.108063) (xy 132.505284 -176.144319) (xy 132.461248 -176.174347) (xy 132.413229 -176.197477)
			(xy 132.362299 -176.213193) (xy 132.309596 -176.221143) (xy 132.282946 -176.221644) (xy 132.282692 -176.221644)
			(xy 132.255399 -176.221065) (xy 132.201455 -176.212712) (xy 132.149414 -176.196233) (xy 132.100494 -176.172013)
			(xy 132.055839 -176.140619) (xy 132.035804 -176.122076) (xy 132.028438 -176.114964) (xy 132.010658 -176.107852)
			(xy 131.920234 -176.107852) (xy 131.902454 -176.114964) (xy 131.895088 -176.122076) (xy 131.875069 -176.140682)
			(xy 131.830378 -176.17214) (xy 131.781401 -176.196391) (xy 131.72929 -176.212864) (xy 131.675273 -176.221171)
			(xy 131.647946 -176.221644) (xy 131.619036 -176.221112) (xy 131.561973 -176.211799) (xy 131.507162 -176.193393)
			(xy 131.456043 -176.166378) (xy 131.409957 -176.131462) (xy 131.389628 -176.1109) (xy 131.382008 -176.102772)
			(xy 131.361434 -176.09439) (xy 131.273804 -176.098708) (xy 131.262896 -176.099765) (xy 131.243415 -176.109754)
			(xy 131.236212 -176.118012) (xy 131.235958 -176.118266) (xy 131.219566 -176.138489) (xy 131.181872 -176.174391)
			(xy 131.139345 -176.204411) (xy 131.116324 -176.216564) (xy 131.103624 -176.222914) (xy 131.088892 -176.246536)
			(xy 131.086606 -176.365154) (xy 131.100576 -176.389284) (xy 131.113022 -176.396142) (xy 131.137625 -176.410325)
			(xy 131.18261 -176.444981) (xy 131.221811 -176.486066) (xy 131.25432 -176.532626) (xy 131.279381 -176.583583)
			(xy 131.296415 -176.637755) (xy 131.305025 -176.693885) (xy 131.305554 -176.722278) (xy 131.305033 -176.750163)
			(xy 131.296721 -176.80531) (xy 131.280283 -176.858602) (xy 131.256085 -176.908848) (xy 131.224669 -176.954927)
			(xy 131.186736 -176.995809) (xy 131.143134 -177.030581) (xy 131.094836 -177.058466) (xy 131.042921 -177.078841)
			(xy 130.98855 -177.091251) (xy 130.932936 -177.095419) (xy 130.877322 -177.091251) (xy 130.822951 -177.078841)
			(xy 130.771036 -177.058466) (xy 130.722738 -177.030581) (xy 130.679136 -176.995809) (xy 130.641203 -176.954927)
			(xy 130.609787 -176.908848) (xy 130.585589 -176.858602) (xy 130.569151 -176.80531) (xy 130.560839 -176.750163)
			(xy 130.560318 -176.722278) (xy 127.902208 -176.722278) (xy 127.902208 -176.91862) (xy 127.901747 -176.942186)
			(xy 127.894501 -176.988757) (xy 127.88017 -177.033657) (xy 127.859096 -177.075815) (xy 127.831781 -177.114225)
			(xy 127.798878 -177.14797) (xy 127.780288 -177.16246) (xy 127.667766 -177.247296) (xy 127.662958 -177.250697)
			(xy 127.652184 -177.255441) (xy 127.64643 -177.256694) (xy 127.52705 -177.278538) (xy 127.52102 -177.27954)
			(xy 127.508815 -177.278886) (xy 127.50292 -177.277268) (xy 127.446278 -177.259996) (xy 127.445008 -177.259488)
			(xy 127.436725 -177.257356) (xy 127.419777 -177.255057) (xy 127.411226 -177.254916) (xy 127.410972 -177.254916)
			(xy 127.395997 -177.255315) (xy 127.366868 -177.262269) (xy 127.340169 -177.275834) (xy 127.317375 -177.295259)
			(xy 127.299748 -177.31947) (xy 127.288263 -177.347128) (xy 127.285496 -177.36185) (xy 127.285496 -177.362104)
			(xy 127.276352 -177.421794) (xy 127.275261 -177.433025) (xy 127.281696 -177.454624) (xy 127.296698 -177.471442)
			(xy 127.306832 -177.476404) (xy 127.362712 -177.499772) (xy 127.374272 -177.504251) (xy 127.398579 -177.509108)
			(xy 127.410972 -177.509424) (xy 127.425346 -177.509027) (xy 127.453361 -177.502573) (xy 127.479219 -177.490008)
			(xy 127.501606 -177.471971) (xy 127.510794 -177.46091) (xy 127.511048 -177.460402) (xy 127.545084 -177.41773)
			(xy 127.54846 -177.413684) (xy 127.556521 -177.406899) (xy 127.561086 -177.404268) (xy 127.657352 -177.353722)
			(xy 127.662176 -177.351307) (xy 127.672553 -177.348363) (xy 127.677926 -177.34788) (xy 127.808482 -177.34026)
			(xy 127.834234 -177.339277) (xy 127.885454 -177.344914) (xy 127.935002 -177.359067) (xy 127.981471 -177.381336)
			(xy 128.023543 -177.411089) (xy 128.042162 -177.428906) (xy 128.75641 -178.143154) (xy 130.5649 -178.143154)
			(xy 130.568876 -178.088828) (xy 130.580719 -178.035659) (xy 130.600178 -177.984782) (xy 130.626838 -177.93728)
			(xy 130.660129 -177.894166) (xy 130.699343 -177.856359) (xy 130.743645 -177.824664) (xy 130.792088 -177.799758)
			(xy 130.843642 -177.78217) (xy 130.897208 -177.772276) (xy 130.951643 -177.770286) (xy 131.005788 -177.776244)
			(xy 131.058488 -177.790022) (xy 131.108621 -177.811326) (xy 131.155117 -177.839702) (xy 131.196987 -177.874546)
			(xy 131.233336 -177.915115) (xy 131.263392 -177.960544) (xy 131.286513 -178.009865) (xy 131.302206 -178.062027)
			(xy 131.310137 -178.115918) (xy 131.310634 -178.143154) (xy 131.310137 -178.17039) (xy 131.302206 -178.224281)
			(xy 131.286513 -178.276443) (xy 131.263392 -178.325764) (xy 131.233336 -178.371193) (xy 131.196987 -178.411762)
			(xy 131.155117 -178.446606) (xy 131.108621 -178.474982) (xy 131.058488 -178.496286) (xy 131.005788 -178.510064)
			(xy 130.951643 -178.516022) (xy 130.897208 -178.514032) (xy 130.843642 -178.504138) (xy 130.792088 -178.48655)
			(xy 130.743645 -178.461644) (xy 130.699343 -178.429949) (xy 130.660129 -178.392142) (xy 130.626838 -178.349028)
			(xy 130.600178 -178.301526) (xy 130.580719 -178.250649) (xy 130.568876 -178.19748) (xy 130.5649 -178.143154)
			(xy 128.75641 -178.143154) (xy 129.482342 -178.869086) (xy 141.546072 -178.869086) (xy 141.546072 -178.005486)
			(xy 141.546562 -177.975518) (xy 141.554385 -177.916096) (xy 141.569898 -177.858203) (xy 141.592834 -177.80283)
			(xy 141.622801 -177.750924) (xy 141.659288 -177.703374) (xy 141.701668 -177.660994) (xy 141.749218 -177.624507)
			(xy 141.801124 -177.59454) (xy 141.856497 -177.571604) (xy 141.91439 -177.556091) (xy 141.973812 -177.548268)
			(xy 142.033748 -177.548268) (xy 142.09317 -177.556091) (xy 142.151063 -177.571604) (xy 142.206436 -177.59454)
			(xy 142.258342 -177.624507) (xy 142.305892 -177.660994) (xy 142.348272 -177.703374) (xy 142.384759 -177.750924)
			(xy 142.414726 -177.80283) (xy 142.437662 -177.858203) (xy 142.453175 -177.916096) (xy 142.460998 -177.975518)
			(xy 142.461488 -178.005486) (xy 142.461488 -178.869086) (xy 142.460998 -178.899054) (xy 142.453175 -178.958476)
			(xy 142.437662 -179.016369) (xy 142.414726 -179.071742) (xy 142.384759 -179.123648) (xy 142.348272 -179.171198)
			(xy 142.305892 -179.213578) (xy 142.258342 -179.250065) (xy 142.206436 -179.280032) (xy 142.151063 -179.302968)
			(xy 142.09317 -179.318481) (xy 142.033748 -179.326304) (xy 141.973812 -179.326304) (xy 141.91439 -179.318481)
			(xy 141.856497 -179.302968) (xy 141.801124 -179.280032) (xy 141.749218 -179.250065) (xy 141.701668 -179.213578)
			(xy 141.659288 -179.171198) (xy 141.622801 -179.123648) (xy 141.592834 -179.071742) (xy 141.569898 -179.016369)
			(xy 141.554385 -178.958476) (xy 141.546562 -178.899054) (xy 141.546072 -178.869086) (xy 129.482342 -178.869086)
			(xy 130.035856 -179.4226) (xy 130.601585 -179.4226) (xy 130.605755 -179.366971) (xy 130.618169 -179.312585)
			(xy 130.638551 -179.260656) (xy 130.666446 -179.212346) (xy 130.701229 -179.168734) (xy 130.742125 -179.130793)
			(xy 130.788219 -179.099371) (xy 130.838482 -179.075172) (xy 130.89179 -179.058734) (xy 130.946953 -179.050426)
			(xy 130.974846 -179.049934) (xy 131.000437 -179.050342) (xy 131.051131 -179.057392) (xy 131.100383 -179.071313)
			(xy 131.147268 -179.091843) (xy 131.190902 -179.118595) (xy 131.230465 -179.151066) (xy 131.24815 -179.169568)
			(xy 131.255704 -179.176897) (xy 131.274977 -179.185295) (xy 131.285488 -179.185824) (xy 131.360164 -179.185824)
			(xy 131.370689 -179.185353) (xy 131.389981 -179.176947) (xy 131.397502 -179.169568) (xy 131.41516 -179.15104)
			(xy 131.454728 -179.118574) (xy 131.498368 -179.091829) (xy 131.545259 -179.071311) (xy 131.594517 -179.057404)
			(xy 131.645215 -179.050371) (xy 131.670806 -179.049934) (xy 131.696761 -179.050402) (xy 131.748167 -179.057608)
			(xy 131.798077 -179.071878) (xy 131.845522 -179.092938) (xy 131.889585 -179.120378) (xy 131.929414 -179.153669)
			(xy 131.947158 -179.172616) (xy 131.954607 -179.180257) (xy 131.974087 -179.18893) (xy 131.98475 -179.18938)
			(xy 132.060442 -179.18938) (xy 132.07107 -179.188786) (xy 132.090488 -179.180124) (xy 132.098034 -179.172616)
			(xy 132.117413 -179.151956) (xy 132.161313 -179.116161) (xy 132.210127 -179.087426) (xy 132.262729 -179.066415)
			(xy 132.317906 -179.053611) (xy 132.374386 -179.04931) (xy 132.430866 -179.053611) (xy 132.486043 -179.066415)
			(xy 132.538645 -179.087426) (xy 132.587459 -179.116161) (xy 132.631359 -179.151956) (xy 132.650738 -179.172616)
			(xy 132.658195 -179.180248) (xy 132.677669 -179.188926) (xy 132.68833 -179.18938) (xy 132.764022 -179.18938)
			(xy 132.774648 -179.188775) (xy 132.794067 -179.18012) (xy 132.801614 -179.172616) (xy 132.820993 -179.151956)
			(xy 132.864893 -179.116161) (xy 132.913707 -179.087426) (xy 132.966309 -179.066415) (xy 133.021486 -179.053611)
			(xy 133.077966 -179.04931) (xy 133.134446 -179.053611) (xy 133.189623 -179.066415) (xy 133.242225 -179.087426)
			(xy 133.291039 -179.116161) (xy 133.334939 -179.151956) (xy 133.354318 -179.172616) (xy 133.361782 -179.180239)
			(xy 133.381251 -179.188922) (xy 133.39191 -179.18938) (xy 133.467602 -179.18938) (xy 133.478227 -179.188765)
			(xy 133.497646 -179.180117) (xy 133.505194 -179.172616) (xy 133.522919 -179.153649) (xy 133.562749 -179.120353)
			(xy 133.606815 -179.09291) (xy 133.654264 -179.07185) (xy 133.704178 -179.057581) (xy 133.755589 -179.05038)
			(xy 133.781546 -179.049934) (xy 133.810645 -179.050478) (xy 133.868132 -179.059541) (xy 133.923509 -179.077439)
			(xy 133.975426 -179.103735) (xy 134.022619 -179.137791) (xy 134.043674 -179.157884) (xy 134.043928 -179.158138)
			(xy 134.051887 -179.165112) (xy 134.071701 -179.172468) (xy 134.082282 -179.172362) (xy 134.168642 -179.167536)
			(xy 134.187692 -179.15763) (xy 134.19455 -179.149248) (xy 134.212347 -179.1279) (xy 134.253176 -179.090195)
			(xy 134.299154 -179.058972) (xy 134.349259 -179.034925) (xy 134.402379 -179.018587) (xy 134.457338 -179.010321)
			(xy 134.485126 -179.009802) (xy 134.513011 -179.010285) (xy 134.568158 -179.0186) (xy 134.621449 -179.035042)
			(xy 134.671695 -179.059242) (xy 134.717773 -179.090661) (xy 134.758654 -179.128595) (xy 134.793425 -179.172199)
			(xy 134.821309 -179.220498) (xy 134.841683 -179.272414) (xy 134.854093 -179.326786) (xy 134.858261 -179.3824)
			(xy 134.854093 -179.438014) (xy 134.841683 -179.492386) (xy 134.821309 -179.544302) (xy 134.793425 -179.592601)
			(xy 134.758654 -179.636205) (xy 134.717773 -179.674139) (xy 134.671695 -179.705558) (xy 134.621449 -179.729758)
			(xy 134.568158 -179.7462) (xy 134.513011 -179.754515) (xy 134.485126 -179.755038) (xy 134.456029 -179.754457)
			(xy 134.398543 -179.745405) (xy 134.343166 -179.727516) (xy 134.291248 -179.701227) (xy 134.244054 -179.667178)
			(xy 134.222998 -179.647088) (xy 134.222744 -179.646834) (xy 134.214798 -179.639843) (xy 134.194974 -179.632498)
			(xy 134.18439 -179.63261) (xy 134.09803 -179.637436) (xy 134.07898 -179.647342) (xy 134.072122 -179.655724)
			(xy 134.05492 -179.67638) (xy 134.015629 -179.713062) (xy 133.971473 -179.743713) (xy 133.923367 -179.767695)
			(xy 133.872314 -179.784512) (xy 133.819372 -179.793812) (xy 133.765644 -179.795403) (xy 133.712245 -179.789252)
			(xy 133.660285 -179.775486) (xy 133.610845 -179.754392) (xy 133.564952 -179.726408) (xy 133.52356 -179.692116)
			(xy 133.505194 -179.672488) (xy 133.497725 -179.66487) (xy 133.47826 -179.656184) (xy 133.467602 -179.655724)
			(xy 133.39191 -179.655724) (xy 133.381285 -179.656344) (xy 133.361867 -179.664988) (xy 133.354318 -179.672488)
			(xy 133.334939 -179.693148) (xy 133.291039 -179.728943) (xy 133.242225 -179.757678) (xy 133.189623 -179.778689)
			(xy 133.134446 -179.791493) (xy 133.077966 -179.795794) (xy 133.021486 -179.791493) (xy 132.966309 -179.778689)
			(xy 132.913707 -179.757678) (xy 132.864893 -179.728943) (xy 132.820993 -179.693148) (xy 132.801614 -179.672488)
			(xy 132.794137 -179.664879) (xy 132.774678 -179.656188) (xy 132.764022 -179.655724) (xy 132.68833 -179.655724)
			(xy 132.677707 -179.656355) (xy 132.658288 -179.664991) (xy 132.650738 -179.672488) (xy 132.631359 -179.693148)
			(xy 132.587459 -179.728943) (xy 132.538645 -179.757678) (xy 132.486043 -179.778689) (xy 132.430866 -179.791493)
			(xy 132.374386 -179.795794) (xy 132.317906 -179.791493) (xy 132.262729 -179.778689) (xy 132.210127 -179.757678)
			(xy 132.161313 -179.728943) (xy 132.117413 -179.693148) (xy 132.098034 -179.672488) (xy 132.090588 -179.664843)
			(xy 132.071106 -179.656173) (xy 132.060442 -179.655724) (xy 131.98475 -179.655724) (xy 131.974122 -179.656312)
			(xy 131.954703 -179.664978) (xy 131.947158 -179.672488) (xy 131.929408 -179.69143) (xy 131.889584 -179.724728)
			(xy 131.845523 -179.752175) (xy 131.798078 -179.773239) (xy 131.748169 -179.787513) (xy 131.696761 -179.794721)
			(xy 131.670806 -179.79517) (xy 131.645217 -179.794726) (xy 131.594524 -179.787683) (xy 131.545272 -179.773769)
			(xy 131.498388 -179.753246) (xy 131.454753 -179.7265) (xy 131.415188 -179.694035) (xy 131.397502 -179.675536)
			(xy 131.389966 -179.668186) (xy 131.370679 -179.6598) (xy 131.360164 -179.65928) (xy 131.285488 -179.65928)
			(xy 131.27496 -179.659724) (xy 131.255668 -179.668149) (xy 131.24815 -179.675536) (xy 131.230468 -179.694039)
			(xy 131.190905 -179.726508) (xy 131.147269 -179.753255) (xy 131.100384 -179.773778) (xy 131.05113 -179.78769)
			(xy 131.000436 -179.794729) (xy 130.974846 -179.79517) (xy 130.946953 -179.794774) (xy 130.89179 -179.786466)
			(xy 130.838482 -179.770028) (xy 130.788219 -179.745829) (xy 130.742125 -179.714407) (xy 130.701229 -179.676466)
			(xy 130.666446 -179.632854) (xy 130.638551 -179.584544) (xy 130.618169 -179.532615) (xy 130.605755 -179.478229)
			(xy 130.601585 -179.4226) (xy 130.035856 -179.4226) (xy 131.514342 -180.901086) (xy 142.181072 -180.901086)
			(xy 142.181072 -180.037486) (xy 142.181562 -180.007518) (xy 142.189385 -179.948096) (xy 142.204898 -179.890203)
			(xy 142.227834 -179.83483) (xy 142.257801 -179.782924) (xy 142.294288 -179.735374) (xy 142.336668 -179.692994)
			(xy 142.384218 -179.656507) (xy 142.436124 -179.62654) (xy 142.491497 -179.603604) (xy 142.54939 -179.588091)
			(xy 142.608812 -179.580268) (xy 142.668748 -179.580268) (xy 142.72817 -179.588091) (xy 142.786063 -179.603604)
			(xy 142.841436 -179.62654) (xy 142.893342 -179.656507) (xy 142.940892 -179.692994) (xy 142.983272 -179.735374)
			(xy 143.019759 -179.782924) (xy 143.049726 -179.83483) (xy 143.072662 -179.890203) (xy 143.088175 -179.948096)
			(xy 143.095998 -180.007518) (xy 143.096488 -180.037486) (xy 143.096488 -180.901086) (xy 143.095998 -180.931054)
			(xy 143.088175 -180.990476) (xy 143.072662 -181.048369) (xy 143.049726 -181.103742) (xy 143.019759 -181.155648)
			(xy 142.983272 -181.203198) (xy 142.940892 -181.245578) (xy 142.893342 -181.282065) (xy 142.841436 -181.312032)
			(xy 142.786063 -181.334968) (xy 142.72817 -181.350481) (xy 142.668748 -181.358304) (xy 142.608812 -181.358304)
			(xy 142.54939 -181.350481) (xy 142.491497 -181.334968) (xy 142.436124 -181.312032) (xy 142.384218 -181.282065)
			(xy 142.336668 -181.245578) (xy 142.294288 -181.203198) (xy 142.257801 -181.155648) (xy 142.227834 -181.103742)
			(xy 142.204898 -181.048369) (xy 142.189385 -180.990476) (xy 142.181562 -180.931054) (xy 142.181072 -180.901086)
			(xy 131.514342 -180.901086) (xy 132.024374 -181.411118) (xy 132.041046 -181.428393) (xy 132.069301 -181.467206)
			(xy 132.091136 -181.509961) (xy 132.106014 -181.555605) (xy 132.113568 -181.603015) (xy 132.114036 -181.627018)
			(xy 132.114036 -182.782972) (xy 132.113559 -182.806976) (xy 132.11063 -182.82539) (xy 136.874248 -182.82539)
			(xy 136.878319 -182.769768) (xy 136.890445 -182.715331) (xy 136.910368 -182.66324) (xy 136.937664 -182.614605)
			(xy 136.97175 -182.570462) (xy 137.011899 -182.531753) (xy 137.057257 -182.499302) (xy 137.106857 -182.473801)
			(xy 137.159641 -182.455794) (xy 137.214484 -182.445664) (xy 137.270218 -182.443627) (xy 137.325655 -182.449727)
			(xy 137.379612 -182.463833) (xy 137.430941 -182.485645) (xy 137.478547 -182.514699) (xy 137.521415 -182.550374)
			(xy 137.558632 -182.591911) (xy 137.589405 -182.638424) (xy 137.613077 -182.688921) (xy 137.629145 -182.742328)
			(xy 137.637265 -182.797504) (xy 137.637774 -182.82539) (xy 137.637265 -182.853276) (xy 137.629145 -182.908452)
			(xy 137.621581 -182.933594) (xy 141.546072 -182.933594) (xy 141.546072 -182.069486) (xy 141.546562 -182.039518)
			(xy 141.554385 -181.980096) (xy 141.569898 -181.922203) (xy 141.592834 -181.86683) (xy 141.622801 -181.814924)
			(xy 141.659288 -181.767374) (xy 141.701668 -181.724994) (xy 141.749218 -181.688507) (xy 141.801124 -181.65854)
			(xy 141.856497 -181.635604) (xy 141.91439 -181.620091) (xy 141.973812 -181.612268) (xy 142.033748 -181.612268)
			(xy 142.09317 -181.620091) (xy 142.151063 -181.635604) (xy 142.206436 -181.65854) (xy 142.258342 -181.688507)
			(xy 142.305892 -181.724994) (xy 142.348272 -181.767374) (xy 142.384759 -181.814924) (xy 142.414726 -181.86683)
			(xy 142.437662 -181.922203) (xy 142.453175 -181.980096) (xy 142.460998 -182.039518) (xy 142.461488 -182.069486)
			(xy 142.461488 -182.933086) (xy 142.461368 -182.951323) (xy 142.458569 -182.987689) (xy 142.4559 -183.00573)
			(xy 142.45482 -183.015233) (xy 142.458872 -183.033903) (xy 142.469488 -183.049788) (xy 142.485187 -183.060676)
			(xy 142.503785 -183.065049) (xy 142.522692 -183.0623) (xy 142.539274 -183.05281) (xy 142.545562 -183.045608)
			(xy 142.563811 -183.023798) (xy 142.605621 -182.985255) (xy 142.652687 -182.953343) (xy 142.703968 -182.928769)
			(xy 142.758328 -182.912078) (xy 142.814564 -182.903639) (xy 142.842996 -182.903114) (xy 142.870251 -182.903533)
			(xy 142.924205 -182.91129) (xy 142.976507 -182.926646) (xy 143.02609 -182.94929) (xy 143.071946 -182.978759)
			(xy 143.113142 -183.014455) (xy 143.148838 -183.05565) (xy 143.178308 -183.101506) (xy 143.200952 -183.15109)
			(xy 143.21631 -183.203391) (xy 143.224067 -183.257345) (xy 143.224067 -183.311855) (xy 143.21631 -183.365809)
			(xy 143.200952 -183.41811) (xy 143.178308 -183.467694) (xy 143.148838 -183.51355) (xy 143.113142 -183.554745)
			(xy 143.071946 -183.590441) (xy 143.02609 -183.61991) (xy 142.976507 -183.642554) (xy 142.924205 -183.65791)
			(xy 142.870251 -183.665667) (xy 142.842996 -183.66613) (xy 142.815988 -183.665684) (xy 142.762509 -183.658078)
			(xy 142.710639 -183.643002) (xy 142.661414 -183.62076) (xy 142.615819 -183.591796) (xy 142.574767 -183.556689)
			(xy 142.539078 -183.516142) (xy 142.509465 -183.470965) (xy 142.486523 -183.422063) (xy 142.470708 -183.370413)
			(xy 142.46606 -183.343804) (xy 142.464028 -183.330088) (xy 142.446756 -183.309006) (xy 142.35049 -183.273192)
			(xy 142.341985 -183.270451) (xy 142.324127 -183.270396) (xy 142.307318 -183.276426) (xy 142.300198 -183.281828)
			(xy 142.29969 -183.282336) (xy 142.274795 -183.302764) (xy 142.220337 -183.337135) (xy 142.161597 -183.363532)
			(xy 142.099737 -183.381434) (xy 142.035979 -183.390487) (xy 142.00378 -183.391048) (xy 141.973824 -183.390538)
			(xy 141.914425 -183.382718) (xy 141.856553 -183.367216) (xy 141.801199 -183.344296) (xy 141.749308 -183.31435)
			(xy 141.701768 -183.277889) (xy 141.659392 -183.235538) (xy 141.622903 -183.18802) (xy 141.592925 -183.136147)
			(xy 141.569972 -183.080806) (xy 141.554435 -183.022944) (xy 141.54658 -182.96355) (xy 141.546072 -182.933594)
			(xy 137.621581 -182.933594) (xy 137.613077 -182.961859) (xy 137.589405 -183.012356) (xy 137.558632 -183.058869)
			(xy 137.521415 -183.100406) (xy 137.478547 -183.136081) (xy 137.430941 -183.165135) (xy 137.379612 -183.186947)
			(xy 137.325655 -183.201053) (xy 137.270218 -183.207153) (xy 137.214484 -183.205116) (xy 137.159641 -183.194986)
			(xy 137.106857 -183.176979) (xy 137.057257 -183.151478) (xy 137.011899 -183.119027) (xy 136.97175 -183.080318)
			(xy 136.937664 -183.036175) (xy 136.910368 -182.98754) (xy 136.890445 -182.935449) (xy 136.878319 -182.881012)
			(xy 136.874248 -182.82539) (xy 132.11063 -182.82539) (xy 132.106017 -182.854388) (xy 132.091145 -182.900035)
			(xy 132.06931 -182.942791) (xy 132.041051 -182.981601) (xy 132.024374 -182.998872) (xy 131.78409 -183.239156)
			(xy 131.766817 -183.255776) (xy 131.728032 -183.283939) (xy 131.685326 -183.305704) (xy 131.639746 -183.320535)
			(xy 131.59241 -183.32807) (xy 131.568444 -183.328564) (xy 128.201166 -183.328564) (xy 128.172429 -183.327905)
			(xy 128.115963 -183.317185) (xy 128.062492 -183.29611) (xy 128.037844 -183.28132) (xy 128.028212 -183.275879)
			(xy 128.00629 -183.273052) (xy 127.985195 -183.279649) (xy 127.97663 -183.286654) (xy 127.955425 -183.305317)
			(xy 127.908522 -183.336794) (xy 127.857491 -183.361013) (xy 127.803447 -183.377445) (xy 127.747572 -183.385732)
			(xy 127.719328 -183.386222) (xy 127.691085 -183.385728) (xy 127.635209 -183.377446) (xy 127.581167 -183.361013)
			(xy 127.530138 -183.336789) (xy 127.483241 -183.305305) (xy 127.462026 -183.286654) (xy 127.453461 -183.279637)
			(xy 127.43237 -183.272995) (xy 127.410446 -183.275867) (xy 127.400812 -183.28132) (xy 127.376168 -183.296121)
			(xy 127.322702 -183.317221) (xy 127.26623 -183.327931) (xy 127.23749 -183.328564) (xy 126.316232 -183.328564)
			(xy 126.292261 -183.328092) (xy 126.244909 -183.320601) (xy 126.199316 -183.305783) (xy 126.156607 -183.284005)
			(xy 126.117839 -183.255803) (xy 126.100586 -183.239156) (xy 124.35332 -181.49189) (xy 124.336696 -181.474621)
			(xy 124.308534 -181.435834) (xy 124.286771 -181.393127) (xy 124.271941 -181.347546) (xy 124.264406 -181.30021)
			(xy 124.263912 -181.276244) (xy 121.286524 -181.276244) (xy 121.286524 -182.73522) (xy 121.285982 -182.761243)
			(xy 121.277819 -182.812646) (xy 121.261728 -182.862143) (xy 121.238104 -182.908519) (xy 121.207527 -182.950637)
			(xy 121.189496 -182.969408) (xy 118.068964 -186.089848) (xy 141.507498 -186.089848) (xy 141.507498 -186.035352)
			(xy 141.515253 -185.98141) (xy 141.530606 -185.929121) (xy 141.553243 -185.879549) (xy 141.582704 -185.833703)
			(xy 141.61839 -185.792516) (xy 141.659574 -185.756826) (xy 141.705417 -185.72736) (xy 141.754987 -185.704718)
			(xy 141.807275 -185.689361) (xy 141.861216 -185.681601) (xy 141.888464 -185.681112) (xy 141.916961 -185.681633)
			(xy 141.973321 -185.690107) (xy 142.027793 -185.706871) (xy 142.079165 -185.731552) (xy 142.126293 -185.763602)
			(xy 142.168129 -185.802306) (xy 142.203742 -185.846803) (xy 142.232338 -185.896104) (xy 142.243302 -185.922412)
			(xy 142.248869 -185.935335) (xy 142.265945 -185.957689) (xy 142.288471 -185.974537) (xy 142.314739 -185.984601)
			(xy 142.342756 -185.987118) (xy 142.370397 -185.981897) (xy 142.395566 -185.969334) (xy 142.416353 -185.950382)
			(xy 142.42415 -185.938668) (xy 142.439172 -185.915414) (xy 142.474842 -185.87308) (xy 142.51626 -185.836349)
			(xy 142.562554 -185.805994) (xy 142.612752 -185.782653) (xy 142.665797 -185.766817) (xy 142.720575 -185.758819)
			(xy 142.748254 -185.758328) (xy 142.775512 -185.758716) (xy 142.829473 -185.766468) (xy 142.881781 -185.781822)
			(xy 142.931372 -185.804464) (xy 142.977235 -185.833933) (xy 143.018437 -185.86963) (xy 143.054139 -185.910828)
			(xy 143.083614 -185.956688) (xy 143.106262 -186.006276) (xy 143.121622 -186.058582) (xy 143.129381 -186.112542)
			(xy 143.129381 -186.167058) (xy 143.121622 -186.221018) (xy 143.106262 -186.273324) (xy 143.083614 -186.322912)
			(xy 143.054139 -186.368772) (xy 143.018437 -186.40997) (xy 142.977235 -186.445667) (xy 142.931372 -186.475136)
			(xy 142.881781 -186.497778) (xy 142.829473 -186.513132) (xy 142.775512 -186.520884) (xy 142.748254 -186.521344)
			(xy 142.719756 -186.520835) (xy 142.663395 -186.512363) (xy 142.608921 -186.495599) (xy 142.557547 -186.470917)
			(xy 142.510418 -186.438865) (xy 142.468582 -186.400158) (xy 142.432971 -186.355658) (xy 142.404378 -186.306354)
			(xy 142.393416 -186.280044) (xy 142.387818 -186.267133) (xy 142.370752 -186.244772) (xy 142.348232 -186.227916)
			(xy 142.321967 -186.217847) (xy 142.29395 -186.215327) (xy 142.26631 -186.220548) (xy 142.241143 -186.233114)
			(xy 142.220362 -186.252071) (xy 142.212568 -186.263788) (xy 142.197553 -186.287046) (xy 142.161879 -186.329378)
			(xy 142.12046 -186.366107) (xy 142.074164 -186.39646) (xy 142.023966 -186.4198) (xy 141.970921 -186.435636)
			(xy 141.916143 -186.443636) (xy 141.888464 -186.444128) (xy 141.861216 -186.443599) (xy 141.807275 -186.435839)
			(xy 141.754987 -186.420482) (xy 141.705417 -186.39784) (xy 141.659574 -186.368374) (xy 141.61839 -186.332684)
			(xy 141.582704 -186.291497) (xy 141.553243 -186.245651) (xy 141.530606 -186.196079) (xy 141.515253 -186.14379)
			(xy 141.507498 -186.089848) (xy 118.068964 -186.089848) (xy 117.034199 -187.124582) (xy 135.58115 -187.124582)
			(xy 135.58115 -187.064618) (xy 135.588977 -187.005166) (xy 135.604497 -186.947244) (xy 135.627444 -186.891844)
			(xy 135.657426 -186.839912) (xy 135.69393 -186.792339) (xy 135.736331 -186.749937) (xy 135.783904 -186.713432)
			(xy 135.835835 -186.683448) (xy 135.891235 -186.6605) (xy 135.949156 -186.644979) (xy 136.008608 -186.637151)
			(xy 136.03859 -186.63666) (xy 136.90219 -186.63666) (xy 136.932178 -186.637085) (xy 136.99164 -186.644912)
			(xy 137.049571 -186.660433) (xy 137.104981 -186.683384) (xy 137.156922 -186.713371) (xy 137.204504 -186.749881)
			(xy 137.246913 -186.792289) (xy 137.283424 -186.83987) (xy 137.313412 -186.89181) (xy 137.336363 -186.947219)
			(xy 137.351886 -187.005151) (xy 137.359715 -187.064612) (xy 137.359715 -187.124588) (xy 137.351886 -187.184049)
			(xy 137.336363 -187.241981) (xy 137.313412 -187.29739) (xy 137.283424 -187.34933) (xy 137.246913 -187.396911)
			(xy 137.204504 -187.439319) (xy 137.156922 -187.475829) (xy 137.104981 -187.505816) (xy 137.049571 -187.528767)
			(xy 136.99164 -187.544288) (xy 136.932178 -187.552115) (xy 136.90219 -187.552584) (xy 136.03859 -187.552584)
			(xy 136.008608 -187.552049) (xy 135.949156 -187.544221) (xy 135.891235 -187.5287) (xy 135.835835 -187.505752)
			(xy 135.783904 -187.475768) (xy 135.736331 -187.439263) (xy 135.69393 -187.396861) (xy 135.657426 -187.349288)
			(xy 135.627444 -187.297356) (xy 135.604497 -187.241956) (xy 135.588977 -187.184034) (xy 135.58115 -187.124582)
			(xy 117.034199 -187.124582) (xy 115.905863 -188.252885) (xy 128.656818 -188.252885) (xy 128.656818 -188.192915)
			(xy 128.664646 -188.133459) (xy 128.680167 -188.075533) (xy 128.703116 -188.020128) (xy 128.733101 -187.968193)
			(xy 128.769608 -187.920615) (xy 128.812012 -187.87821) (xy 128.859589 -187.841703) (xy 128.911524 -187.811718)
			(xy 128.966929 -187.788768) (xy 129.024855 -187.773246) (xy 129.084311 -187.765418) (xy 129.114296 -187.764928)
			(xy 129.977896 -187.764928) (xy 130.007881 -187.765417) (xy 130.067339 -187.773244) (xy 130.125266 -187.788765)
			(xy 130.180671 -187.811714) (xy 130.232607 -187.841699) (xy 130.280185 -187.878207) (xy 130.322591 -187.920612)
			(xy 130.359098 -187.96819) (xy 130.389084 -188.020125) (xy 130.412034 -188.075531) (xy 130.427555 -188.133458)
			(xy 130.435383 -188.192915) (xy 130.435383 -188.252885) (xy 130.434185 -188.261981) (xy 131.046262 -188.261981)
			(xy 131.046262 -188.202019) (xy 131.054088 -188.14257) (xy 131.069607 -188.084651) (xy 131.092553 -188.029253)
			(xy 131.122533 -187.977324) (xy 131.159034 -187.929752) (xy 131.201432 -187.887351) (xy 131.249002 -187.850847)
			(xy 131.30093 -187.820864) (xy 131.356326 -187.797915) (xy 131.414244 -187.782393) (xy 131.473693 -187.774564)
			(xy 131.503674 -187.774072) (xy 132.367274 -187.774072) (xy 132.397263 -187.774472) (xy 132.456728 -187.782297)
			(xy 132.514663 -187.797818) (xy 132.570077 -187.820768) (xy 132.62202 -187.850755) (xy 132.631984 -187.8584)
			(xy 142.670782 -187.8584) (xy 142.674853 -187.802778) (xy 142.686979 -187.748341) (xy 142.706902 -187.69625)
			(xy 142.734198 -187.647615) (xy 142.768284 -187.603472) (xy 142.808433 -187.564763) (xy 142.853791 -187.532312)
			(xy 142.903391 -187.506811) (xy 142.956175 -187.488804) (xy 143.011018 -187.478674) (xy 143.066752 -187.476637)
			(xy 143.122189 -187.482737) (xy 143.176146 -187.496843) (xy 143.227475 -187.518655) (xy 143.275081 -187.547709)
			(xy 143.317949 -187.583384) (xy 143.355166 -187.624921) (xy 143.385939 -187.671434) (xy 143.409611 -187.721931)
			(xy 143.425679 -187.775338) (xy 143.433799 -187.830514) (xy 143.434308 -187.8584) (xy 143.433799 -187.886286)
			(xy 143.425679 -187.941462) (xy 143.409611 -187.994869) (xy 143.385939 -188.045366) (xy 143.355166 -188.091879)
			(xy 143.317949 -188.133416) (xy 143.275081 -188.169091) (xy 143.227475 -188.198145) (xy 143.176146 -188.219957)
			(xy 143.122189 -188.234063) (xy 143.066752 -188.240163) (xy 143.011018 -188.238126) (xy 142.956175 -188.227996)
			(xy 142.903391 -188.209989) (xy 142.853791 -188.184488) (xy 142.808433 -188.152037) (xy 142.768284 -188.113328)
			(xy 142.734198 -188.069185) (xy 142.706902 -188.02055) (xy 142.686979 -187.968459) (xy 142.674853 -187.914022)
			(xy 142.670782 -187.8584) (xy 132.631984 -187.8584) (xy 132.669605 -187.887266) (xy 132.712017 -187.929675)
			(xy 132.74853 -187.977258) (xy 132.77852 -188.0292) (xy 132.801474 -188.084612) (xy 132.816998 -188.142546)
			(xy 132.824827 -188.202011) (xy 132.824827 -188.261989) (xy 132.816998 -188.321454) (xy 132.801474 -188.379388)
			(xy 132.79518 -188.394582) (xy 133.54915 -188.394582) (xy 133.54915 -188.334618) (xy 133.556977 -188.275166)
			(xy 133.572497 -188.217244) (xy 133.595444 -188.161844) (xy 133.625426 -188.109912) (xy 133.66193 -188.062339)
			(xy 133.704331 -188.019937) (xy 133.751904 -187.983432) (xy 133.803835 -187.953448) (xy 133.859235 -187.9305)
			(xy 133.917156 -187.914979) (xy 133.976608 -187.907151) (xy 134.00659 -187.90666) (xy 134.87019 -187.90666)
			(xy 134.900178 -187.907085) (xy 134.95964 -187.914912) (xy 135.017571 -187.930433) (xy 135.072981 -187.953384)
			(xy 135.124922 -187.983371) (xy 135.172504 -188.019881) (xy 135.214913 -188.062289) (xy 135.251424 -188.10987)
			(xy 135.281412 -188.16181) (xy 135.304363 -188.217219) (xy 135.319886 -188.275151) (xy 135.327715 -188.334612)
			(xy 135.327715 -188.394588) (xy 135.319886 -188.454049) (xy 135.304363 -188.511981) (xy 135.281412 -188.56739)
			(xy 135.251424 -188.61933) (xy 135.214913 -188.666911) (xy 135.172504 -188.709319) (xy 135.124922 -188.745829)
			(xy 135.072981 -188.775816) (xy 135.017571 -188.798767) (xy 134.95964 -188.814288) (xy 134.900178 -188.822115)
			(xy 134.87019 -188.822584) (xy 134.00659 -188.822584) (xy 133.976608 -188.822049) (xy 133.917156 -188.814221)
			(xy 133.859235 -188.7987) (xy 133.803835 -188.775752) (xy 133.751904 -188.745768) (xy 133.704331 -188.709263)
			(xy 133.66193 -188.666861) (xy 133.625426 -188.619288) (xy 133.595444 -188.567356) (xy 133.572497 -188.511956)
			(xy 133.556977 -188.454034) (xy 133.54915 -188.394582) (xy 132.79518 -188.394582) (xy 132.77852 -188.4348)
			(xy 132.74853 -188.486742) (xy 132.712017 -188.534325) (xy 132.669605 -188.576734) (xy 132.62202 -188.613245)
			(xy 132.570077 -188.643232) (xy 132.514663 -188.666182) (xy 132.456728 -188.681703) (xy 132.397263 -188.689528)
			(xy 132.367274 -188.689996) (xy 131.503674 -188.689996) (xy 131.473693 -188.689436) (xy 131.414244 -188.681607)
			(xy 131.356326 -188.666085) (xy 131.30093 -188.643136) (xy 131.249002 -188.613153) (xy 131.201432 -188.576649)
			(xy 131.159034 -188.534248) (xy 131.122533 -188.486676) (xy 131.092553 -188.434747) (xy 131.069607 -188.379349)
			(xy 131.054088 -188.32143) (xy 131.046262 -188.261981) (xy 130.434185 -188.261981) (xy 130.427555 -188.312342)
			(xy 130.412034 -188.370269) (xy 130.389084 -188.425675) (xy 130.359098 -188.47761) (xy 130.322591 -188.525188)
			(xy 130.280185 -188.567593) (xy 130.232607 -188.604101) (xy 130.180671 -188.634086) (xy 130.125266 -188.657035)
			(xy 130.067339 -188.672556) (xy 130.007881 -188.680383) (xy 129.977896 -188.680852) (xy 129.114296 -188.680852)
			(xy 129.084311 -188.680382) (xy 129.024855 -188.672554) (xy 128.966929 -188.657032) (xy 128.911524 -188.634082)
			(xy 128.859589 -188.604097) (xy 128.812012 -188.56759) (xy 128.769608 -188.525185) (xy 128.733101 -188.477607)
			(xy 128.703116 -188.425672) (xy 128.680167 -188.370267) (xy 128.664646 -188.312341) (xy 128.656818 -188.252885)
			(xy 115.905863 -188.252885) (xy 115.030576 -189.128146) (xy 141.31112 -189.128146) (xy 141.315191 -189.072524)
			(xy 141.327317 -189.018087) (xy 141.34724 -188.965996) (xy 141.374536 -188.917361) (xy 141.408622 -188.873218)
			(xy 141.448771 -188.834509) (xy 141.494129 -188.802058) (xy 141.543729 -188.776557) (xy 141.596513 -188.75855)
			(xy 141.651356 -188.74842) (xy 141.70709 -188.746383) (xy 141.762527 -188.752483) (xy 141.816484 -188.766589)
			(xy 141.867813 -188.788401) (xy 141.915419 -188.817455) (xy 141.958287 -188.85313) (xy 141.995504 -188.894667)
			(xy 142.026277 -188.94118) (xy 142.049949 -188.991677) (xy 142.066017 -189.045084) (xy 142.074137 -189.10026)
			(xy 142.074646 -189.128146) (xy 142.074137 -189.156032) (xy 142.066017 -189.211208) (xy 142.049949 -189.264615)
			(xy 142.026277 -189.315112) (xy 141.995504 -189.361625) (xy 141.958287 -189.403162) (xy 141.915419 -189.438837)
			(xy 141.867813 -189.467891) (xy 141.816484 -189.489703) (xy 141.762527 -189.503809) (xy 141.70709 -189.509909)
			(xy 141.651356 -189.507872) (xy 141.596513 -189.497742) (xy 141.543729 -189.479735) (xy 141.494129 -189.454234)
			(xy 141.448771 -189.421783) (xy 141.408622 -189.383074) (xy 141.374536 -189.338931) (xy 141.34724 -189.290296)
			(xy 141.327317 -189.238205) (xy 141.315191 -189.183768) (xy 141.31112 -189.128146) (xy 115.030576 -189.128146)
			(xy 114.309703 -189.848998) (xy 145.357594 -189.848998) (xy 145.361665 -189.793376) (xy 145.373791 -189.738939)
			(xy 145.393714 -189.686848) (xy 145.42101 -189.638213) (xy 145.455096 -189.59407) (xy 145.495245 -189.555361)
			(xy 145.540603 -189.52291) (xy 145.590203 -189.497409) (xy 145.642987 -189.479402) (xy 145.69783 -189.469272)
			(xy 145.753564 -189.467235) (xy 145.809001 -189.473335) (xy 145.862958 -189.487441) (xy 145.914287 -189.509253)
			(xy 145.961893 -189.538307) (xy 146.004761 -189.573982) (xy 146.041978 -189.615519) (xy 146.072751 -189.662032)
			(xy 146.096423 -189.712529) (xy 146.112491 -189.765936) (xy 146.120611 -189.821112) (xy 146.12112 -189.848998)
			(xy 146.120611 -189.876884) (xy 146.112491 -189.93206) (xy 146.096423 -189.985467) (xy 146.072751 -190.035964)
			(xy 146.041978 -190.082477) (xy 146.004761 -190.124014) (xy 145.961893 -190.159689) (xy 145.914287 -190.188743)
			(xy 145.862958 -190.210555) (xy 145.809001 -190.224661) (xy 145.753564 -190.230761) (xy 145.69783 -190.228724)
			(xy 145.642987 -190.218594) (xy 145.590203 -190.200587) (xy 145.540603 -190.175086) (xy 145.495245 -190.142635)
			(xy 145.455096 -190.103926) (xy 145.42101 -190.059783) (xy 145.393714 -190.011148) (xy 145.373791 -189.959057)
			(xy 145.361665 -189.90462) (xy 145.357594 -189.848998) (xy 114.309703 -189.848998) (xy 113.442522 -190.716154)
			(xy 141.286736 -190.716154) (xy 141.290807 -190.660532) (xy 141.302933 -190.606095) (xy 141.322856 -190.554004)
			(xy 141.350152 -190.505369) (xy 141.384238 -190.461226) (xy 141.424387 -190.422517) (xy 141.469745 -190.390066)
			(xy 141.519345 -190.364565) (xy 141.572129 -190.346558) (xy 141.626972 -190.336428) (xy 141.682706 -190.334391)
			(xy 141.738143 -190.340491) (xy 141.7921 -190.354597) (xy 141.843429 -190.376409) (xy 141.891035 -190.405463)
			(xy 141.933903 -190.441138) (xy 141.97112 -190.482675) (xy 142.001893 -190.529188) (xy 142.005475 -190.53683)
			(xy 143.744694 -190.53683) (xy 143.748765 -190.481208) (xy 143.760891 -190.426771) (xy 143.780814 -190.37468)
			(xy 143.80811 -190.326045) (xy 143.842196 -190.281902) (xy 143.882345 -190.243193) (xy 143.927703 -190.210742)
			(xy 143.977303 -190.185241) (xy 144.030087 -190.167234) (xy 144.08493 -190.157104) (xy 144.140664 -190.155067)
			(xy 144.196101 -190.161167) (xy 144.250058 -190.175273) (xy 144.301387 -190.197085) (xy 144.348993 -190.226139)
			(xy 144.391861 -190.261814) (xy 144.429078 -190.303351) (xy 144.459851 -190.349864) (xy 144.483523 -190.400361)
			(xy 144.499591 -190.453768) (xy 144.507711 -190.508944) (xy 144.50822 -190.53683) (xy 144.507711 -190.564716)
			(xy 144.499591 -190.619892) (xy 144.483523 -190.673299) (xy 144.459851 -190.723796) (xy 144.429078 -190.770309)
			(xy 144.391861 -190.811846) (xy 144.348993 -190.847521) (xy 144.301387 -190.876575) (xy 144.250058 -190.898387)
			(xy 144.196101 -190.912493) (xy 144.140664 -190.918593) (xy 144.08493 -190.916556) (xy 144.030087 -190.906426)
			(xy 143.977303 -190.888419) (xy 143.927703 -190.862918) (xy 143.882345 -190.830467) (xy 143.842196 -190.791758)
			(xy 143.80811 -190.747615) (xy 143.780814 -190.69898) (xy 143.760891 -190.646889) (xy 143.748765 -190.592452)
			(xy 143.744694 -190.53683) (xy 142.005475 -190.53683) (xy 142.025565 -190.579685) (xy 142.041633 -190.633092)
			(xy 142.049753 -190.688268) (xy 142.050262 -190.716154) (xy 142.049753 -190.74404) (xy 142.041633 -190.799216)
			(xy 142.025565 -190.852623) (xy 142.001893 -190.90312) (xy 141.97112 -190.949633) (xy 141.933903 -190.99117)
			(xy 141.891035 -191.026845) (xy 141.843429 -191.055899) (xy 141.7921 -191.077711) (xy 141.738143 -191.091817)
			(xy 141.71734 -191.094106) (xy 144.407634 -191.094106) (xy 144.411705 -191.038484) (xy 144.423831 -190.984047)
			(xy 144.443754 -190.931956) (xy 144.47105 -190.883321) (xy 144.505136 -190.839178) (xy 144.545285 -190.800469)
			(xy 144.590643 -190.768018) (xy 144.640243 -190.742517) (xy 144.693027 -190.72451) (xy 144.74787 -190.71438)
			(xy 144.803604 -190.712343) (xy 144.859041 -190.718443) (xy 144.912998 -190.732549) (xy 144.964327 -190.754361)
			(xy 145.011933 -190.783415) (xy 145.054801 -190.81909) (xy 145.092018 -190.860627) (xy 145.122791 -190.90714)
			(xy 145.146463 -190.957637) (xy 145.162531 -191.011044) (xy 145.170651 -191.06622) (xy 145.17116 -191.094106)
			(xy 145.170651 -191.121992) (xy 145.162531 -191.177168) (xy 145.146463 -191.230575) (xy 145.122791 -191.281072)
			(xy 145.092018 -191.327585) (xy 145.054801 -191.369122) (xy 145.011933 -191.404797) (xy 144.964327 -191.433851)
			(xy 144.912998 -191.455663) (xy 144.859041 -191.469769) (xy 144.803604 -191.475869) (xy 144.74787 -191.473832)
			(xy 144.693027 -191.463702) (xy 144.640243 -191.445695) (xy 144.590643 -191.420194) (xy 144.545285 -191.387743)
			(xy 144.505136 -191.349034) (xy 144.47105 -191.304891) (xy 144.443754 -191.256256) (xy 144.423831 -191.204165)
			(xy 144.411705 -191.149728) (xy 144.407634 -191.094106) (xy 141.71734 -191.094106) (xy 141.682706 -191.097917)
			(xy 141.626972 -191.09588) (xy 141.572129 -191.08575) (xy 141.519345 -191.067743) (xy 141.469745 -191.042242)
			(xy 141.424387 -191.009791) (xy 141.384238 -190.971082) (xy 141.350152 -190.926939) (xy 141.322856 -190.878304)
			(xy 141.302933 -190.826213) (xy 141.290807 -190.771776) (xy 141.286736 -190.716154) (xy 113.442522 -190.716154)
			(xy 112.878371 -191.280288) (xy 128.928366 -191.280288) (xy 128.932437 -191.224666) (xy 128.944563 -191.170229)
			(xy 128.964486 -191.118138) (xy 128.991782 -191.069503) (xy 129.025868 -191.02536) (xy 129.066017 -190.986651)
			(xy 129.111375 -190.9542) (xy 129.160975 -190.928699) (xy 129.213759 -190.910692) (xy 129.268602 -190.900562)
			(xy 129.324336 -190.898525) (xy 129.379773 -190.904625) (xy 129.43373 -190.918731) (xy 129.485059 -190.940543)
			(xy 129.532665 -190.969597) (xy 129.575533 -191.005272) (xy 129.61275 -191.046809) (xy 129.643523 -191.093322)
			(xy 129.667195 -191.143819) (xy 129.683263 -191.197226) (xy 129.691383 -191.252402) (xy 129.691892 -191.280288)
			(xy 129.691383 -191.308174) (xy 129.683263 -191.36335) (xy 129.667195 -191.416757) (xy 129.643523 -191.467254)
			(xy 129.61275 -191.513767) (xy 129.575533 -191.555304) (xy 129.532665 -191.590979) (xy 129.485059 -191.620033)
			(xy 129.43373 -191.641845) (xy 129.379773 -191.655951) (xy 129.324336 -191.662051) (xy 129.268602 -191.660014)
			(xy 129.213759 -191.649884) (xy 129.160975 -191.631877) (xy 129.111375 -191.606376) (xy 129.066017 -191.573925)
			(xy 129.025868 -191.535216) (xy 128.991782 -191.491073) (xy 128.964486 -191.442438) (xy 128.944563 -191.390347)
			(xy 128.932437 -191.33591) (xy 128.928366 -191.280288) (xy 112.878371 -191.280288) (xy 112.589818 -191.568832)
			(xy 112.582974 -191.576229) (xy 112.575256 -191.59483) (xy 112.574832 -191.6049) (xy 112.574832 -192.001436)
			(xy 130.04897 -192.001436) (xy 130.048972 -191.946932) (xy 130.056731 -191.892984) (xy 130.072089 -191.840689)
			(xy 130.094733 -191.791112) (xy 130.124201 -191.745262) (xy 130.159895 -191.704072) (xy 130.201088 -191.668382)
			(xy 130.24694 -191.638917) (xy 130.296519 -191.616278) (xy 130.348815 -191.600925) (xy 130.402764 -191.59317)
			(xy 130.430016 -191.592708) (xy 130.443986 -191.592962) (xy 130.4574 -191.593097) (xy 130.483522 -191.587017)
			(xy 130.507163 -191.57435) (xy 130.526692 -191.555966) (xy 130.540766 -191.533135) (xy 130.548413 -191.507427)
			(xy 130.549107 -191.480616) (xy 130.546348 -191.467486) (xy 130.541379 -191.445533) (xy 130.536037 -191.400838)
			(xy 130.53568 -191.378332) (xy 130.53568 -191.37757) (xy 130.53621 -191.350321) (xy 130.54397 -191.296379)
			(xy 130.559328 -191.24409) (xy 130.581971 -191.194519) (xy 130.611438 -191.148675) (xy 130.647129 -191.107491)
			(xy 130.688318 -191.071805) (xy 130.734166 -191.042345) (xy 130.783741 -191.019709) (xy 130.836032 -191.004359)
			(xy 130.889975 -190.996606) (xy 130.944473 -190.99661) (xy 130.998415 -191.004369) (xy 131.050704 -191.019726)
			(xy 131.100276 -191.042368) (xy 131.14612 -191.071834) (xy 131.187305 -191.107525) (xy 131.222991 -191.148713)
			(xy 131.252452 -191.194561) (xy 131.275089 -191.244135) (xy 131.29044 -191.296426) (xy 131.298193 -191.350369)
			(xy 131.298193 -191.360298) (xy 132.865874 -191.360298) (xy 132.869945 -191.304676) (xy 132.882071 -191.250239)
			(xy 132.901994 -191.198148) (xy 132.92929 -191.149513) (xy 132.963376 -191.10537) (xy 133.003525 -191.066661)
			(xy 133.048883 -191.03421) (xy 133.098483 -191.008709) (xy 133.151267 -190.990702) (xy 133.20611 -190.980572)
			(xy 133.261844 -190.978535) (xy 133.317281 -190.984635) (xy 133.371238 -190.998741) (xy 133.422567 -191.020553)
			(xy 133.470173 -191.049607) (xy 133.513041 -191.085282) (xy 133.550258 -191.126819) (xy 133.581031 -191.173332)
			(xy 133.604703 -191.223829) (xy 133.620771 -191.277236) (xy 133.628891 -191.332412) (xy 133.6294 -191.360298)
			(xy 133.628891 -191.388184) (xy 133.620771 -191.44336) (xy 133.604703 -191.496767) (xy 133.581031 -191.547264)
			(xy 133.550258 -191.593777) (xy 133.513041 -191.635314) (xy 133.470173 -191.670989) (xy 133.422567 -191.700043)
			(xy 133.371238 -191.721855) (xy 133.317281 -191.735961) (xy 133.261844 -191.742061) (xy 133.20611 -191.740024)
			(xy 133.151267 -191.729894) (xy 133.098483 -191.711887) (xy 133.048883 -191.686386) (xy 133.003525 -191.653935)
			(xy 132.963376 -191.615226) (xy 132.92929 -191.571083) (xy 132.901994 -191.522448) (xy 132.882071 -191.470357)
			(xy 132.869945 -191.41592) (xy 132.865874 -191.360298) (xy 131.298193 -191.360298) (xy 131.298191 -191.404867)
			(xy 131.290432 -191.458809) (xy 131.275076 -191.511099) (xy 131.252435 -191.56067) (xy 131.222969 -191.606516)
			(xy 131.187279 -191.647701) (xy 131.146092 -191.683387) (xy 131.100244 -191.712849) (xy 131.050671 -191.735487)
			(xy 130.99838 -191.750839) (xy 130.944437 -191.758593) (xy 130.917188 -191.759078) (xy 130.903218 -191.758824)
			(xy 130.889805 -191.75871) (xy 130.863686 -191.764787) (xy 130.840047 -191.777452) (xy 130.820518 -191.795832)
			(xy 130.806445 -191.81866) (xy 130.798796 -191.844363) (xy 130.798099 -191.871172) (xy 130.800856 -191.8843)
			(xy 130.805823 -191.906254) (xy 130.811167 -191.950948) (xy 130.811524 -191.973454) (xy 130.811524 -191.974216)
			(xy 130.811028 -192.001468) (xy 130.803269 -192.055416) (xy 130.787911 -192.107711) (xy 130.765267 -192.157288)
			(xy 130.735799 -192.203138) (xy 130.700105 -192.244328) (xy 130.658912 -192.280018) (xy 130.61306 -192.309483)
			(xy 130.563481 -192.332122) (xy 130.511185 -192.347475) (xy 130.457236 -192.35523) (xy 130.402732 -192.355228)
			(xy 130.348784 -192.347469) (xy 130.296489 -192.332111) (xy 130.246912 -192.309467) (xy 130.201062 -192.279999)
			(xy 130.159872 -192.244305) (xy 130.124182 -192.203112) (xy 130.094717 -192.15726) (xy 130.072078 -192.107681)
			(xy 130.056725 -192.055385) (xy 130.04897 -192.001436) (xy 112.574832 -192.001436) (xy 112.574832 -192.526666)
			(xy 142.96593 -192.526666) (xy 142.970001 -192.471044) (xy 142.982127 -192.416607) (xy 143.00205 -192.364516)
			(xy 143.029346 -192.315881) (xy 143.063432 -192.271738) (xy 143.103581 -192.233029) (xy 143.148939 -192.200578)
			(xy 143.198539 -192.175077) (xy 143.251323 -192.15707) (xy 143.306166 -192.14694) (xy 143.3619 -192.144903)
			(xy 143.417337 -192.151003) (xy 143.471294 -192.165109) (xy 143.522623 -192.186921) (xy 143.570229 -192.215975)
			(xy 143.613097 -192.25165) (xy 143.650314 -192.293187) (xy 143.681087 -192.3397) (xy 143.704759 -192.390197)
			(xy 143.720827 -192.443604) (xy 143.728947 -192.49878) (xy 143.729456 -192.526666) (xy 143.728947 -192.554552)
			(xy 143.720827 -192.609728) (xy 143.704759 -192.663135) (xy 143.681087 -192.713632) (xy 143.650314 -192.760145)
			(xy 143.613097 -192.801682) (xy 143.570229 -192.837357) (xy 143.522623 -192.866411) (xy 143.471294 -192.888223)
			(xy 143.417337 -192.902329) (xy 143.3619 -192.908429) (xy 143.306166 -192.906392) (xy 143.251323 -192.896262)
			(xy 143.198539 -192.878255) (xy 143.148939 -192.852754) (xy 143.103581 -192.820303) (xy 143.063432 -192.781594)
			(xy 143.029346 -192.737451) (xy 143.00205 -192.688816) (xy 142.982127 -192.636725) (xy 142.970001 -192.582288)
			(xy 142.96593 -192.526666) (xy 112.574832 -192.526666) (xy 112.574832 -193.543428) (xy 131.837428 -193.543428)
			(xy 131.841499 -193.487806) (xy 131.853625 -193.433369) (xy 131.873548 -193.381278) (xy 131.900844 -193.332643)
			(xy 131.93493 -193.2885) (xy 131.975079 -193.249791) (xy 132.020437 -193.21734) (xy 132.070037 -193.191839)
			(xy 132.122821 -193.173832) (xy 132.177664 -193.163702) (xy 132.233398 -193.161665) (xy 132.288835 -193.167765)
			(xy 132.342792 -193.181871) (xy 132.394121 -193.203683) (xy 132.441727 -193.232737) (xy 132.484595 -193.268412)
			(xy 132.521812 -193.309949) (xy 132.552585 -193.356462) (xy 132.576257 -193.406959) (xy 132.592325 -193.460366)
			(xy 132.600445 -193.515542) (xy 132.600954 -193.543428) (xy 132.600445 -193.571314) (xy 132.592325 -193.62649)
			(xy 132.576257 -193.679897) (xy 132.552585 -193.730394) (xy 132.521812 -193.776907) (xy 132.484595 -193.818444)
			(xy 132.476885 -193.82486) (xy 144.777204 -193.82486) (xy 144.781275 -193.769238) (xy 144.793401 -193.714801)
			(xy 144.813324 -193.66271) (xy 144.84062 -193.614075) (xy 144.874706 -193.569932) (xy 144.914855 -193.531223)
			(xy 144.960213 -193.498772) (xy 145.009813 -193.473271) (xy 145.062597 -193.455264) (xy 145.11744 -193.445134)
			(xy 145.173174 -193.443097) (xy 145.228611 -193.449197) (xy 145.282568 -193.463303) (xy 145.333897 -193.485115)
			(xy 145.381503 -193.514169) (xy 145.424371 -193.549844) (xy 145.461588 -193.591381) (xy 145.492361 -193.637894)
			(xy 145.516033 -193.688391) (xy 145.532101 -193.741798) (xy 145.540221 -193.796974) (xy 145.54073 -193.82486)
			(xy 145.540221 -193.852746) (xy 145.532101 -193.907922) (xy 145.52148 -193.943224) (xy 146.498816 -193.943224)
			(xy 146.502887 -193.887602) (xy 146.515013 -193.833165) (xy 146.534936 -193.781074) (xy 146.562232 -193.732439)
			(xy 146.596318 -193.688296) (xy 146.636467 -193.649587) (xy 146.681825 -193.617136) (xy 146.731425 -193.591635)
			(xy 146.784209 -193.573628) (xy 146.839052 -193.563498) (xy 146.894786 -193.561461) (xy 146.950223 -193.567561)
			(xy 147.00418 -193.581667) (xy 147.055509 -193.603479) (xy 147.103115 -193.632533) (xy 147.145983 -193.668208)
			(xy 147.1832 -193.709745) (xy 147.213973 -193.756258) (xy 147.237645 -193.806755) (xy 147.253713 -193.860162)
			(xy 147.261833 -193.915338) (xy 147.262342 -193.943224) (xy 147.261833 -193.97111) (xy 147.253713 -194.026286)
			(xy 147.237645 -194.079693) (xy 147.213973 -194.13019) (xy 147.1832 -194.176703) (xy 147.145983 -194.21824)
			(xy 147.103115 -194.253915) (xy 147.055509 -194.282969) (xy 147.00418 -194.304781) (xy 146.950223 -194.318887)
			(xy 146.894786 -194.324987) (xy 146.839052 -194.32295) (xy 146.784209 -194.31282) (xy 146.731425 -194.294813)
			(xy 146.681825 -194.269312) (xy 146.636467 -194.236861) (xy 146.596318 -194.198152) (xy 146.562232 -194.154009)
			(xy 146.534936 -194.105374) (xy 146.515013 -194.053283) (xy 146.502887 -193.998846) (xy 146.498816 -193.943224)
			(xy 145.52148 -193.943224) (xy 145.516033 -193.961329) (xy 145.492361 -194.011826) (xy 145.461588 -194.058339)
			(xy 145.424371 -194.099876) (xy 145.381503 -194.135551) (xy 145.333897 -194.164605) (xy 145.282568 -194.186417)
			(xy 145.228611 -194.200523) (xy 145.173174 -194.206623) (xy 145.11744 -194.204586) (xy 145.062597 -194.194456)
			(xy 145.009813 -194.176449) (xy 144.960213 -194.150948) (xy 144.914855 -194.118497) (xy 144.874706 -194.079788)
			(xy 144.84062 -194.035645) (xy 144.813324 -193.98701) (xy 144.793401 -193.934919) (xy 144.781275 -193.880482)
			(xy 144.777204 -193.82486) (xy 132.476885 -193.82486) (xy 132.441727 -193.854119) (xy 132.394121 -193.883173)
			(xy 132.342792 -193.904985) (xy 132.288835 -193.919091) (xy 132.233398 -193.925191) (xy 132.177664 -193.923154)
			(xy 132.122821 -193.913024) (xy 132.070037 -193.895017) (xy 132.020437 -193.869516) (xy 131.975079 -193.837065)
			(xy 131.93493 -193.798356) (xy 131.900844 -193.754213) (xy 131.873548 -193.705578) (xy 131.853625 -193.653487)
			(xy 131.841499 -193.59905) (xy 131.837428 -193.543428) (xy 112.574832 -193.543428) (xy 112.574832 -195.726088)
			(xy 126.922185 -195.726088) (xy 126.922185 -195.666112) (xy 126.930014 -195.606648) (xy 126.945538 -195.548715)
			(xy 126.968491 -195.493304) (xy 126.99848 -195.441364) (xy 127.034993 -195.393782) (xy 127.077404 -195.351373)
			(xy 127.124989 -195.314864) (xy 127.176931 -195.284878) (xy 127.232344 -195.261928) (xy 127.290278 -195.246408)
			(xy 127.349742 -195.238583) (xy 127.37973 -195.238116) (xy 128.24333 -195.238116) (xy 128.273312 -195.238652)
			(xy 128.332761 -195.246482) (xy 128.39068 -195.262005) (xy 128.446078 -195.284955) (xy 128.498007 -195.314939)
			(xy 128.545577 -195.351444) (xy 128.587976 -195.393845) (xy 128.624478 -195.441418) (xy 128.654459 -195.493349)
			(xy 128.666363 -195.522088) (xy 146.338034 -195.522088) (xy 146.342105 -195.466466) (xy 146.354231 -195.412029)
			(xy 146.374154 -195.359938) (xy 146.40145 -195.311303) (xy 146.435536 -195.26716) (xy 146.475685 -195.228451)
			(xy 146.521043 -195.196) (xy 146.570643 -195.170499) (xy 146.623427 -195.152492) (xy 146.67827 -195.142362)
			(xy 146.734004 -195.140325) (xy 146.789441 -195.146425) (xy 146.843398 -195.160531) (xy 146.894727 -195.182343)
			(xy 146.942333 -195.211397) (xy 146.985201 -195.247072) (xy 147.022418 -195.288609) (xy 147.053191 -195.335122)
			(xy 147.076863 -195.385619) (xy 147.092931 -195.439026) (xy 147.101051 -195.494202) (xy 147.10156 -195.522088)
			(xy 147.101051 -195.549974) (xy 147.092931 -195.60515) (xy 147.076863 -195.658557) (xy 147.053191 -195.709054)
			(xy 147.022418 -195.755567) (xy 146.985201 -195.797104) (xy 146.942333 -195.832779) (xy 146.894727 -195.861833)
			(xy 146.843398 -195.883645) (xy 146.789441 -195.897751) (xy 146.734004 -195.903851) (xy 146.67827 -195.901814)
			(xy 146.623427 -195.891684) (xy 146.570643 -195.873677) (xy 146.521043 -195.848176) (xy 146.475685 -195.815725)
			(xy 146.435536 -195.777016) (xy 146.40145 -195.732873) (xy 146.374154 -195.684238) (xy 146.354231 -195.632147)
			(xy 146.342105 -195.57771) (xy 146.338034 -195.522088) (xy 128.666363 -195.522088) (xy 128.677405 -195.548748)
			(xy 128.692924 -195.606668) (xy 128.70075 -195.666118) (xy 128.70075 -195.726082) (xy 128.692924 -195.785532)
			(xy 128.677405 -195.843452) (xy 128.654459 -195.898851) (xy 128.624478 -195.950782) (xy 128.587976 -195.998355)
			(xy 128.545577 -196.040756) (xy 128.498007 -196.077261) (xy 128.446078 -196.107245) (xy 128.39068 -196.130195)
			(xy 128.332761 -196.145718) (xy 128.273312 -196.153548) (xy 128.24333 -196.15404) (xy 127.37973 -196.15404)
			(xy 127.349742 -196.153617) (xy 127.290278 -196.145792) (xy 127.232344 -196.130272) (xy 127.176931 -196.107322)
			(xy 127.124989 -196.077336) (xy 127.077404 -196.040827) (xy 127.034993 -195.998418) (xy 126.99848 -195.950836)
			(xy 126.968491 -195.898896) (xy 126.945538 -195.843485) (xy 126.930014 -195.785552) (xy 126.922185 -195.726088)
			(xy 112.574832 -195.726088) (xy 112.574832 -196.393562) (xy 130.059936 -196.393562) (xy 130.064007 -196.33794)
			(xy 130.076133 -196.283503) (xy 130.096056 -196.231412) (xy 130.123352 -196.182777) (xy 130.157438 -196.138634)
			(xy 130.197587 -196.099925) (xy 130.242945 -196.067474) (xy 130.292545 -196.041973) (xy 130.345329 -196.023966)
			(xy 130.400172 -196.013836) (xy 130.455906 -196.011799) (xy 130.511343 -196.017899) (xy 130.5653 -196.032005)
			(xy 130.616629 -196.053817) (xy 130.664235 -196.082871) (xy 130.707103 -196.118546) (xy 130.74432 -196.160083)
			(xy 130.775093 -196.206596) (xy 130.798765 -196.257093) (xy 130.814833 -196.3105) (xy 130.822953 -196.365676)
			(xy 130.823462 -196.393562) (xy 130.822953 -196.421448) (xy 130.820104 -196.440806) (xy 131.909564 -196.440806)
			(xy 131.913635 -196.385184) (xy 131.925761 -196.330747) (xy 131.945684 -196.278656) (xy 131.97298 -196.230021)
			(xy 132.007066 -196.185878) (xy 132.047215 -196.147169) (xy 132.092573 -196.114718) (xy 132.142173 -196.089217)
			(xy 132.194957 -196.07121) (xy 132.2498 -196.06108) (xy 132.305534 -196.059043) (xy 132.360971 -196.065143)
			(xy 132.414928 -196.079249) (xy 132.466257 -196.101061) (xy 132.513863 -196.130115) (xy 132.556731 -196.16579)
			(xy 132.584437 -196.196712) (xy 136.162794 -196.196712) (xy 136.166865 -196.14109) (xy 136.178991 -196.086653)
			(xy 136.198914 -196.034562) (xy 136.22621 -195.985927) (xy 136.260296 -195.941784) (xy 136.300445 -195.903075)
			(xy 136.345803 -195.870624) (xy 136.395403 -195.845123) (xy 136.448187 -195.827116) (xy 136.50303 -195.816986)
			(xy 136.558764 -195.814949) (xy 136.614201 -195.821049) (xy 136.668158 -195.835155) (xy 136.719487 -195.856967)
			(xy 136.767093 -195.886021) (xy 136.809961 -195.921696) (xy 136.847178 -195.963233) (xy 136.877951 -196.009746)
			(xy 136.901623 -196.060243) (xy 136.917691 -196.11365) (xy 136.925811 -196.168826) (xy 136.92632 -196.196712)
			(xy 136.925811 -196.224598) (xy 136.917691 -196.279774) (xy 136.901623 -196.333181) (xy 136.877951 -196.383678)
			(xy 136.847178 -196.430191) (xy 136.809961 -196.471728) (xy 136.767093 -196.507403) (xy 136.719487 -196.536457)
			(xy 136.668158 -196.558269) (xy 136.614201 -196.572375) (xy 136.558764 -196.578475) (xy 136.50303 -196.576438)
			(xy 136.448187 -196.566308) (xy 136.395403 -196.548301) (xy 136.345803 -196.5228) (xy 136.300445 -196.490349)
			(xy 136.260296 -196.45164) (xy 136.22621 -196.407497) (xy 136.198914 -196.358862) (xy 136.178991 -196.306771)
			(xy 136.166865 -196.252334) (xy 136.162794 -196.196712) (xy 132.584437 -196.196712) (xy 132.593948 -196.207327)
			(xy 132.624721 -196.25384) (xy 132.648393 -196.304337) (xy 132.664461 -196.357744) (xy 132.672581 -196.41292)
			(xy 132.67309 -196.440806) (xy 132.672581 -196.468692) (xy 132.664461 -196.523868) (xy 132.648393 -196.577275)
			(xy 132.624721 -196.627772) (xy 132.593948 -196.674285) (xy 132.556731 -196.715822) (xy 132.513863 -196.751497)
			(xy 132.466257 -196.780551) (xy 132.414928 -196.802363) (xy 132.360971 -196.816469) (xy 132.305534 -196.822569)
			(xy 132.2498 -196.820532) (xy 132.194957 -196.810402) (xy 132.142173 -196.792395) (xy 132.092573 -196.766894)
			(xy 132.047215 -196.734443) (xy 132.007066 -196.695734) (xy 131.97298 -196.651591) (xy 131.945684 -196.602956)
			(xy 131.925761 -196.550865) (xy 131.913635 -196.496428) (xy 131.909564 -196.440806) (xy 130.820104 -196.440806)
			(xy 130.814833 -196.476624) (xy 130.798765 -196.530031) (xy 130.775093 -196.580528) (xy 130.74432 -196.627041)
			(xy 130.707103 -196.668578) (xy 130.664235 -196.704253) (xy 130.616629 -196.733307) (xy 130.5653 -196.755119)
			(xy 130.511343 -196.769225) (xy 130.455906 -196.775325) (xy 130.400172 -196.773288) (xy 130.345329 -196.763158)
			(xy 130.292545 -196.745151) (xy 130.242945 -196.71965) (xy 130.197587 -196.687199) (xy 130.157438 -196.64849)
			(xy 130.123352 -196.604347) (xy 130.096056 -196.555712) (xy 130.076133 -196.503621) (xy 130.064007 -196.449184)
			(xy 130.059936 -196.393562) (xy 112.574832 -196.393562) (xy 112.574832 -196.884798) (xy 146.481798 -196.884798)
			(xy 146.485869 -196.829176) (xy 146.497995 -196.774739) (xy 146.517918 -196.722648) (xy 146.545214 -196.674013)
			(xy 146.5793 -196.62987) (xy 146.619449 -196.591161) (xy 146.664807 -196.55871) (xy 146.714407 -196.533209)
			(xy 146.767191 -196.515202) (xy 146.822034 -196.505072) (xy 146.877768 -196.503035) (xy 146.933205 -196.509135)
			(xy 146.987162 -196.523241) (xy 147.038491 -196.545053) (xy 147.086097 -196.574107) (xy 147.128965 -196.609782)
			(xy 147.166182 -196.651319) (xy 147.196955 -196.697832) (xy 147.220627 -196.748329) (xy 147.236695 -196.801736)
			(xy 147.244815 -196.856912) (xy 147.245324 -196.884798) (xy 147.244815 -196.912684) (xy 147.236695 -196.96786)
			(xy 147.220627 -197.021267) (xy 147.196955 -197.071764) (xy 147.166182 -197.118277) (xy 147.128965 -197.159814)
			(xy 147.086097 -197.195489) (xy 147.038491 -197.224543) (xy 146.987162 -197.246355) (xy 146.933205 -197.260461)
			(xy 146.877768 -197.266561) (xy 146.822034 -197.264524) (xy 146.767191 -197.254394) (xy 146.714407 -197.236387)
			(xy 146.664807 -197.210886) (xy 146.619449 -197.178435) (xy 146.5793 -197.139726) (xy 146.545214 -197.095583)
			(xy 146.517918 -197.046948) (xy 146.497995 -196.994857) (xy 146.485869 -196.94042) (xy 146.481798 -196.884798)
			(xy 112.574832 -196.884798) (xy 112.574832 -199.462136) (xy 112.57523 -199.472208) (xy 112.582969 -199.490806)
			(xy 112.589818 -199.498204) (xy 115.671444 -202.579732) (xy 123.927106 -202.579732) (xy 123.931177 -202.52411)
			(xy 123.943303 -202.469673) (xy 123.963226 -202.417582) (xy 123.990522 -202.368947) (xy 124.024608 -202.324804)
			(xy 124.064757 -202.286095) (xy 124.110115 -202.253644) (xy 124.159715 -202.228143) (xy 124.212499 -202.210136)
			(xy 124.267342 -202.200006) (xy 124.323076 -202.197969) (xy 124.378513 -202.204069) (xy 124.43247 -202.218175)
			(xy 124.483799 -202.239987) (xy 124.531405 -202.269041) (xy 124.574273 -202.304716) (xy 124.61149 -202.346253)
			(xy 124.642263 -202.392766) (xy 124.665935 -202.443263) (xy 124.682003 -202.49667) (xy 124.690123 -202.551846)
			(xy 124.690632 -202.579732) (xy 124.690123 -202.607618) (xy 124.682003 -202.662794) (xy 124.665935 -202.716201)
			(xy 124.642263 -202.766698) (xy 124.61149 -202.813211) (xy 124.574273 -202.854748) (xy 124.531405 -202.890423)
			(xy 124.483799 -202.919477) (xy 124.43247 -202.941289) (xy 124.378513 -202.955395) (xy 124.323076 -202.961495)
			(xy 124.267342 -202.959458) (xy 124.212499 -202.949328) (xy 124.159715 -202.931321) (xy 124.110115 -202.90582)
			(xy 124.064757 -202.873369) (xy 124.024608 -202.83466) (xy 123.990522 -202.790517) (xy 123.963226 -202.741882)
			(xy 123.943303 -202.689791) (xy 123.931177 -202.635354) (xy 123.927106 -202.579732) (xy 115.671444 -202.579732)
			(xy 116.164728 -203.073) (xy 118.820182 -203.073) (xy 118.824253 -203.017378) (xy 118.836379 -202.962941)
			(xy 118.856302 -202.91085) (xy 118.883598 -202.862215) (xy 118.917684 -202.818072) (xy 118.957833 -202.779363)
			(xy 119.003191 -202.746912) (xy 119.052791 -202.721411) (xy 119.105575 -202.703404) (xy 119.160418 -202.693274)
			(xy 119.216152 -202.691237) (xy 119.271589 -202.697337) (xy 119.325546 -202.711443) (xy 119.376875 -202.733255)
			(xy 119.424481 -202.762309) (xy 119.467349 -202.797984) (xy 119.504566 -202.839521) (xy 119.535339 -202.886034)
			(xy 119.559011 -202.936531) (xy 119.575079 -202.989938) (xy 119.583199 -203.045114) (xy 119.583708 -203.073)
			(xy 119.583199 -203.100886) (xy 119.575079 -203.156062) (xy 119.559011 -203.209469) (xy 119.535339 -203.259966)
			(xy 119.504566 -203.306479) (xy 119.467349 -203.348016) (xy 119.424481 -203.383691) (xy 119.376875 -203.412745)
			(xy 119.325546 -203.434557) (xy 119.271589 -203.448663) (xy 119.216152 -203.454763) (xy 119.160418 -203.452726)
			(xy 119.105575 -203.442596) (xy 119.052791 -203.424589) (xy 119.003191 -203.399088) (xy 118.957833 -203.366637)
			(xy 118.917684 -203.327928) (xy 118.883598 -203.283785) (xy 118.856302 -203.23515) (xy 118.836379 -203.183059)
			(xy 118.824253 -203.128622) (xy 118.820182 -203.073) (xy 116.164728 -203.073) (xy 120.542812 -207.450944)
			(xy 120.560836 -207.469723) (xy 120.591417 -207.511838) (xy 120.615045 -207.558212) (xy 120.631142 -207.607707)
			(xy 120.639311 -207.659109) (xy 120.63984 -207.685132) (xy 120.63984 -208.392268) (xy 120.640043 -208.398417)
			(xy 120.64299 -208.410358) (xy 120.645682 -208.41589) (xy 120.659517 -208.443417) (xy 120.679082 -208.501834)
			(xy 120.689015 -208.562633) (xy 120.689624 -208.593436) (xy 120.689138 -208.620687) (xy 120.681382 -208.674635)
			(xy 120.666027 -208.72693) (xy 120.643385 -208.776507) (xy 120.613919 -208.822357) (xy 120.578228 -208.863548)
			(xy 120.537037 -208.899239) (xy 120.491187 -208.928705) (xy 120.44161 -208.951347) (xy 120.389315 -208.966702)
			(xy 120.335367 -208.974458) (xy 120.280865 -208.974458) (xy 120.226917 -208.966702) (xy 120.174622 -208.951347)
			(xy 120.125045 -208.928705) (xy 120.079195 -208.899239) (xy 120.038004 -208.863548) (xy 120.002313 -208.822357)
			(xy 119.972847 -208.776507) (xy 119.950205 -208.72693) (xy 119.93485 -208.674635) (xy 119.927094 -208.620687)
			(xy 119.926608 -208.593436) (xy 119.927198 -208.562632) (xy 119.937132 -208.501831) (xy 119.956713 -208.443418)
			(xy 119.97055 -208.41589) (xy 119.973271 -208.410368) (xy 119.976223 -208.398421) (xy 119.976392 -208.392268)
			(xy 119.976392 -207.844136) (xy 119.97595 -207.834069) (xy 119.968241 -207.81547) (xy 119.961406 -207.808068)
			(xy 117.193822 -205.040484) (xy 117.187056 -205.034248) (xy 117.170288 -205.026694) (xy 117.151936 -205.025495)
			(xy 117.143022 -205.027784) (xy 117.043708 -205.057756) (xy 117.024912 -205.07833) (xy 117.022118 -205.092046)
			(xy 117.016283 -205.118718) (xy 116.997951 -205.170148) (xy 116.972474 -205.218439) (xy 116.940374 -205.262605)
			(xy 116.902305 -205.301744) (xy 116.859045 -205.335056) (xy 116.811478 -205.36186) (xy 116.760576 -205.38161)
			(xy 116.734082 -205.38821) (xy 116.725431 -205.390611) (xy 116.710487 -205.400548) (xy 116.69985 -205.415001)
			(xy 116.696998 -205.423516) (xy 116.67236 -205.509368) (xy 116.670166 -205.51812) (xy 116.671466 -205.536105)
			(xy 116.678953 -205.552509) (xy 116.68506 -205.559152) (xy 117.595904 -206.469742) (xy 117.613925 -206.488523)
			(xy 117.644507 -206.530637) (xy 117.668136 -206.577011) (xy 117.684233 -206.626506) (xy 117.692403 -206.677907)
			(xy 117.692932 -206.70393) (xy 117.692932 -208.99247) (xy 123.96927 -208.99247) (xy 123.973341 -208.936848)
			(xy 123.985467 -208.882411) (xy 124.00539 -208.83032) (xy 124.032686 -208.781685) (xy 124.066772 -208.737542)
			(xy 124.106921 -208.698833) (xy 124.152279 -208.666382) (xy 124.201879 -208.640881) (xy 124.254663 -208.622874)
			(xy 124.309506 -208.612744) (xy 124.36524 -208.610707) (xy 124.420677 -208.616807) (xy 124.474634 -208.630913)
			(xy 124.525963 -208.652725) (xy 124.573569 -208.681779) (xy 124.616437 -208.717454) (xy 124.653654 -208.758991)
			(xy 124.684427 -208.805504) (xy 124.708099 -208.856001) (xy 124.724167 -208.909408) (xy 124.732287 -208.964584)
			(xy 124.732796 -208.99247) (xy 124.732287 -209.020356) (xy 124.724167 -209.075532) (xy 124.708099 -209.128939)
			(xy 124.684427 -209.179436) (xy 124.653654 -209.225949) (xy 124.616437 -209.267486) (xy 124.573569 -209.303161)
			(xy 124.525963 -209.332215) (xy 124.474634 -209.354027) (xy 124.420677 -209.368133) (xy 124.36524 -209.374233)
			(xy 124.309506 -209.372196) (xy 124.254663 -209.362066) (xy 124.201879 -209.344059) (xy 124.152279 -209.318558)
			(xy 124.106921 -209.286107) (xy 124.066772 -209.247398) (xy 124.032686 -209.203255) (xy 124.00539 -209.15462)
			(xy 123.985467 -209.102529) (xy 123.973341 -209.048092) (xy 123.96927 -208.99247) (xy 117.692932 -208.99247)
			(xy 117.692932 -210.462876) (xy 121.397774 -210.462876) (xy 121.401845 -210.407254) (xy 121.413971 -210.352817)
			(xy 121.433894 -210.300726) (xy 121.46119 -210.252091) (xy 121.495276 -210.207948) (xy 121.535425 -210.169239)
			(xy 121.580783 -210.136788) (xy 121.630383 -210.111287) (xy 121.683167 -210.09328) (xy 121.73801 -210.08315)
			(xy 121.793744 -210.081113) (xy 121.849181 -210.087213) (xy 121.903138 -210.101319) (xy 121.954467 -210.123131)
			(xy 122.002073 -210.152185) (xy 122.044941 -210.18786) (xy 122.082158 -210.229397) (xy 122.112931 -210.27591)
			(xy 122.136603 -210.326407) (xy 122.152671 -210.379814) (xy 122.160791 -210.43499) (xy 122.1613 -210.462876)
			(xy 122.160791 -210.490762) (xy 122.152671 -210.545938) (xy 122.136603 -210.599345) (xy 122.112931 -210.649842)
			(xy 122.082158 -210.696355) (xy 122.044941 -210.737892) (xy 122.002073 -210.773567) (xy 121.954467 -210.802621)
			(xy 121.903138 -210.824433) (xy 121.849181 -210.838539) (xy 121.793744 -210.844639) (xy 121.73801 -210.842602)
			(xy 121.683167 -210.832472) (xy 121.630383 -210.814465) (xy 121.580783 -210.788964) (xy 121.535425 -210.756513)
			(xy 121.495276 -210.717804) (xy 121.46119 -210.673661) (xy 121.433894 -210.625026) (xy 121.413971 -210.572935)
			(xy 121.401845 -210.518498) (xy 121.397774 -210.462876) (xy 117.692932 -210.462876) (xy 117.692932 -210.46313)
			(xy 117.693334 -210.473202) (xy 117.70107 -210.4918) (xy 117.707918 -210.499198) (xy 118.147639 -210.938872)
			(xy 125.26594 -210.938872) (xy 125.270011 -210.88325) (xy 125.282137 -210.828813) (xy 125.30206 -210.776722)
			(xy 125.329356 -210.728087) (xy 125.363442 -210.683944) (xy 125.403591 -210.645235) (xy 125.448949 -210.612784)
			(xy 125.498549 -210.587283) (xy 125.551333 -210.569276) (xy 125.606176 -210.559146) (xy 125.66191 -210.557109)
			(xy 125.717347 -210.563209) (xy 125.771304 -210.577315) (xy 125.822633 -210.599127) (xy 125.870239 -210.628181)
			(xy 125.913107 -210.663856) (xy 125.950324 -210.705393) (xy 125.981097 -210.751906) (xy 126.004769 -210.802403)
			(xy 126.020837 -210.85581) (xy 126.028957 -210.910986) (xy 126.029466 -210.938872) (xy 126.028957 -210.966758)
			(xy 126.020837 -211.021934) (xy 126.004769 -211.075341) (xy 125.981097 -211.125838) (xy 125.950324 -211.172351)
			(xy 125.913107 -211.213888) (xy 125.870239 -211.249563) (xy 125.822633 -211.278617) (xy 125.771304 -211.300429)
			(xy 125.717347 -211.314535) (xy 125.66191 -211.320635) (xy 125.606176 -211.318598) (xy 125.551333 -211.308468)
			(xy 125.498549 -211.290461) (xy 125.448949 -211.26496) (xy 125.403591 -211.232509) (xy 125.363442 -211.1938)
			(xy 125.329356 -211.149657) (xy 125.30206 -211.101022) (xy 125.282137 -211.048931) (xy 125.270011 -210.994494)
			(xy 125.26594 -210.938872) (xy 118.147639 -210.938872) (xy 119.44775 -212.238844) (xy 125.366524 -212.238844)
			(xy 125.370595 -212.183222) (xy 125.382721 -212.128785) (xy 125.402644 -212.076694) (xy 125.42994 -212.028059)
			(xy 125.464026 -211.983916) (xy 125.504175 -211.945207) (xy 125.549533 -211.912756) (xy 125.599133 -211.887255)
			(xy 125.651917 -211.869248) (xy 125.70676 -211.859118) (xy 125.762494 -211.857081) (xy 125.817931 -211.863181)
			(xy 125.871888 -211.877287) (xy 125.923217 -211.899099) (xy 125.970823 -211.928153) (xy 126.013691 -211.963828)
			(xy 126.050908 -212.005365) (xy 126.081681 -212.051878) (xy 126.105353 -212.102375) (xy 126.121421 -212.155782)
			(xy 126.129541 -212.210958) (xy 126.13005 -212.238844) (xy 126.129541 -212.26673) (xy 126.121421 -212.321906)
			(xy 126.105353 -212.375313) (xy 126.081681 -212.42581) (xy 126.050908 -212.472323) (xy 126.013691 -212.51386)
			(xy 125.970823 -212.549535) (xy 125.923217 -212.578589) (xy 125.871888 -212.600401) (xy 125.817931 -212.614507)
			(xy 125.762494 -212.620607) (xy 125.70676 -212.61857) (xy 125.651917 -212.60844) (xy 125.599133 -212.590433)
			(xy 125.549533 -212.564932) (xy 125.504175 -212.532481) (xy 125.464026 -212.493772) (xy 125.42994 -212.449629)
			(xy 125.402644 -212.400994) (xy 125.382721 -212.348903) (xy 125.370595 -212.294466) (xy 125.366524 -212.238844)
			(xy 119.44775 -212.238844) (xy 120.082056 -212.873082) (xy 120.086447 -212.877201) (xy 120.096713 -212.883485)
			(xy 120.102376 -212.885528) (xy 120.102884 -212.885528) (xy 120.128423 -212.89399) (xy 120.177025 -212.917061)
			(xy 120.221904 -212.94673) (xy 120.26217 -212.98241) (xy 120.297026 -213.023392) (xy 120.325778 -213.068864)
			(xy 120.347859 -213.117923) (xy 120.362828 -213.169599) (xy 120.370391 -213.222864) (xy 120.370854 -213.249764)
			(xy 120.370288 -213.277012) (xy 120.362538 -213.330955) (xy 120.34719 -213.383245) (xy 120.324556 -213.432819)
			(xy 120.295098 -213.478667) (xy 120.259415 -213.519857) (xy 120.218233 -213.555549) (xy 120.172391 -213.585017)
			(xy 120.122822 -213.607661) (xy 120.070535 -213.623021) (xy 120.016594 -213.630783) (xy 119.989346 -213.631272)
			(xy 119.962434 -213.63084) (xy 119.909148 -213.623255) (xy 119.857455 -213.608259) (xy 119.808383 -213.586147)
			(xy 119.762905 -213.55736) (xy 119.721922 -213.522468) (xy 119.68625 -213.482164) (xy 119.656594 -213.437247)
			(xy 119.633544 -213.388608) (xy 119.62511 -213.363048) (xy 119.62511 -213.362794) (xy 119.623128 -213.357102)
			(xy 119.616834 -213.346826) (xy 119.612664 -213.342474) (xy 117.126512 -210.856322) (xy 117.108166 -210.837251)
			(xy 117.077155 -210.794374) (xy 117.06479 -210.770978) (xy 117.05844 -210.758024) (xy 117.034056 -210.743038)
			(xy 117.019324 -210.743038) (xy 117.0093 -210.74344) (xy 116.990776 -210.751109) (xy 116.976602 -210.765288)
			(xy 116.968938 -210.783813) (xy 116.968524 -210.793838) (xy 116.968524 -211.123022) (xy 116.968932 -211.133093)
			(xy 116.976664 -211.151691) (xy 116.98351 -211.15909) (xy 120.269254 -214.444834) (xy 125.467362 -214.444834)
			(xy 125.471433 -214.389212) (xy 125.483559 -214.334775) (xy 125.503482 -214.282684) (xy 125.530778 -214.234049)
			(xy 125.564864 -214.189906) (xy 125.605013 -214.151197) (xy 125.650371 -214.118746) (xy 125.699971 -214.093245)
			(xy 125.752755 -214.075238) (xy 125.807598 -214.065108) (xy 125.863332 -214.063071) (xy 125.918769 -214.069171)
			(xy 125.972726 -214.083277) (xy 126.024055 -214.105089) (xy 126.071661 -214.134143) (xy 126.114529 -214.169818)
			(xy 126.151746 -214.211355) (xy 126.182519 -214.257868) (xy 126.206191 -214.308365) (xy 126.222259 -214.361772)
			(xy 126.230379 -214.416948) (xy 126.230888 -214.444834) (xy 126.230379 -214.47272) (xy 126.222259 -214.527896)
			(xy 126.206191 -214.581303) (xy 126.182519 -214.6318) (xy 126.151746 -214.678313) (xy 126.114529 -214.71985)
			(xy 126.071661 -214.755525) (xy 126.024055 -214.784579) (xy 125.972726 -214.806391) (xy 125.918769 -214.820497)
			(xy 125.863332 -214.826597) (xy 125.807598 -214.82456) (xy 125.752755 -214.81443) (xy 125.699971 -214.796423)
			(xy 125.650371 -214.770922) (xy 125.605013 -214.738471) (xy 125.564864 -214.699762) (xy 125.530778 -214.655619)
			(xy 125.503482 -214.606984) (xy 125.483559 -214.554893) (xy 125.471433 -214.500456) (xy 125.467362 -214.444834)
			(xy 120.269254 -214.444834) (xy 120.71731 -214.89289) (xy 120.724714 -214.899726) (xy 120.74331 -214.907448)
			(xy 120.753378 -214.907876) (xy 121.8438 -214.907876) (xy 121.871124 -214.908363) (xy 121.925215 -214.916141)
			(xy 121.977649 -214.931537) (xy 122.027358 -214.954238) (xy 122.073331 -214.983783) (xy 122.114631 -215.019569)
			(xy 122.150417 -215.060869) (xy 122.179962 -215.106842) (xy 122.202663 -215.156551) (xy 122.218059 -215.208985)
			(xy 122.225837 -215.263076) (xy 122.225837 -215.317724) (xy 122.218059 -215.371815) (xy 122.202663 -215.424249)
			(xy 122.179962 -215.473958) (xy 122.150417 -215.519931) (xy 122.114631 -215.561231) (xy 122.073331 -215.597017)
			(xy 122.027358 -215.626562) (xy 121.977649 -215.649263) (xy 121.925215 -215.664659) (xy 121.871124 -215.672437)
			(xy 121.8438 -215.672924) (xy 120.5738 -215.672924) (xy 120.543735 -215.672395) (xy 120.484345 -215.662999)
			(xy 120.427158 -215.644423) (xy 120.373583 -215.617124) (xy 120.324941 -215.581777) (xy 120.30329 -215.56091)
			(xy 116.31549 -211.57311) (xy 116.294642 -211.551447) (xy 116.259318 -211.502797) (xy 116.232036 -211.449223)
			(xy 116.213466 -211.392042) (xy 116.204065 -211.33266) (xy 116.203476 -211.3026) (xy 116.203476 -207.164178)
			(xy 116.203068 -207.154107) (xy 116.195336 -207.135509) (xy 116.18849 -207.12811) (xy 110.645956 -201.585576)
			(xy 110.625052 -201.563948) (xy 110.589663 -201.515312) (xy 110.562321 -201.461737) (xy 110.543701 -201.404543)
			(xy 110.534261 -201.34514) (xy 110.533688 -201.315066) (xy 110.533688 -193.290444) (xy 110.533242 -193.280377)
			(xy 110.525536 -193.261779) (xy 110.518702 -193.254376) (xy 108.16209 -190.89751) (xy 108.154686 -190.890674)
			(xy 108.13609 -190.882952) (xy 108.126022 -190.882524) (xy 94.5642 -190.882524) (xy 94.536876 -190.882037)
			(xy 94.482785 -190.874259) (xy 94.430351 -190.858863) (xy 94.380642 -190.836162) (xy 94.334669 -190.806617)
			(xy 94.293369 -190.770831) (xy 94.257583 -190.729531) (xy 94.228038 -190.683558) (xy 94.205337 -190.633849)
			(xy 94.189941 -190.581415) (xy 94.182163 -190.527324) (xy 94.182163 -190.472676) (xy 94.189941 -190.418585)
			(xy 94.205337 -190.366151) (xy 94.228038 -190.316442) (xy 94.257583 -190.270469) (xy 94.293369 -190.229169)
			(xy 94.334669 -190.193383) (xy 94.380642 -190.163838) (xy 94.430351 -190.141137) (xy 94.482785 -190.125741)
			(xy 94.536876 -190.117963) (xy 94.5642 -190.117476) (xy 108.3056 -190.117476) (xy 108.335665 -190.118005)
			(xy 108.395055 -190.127401) (xy 108.452242 -190.145977) (xy 108.505817 -190.173276) (xy 108.554459 -190.208623)
			(xy 108.57611 -190.22949) (xy 110.96879 -192.621916) (xy 110.998762 -192.627758) (xy 111.012986 -192.621916)
			(xy 111.022005 -192.61758) (xy 111.036088 -192.603393) (xy 111.043728 -192.58492) (xy 111.044228 -192.574926)
			(xy 111.044228 -188.820298) (xy 111.043823 -188.810226) (xy 111.03609 -188.791627) (xy 111.029242 -188.78423)
			(xy 107.713526 -185.468514) (xy 107.695421 -185.449726) (xy 107.664737 -185.40753) (xy 107.641035 -185.361051)
			(xy 107.624901 -185.311435) (xy 107.616731 -185.259905) (xy 107.616244 -185.233818) (xy 107.616244 -185.180478)
			(xy 107.613704 -185.169302) (xy 107.61091 -185.163968) (xy 107.610402 -185.162952) (xy 107.596693 -185.135471)
			(xy 107.577235 -185.077226) (xy 107.567353 -185.016618) (xy 107.566714 -184.985914) (xy 107.567168 -184.95866)
			(xy 107.574924 -184.904708) (xy 107.590279 -184.852409) (xy 107.612922 -184.802827) (xy 107.64239 -184.756973)
			(xy 107.678085 -184.71578) (xy 107.719279 -184.680086) (xy 107.765134 -184.650618) (xy 107.814716 -184.627977)
			(xy 107.867016 -184.612622) (xy 107.920968 -184.604868) (xy 107.948222 -184.604406) (xy 107.979025 -184.605013)
			(xy 108.039826 -184.614939) (xy 108.09824 -184.634514) (xy 108.125768 -184.648348) (xy 108.126276 -184.648602)
			(xy 108.131589 -184.651099) (xy 108.143013 -184.653789) (xy 108.148882 -184.653936) (xy 116.98859 -184.653936)
			(xy 116.998661 -184.653522) (xy 117.01726 -184.645795) (xy 117.024658 -184.63895) (xy 119.692166 -181.971442)
			(xy 119.698975 -181.964017) (xy 119.706714 -181.945437) (xy 119.707152 -181.935374) (xy 119.707152 -168.965626)
			(xy 119.706726 -168.955557) (xy 119.699007 -168.936958) (xy 119.692166 -168.929558) (xy 115.70843 -164.945822)
			(xy 115.69033 -164.92703) (xy 115.659644 -164.884835) (xy 115.635942 -164.838357) (xy 115.619807 -164.788742)
			(xy 115.611636 -164.737212) (xy 115.611148 -164.711126) (xy 115.611148 -162.323272) (xy 115.608608 -162.312096)
			(xy 115.605814 -162.306762) (xy 115.605306 -162.305746) (xy 115.591596 -162.278265) (xy 115.572138 -162.220021)
			(xy 115.562257 -162.159412) (xy 115.561618 -162.128708) (xy 115.562104 -162.101457) (xy 115.56986 -162.047509)
			(xy 115.585215 -161.995214) (xy 115.607857 -161.945637) (xy 115.637323 -161.899787) (xy 115.673014 -161.858596)
			(xy 115.714205 -161.822905) (xy 115.760055 -161.793439) (xy 115.809632 -161.770797) (xy 115.861927 -161.755442)
			(xy 115.915875 -161.747686) (xy 115.970377 -161.747686) (xy 116.024325 -161.755442) (xy 116.07662 -161.770797)
			(xy 116.126197 -161.793439) (xy 116.172047 -161.822905) (xy 116.213238 -161.858596) (xy 116.248929 -161.899787)
			(xy 116.278395 -161.945637) (xy 116.301037 -161.995214) (xy 116.316392 -162.047509) (xy 116.324148 -162.101457)
			(xy 116.324634 -162.128708) (xy 116.324018 -162.15951) (xy 116.314095 -162.220311) (xy 116.294524 -162.278725)
			(xy 116.280692 -162.306254) (xy 116.280438 -162.306762) (xy 116.277955 -162.31208) (xy 116.275266 -162.323501)
			(xy 116.275104 -162.329368) (xy 116.275104 -164.55263) (xy 116.275486 -164.562705) (xy 116.283234 -164.581304)
			(xy 116.29009 -164.588698) (xy 119.048784 -167.347392) (xy 119.078756 -167.353488) (xy 119.09298 -167.347392)
			(xy 119.102105 -167.34317) (xy 119.116342 -167.328997) (xy 119.124051 -167.310446) (xy 119.124476 -167.300402)
			(xy 119.124476 -145.23085) (xy 119.125 -145.204826) (xy 119.133167 -145.153423) (xy 119.149262 -145.103926)
			(xy 119.172891 -145.05755) (xy 119.203472 -145.015433) (xy 119.221504 -144.996662) (xy 119.497094 -144.721072)
			(xy 119.503938 -144.713675) (xy 119.511656 -144.695073) (xy 119.51208 -144.685004) (xy 119.51208 -138.938508)
			(xy 119.511665 -138.928727) (xy 119.504374 -138.910576) (xy 119.49084 -138.896454) (xy 119.482108 -138.892026)
			(xy 119.397526 -138.85418) (xy 119.388357 -138.850634) (xy 119.368735 -138.849916) (xy 119.35027 -138.856595)
			(xy 119.342662 -138.862816) (xy 119.321558 -138.881089) (xy 119.275021 -138.911916) (xy 119.224487 -138.935632)
			(xy 119.171037 -138.95173) (xy 119.115811 -138.959866) (xy 119.0879 -138.960352) (xy 119.060652 -138.959778)
			(xy 119.00671 -138.952022) (xy 118.954422 -138.936669) (xy 118.90485 -138.91403) (xy 118.859005 -138.884568)
			(xy 118.81782 -138.84888) (xy 118.782132 -138.807695) (xy 118.75267 -138.76185) (xy 118.730031 -138.712278)
			(xy 118.714678 -138.65999) (xy 118.706922 -138.606048) (xy 118.706922 -138.551552) (xy 118.714678 -138.49761)
			(xy 118.730031 -138.445322) (xy 118.75267 -138.39575) (xy 118.782132 -138.349905) (xy 118.81782 -138.30872)
			(xy 118.859005 -138.273032) (xy 118.90485 -138.24357) (xy 118.954422 -138.220931) (xy 119.00671 -138.205578)
			(xy 119.060652 -138.197822) (xy 119.0879 -138.197336) (xy 119.11581 -138.197842) (xy 119.171035 -138.205975)
			(xy 119.224485 -138.222069) (xy 119.27502 -138.245778) (xy 119.321561 -138.276598) (xy 119.342662 -138.294872)
			(xy 119.350252 -138.301133) (xy 119.368729 -138.307843) (xy 119.388374 -138.307121) (xy 119.397526 -138.303508)
			(xy 119.482108 -138.265662) (xy 119.490854 -138.261245) (xy 119.504428 -138.247145) (xy 119.511688 -138.228969)
			(xy 119.51208 -138.21918) (xy 119.51208 -133.43636) (xy 119.511681 -133.426288) (xy 119.503942 -133.40769)
			(xy 119.497094 -133.400292) (xy 116.515134 -130.418332) (xy 116.497039 -130.399535) (xy 116.466353 -130.357341)
			(xy 116.442649 -130.310865) (xy 116.426513 -130.26125) (xy 116.418341 -130.209722) (xy 116.417852 -130.183636)
			(xy 116.417852 -129.604008) (xy 116.415312 -129.592832) (xy 116.412518 -129.587498) (xy 116.41201 -129.586482)
			(xy 116.398277 -129.559012) (xy 116.378828 -129.500762) (xy 116.368956 -129.440149) (xy 116.368322 -129.409444)
			(xy 116.368808 -129.382193) (xy 116.376564 -129.328245) (xy 116.391919 -129.27595) (xy 116.414561 -129.226373)
			(xy 116.444027 -129.180523) (xy 116.479718 -129.139332) (xy 116.520909 -129.103641) (xy 116.566759 -129.074175)
			(xy 116.616336 -129.051533) (xy 116.668631 -129.036178) (xy 116.722579 -129.028422) (xy 116.777081 -129.028422)
			(xy 116.831029 -129.036178) (xy 116.883324 -129.051533) (xy 116.932901 -129.074175) (xy 116.978751 -129.103641)
			(xy 117.019942 -129.139332) (xy 117.055633 -129.180523) (xy 117.085099 -129.226373) (xy 117.107741 -129.27595)
			(xy 117.123096 -129.328245) (xy 117.130852 -129.382193) (xy 117.131338 -129.409444) (xy 117.130735 -129.440247)
			(xy 117.120806 -129.501048) (xy 117.10123 -129.559462) (xy 117.087524 -129.586736) (xy 117.524528 -129.586736)
			(xy 117.528599 -129.531114) (xy 117.540725 -129.476677) (xy 117.560648 -129.424586) (xy 117.587944 -129.375951)
			(xy 117.62203 -129.331808) (xy 117.662179 -129.293099) (xy 117.707537 -129.260648) (xy 117.757137 -129.235147)
			(xy 117.809921 -129.21714) (xy 117.864764 -129.20701) (xy 117.920498 -129.204973) (xy 117.975935 -129.211073)
			(xy 118.029892 -129.225179) (xy 118.081221 -129.246991) (xy 118.128827 -129.276045) (xy 118.171695 -129.31172)
			(xy 118.208912 -129.353257) (xy 118.239685 -129.39977) (xy 118.263357 -129.450267) (xy 118.279425 -129.503674)
			(xy 118.287545 -129.55885) (xy 118.288054 -129.586736) (xy 118.287545 -129.614622) (xy 118.279425 -129.669798)
			(xy 118.263357 -129.723205) (xy 118.239685 -129.773702) (xy 118.208912 -129.820215) (xy 118.171695 -129.861752)
			(xy 118.128827 -129.897427) (xy 118.081221 -129.926481) (xy 118.029892 -129.948293) (xy 117.975935 -129.962399)
			(xy 117.920498 -129.968499) (xy 117.864764 -129.966462) (xy 117.809921 -129.956332) (xy 117.757137 -129.938325)
			(xy 117.707537 -129.912824) (xy 117.662179 -129.880373) (xy 117.62203 -129.841664) (xy 117.587944 -129.797521)
			(xy 117.560648 -129.748886) (xy 117.540725 -129.696795) (xy 117.528599 -129.642358) (xy 117.524528 -129.586736)
			(xy 117.087524 -129.586736) (xy 117.087396 -129.58699) (xy 117.087142 -129.587498) (xy 117.084679 -129.592824)
			(xy 117.081977 -129.604239) (xy 117.081808 -129.610104) (xy 117.081808 -130.02514) (xy 117.082211 -130.035212)
			(xy 117.089947 -130.05381) (xy 117.096794 -130.061208) (xy 118.254272 -131.218686) (xy 118.631714 -131.218686)
			(xy 118.635785 -131.163064) (xy 118.647911 -131.108627) (xy 118.667834 -131.056536) (xy 118.69513 -131.007901)
			(xy 118.729216 -130.963758) (xy 118.769365 -130.925049) (xy 118.814723 -130.892598) (xy 118.864323 -130.867097)
			(xy 118.917107 -130.84909) (xy 118.97195 -130.83896) (xy 119.027684 -130.836923) (xy 119.083121 -130.843023)
			(xy 119.137078 -130.857129) (xy 119.188407 -130.878941) (xy 119.236013 -130.907995) (xy 119.278881 -130.94367)
			(xy 119.316098 -130.985207) (xy 119.346871 -131.03172) (xy 119.370543 -131.082217) (xy 119.386611 -131.135624)
			(xy 119.394731 -131.1908) (xy 119.39524 -131.218686) (xy 119.394731 -131.246572) (xy 119.386611 -131.301748)
			(xy 119.370543 -131.355155) (xy 119.346871 -131.405652) (xy 119.316098 -131.452165) (xy 119.278881 -131.493702)
			(xy 119.236013 -131.529377) (xy 119.188407 -131.558431) (xy 119.137078 -131.580243) (xy 119.083121 -131.594349)
			(xy 119.027684 -131.600449) (xy 118.97195 -131.598412) (xy 118.917107 -131.588282) (xy 118.864323 -131.570275)
			(xy 118.814723 -131.544774) (xy 118.769365 -131.512323) (xy 118.729216 -131.473614) (xy 118.69513 -131.429471)
			(xy 118.667834 -131.380836) (xy 118.647911 -131.328745) (xy 118.635785 -131.274308) (xy 118.631714 -131.218686)
			(xy 118.254272 -131.218686) (xy 119.794782 -132.759196) (xy 119.824754 -132.765038) (xy 119.838978 -132.759196)
			(xy 119.848003 -132.754871) (xy 119.862087 -132.74068) (xy 119.869723 -132.722202) (xy 119.87022 -132.712206)
			(xy 119.87022 -128.262888) (xy 119.869822 -128.252815) (xy 119.862084 -128.234216) (xy 119.855234 -128.22682)
			(xy 118.921022 -127.292608) (xy 118.916636 -127.288483) (xy 118.906367 -127.282203) (xy 118.900702 -127.280162)
			(xy 118.900194 -127.280162) (xy 118.874648 -127.271722) (xy 118.826046 -127.248647) (xy 118.781167 -127.218975)
			(xy 118.740901 -127.183292) (xy 118.706047 -127.142308) (xy 118.677295 -127.096833) (xy 118.655216 -127.047771)
			(xy 118.640248 -126.996094) (xy 118.632687 -126.942827) (xy 118.632224 -126.915926) (xy 118.63268 -126.888672)
			(xy 118.640434 -126.834719) (xy 118.655788 -126.78242) (xy 118.67843 -126.732837) (xy 118.707898 -126.686983)
			(xy 118.743593 -126.645789) (xy 118.784787 -126.610095) (xy 118.830643 -126.580627) (xy 118.880225 -126.557986)
			(xy 118.932525 -126.542633) (xy 118.986478 -126.534879) (xy 119.013732 -126.534418) (xy 119.040643 -126.534877)
			(xy 119.093928 -126.542458) (xy 119.145619 -126.557451) (xy 119.194691 -126.579559) (xy 119.240169 -126.608343)
			(xy 119.281152 -126.643232) (xy 119.316825 -126.683533) (xy 119.346482 -126.728447) (xy 119.369533 -126.777083)
			(xy 119.377968 -126.802642) (xy 119.377968 -126.802896) (xy 119.379957 -126.808586) (xy 119.386246 -126.818863)
			(xy 119.390414 -126.823216) (xy 120.000522 -127.433324) (xy 120.030494 -127.439166) (xy 120.044718 -127.433324)
			(xy 120.053719 -127.428954) (xy 120.06781 -127.414786) (xy 120.075456 -127.396324) (xy 120.07596 -127.386334)
			(xy 120.07596 -121.476262) (xy 120.07642 -121.44376) (xy 120.08365 -121.379159) (xy 120.097994 -121.315757)
			(xy 120.119276 -121.254335) (xy 120.132856 -121.224802) (xy 120.13692 -121.21642) (xy 120.138444 -121.198386)
			(xy 120.115584 -121.116598) (xy 120.104916 -121.101866) (xy 120.09755 -121.096786) (xy 120.075475 -121.081582)
			(xy 120.035481 -121.045893) (xy 120.000874 -121.00496) (xy 119.972335 -120.959587) (xy 119.950424 -120.910667)
			(xy 119.935574 -120.859163) (xy 119.928076 -120.806087) (xy 119.927624 -120.779286) (xy 119.928042 -120.752031)
			(xy 119.935802 -120.698077) (xy 119.951161 -120.645776) (xy 119.973808 -120.596194) (xy 120.00328 -120.550339)
			(xy 120.038979 -120.509146) (xy 120.080176 -120.473452) (xy 120.126034 -120.443985) (xy 120.17562 -120.421345)
			(xy 120.227922 -120.405992) (xy 120.281877 -120.398239) (xy 120.309132 -120.397778) (xy 120.319952 -120.397873)
			(xy 120.341555 -120.399146) (xy 120.352312 -120.400318) (xy 120.36305 -120.401084) (xy 120.383572 -120.394648)
			(xy 120.391936 -120.387872) (xy 120.448578 -120.337326) (xy 120.456356 -120.329797) (xy 120.465166 -120.310044)
			(xy 120.465596 -120.299226) (xy 120.465596 -119.989346) (xy 120.465109 -119.978543) (xy 120.456303 -119.958813)
			(xy 120.448578 -119.951246) (xy 120.383554 -119.893588) (xy 120.363234 -119.886984) (xy 120.352312 -119.888254)
			(xy 120.341555 -119.889428) (xy 120.319952 -119.890698) (xy 120.309132 -119.890794) (xy 120.281877 -119.890361)
			(xy 120.22792 -119.882608) (xy 120.175617 -119.867254) (xy 120.12603 -119.844612) (xy 120.080172 -119.815144)
			(xy 120.038974 -119.779449) (xy 120.003275 -119.738254) (xy 119.973803 -119.692398) (xy 119.951157 -119.642813)
			(xy 119.935799 -119.590511) (xy 119.928041 -119.536555) (xy 119.928041 -119.482045) (xy 119.935799 -119.428089)
			(xy 119.951157 -119.375787) (xy 119.973803 -119.326202) (xy 120.003275 -119.280346) (xy 120.038974 -119.239151)
			(xy 120.080172 -119.203456) (xy 120.12603 -119.173988) (xy 120.175617 -119.151346) (xy 120.22792 -119.135992)
			(xy 120.281877 -119.128239) (xy 120.309132 -119.127778) (xy 120.319952 -119.127873) (xy 120.341555 -119.129146)
			(xy 120.352312 -119.130318) (xy 120.36305 -119.131084) (xy 120.383572 -119.124648) (xy 120.391936 -119.117872)
			(xy 120.448578 -119.067326) (xy 120.456356 -119.059797) (xy 120.465166 -119.040044) (xy 120.465596 -119.029226)
			(xy 120.465596 -118.346982) (xy 120.465208 -118.336908) (xy 120.457464 -118.318309) (xy 120.45061 -118.310914)
			(xy 115.65382 -113.514378) (xy 115.623848 -113.508282) (xy 115.609624 -113.514378) (xy 115.600512 -113.518623)
			(xy 115.586274 -113.532786) (xy 115.578559 -113.551327) (xy 115.578128 -113.561368) (xy 115.578128 -114.099848)
			(xy 115.577602 -114.125872) (xy 115.569435 -114.177275) (xy 115.55334 -114.226772) (xy 115.529713 -114.273148)
			(xy 115.499132 -114.315265) (xy 115.4811 -114.334036) (xy 113.14049 -116.674646) (xy 113.121708 -116.692758)
			(xy 113.079511 -116.723442) (xy 113.03303 -116.747143) (xy 112.983413 -116.763276) (xy 112.931881 -116.771442)
			(xy 112.905794 -116.771928) (xy 110.457742 -116.771928) (xy 110.447316 -116.772455) (xy 110.428207 -116.780814)
			(xy 110.413972 -116.796059) (xy 110.40999 -116.80571) (xy 110.372398 -116.91112) (xy 110.381034 -116.941854)
			(xy 110.393734 -116.952268) (xy 110.415296 -116.970507) (xy 110.421912 -116.977754) (xy 116.998945 -116.977754)
			(xy 116.998945 -116.923246) (xy 117.006702 -116.869293) (xy 117.022059 -116.816994) (xy 117.044702 -116.767412)
			(xy 117.074171 -116.721558) (xy 117.109866 -116.680364) (xy 117.151061 -116.644669) (xy 117.196916 -116.6152)
			(xy 117.246498 -116.592557) (xy 117.298797 -116.577201) (xy 117.35275 -116.569445) (xy 117.380004 -116.568982)
			(xy 117.408923 -116.569466) (xy 117.466097 -116.578198) (xy 117.521298 -116.595461) (xy 117.57326 -116.620859)
			(xy 117.620793 -116.65381) (xy 117.662806 -116.693559) (xy 117.680994 -116.716048) (xy 117.688605 -116.72485)
			(xy 117.709503 -116.735035) (xy 117.721126 -116.735606) (xy 117.800882 -116.735606) (xy 117.81251 -116.73504)
			(xy 117.83342 -116.72487) (xy 117.841014 -116.716048) (xy 117.859184 -116.693547) (xy 117.90121 -116.653815)
			(xy 117.948749 -116.62088) (xy 118.000715 -116.595495) (xy 118.055915 -116.578242) (xy 118.113087 -116.569516)
			(xy 118.142004 -116.568982) (xy 118.169254 -116.569489) (xy 118.2232 -116.577245) (xy 118.275493 -116.5926)
			(xy 118.325068 -116.615241) (xy 118.370917 -116.644707) (xy 118.412106 -116.680397) (xy 118.447796 -116.721586)
			(xy 118.477261 -116.767435) (xy 118.499901 -116.817011) (xy 118.515256 -116.869304) (xy 118.523012 -116.92325)
			(xy 118.523012 -116.97775) (xy 118.515256 -117.031696) (xy 118.499901 -117.083989) (xy 118.477261 -117.133565)
			(xy 118.447796 -117.179414) (xy 118.412106 -117.220603) (xy 118.370917 -117.256293) (xy 118.325068 -117.285759)
			(xy 118.275493 -117.3084) (xy 118.2232 -117.323755) (xy 118.169254 -117.331511) (xy 118.142004 -117.331998)
			(xy 118.113087 -117.331477) (xy 118.055916 -117.322749) (xy 118.000717 -117.305491) (xy 117.948756 -117.2801)
			(xy 117.901222 -117.247157) (xy 117.859204 -117.207417) (xy 117.841014 -117.184932) (xy 117.833403 -117.17613)
			(xy 117.812505 -117.165946) (xy 117.800882 -117.165374) (xy 117.721126 -117.165374) (xy 117.709494 -117.165916)
			(xy 117.688582 -117.1761) (xy 117.680994 -117.184932) (xy 117.662814 -117.207425) (xy 117.620791 -117.247158)
			(xy 117.573254 -117.280095) (xy 117.52129 -117.305482) (xy 117.466091 -117.322736) (xy 117.408921 -117.331464)
			(xy 117.380004 -117.331998) (xy 117.35275 -117.331555) (xy 117.298797 -117.323799) (xy 117.246498 -117.308443)
			(xy 117.196916 -117.2858) (xy 117.151061 -117.256331) (xy 117.109866 -117.220636) (xy 117.074171 -117.179442)
			(xy 117.044702 -117.133588) (xy 117.022059 -117.084006) (xy 117.006702 -117.031707) (xy 116.998945 -116.977754)
			(xy 110.421912 -116.977754) (xy 110.45337 -117.012212) (xy 110.48488 -117.059076) (xy 110.509137 -117.110072)
			(xy 110.525609 -117.164088) (xy 110.533938 -117.219942) (xy 110.53445 -117.248178) (xy 110.533901 -117.275427)
			(xy 110.526149 -117.32937) (xy 110.510799 -117.381661) (xy 110.488163 -117.431235) (xy 110.458703 -117.477084)
			(xy 110.423018 -117.518273) (xy 110.381835 -117.553965) (xy 110.335991 -117.583433) (xy 110.286421 -117.606076)
			(xy 110.234133 -117.621435) (xy 110.180191 -117.629197) (xy 110.152942 -117.629686) (xy 110.125916 -117.629171)
			(xy 110.072406 -117.621534) (xy 110.020509 -117.606422) (xy 109.971265 -117.584137) (xy 109.925658 -117.555125)
			(xy 109.884603 -117.519967) (xy 109.84892 -117.479366) (xy 109.819325 -117.434136) (xy 109.796409 -117.385182)
			(xy 109.780632 -117.333483) (xy 109.776006 -117.306852) (xy 109.77372 -117.292628) (xy 109.755178 -117.270784)
			(xy 109.65561 -117.238272) (xy 109.646585 -117.235635) (xy 109.627815 -117.236608) (xy 109.610666 -117.244298)
			(xy 109.603794 -117.250718) (xy 109.513624 -117.340888) (xy 109.509522 -117.345293) (xy 109.503228 -117.355549)
			(xy 109.501178 -117.361208) (xy 109.501178 -117.361716) (xy 109.49273 -117.387259) (xy 109.469656 -117.43586)
			(xy 109.439983 -117.480738) (xy 109.404302 -117.521004) (xy 109.363318 -117.555858) (xy 109.317845 -117.58461)
			(xy 109.268784 -117.60669) (xy 109.217108 -117.62166) (xy 109.163842 -117.629222) (xy 109.136942 -117.629686)
			(xy 109.109689 -117.629206) (xy 109.055738 -117.621454) (xy 109.003439 -117.606102) (xy 108.953857 -117.583463)
			(xy 108.908003 -117.553997) (xy 108.866809 -117.518305) (xy 108.831115 -117.477113) (xy 108.801647 -117.43126)
			(xy 108.779005 -117.38168) (xy 108.763651 -117.329382) (xy 108.755896 -117.275431) (xy 108.755434 -117.248178)
			(xy 108.75589 -117.221267) (xy 108.76347 -117.167981) (xy 108.778463 -117.116289) (xy 108.800571 -117.067217)
			(xy 108.829355 -117.021738) (xy 108.864245 -116.980756) (xy 108.904547 -116.945082) (xy 108.949462 -116.915426)
			(xy 108.998098 -116.892376) (xy 109.023658 -116.883942) (xy 109.023912 -116.883942) (xy 109.029602 -116.881956)
			(xy 109.039879 -116.875665) (xy 109.044232 -116.871496) (xy 109.710474 -116.205254) (xy 109.729272 -116.18716)
			(xy 109.771465 -116.156473) (xy 109.817941 -116.132769) (xy 109.867555 -116.116632) (xy 109.919084 -116.10846)
			(xy 109.94517 -116.107972) (xy 112.747298 -116.107972) (xy 112.757368 -116.107553) (xy 112.775966 -116.099829)
			(xy 112.783366 -116.092986) (xy 114.899694 -113.976912) (xy 114.90652 -113.969501) (xy 114.914248 -113.95091)
			(xy 114.91468 -113.940844) (xy 114.91468 -102.1715) (xy 114.91426 -102.16143) (xy 114.906536 -102.142832)
			(xy 114.899694 -102.135432) (xy 109.184948 -96.420686) (xy 109.177527 -96.413873) (xy 109.158944 -96.406138)
			(xy 109.14888 -96.4057) (xy 104.71912 -96.4057) (xy 104.693098 -96.405139) (xy 104.641696 -96.396982)
			(xy 104.592199 -96.380896) (xy 104.545822 -96.357276) (xy 104.503704 -96.326702) (xy 104.484932 -96.308672)
			(xy 102.077012 -93.900498) (xy 102.069602 -93.89367) (xy 102.05101 -93.885944) (xy 102.040944 -93.885512)
			(xy 97.69221 -93.885512) (xy 97.682141 -93.88594) (xy 97.663543 -93.893658) (xy 97.656142 -93.900498)
			(xy 97.21088 -94.346014) (xy 97.206766 -94.350409) (xy 97.20048 -94.360672) (xy 97.198434 -94.366334)
			(xy 97.198434 -94.366842) (xy 97.18998 -94.392384) (xy 97.166911 -94.440989) (xy 97.137243 -94.48587)
			(xy 97.101563 -94.526138) (xy 97.06058 -94.560994) (xy 97.015106 -94.589747) (xy 96.966044 -94.611826)
			(xy 96.914366 -94.626793) (xy 96.861099 -94.634351) (xy 96.834198 -94.634812) (xy 96.806947 -94.634324)
			(xy 96.752999 -94.626567) (xy 96.700705 -94.611212) (xy 96.651128 -94.588571) (xy 96.605278 -94.559105)
			(xy 96.564088 -94.523414) (xy 96.528396 -94.482224) (xy 96.49893 -94.436374) (xy 96.476288 -94.386797)
			(xy 96.460933 -94.334503) (xy 96.453176 -94.280555) (xy 96.45269 -94.253304) (xy 96.4532 -94.226395)
			(xy 96.460776 -94.173113) (xy 96.475763 -94.121424) (xy 96.497865 -94.072354) (xy 96.526642 -94.026876)
			(xy 96.561525 -93.985893) (xy 96.60182 -93.950218) (xy 96.646728 -93.920559) (xy 96.695358 -93.897505)
			(xy 96.720914 -93.889068) (xy 96.721168 -93.889068) (xy 96.726863 -93.887092) (xy 96.737136 -93.880793)
			(xy 96.741488 -93.876622) (xy 97.299018 -93.319092) (xy 97.317809 -93.301081) (xy 97.359921 -93.270499)
			(xy 97.406292 -93.246868) (xy 97.455784 -93.230768) (xy 97.507184 -93.222595) (xy 97.533206 -93.222064)
			(xy 101.827076 -93.222064) (xy 101.8371 -93.22166) (xy 101.855623 -93.213991) (xy 101.869798 -93.199813)
			(xy 101.877462 -93.181288) (xy 101.877876 -93.171264) (xy 101.877876 -90.183716) (xy 101.877443 -90.173834)
			(xy 101.869986 -90.155535) (xy 101.863398 -90.148156) (xy 101.806248 -90.08999) (xy 101.788214 -90.082116)
			(xy 101.778054 -90.082116) (xy 101.751125 -90.081179) (xy 101.697924 -90.072629) (xy 101.646455 -90.05668)
			(xy 101.597741 -90.033649) (xy 101.552751 -90.003995) (xy 101.512381 -89.968306) (xy 101.477432 -89.927294)
			(xy 101.448601 -89.881772) (xy 101.42646 -89.832648) (xy 101.411449 -89.780897) (xy 101.403868 -89.72755)
			(xy 101.403404 -89.700608) (xy 101.403872 -89.67338) (xy 101.41161 -89.619477) (xy 101.42693 -89.567221)
			(xy 101.449521 -89.517673) (xy 101.478924 -89.471838) (xy 101.496368 -89.450926) (xy 101.502718 -89.443814)
			(xy 101.509068 -89.425526) (xy 101.506274 -89.346532) (xy 101.505479 -89.337003) (xy 101.497784 -89.319513)
			(xy 101.491288 -89.312496) (xy 101.287326 -89.108534) (xy 101.264399 -89.084996) (xy 101.223437 -89.033614)
			(xy 101.188486 -88.97797) (xy 101.159985 -88.918761) (xy 101.138291 -88.856734) (xy 101.123679 -88.792669)
			(xy 101.116331 -88.72737) (xy 101.115876 -88.694514) (xy 101.115876 -86.279228) (xy 101.115442 -86.26916)
			(xy 101.107728 -86.250561) (xy 101.10089 -86.24316) (xy 100.833682 -85.976206) (xy 100.80371 -85.970364)
			(xy 100.789486 -85.976206) (xy 100.780473 -85.980556) (xy 100.766382 -85.994732) (xy 100.758742 -86.013203)
			(xy 100.758244 -86.023196) (xy 100.758244 -86.811358) (xy 100.757754 -86.841342) (xy 100.749926 -86.900798)
			(xy 100.734405 -86.958723) (xy 100.711456 -87.014127) (xy 100.681472 -87.066061) (xy 100.644966 -87.113637)
			(xy 100.602561 -87.156042) (xy 100.554985 -87.192548) (xy 100.503051 -87.222532) (xy 100.447647 -87.245481)
			(xy 100.389722 -87.261002) (xy 100.330266 -87.26883) (xy 100.270298 -87.26883) (xy 100.210842 -87.261002)
			(xy 100.152917 -87.245481) (xy 100.097513 -87.222532) (xy 100.045579 -87.192548) (xy 99.998003 -87.156042)
			(xy 99.955598 -87.113637) (xy 99.919092 -87.066061) (xy 99.889108 -87.014127) (xy 99.866159 -86.958723)
			(xy 99.850638 -86.900798) (xy 99.84281 -86.841342) (xy 99.84232 -86.811358) (xy 99.84232 -85.947758)
			(xy 99.842843 -85.91632) (xy 99.851442 -85.854034) (xy 99.868487 -85.793511) (xy 99.893657 -85.735892)
			(xy 99.926477 -85.682261) (xy 99.96633 -85.633627) (xy 100.012466 -85.590907) (xy 100.064015 -85.554905)
			(xy 100.120007 -85.526298) (xy 100.179388 -85.505625) (xy 100.210112 -85.49894) (xy 100.210366 -85.49894)
			(xy 100.221104 -85.496073) (xy 100.238884 -85.482782) (xy 100.244656 -85.473286) (xy 100.287328 -85.394292)
			(xy 100.288598 -85.37194) (xy 100.28428 -85.361272) (xy 100.270815 -85.326354) (xy 100.251835 -85.253963)
			(xy 100.242234 -85.179743) (xy 100.241608 -85.142324) (xy 100.241608 -84.760054) (xy 100.22459 -84.7344)
			(xy 100.210112 -84.728558) (xy 100.20073 -84.725184) (xy 100.180809 -84.725196) (xy 100.162396 -84.732798)
			(xy 100.154994 -84.73948) (xy 99.37623 -85.51799) (xy 99.369406 -85.525403) (xy 99.361676 -85.543992)
			(xy 99.361244 -85.554058) (xy 99.361244 -87.40648) (xy 99.360699 -87.432503) (xy 99.35254 -87.483907)
			(xy 99.336451 -87.533404) (xy 99.312827 -87.579781) (xy 99.282248 -87.621897) (xy 99.264216 -87.640668)
			(xy 92.655644 -94.24924) (xy 95.43618 -94.24924) (xy 95.440251 -94.193618) (xy 95.452377 -94.139181)
			(xy 95.4723 -94.08709) (xy 95.499596 -94.038455) (xy 95.533682 -93.994312) (xy 95.573831 -93.955603)
			(xy 95.619189 -93.923152) (xy 95.668789 -93.897651) (xy 95.721573 -93.879644) (xy 95.776416 -93.869514)
			(xy 95.83215 -93.867477) (xy 95.887587 -93.873577) (xy 95.941544 -93.887683) (xy 95.992873 -93.909495)
			(xy 96.040479 -93.938549) (xy 96.083347 -93.974224) (xy 96.120564 -94.015761) (xy 96.151337 -94.062274)
			(xy 96.175009 -94.112771) (xy 96.191077 -94.166178) (xy 96.199197 -94.221354) (xy 96.199706 -94.24924)
			(xy 96.199197 -94.277126) (xy 96.191077 -94.332302) (xy 96.175009 -94.385709) (xy 96.151337 -94.436206)
			(xy 96.120564 -94.482719) (xy 96.083347 -94.524256) (xy 96.040479 -94.559931) (xy 95.992873 -94.588985)
			(xy 95.941544 -94.610797) (xy 95.887587 -94.624903) (xy 95.83215 -94.631003) (xy 95.776416 -94.628966)
			(xy 95.721573 -94.618836) (xy 95.668789 -94.600829) (xy 95.619189 -94.575328) (xy 95.573831 -94.542877)
			(xy 95.533682 -94.504168) (xy 95.499596 -94.460025) (xy 95.4723 -94.41139) (xy 95.452377 -94.359299)
			(xy 95.440251 -94.304862) (xy 95.43618 -94.24924) (xy 92.655644 -94.24924) (xy 91.403678 -95.501206)
			(xy 91.39684 -95.508607) (xy 91.389119 -95.527206) (xy 91.388692 -95.537274) (xy 91.388692 -95.607378)
			(xy 91.391232 -95.618554) (xy 91.394026 -95.623888) (xy 91.394534 -95.624904) (xy 91.408258 -95.652378)
			(xy 91.427712 -95.710626) (xy 91.437587 -95.771237) (xy 91.438222 -95.801942) (xy 92.715586 -95.801942)
			(xy 92.719657 -95.74632) (xy 92.731783 -95.691883) (xy 92.751706 -95.639792) (xy 92.779002 -95.591157)
			(xy 92.813088 -95.547014) (xy 92.853237 -95.508305) (xy 92.898595 -95.475854) (xy 92.948195 -95.450353)
			(xy 93.000979 -95.432346) (xy 93.055822 -95.422216) (xy 93.111556 -95.420179) (xy 93.166993 -95.426279)
			(xy 93.22095 -95.440385) (xy 93.272279 -95.462197) (xy 93.319885 -95.491251) (xy 93.362753 -95.526926)
			(xy 93.39997 -95.568463) (xy 93.430743 -95.614976) (xy 93.454415 -95.665473) (xy 93.470483 -95.71888)
			(xy 93.478603 -95.774056) (xy 93.479112 -95.801942) (xy 93.721426 -95.801942) (xy 93.725497 -95.74632)
			(xy 93.737623 -95.691883) (xy 93.757546 -95.639792) (xy 93.784842 -95.591157) (xy 93.818928 -95.547014)
			(xy 93.859077 -95.508305) (xy 93.904435 -95.475854) (xy 93.954035 -95.450353) (xy 94.006819 -95.432346)
			(xy 94.061662 -95.422216) (xy 94.117396 -95.420179) (xy 94.172833 -95.426279) (xy 94.22679 -95.440385)
			(xy 94.278119 -95.462197) (xy 94.325725 -95.491251) (xy 94.368593 -95.526926) (xy 94.40581 -95.568463)
			(xy 94.436583 -95.614976) (xy 94.460255 -95.665473) (xy 94.476323 -95.71888) (xy 94.484443 -95.774056)
			(xy 94.484952 -95.801942) (xy 94.484443 -95.829828) (xy 94.477301 -95.878357) (xy 99.120179 -95.878357)
			(xy 99.127934 -95.82441) (xy 99.143288 -95.772116) (xy 99.165927 -95.722539) (xy 99.195392 -95.676689)
			(xy 99.231081 -95.635498) (xy 99.27227 -95.599806) (xy 99.318118 -95.570339) (xy 99.367693 -95.547696)
			(xy 99.419986 -95.53234) (xy 99.473933 -95.524581) (xy 99.528434 -95.524579) (xy 99.582381 -95.532332)
			(xy 99.634675 -95.547685) (xy 99.684253 -95.570323) (xy 99.730104 -95.599786) (xy 99.771295 -95.635475)
			(xy 99.806988 -95.676662) (xy 99.836457 -95.72251) (xy 99.8591 -95.772085) (xy 99.874458 -95.824377)
			(xy 99.882218 -95.878323) (xy 99.882706 -95.905574) (xy 99.882706 -95.906082) (xy 99.882623 -95.916454)
			(xy 99.881481 -95.937166) (xy 99.88042 -95.947484) (xy 99.879281 -95.962029) (xy 99.884489 -95.990727)
			(xy 99.897586 -96.016789) (xy 99.917505 -96.038095) (xy 99.942628 -96.052912) (xy 99.970911 -96.060037)
			(xy 100.000056 -96.05889) (xy 100.014024 -96.054672) (xy 100.043635 -96.045328) (xy 100.1049 -96.03524)
			(xy 100.135944 -96.034606) (xy 100.136198 -96.034606) (xy 100.163449 -96.035076) (xy 100.217397 -96.042832)
			(xy 100.269692 -96.058187) (xy 100.319269 -96.080827) (xy 100.36512 -96.110293) (xy 100.40631 -96.145984)
			(xy 100.442002 -96.187174) (xy 100.471469 -96.233024) (xy 100.494111 -96.282601) (xy 100.509466 -96.334895)
			(xy 100.517224 -96.388843) (xy 100.517225 -96.443345) (xy 100.509469 -96.497293) (xy 100.494115 -96.549588)
			(xy 100.471475 -96.599166) (xy 100.442009 -96.645016) (xy 100.406319 -96.686207) (xy 100.365129 -96.7219)
			(xy 100.31928 -96.751367) (xy 100.269703 -96.774009) (xy 100.217409 -96.789366) (xy 100.163461 -96.797124)
			(xy 100.108959 -96.797125) (xy 100.055011 -96.78937) (xy 100.002716 -96.774016) (xy 99.953138 -96.751377)
			(xy 99.907287 -96.721912) (xy 99.866095 -96.686222) (xy 99.830403 -96.645032) (xy 99.800935 -96.599183)
			(xy 99.778292 -96.549607) (xy 99.762935 -96.497313) (xy 99.755177 -96.443365) (xy 99.75469 -96.416114)
			(xy 99.75469 -96.415606) (xy 99.754772 -96.405234) (xy 99.755915 -96.384522) (xy 99.756976 -96.374204)
			(xy 99.758131 -96.35966) (xy 99.75292 -96.33096) (xy 99.73982 -96.304898) (xy 99.719898 -96.283592)
			(xy 99.694773 -96.268774) (xy 99.666488 -96.26165) (xy 99.637341 -96.262798) (xy 99.623372 -96.267016)
			(xy 99.593761 -96.276361) (xy 99.532496 -96.286449) (xy 99.501452 -96.287082) (xy 99.501198 -96.287082)
			(xy 99.473947 -96.28662) (xy 99.420001 -96.278864) (xy 99.367707 -96.263509) (xy 99.318131 -96.240868)
			(xy 99.272281 -96.211403) (xy 99.231092 -96.175712) (xy 99.195401 -96.134523) (xy 99.165934 -96.088674)
			(xy 99.143293 -96.039098) (xy 99.127938 -95.986804) (xy 99.12018 -95.932858) (xy 99.120179 -95.878357)
			(xy 94.477301 -95.878357) (xy 94.476323 -95.885004) (xy 94.460255 -95.938411) (xy 94.436583 -95.988908)
			(xy 94.40581 -96.035421) (xy 94.368593 -96.076958) (xy 94.325725 -96.112633) (xy 94.278119 -96.141687)
			(xy 94.22679 -96.163499) (xy 94.172833 -96.177605) (xy 94.117396 -96.183705) (xy 94.061662 -96.181668)
			(xy 94.006819 -96.171538) (xy 93.954035 -96.153531) (xy 93.904435 -96.12803) (xy 93.859077 -96.095579)
			(xy 93.818928 -96.05687) (xy 93.784842 -96.012727) (xy 93.757546 -95.964092) (xy 93.737623 -95.912001)
			(xy 93.725497 -95.857564) (xy 93.721426 -95.801942) (xy 93.479112 -95.801942) (xy 93.478603 -95.829828)
			(xy 93.470483 -95.885004) (xy 93.454415 -95.938411) (xy 93.430743 -95.988908) (xy 93.39997 -96.035421)
			(xy 93.362753 -96.076958) (xy 93.319885 -96.112633) (xy 93.272279 -96.141687) (xy 93.22095 -96.163499)
			(xy 93.166993 -96.177605) (xy 93.111556 -96.183705) (xy 93.055822 -96.181668) (xy 93.000979 -96.171538)
			(xy 92.948195 -96.153531) (xy 92.898595 -96.12803) (xy 92.853237 -96.095579) (xy 92.813088 -96.05687)
			(xy 92.779002 -96.012727) (xy 92.751706 -95.964092) (xy 92.731783 -95.912001) (xy 92.719657 -95.857564)
			(xy 92.715586 -95.801942) (xy 91.438222 -95.801942) (xy 91.437736 -95.829193) (xy 91.42998 -95.883141)
			(xy 91.414625 -95.935436) (xy 91.391983 -95.985013) (xy 91.362517 -96.030863) (xy 91.326826 -96.072054)
			(xy 91.285635 -96.107745) (xy 91.239785 -96.137211) (xy 91.190208 -96.159853) (xy 91.137913 -96.175208)
			(xy 91.083965 -96.182964) (xy 91.029463 -96.182964) (xy 90.975515 -96.175208) (xy 90.92322 -96.159853)
			(xy 90.873643 -96.137211) (xy 90.827793 -96.107745) (xy 90.786602 -96.072054) (xy 90.750911 -96.030863)
			(xy 90.721445 -95.985013) (xy 90.698803 -95.935436) (xy 90.683448 -95.883141) (xy 90.675692 -95.829193)
			(xy 90.675206 -95.801942) (xy 89.404952 -95.801942) (xy 89.404443 -95.829828) (xy 89.396323 -95.885004)
			(xy 89.380255 -95.938411) (xy 89.356583 -95.988908) (xy 89.32581 -96.035421) (xy 89.288593 -96.076958)
			(xy 89.245725 -96.112633) (xy 89.198119 -96.141687) (xy 89.14679 -96.163499) (xy 89.092833 -96.177605)
			(xy 89.037396 -96.183705) (xy 88.981662 -96.181668) (xy 88.926819 -96.171538) (xy 88.874035 -96.153531)
			(xy 88.824435 -96.12803) (xy 88.779077 -96.095579) (xy 88.738928 -96.05687) (xy 88.704842 -96.012727)
			(xy 88.677546 -95.964092) (xy 88.657623 -95.912001) (xy 88.645497 -95.857564) (xy 88.641426 -95.801942)
			(xy 85.148237 -95.801942) (xy 85.034546 -96.374966) (xy 94.427038 -96.374966) (xy 94.431109 -96.319344)
			(xy 94.443235 -96.264907) (xy 94.463158 -96.212816) (xy 94.490454 -96.164181) (xy 94.52454 -96.120038)
			(xy 94.564689 -96.081329) (xy 94.610047 -96.048878) (xy 94.659647 -96.023377) (xy 94.712431 -96.00537)
			(xy 94.767274 -95.99524) (xy 94.823008 -95.993203) (xy 94.878445 -95.999303) (xy 94.932402 -96.013409)
			(xy 94.983731 -96.035221) (xy 95.031337 -96.064275) (xy 95.074205 -96.09995) (xy 95.111422 -96.141487)
			(xy 95.142195 -96.188) (xy 95.165867 -96.238497) (xy 95.180866 -96.288352) (xy 95.852232 -96.288352)
			(xy 95.856303 -96.23273) (xy 95.868429 -96.178293) (xy 95.888352 -96.126202) (xy 95.915648 -96.077567)
			(xy 95.949734 -96.033424) (xy 95.989883 -95.994715) (xy 96.035241 -95.962264) (xy 96.084841 -95.936763)
			(xy 96.137625 -95.918756) (xy 96.192468 -95.908626) (xy 96.248202 -95.906589) (xy 96.303639 -95.912689)
			(xy 96.357596 -95.926795) (xy 96.408925 -95.948607) (xy 96.456531 -95.977661) (xy 96.499399 -96.013336)
			(xy 96.536616 -96.054873) (xy 96.567389 -96.101386) (xy 96.591061 -96.151883) (xy 96.607129 -96.20529)
			(xy 96.615249 -96.260466) (xy 96.61548 -96.273112) (xy 97.197924 -96.273112) (xy 97.201995 -96.21749)
			(xy 97.214121 -96.163053) (xy 97.234044 -96.110962) (xy 97.26134 -96.062327) (xy 97.295426 -96.018184)
			(xy 97.335575 -95.979475) (xy 97.380933 -95.947024) (xy 97.430533 -95.921523) (xy 97.483317 -95.903516)
			(xy 97.53816 -95.893386) (xy 97.593894 -95.891349) (xy 97.649331 -95.897449) (xy 97.703288 -95.911555)
			(xy 97.754617 -95.933367) (xy 97.802223 -95.962421) (xy 97.845091 -95.998096) (xy 97.882308 -96.039633)
			(xy 97.913081 -96.086146) (xy 97.936753 -96.136643) (xy 97.952821 -96.19005) (xy 97.960941 -96.245226)
			(xy 97.96145 -96.273112) (xy 97.960941 -96.300998) (xy 97.952821 -96.356174) (xy 97.936753 -96.409581)
			(xy 97.913081 -96.460078) (xy 97.882308 -96.506591) (xy 97.845091 -96.548128) (xy 97.802223 -96.583803)
			(xy 97.754617 -96.612857) (xy 97.703288 -96.634669) (xy 97.649331 -96.648775) (xy 97.593894 -96.654875)
			(xy 97.53816 -96.652838) (xy 97.483317 -96.642708) (xy 97.430533 -96.624701) (xy 97.380933 -96.5992)
			(xy 97.335575 -96.566749) (xy 97.295426 -96.52804) (xy 97.26134 -96.483897) (xy 97.234044 -96.435262)
			(xy 97.214121 -96.383171) (xy 97.201995 -96.328734) (xy 97.197924 -96.273112) (xy 96.61548 -96.273112)
			(xy 96.615758 -96.288352) (xy 96.615249 -96.316238) (xy 96.607129 -96.371414) (xy 96.591061 -96.424821)
			(xy 96.567389 -96.475318) (xy 96.536616 -96.521831) (xy 96.499399 -96.563368) (xy 96.456531 -96.599043)
			(xy 96.408925 -96.628097) (xy 96.357596 -96.649909) (xy 96.303639 -96.664015) (xy 96.248202 -96.670115)
			(xy 96.192468 -96.668078) (xy 96.137625 -96.657948) (xy 96.084841 -96.639941) (xy 96.035241 -96.61444)
			(xy 95.989883 -96.581989) (xy 95.949734 -96.54328) (xy 95.915648 -96.499137) (xy 95.888352 -96.450502)
			(xy 95.868429 -96.398411) (xy 95.856303 -96.343974) (xy 95.852232 -96.288352) (xy 95.180866 -96.288352)
			(xy 95.181935 -96.291904) (xy 95.190055 -96.34708) (xy 95.190564 -96.374966) (xy 95.190055 -96.402852)
			(xy 95.181935 -96.458028) (xy 95.165867 -96.511435) (xy 95.142195 -96.561932) (xy 95.111422 -96.608445)
			(xy 95.074205 -96.649982) (xy 95.031337 -96.685657) (xy 94.983731 -96.714711) (xy 94.932402 -96.736523)
			(xy 94.878445 -96.750629) (xy 94.823008 -96.756729) (xy 94.767274 -96.754692) (xy 94.712431 -96.744562)
			(xy 94.659647 -96.726555) (xy 94.610047 -96.701054) (xy 94.564689 -96.668603) (xy 94.52454 -96.629894)
			(xy 94.490454 -96.585751) (xy 94.463158 -96.537116) (xy 94.443235 -96.485025) (xy 94.431109 -96.430588)
			(xy 94.427038 -96.374966) (xy 85.034546 -96.374966) (xy 84.721341 -97.953576) (xy 88.342976 -97.953576)
			(xy 88.347047 -97.897954) (xy 88.359173 -97.843517) (xy 88.379096 -97.791426) (xy 88.406392 -97.742791)
			(xy 88.440478 -97.698648) (xy 88.480627 -97.659939) (xy 88.525985 -97.627488) (xy 88.575585 -97.601987)
			(xy 88.628369 -97.58398) (xy 88.683212 -97.57385) (xy 88.738946 -97.571813) (xy 88.794383 -97.577913)
			(xy 88.84834 -97.592019) (xy 88.899669 -97.613831) (xy 88.947275 -97.642885) (xy 88.990143 -97.67856)
			(xy 89.02736 -97.720097) (xy 89.058133 -97.76661) (xy 89.081805 -97.817107) (xy 89.083049 -97.821242)
			(xy 89.657426 -97.821242) (xy 89.661497 -97.76562) (xy 89.673623 -97.711183) (xy 89.693546 -97.659092)
			(xy 89.720842 -97.610457) (xy 89.754928 -97.566314) (xy 89.795077 -97.527605) (xy 89.840435 -97.495154)
			(xy 89.890035 -97.469653) (xy 89.942819 -97.451646) (xy 89.997662 -97.441516) (xy 90.053396 -97.439479)
			(xy 90.108833 -97.445579) (xy 90.16279 -97.459685) (xy 90.214119 -97.481497) (xy 90.261725 -97.510551)
			(xy 90.304593 -97.546226) (xy 90.34181 -97.587763) (xy 90.372583 -97.634276) (xy 90.396255 -97.684773)
			(xy 90.412323 -97.73818) (xy 90.420443 -97.793356) (xy 90.420952 -97.821242) (xy 90.420455 -97.848452)
			(xy 90.928397 -97.848452) (xy 90.928397 -97.793948) (xy 90.936155 -97.739999) (xy 90.951511 -97.687704)
			(xy 90.974154 -97.638126) (xy 91.003623 -97.592276) (xy 91.039318 -97.551087) (xy 91.080511 -97.515397)
			(xy 91.126365 -97.485933) (xy 91.175945 -97.463296) (xy 91.228242 -97.447945) (xy 91.282192 -97.440194)
			(xy 91.309444 -97.439734) (xy 91.33836 -97.44028) (xy 91.395531 -97.449001) (xy 91.450729 -97.466253)
			(xy 91.502692 -97.491639) (xy 91.550226 -97.524579) (xy 91.592244 -97.564316) (xy 91.610434 -97.5868)
			(xy 91.618036 -97.595613) (xy 91.638941 -97.605793) (xy 91.650566 -97.606358) (xy 91.730322 -97.606358)
			(xy 91.741956 -97.605832) (xy 91.762866 -97.595635) (xy 91.770454 -97.5868) (xy 91.788671 -97.564339)
			(xy 91.830685 -97.524602) (xy 91.878215 -97.49166) (xy 91.930171 -97.466268) (xy 91.985364 -97.449007)
			(xy 92.04253 -97.440272) (xy 92.071444 -97.439734) (xy 92.098696 -97.440139) (xy 92.152645 -97.447901)
			(xy 92.20494 -97.463262) (xy 92.254517 -97.485908) (xy 92.300367 -97.515379) (xy 92.341557 -97.551074)
			(xy 92.377248 -97.592268) (xy 92.406713 -97.638121) (xy 92.429353 -97.687701) (xy 92.444708 -97.739998)
			(xy 92.452464 -97.793948) (xy 92.452464 -97.821242) (xy 92.705426 -97.821242) (xy 92.709497 -97.76562)
			(xy 92.721623 -97.711183) (xy 92.741546 -97.659092) (xy 92.768842 -97.610457) (xy 92.802928 -97.566314)
			(xy 92.843077 -97.527605) (xy 92.888435 -97.495154) (xy 92.938035 -97.469653) (xy 92.990819 -97.451646)
			(xy 93.045662 -97.441516) (xy 93.101396 -97.439479) (xy 93.156833 -97.445579) (xy 93.21079 -97.459685)
			(xy 93.262119 -97.481497) (xy 93.309725 -97.510551) (xy 93.352593 -97.546226) (xy 93.38981 -97.587763)
			(xy 93.420583 -97.634276) (xy 93.444255 -97.684773) (xy 93.460323 -97.73818) (xy 93.468443 -97.793356)
			(xy 93.468952 -97.821242) (xy 93.468443 -97.849128) (xy 93.460323 -97.904304) (xy 93.444255 -97.957711)
			(xy 93.420583 -98.008208) (xy 93.38981 -98.054721) (xy 93.352593 -98.096258) (xy 93.309725 -98.131933)
			(xy 93.262119 -98.160987) (xy 93.21079 -98.182799) (xy 93.156833 -98.196905) (xy 93.101396 -98.203005)
			(xy 93.045662 -98.200968) (xy 92.990819 -98.190838) (xy 92.938035 -98.172831) (xy 92.888435 -98.14733)
			(xy 92.843077 -98.114879) (xy 92.802928 -98.07617) (xy 92.768842 -98.032027) (xy 92.741546 -97.983392)
			(xy 92.721623 -97.931301) (xy 92.709497 -97.876864) (xy 92.705426 -97.821242) (xy 92.452464 -97.821242)
			(xy 92.452464 -97.848452) (xy 92.444708 -97.902402) (xy 92.429353 -97.954699) (xy 92.406713 -98.004279)
			(xy 92.377248 -98.050132) (xy 92.341557 -98.091326) (xy 92.300367 -98.127021) (xy 92.254517 -98.156492)
			(xy 92.20494 -98.179138) (xy 92.152645 -98.194499) (xy 92.098696 -98.202261) (xy 92.071444 -98.20275)
			(xy 92.042527 -98.202219) (xy 91.985356 -98.193495) (xy 91.930156 -98.176241) (xy 91.878194 -98.150852)
			(xy 91.83066 -98.11791) (xy 91.788644 -98.078169) (xy 91.770454 -98.055684) (xy 91.76286 -98.046863)
			(xy 91.741949 -98.036687) (xy 91.730322 -98.036126) (xy 91.650566 -98.036126) (xy 91.638932 -98.036651)
			(xy 91.618022 -98.046849) (xy 91.610434 -98.055684) (xy 91.59222 -98.078148) (xy 91.550205 -98.117885)
			(xy 91.502675 -98.150827) (xy 91.450719 -98.176219) (xy 91.395525 -98.193479) (xy 91.338359 -98.202213)
			(xy 91.309444 -98.20275) (xy 91.282192 -98.202206) (xy 91.228242 -98.194455) (xy 91.175945 -98.179104)
			(xy 91.126365 -98.156467) (xy 91.080511 -98.127003) (xy 91.039318 -98.091313) (xy 91.003623 -98.050124)
			(xy 90.974154 -98.004274) (xy 90.951511 -97.954696) (xy 90.936155 -97.902401) (xy 90.928397 -97.848452)
			(xy 90.420455 -97.848452) (xy 90.420443 -97.849128) (xy 90.412323 -97.904304) (xy 90.396255 -97.957711)
			(xy 90.372583 -98.008208) (xy 90.34181 -98.054721) (xy 90.304593 -98.096258) (xy 90.261725 -98.131933)
			(xy 90.214119 -98.160987) (xy 90.16279 -98.182799) (xy 90.108833 -98.196905) (xy 90.053396 -98.203005)
			(xy 89.997662 -98.200968) (xy 89.942819 -98.190838) (xy 89.890035 -98.172831) (xy 89.840435 -98.14733)
			(xy 89.795077 -98.114879) (xy 89.754928 -98.07617) (xy 89.720842 -98.032027) (xy 89.693546 -97.983392)
			(xy 89.673623 -97.931301) (xy 89.661497 -97.876864) (xy 89.657426 -97.821242) (xy 89.083049 -97.821242)
			(xy 89.097873 -97.870514) (xy 89.105993 -97.92569) (xy 89.106502 -97.953576) (xy 89.105993 -97.981462)
			(xy 89.097873 -98.036638) (xy 89.081805 -98.090045) (xy 89.058133 -98.140542) (xy 89.02736 -98.187055)
			(xy 88.990143 -98.228592) (xy 88.947275 -98.264267) (xy 88.899669 -98.293321) (xy 88.84834 -98.315133)
			(xy 88.794383 -98.329239) (xy 88.738946 -98.335339) (xy 88.683212 -98.333302) (xy 88.628369 -98.323172)
			(xy 88.575585 -98.305165) (xy 88.525985 -98.279664) (xy 88.480627 -98.247213) (xy 88.440478 -98.208504)
			(xy 88.406392 -98.164361) (xy 88.379096 -98.115726) (xy 88.359173 -98.063635) (xy 88.347047 -98.009198)
			(xy 88.342976 -97.953576) (xy 84.721341 -97.953576) (xy 84.561438 -98.759518) (xy 99.171252 -98.759518)
			(xy 99.171716 -98.732148) (xy 99.179532 -98.677968) (xy 99.195021 -98.625464) (xy 99.217864 -98.575717)
			(xy 99.24759 -98.529751) (xy 99.265232 -98.50882) (xy 99.265486 -98.508566) (xy 99.27105 -98.501464)
			(xy 99.277311 -98.484559) (xy 99.277678 -98.475546) (xy 99.277678 -98.40849) (xy 99.277331 -98.399472)
			(xy 99.271077 -98.382555) (xy 99.265486 -98.37547) (xy 99.265232 -98.37547) (xy 99.265232 -98.375216)
			(xy 99.247609 -98.354269) (xy 99.217883 -98.308304) (xy 99.195036 -98.25856) (xy 99.179538 -98.20606)
			(xy 99.171708 -98.151883) (xy 99.171706 -98.097144) (xy 99.179532 -98.042966) (xy 99.195027 -97.990465)
			(xy 99.21787 -97.94072) (xy 99.247592 -97.894753) (xy 99.265232 -97.87382) (xy 99.265486 -97.873566)
			(xy 99.27105 -97.866464) (xy 99.277311 -97.849559) (xy 99.277678 -97.840546) (xy 99.277678 -97.77349)
			(xy 99.277331 -97.764472) (xy 99.271077 -97.747555) (xy 99.265486 -97.74047) (xy 99.265232 -97.74047)
			(xy 99.265232 -97.740216) (xy 99.247592 -97.719285) (xy 99.217879 -97.673312) (xy 99.195043 -97.623565)
			(xy 99.179552 -97.571063) (xy 99.171725 -97.516887) (xy 99.171252 -97.489518) (xy 99.171738 -97.462267)
			(xy 99.179494 -97.408319) (xy 99.194849 -97.356024) (xy 99.217491 -97.306447) (xy 99.246957 -97.260597)
			(xy 99.282648 -97.219406) (xy 99.323839 -97.183715) (xy 99.369689 -97.154249) (xy 99.419266 -97.131607)
			(xy 99.471561 -97.116252) (xy 99.525509 -97.108496) (xy 99.580011 -97.108496) (xy 99.633959 -97.116252)
			(xy 99.686254 -97.131607) (xy 99.735831 -97.154249) (xy 99.781681 -97.183715) (xy 99.822872 -97.219406)
			(xy 99.858563 -97.260597) (xy 99.888029 -97.306447) (xy 99.910671 -97.356024) (xy 99.926026 -97.408319)
			(xy 99.933782 -97.462267) (xy 99.934268 -97.489518) (xy 99.93382 -97.516889) (xy 99.925999 -97.571069)
			(xy 99.910506 -97.623573) (xy 99.88766 -97.673319) (xy 99.857931 -97.719285) (xy 99.840288 -97.740216)
			(xy 99.840034 -97.74047) (xy 99.834446 -97.747555) (xy 99.828202 -97.764473) (xy 99.827842 -97.77349)
			(xy 99.827842 -97.840546) (xy 99.828216 -97.849561) (xy 99.834451 -97.866479) (xy 99.840034 -97.873566)
			(xy 99.840288 -97.873566) (xy 99.840288 -97.87382) (xy 99.857946 -97.894739) (xy 99.887669 -97.940709)
			(xy 99.910512 -97.990458) (xy 99.926006 -98.042962) (xy 99.933833 -98.097142) (xy 99.933831 -98.151885)
			(xy 99.926 -98.206064) (xy 99.910502 -98.258567) (xy 99.887656 -98.308314) (xy 99.857929 -98.354283)
			(xy 99.840288 -98.375216) (xy 99.840034 -98.37547) (xy 99.834446 -98.382555) (xy 99.828202 -98.399473)
			(xy 99.827842 -98.40849) (xy 99.827842 -98.475546) (xy 99.828216 -98.484561) (xy 99.834451 -98.501479)
			(xy 99.836082 -98.503549) (xy 100.826086 -98.503549) (xy 100.826086 -98.449051) (xy 100.833841 -98.395108)
			(xy 100.849194 -98.342817) (xy 100.871832 -98.293244) (xy 100.901294 -98.247396) (xy 100.936981 -98.206207)
			(xy 100.978165 -98.170517) (xy 101.02401 -98.14105) (xy 101.073582 -98.118407) (xy 101.125871 -98.103049)
			(xy 101.179813 -98.095288) (xy 101.207062 -98.0948) (xy 101.233377 -98.095226) (xy 101.285508 -98.102469)
			(xy 101.336151 -98.116797) (xy 101.38435 -98.137937) (xy 101.429192 -98.16549) (xy 101.46983 -98.198935)
			(xy 101.487986 -98.21799) (xy 101.495512 -98.225386) (xy 101.514789 -98.233914) (xy 101.525324 -98.2345)
			(xy 101.6 -98.2345) (xy 101.610551 -98.233985) (xy 101.629847 -98.22544) (xy 101.637338 -98.21799)
			(xy 101.65548 -98.198921) (xy 101.696113 -98.165466) (xy 101.740956 -98.137909) (xy 101.789159 -98.116772)
			(xy 101.839809 -98.102458) (xy 101.891945 -98.095237) (xy 101.918262 -98.0948) (xy 101.945517 -98.095245)
			(xy 101.999473 -98.102998) (xy 102.051777 -98.118351) (xy 102.101363 -98.140991) (xy 102.147222 -98.170459)
			(xy 102.18842 -98.206153) (xy 102.224118 -98.247348) (xy 102.25359 -98.293204) (xy 102.273298 -98.336354)
			(xy 102.849426 -98.336354) (xy 102.849917 -98.308985) (xy 102.857728 -98.254806) (xy 102.873211 -98.202303)
			(xy 102.896047 -98.152556) (xy 102.925767 -98.106588) (xy 102.943406 -98.085656) (xy 102.94366 -98.085402)
			(xy 102.949259 -98.078324) (xy 102.955497 -98.0614) (xy 102.955852 -98.052382) (xy 102.955852 -97.985326)
			(xy 102.955493 -97.976309) (xy 102.949248 -97.959392) (xy 102.94366 -97.952306) (xy 102.943406 -97.952306)
			(xy 102.943406 -97.952052) (xy 102.925721 -97.931155) (xy 102.896 -97.885181) (xy 102.873158 -97.835428)
			(xy 102.857667 -97.782921) (xy 102.849843 -97.728738) (xy 102.849848 -97.673993) (xy 102.857681 -97.619811)
			(xy 102.873183 -97.567307) (xy 102.896033 -97.517558) (xy 102.925763 -97.471589) (xy 102.943406 -97.450656)
			(xy 102.94366 -97.450402) (xy 102.949259 -97.443324) (xy 102.955497 -97.4264) (xy 102.955852 -97.417382)
			(xy 102.955852 -97.350326) (xy 102.955493 -97.341309) (xy 102.949248 -97.324392) (xy 102.94366 -97.317306)
			(xy 102.943406 -97.317306) (xy 102.943406 -97.317052) (xy 102.925779 -97.29611) (xy 102.896065 -97.25014)
			(xy 102.873227 -97.200395) (xy 102.857733 -97.147897) (xy 102.849902 -97.093723) (xy 102.849426 -97.066354)
			(xy 102.849912 -97.039103) (xy 102.857668 -96.985155) (xy 102.873023 -96.93286) (xy 102.895665 -96.883283)
			(xy 102.925131 -96.837433) (xy 102.960822 -96.796242) (xy 103.002013 -96.760551) (xy 103.047863 -96.731085)
			(xy 103.09744 -96.708443) (xy 103.149735 -96.693088) (xy 103.203683 -96.685332) (xy 103.258185 -96.685332)
			(xy 103.312133 -96.693088) (xy 103.364428 -96.708443) (xy 103.414005 -96.731085) (xy 103.459855 -96.760551)
			(xy 103.501046 -96.796242) (xy 103.536737 -96.837433) (xy 103.566203 -96.883283) (xy 103.588845 -96.93286)
			(xy 103.6042 -96.985155) (xy 103.611956 -97.039103) (xy 103.612442 -97.066354) (xy 103.611963 -97.093724)
			(xy 103.604151 -97.147903) (xy 103.588665 -97.200407) (xy 103.565826 -97.250154) (xy 103.536103 -97.296121)
			(xy 103.518462 -97.317052) (xy 103.518208 -97.317306) (xy 103.512614 -97.324387) (xy 103.506371 -97.341308)
			(xy 103.506016 -97.350326) (xy 103.506016 -97.417382) (xy 103.506378 -97.426398) (xy 103.512622 -97.443316)
			(xy 103.518208 -97.450402) (xy 103.518462 -97.450402) (xy 103.518462 -97.450656) (xy 103.536058 -97.471625)
			(xy 103.565786 -97.517586) (xy 103.588634 -97.567326) (xy 103.604135 -97.619823) (xy 103.611968 -97.673997)
			(xy 103.611973 -97.728734) (xy 103.604149 -97.782909) (xy 103.588659 -97.835409) (xy 103.565819 -97.885153)
			(xy 103.5361 -97.93112) (xy 103.518462 -97.952052) (xy 103.518208 -97.952306) (xy 103.512614 -97.959387)
			(xy 103.506371 -97.976308) (xy 103.506016 -97.985326) (xy 103.506016 -98.052382) (xy 103.506378 -98.061398)
			(xy 103.512622 -98.078316) (xy 103.518208 -98.085402) (xy 103.518462 -98.085402) (xy 103.518462 -98.085656)
			(xy 103.536088 -98.106599) (xy 103.565803 -98.152568) (xy 103.588642 -98.202313) (xy 103.604136 -98.254811)
			(xy 103.611967 -98.308985) (xy 103.612442 -98.336354) (xy 103.612175 -98.35134) (xy 106.04373 -98.35134)
			(xy 106.044212 -98.32397) (xy 106.052025 -98.269792) (xy 106.06751 -98.217288) (xy 106.090348 -98.167541)
			(xy 106.12007 -98.121574) (xy 106.13771 -98.100642) (xy 106.137964 -98.100388) (xy 106.143569 -98.093315)
			(xy 106.149803 -98.076387) (xy 106.150156 -98.067368) (xy 106.150156 -98.000312) (xy 106.149803 -97.991295)
			(xy 106.143553 -97.974377) (xy 106.137964 -97.967292) (xy 106.13771 -97.967292) (xy 106.13771 -97.967038)
			(xy 106.120109 -97.946073) (xy 106.090384 -97.900111) (xy 106.067537 -97.850369) (xy 106.052039 -97.797872)
			(xy 106.044207 -97.743699) (xy 106.044202 -97.688962) (xy 106.052026 -97.634786) (xy 106.067516 -97.582287)
			(xy 106.090355 -97.532542) (xy 106.120073 -97.486575) (xy 106.13771 -97.465642) (xy 106.137964 -97.465388)
			(xy 106.143569 -97.458315) (xy 106.149803 -97.441387) (xy 106.150156 -97.432368) (xy 106.150156 -97.365312)
			(xy 106.149803 -97.356295) (xy 106.143553 -97.339377) (xy 106.137964 -97.332292) (xy 106.13771 -97.332292)
			(xy 106.13771 -97.332038) (xy 106.120077 -97.311101) (xy 106.090364 -97.26513) (xy 106.067527 -97.215384)
			(xy 106.052034 -97.162884) (xy 106.044205 -97.108709) (xy 106.04373 -97.08134) (xy 106.044216 -97.054089)
			(xy 106.051972 -97.000141) (xy 106.067327 -96.947846) (xy 106.089969 -96.898269) (xy 106.119435 -96.852419)
			(xy 106.155126 -96.811228) (xy 106.196317 -96.775537) (xy 106.242167 -96.746071) (xy 106.291744 -96.723429)
			(xy 106.344039 -96.708074) (xy 106.397987 -96.700318) (xy 106.452489 -96.700318) (xy 106.506437 -96.708074)
			(xy 106.558732 -96.723429) (xy 106.608309 -96.746071) (xy 106.654159 -96.775537) (xy 106.69535 -96.811228)
			(xy 106.731041 -96.852419) (xy 106.760507 -96.898269) (xy 106.783149 -96.947846) (xy 106.798504 -97.000141)
			(xy 106.80626 -97.054089) (xy 106.806746 -97.08134) (xy 106.806258 -97.10871) (xy 106.798447 -97.162888)
			(xy 106.782964 -97.215392) (xy 106.760127 -97.265139) (xy 106.730406 -97.311106) (xy 106.712766 -97.332038)
			(xy 106.712512 -97.332292) (xy 106.706924 -97.339378) (xy 106.700678 -97.356295) (xy 106.70032 -97.365312)
			(xy 106.70032 -97.432368) (xy 106.700688 -97.441384) (xy 106.706928 -97.458301) (xy 106.712512 -97.465388)
			(xy 106.712766 -97.465388) (xy 106.712766 -97.465642) (xy 106.730446 -97.486543) (xy 106.76017 -97.532516)
			(xy 106.783013 -97.582268) (xy 106.798507 -97.634774) (xy 106.806332 -97.688958) (xy 106.806327 -97.743703)
			(xy 106.798494 -97.797884) (xy 106.782992 -97.850389) (xy 106.760141 -97.900137) (xy 106.73041 -97.946105)
			(xy 106.712766 -97.967038) (xy 106.712512 -97.967292) (xy 106.706924 -97.974378) (xy 106.700678 -97.991295)
			(xy 106.70032 -98.000312) (xy 106.70032 -98.067368) (xy 106.700688 -98.076384) (xy 106.706928 -98.093301)
			(xy 106.712512 -98.100388) (xy 106.712766 -98.100388) (xy 106.712766 -98.100642) (xy 106.730386 -98.121589)
			(xy 106.760102 -98.167558) (xy 106.782942 -98.217301) (xy 106.798437 -98.269799) (xy 106.80627 -98.323972)
			(xy 106.806746 -98.35134) (xy 106.80626 -98.378591) (xy 106.798504 -98.432539) (xy 106.783149 -98.484834)
			(xy 106.760507 -98.534411) (xy 106.731041 -98.580261) (xy 106.69535 -98.621452) (xy 106.654159 -98.657143)
			(xy 106.608309 -98.686609) (xy 106.558732 -98.709251) (xy 106.506437 -98.724606) (xy 106.452489 -98.732362)
			(xy 106.397987 -98.732362) (xy 106.344039 -98.724606) (xy 106.291744 -98.709251) (xy 106.242167 -98.686609)
			(xy 106.196317 -98.657143) (xy 106.155126 -98.621452) (xy 106.119435 -98.580261) (xy 106.089969 -98.534411)
			(xy 106.067327 -98.484834) (xy 106.051972 -98.432539) (xy 106.044216 -98.378591) (xy 106.04373 -98.35134)
			(xy 103.612175 -98.35134) (xy 103.611956 -98.363605) (xy 103.6042 -98.417553) (xy 103.588845 -98.469848)
			(xy 103.566203 -98.519425) (xy 103.536737 -98.565275) (xy 103.501046 -98.606466) (xy 103.459855 -98.642157)
			(xy 103.414005 -98.671623) (xy 103.364428 -98.694265) (xy 103.312133 -98.70962) (xy 103.258185 -98.717376)
			(xy 103.203683 -98.717376) (xy 103.149735 -98.70962) (xy 103.09744 -98.694265) (xy 103.047863 -98.671623)
			(xy 103.002013 -98.642157) (xy 102.960822 -98.606466) (xy 102.925131 -98.565275) (xy 102.895665 -98.519425)
			(xy 102.873023 -98.469848) (xy 102.857668 -98.417553) (xy 102.849912 -98.363605) (xy 102.849426 -98.336354)
			(xy 102.273298 -98.336354) (xy 102.276236 -98.342787) (xy 102.291594 -98.395089) (xy 102.299353 -98.449045)
			(xy 102.299353 -98.503555) (xy 102.291594 -98.557511) (xy 102.276236 -98.609813) (xy 102.25359 -98.659396)
			(xy 102.224118 -98.705252) (xy 102.18842 -98.746447) (xy 102.147222 -98.782141) (xy 102.101363 -98.811609)
			(xy 102.051777 -98.834249) (xy 101.999473 -98.849602) (xy 101.945517 -98.857355) (xy 101.918262 -98.857816)
			(xy 101.891947 -98.857369) (xy 101.839818 -98.850129) (xy 101.789175 -98.835806) (xy 101.740977 -98.814669)
			(xy 101.696134 -98.78712) (xy 101.655494 -98.753679) (xy 101.637338 -98.734626) (xy 101.629801 -98.727243)
			(xy 101.610533 -98.718707) (xy 101.6 -98.718116) (xy 101.525324 -98.718116) (xy 101.514774 -98.71864)
			(xy 101.495478 -98.727178) (xy 101.487986 -98.734626) (xy 101.469835 -98.753686) (xy 101.429204 -98.787142)
			(xy 101.384363 -98.8147) (xy 101.336161 -98.835837) (xy 101.285513 -98.850154) (xy 101.233378 -98.857378)
			(xy 101.207062 -98.857816) (xy 101.179813 -98.857312) (xy 101.125871 -98.849551) (xy 101.073582 -98.834193)
			(xy 101.02401 -98.81155) (xy 100.978165 -98.782083) (xy 100.936981 -98.746393) (xy 100.901294 -98.705204)
			(xy 100.871832 -98.659356) (xy 100.849194 -98.609783) (xy 100.833841 -98.557492) (xy 100.826086 -98.503549)
			(xy 99.836082 -98.503549) (xy 99.840034 -98.508566) (xy 99.840288 -98.509074) (xy 99.851231 -98.521809)
			(xy 99.871073 -98.5489) (xy 99.879912 -98.563176) (xy 99.885246 -98.572066) (xy 99.902264 -98.584258)
			(xy 99.995482 -98.604578) (xy 100.016056 -98.60026) (xy 100.024692 -98.594418) (xy 100.048758 -98.578421)
			(xy 100.100688 -98.553077) (xy 100.155846 -98.535851) (xy 100.21297 -98.527135) (xy 100.241862 -98.5266)
			(xy 100.269117 -98.527045) (xy 100.323073 -98.534798) (xy 100.375377 -98.550151) (xy 100.424963 -98.572791)
			(xy 100.470822 -98.602259) (xy 100.51202 -98.637953) (xy 100.547718 -98.679148) (xy 100.57719 -98.725004)
			(xy 100.599836 -98.774587) (xy 100.615194 -98.826889) (xy 100.622953 -98.880845) (xy 100.622953 -98.935355)
			(xy 100.615194 -98.989311) (xy 100.599836 -99.041613) (xy 100.57719 -99.091196) (xy 100.547718 -99.137052)
			(xy 100.51202 -99.178247) (xy 100.470822 -99.213941) (xy 100.424963 -99.243409) (xy 100.375377 -99.266049)
			(xy 100.323073 -99.281402) (xy 100.269117 -99.289155) (xy 100.241862 -99.289616) (xy 100.213769 -99.289152)
			(xy 100.158191 -99.28092) (xy 100.104421 -99.264623) (xy 100.053623 -99.240615) (xy 100.006897 -99.209416)
			(xy 99.965253 -99.171699) (xy 99.929592 -99.128282) (xy 99.91471 -99.10445) (xy 99.909376 -99.09556)
			(xy 99.892358 -99.083368) (xy 99.79914 -99.063048) (xy 99.778566 -99.067366) (xy 99.76993 -99.073208)
			(xy 99.74586 -99.089198) (xy 99.693931 -99.114543) (xy 99.638775 -99.131771) (xy 99.581652 -99.14049)
			(xy 99.55276 -99.141026) (xy 99.525509 -99.140559) (xy 99.471561 -99.132798) (xy 99.419267 -99.117439)
			(xy 99.369691 -99.094794) (xy 99.323842 -99.065325) (xy 99.282652 -99.029632) (xy 99.246961 -98.988441)
			(xy 99.217495 -98.94259) (xy 99.194854 -98.893012) (xy 99.179497 -98.840717) (xy 99.171739 -98.786769)
			(xy 99.171252 -98.759518) (xy 84.561438 -98.759518) (xy 84.424565 -99.449382) (xy 87.906096 -99.449382)
			(xy 87.910167 -99.39376) (xy 87.922293 -99.339323) (xy 87.942216 -99.287232) (xy 87.969512 -99.238597)
			(xy 88.003598 -99.194454) (xy 88.043747 -99.155745) (xy 88.089105 -99.123294) (xy 88.138705 -99.097793)
			(xy 88.191489 -99.079786) (xy 88.246332 -99.069656) (xy 88.302066 -99.067619) (xy 88.357503 -99.073719)
			(xy 88.41146 -99.087825) (xy 88.462789 -99.109637) (xy 88.510395 -99.138691) (xy 88.553263 -99.174366)
			(xy 88.59048 -99.215903) (xy 88.621253 -99.262416) (xy 88.644925 -99.312913) (xy 88.660993 -99.36632)
			(xy 88.669113 -99.421496) (xy 88.669622 -99.449382) (xy 88.669455 -99.458526) (xy 93.638622 -99.458526)
			(xy 93.642693 -99.402904) (xy 93.654819 -99.348467) (xy 93.674742 -99.296376) (xy 93.702038 -99.247741)
			(xy 93.736124 -99.203598) (xy 93.776273 -99.164889) (xy 93.821631 -99.132438) (xy 93.871231 -99.106937)
			(xy 93.924015 -99.08893) (xy 93.978858 -99.0788) (xy 94.034592 -99.076763) (xy 94.090029 -99.082863)
			(xy 94.143986 -99.096969) (xy 94.195315 -99.118781) (xy 94.242921 -99.147835) (xy 94.285789 -99.18351)
			(xy 94.323006 -99.225047) (xy 94.353779 -99.27156) (xy 94.377451 -99.322057) (xy 94.393519 -99.375464)
			(xy 94.401639 -99.43064) (xy 94.402148 -99.458526) (xy 94.401639 -99.486412) (xy 94.393519 -99.541588)
			(xy 94.377451 -99.594995) (xy 94.353779 -99.645492) (xy 94.323006 -99.692005) (xy 94.285789 -99.733542)
			(xy 94.242921 -99.769217) (xy 94.195315 -99.798271) (xy 94.143986 -99.820083) (xy 94.090029 -99.834189)
			(xy 94.034592 -99.840289) (xy 93.978858 -99.838252) (xy 93.924015 -99.828122) (xy 93.871231 -99.810115)
			(xy 93.821631 -99.784614) (xy 93.776273 -99.752163) (xy 93.736124 -99.713454) (xy 93.702038 -99.669311)
			(xy 93.674742 -99.620676) (xy 93.654819 -99.568585) (xy 93.642693 -99.514148) (xy 93.638622 -99.458526)
			(xy 88.669455 -99.458526) (xy 88.669113 -99.477268) (xy 88.660993 -99.532444) (xy 88.644925 -99.585851)
			(xy 88.621253 -99.636348) (xy 88.59048 -99.682861) (xy 88.553263 -99.724398) (xy 88.510395 -99.760073)
			(xy 88.462789 -99.789127) (xy 88.41146 -99.810939) (xy 88.357503 -99.825045) (xy 88.302066 -99.831145)
			(xy 88.246332 -99.829108) (xy 88.191489 -99.818978) (xy 88.138705 -99.800971) (xy 88.089105 -99.77547)
			(xy 88.043747 -99.743019) (xy 88.003598 -99.70431) (xy 87.969512 -99.660167) (xy 87.942216 -99.611532)
			(xy 87.922293 -99.559441) (xy 87.910167 -99.505004) (xy 87.906096 -99.449382) (xy 84.424565 -99.449382)
			(xy 84.079247 -101.189848) (xy 96.99349 -101.189848) (xy 96.99349 -101.135352) (xy 97.001245 -101.08141)
			(xy 97.016598 -101.02912) (xy 97.039235 -100.979547) (xy 97.068696 -100.933701) (xy 97.104382 -100.892513)
			(xy 97.145565 -100.856822) (xy 97.191409 -100.827356) (xy 97.240979 -100.804713) (xy 97.293266 -100.789355)
			(xy 97.347208 -100.781593) (xy 97.374456 -100.781104) (xy 97.401825 -100.781595) (xy 97.456003 -100.789407)
			(xy 97.508506 -100.80489) (xy 97.558254 -100.827726) (xy 97.604221 -100.857445) (xy 97.625154 -100.875084)
			(xy 97.625408 -100.875338) (xy 97.632485 -100.880938) (xy 97.649409 -100.887176) (xy 97.658428 -100.88753)
			(xy 97.725484 -100.88753) (xy 97.734499 -100.887159) (xy 97.751416 -100.88092) (xy 97.758504 -100.875338)
			(xy 97.758504 -100.875084) (xy 97.758758 -100.875084) (xy 97.779693 -100.857449) (xy 97.825665 -100.827737)
			(xy 97.875412 -100.8049) (xy 97.927912 -100.789408) (xy 97.982087 -100.781579) (xy 98.009456 -100.781104)
			(xy 98.036712 -100.78154) (xy 98.090669 -100.789292) (xy 98.142974 -100.804645) (xy 98.192561 -100.827285)
			(xy 98.238422 -100.856753) (xy 98.279621 -100.892448) (xy 98.31532 -100.933643) (xy 98.344793 -100.9795)
			(xy 98.36744 -101.029085) (xy 98.382799 -101.081388) (xy 98.390557 -101.135344) (xy 98.390557 -101.189856)
			(xy 98.382799 -101.243812) (xy 98.36744 -101.296115) (xy 98.344793 -101.3457) (xy 98.31532 -101.391557)
			(xy 98.279621 -101.432752) (xy 98.238422 -101.468447) (xy 98.192561 -101.497915) (xy 98.142974 -101.520555)
			(xy 98.090669 -101.535908) (xy 98.036712 -101.54366) (xy 98.009456 -101.54412) (xy 97.982086 -101.543641)
			(xy 97.927907 -101.535829) (xy 97.875403 -101.520344) (xy 97.825656 -101.497505) (xy 97.779689 -101.467781)
			(xy 97.758758 -101.45014) (xy 97.758504 -101.449886) (xy 97.751422 -101.444293) (xy 97.734502 -101.438051)
			(xy 97.725484 -101.437694) (xy 97.658428 -101.437694) (xy 97.649413 -101.438066) (xy 97.632496 -101.444303)
			(xy 97.625408 -101.449886) (xy 97.625408 -101.45014) (xy 97.625154 -101.45014) (xy 97.604218 -101.467774)
			(xy 97.558246 -101.497485) (xy 97.508499 -101.520322) (xy 97.455999 -101.535814) (xy 97.401825 -101.543645)
			(xy 97.374456 -101.54412) (xy 97.347208 -101.543607) (xy 97.293266 -101.535845) (xy 97.240979 -101.520487)
			(xy 97.191409 -101.497844) (xy 97.145565 -101.468378) (xy 97.104382 -101.432687) (xy 97.068696 -101.391499)
			(xy 97.039235 -101.345653) (xy 97.016598 -101.29608) (xy 97.001245 -101.24379) (xy 96.99349 -101.189848)
			(xy 84.079247 -101.189848) (xy 84.002003 -101.579172) (xy 87.770714 -101.579172) (xy 87.774785 -101.52355)
			(xy 87.786911 -101.469113) (xy 87.806834 -101.417022) (xy 87.83413 -101.368387) (xy 87.868216 -101.324244)
			(xy 87.908365 -101.285535) (xy 87.953723 -101.253084) (xy 88.003323 -101.227583) (xy 88.056107 -101.209576)
			(xy 88.11095 -101.199446) (xy 88.166684 -101.197409) (xy 88.222121 -101.203509) (xy 88.276078 -101.217615)
			(xy 88.327407 -101.239427) (xy 88.375013 -101.268481) (xy 88.417881 -101.304156) (xy 88.455098 -101.345693)
			(xy 88.485871 -101.392206) (xy 88.509543 -101.442703) (xy 88.525611 -101.49611) (xy 88.533731 -101.551286)
			(xy 88.53424 -101.579172) (xy 88.533731 -101.607058) (xy 88.525611 -101.662234) (xy 88.509543 -101.715641)
			(xy 88.485871 -101.766138) (xy 88.455098 -101.812651) (xy 88.417881 -101.854188) (xy 88.397963 -101.870764)
			(xy 93.23908 -101.870764) (xy 93.243151 -101.815142) (xy 93.255277 -101.760705) (xy 93.2752 -101.708614)
			(xy 93.302496 -101.659979) (xy 93.336582 -101.615836) (xy 93.376731 -101.577127) (xy 93.422089 -101.544676)
			(xy 93.471689 -101.519175) (xy 93.524473 -101.501168) (xy 93.579316 -101.491038) (xy 93.63505 -101.489001)
			(xy 93.690487 -101.495101) (xy 93.744444 -101.509207) (xy 93.795773 -101.531019) (xy 93.843379 -101.560073)
			(xy 93.886247 -101.595748) (xy 93.923464 -101.637285) (xy 93.954237 -101.683798) (xy 93.977909 -101.734295)
			(xy 93.993977 -101.787702) (xy 94.002097 -101.842878) (xy 94.002606 -101.870764) (xy 94.002097 -101.89865)
			(xy 93.993977 -101.953826) (xy 93.977909 -102.007233) (xy 93.954237 -102.05773) (xy 93.923464 -102.104243)
			(xy 93.899978 -102.130455) (xy 96.543029 -102.130455) (xy 96.543029 -102.075945) (xy 96.550787 -102.021989)
			(xy 96.566145 -101.969686) (xy 96.58879 -101.920102) (xy 96.618261 -101.874245) (xy 96.653959 -101.833049)
			(xy 96.695156 -101.797353) (xy 96.741014 -101.767883) (xy 96.790599 -101.74524) (xy 96.842902 -101.729884)
			(xy 96.896859 -101.722128) (xy 96.924114 -101.721666) (xy 96.951485 -101.722108) (xy 97.005666 -101.729929)
			(xy 97.05817 -101.745423) (xy 97.107917 -101.76827) (xy 97.153882 -101.798001) (xy 97.174812 -101.815646)
			(xy 97.175066 -101.8159) (xy 97.182158 -101.821478) (xy 97.199071 -101.82773) (xy 97.208086 -101.828092)
			(xy 97.275142 -101.828092) (xy 97.284156 -101.827709) (xy 97.301073 -101.82148) (xy 97.308162 -101.8159)
			(xy 97.308162 -101.815646) (xy 97.308416 -101.815646) (xy 97.329375 -101.79804) (xy 97.37534 -101.768322)
			(xy 97.42508 -101.745479) (xy 97.477575 -101.72998) (xy 97.531747 -101.722144) (xy 97.559114 -101.721666)
			(xy 97.586363 -101.722205) (xy 97.640305 -101.729963) (xy 97.692595 -101.745318) (xy 97.742167 -101.767958)
			(xy 97.788012 -101.797423) (xy 97.829198 -101.833112) (xy 97.864885 -101.874299) (xy 97.894348 -101.920146)
			(xy 97.916987 -101.969719) (xy 97.93234 -102.022009) (xy 97.940096 -102.075951) (xy 97.940096 -102.130449)
			(xy 97.93234 -102.184391) (xy 97.916987 -102.236681) (xy 97.894348 -102.286254) (xy 97.864885 -102.332101)
			(xy 97.829198 -102.373288) (xy 97.788012 -102.408977) (xy 97.742167 -102.438442) (xy 97.692595 -102.461082)
			(xy 97.640305 -102.476437) (xy 97.586363 -102.484195) (xy 97.559114 -102.484682) (xy 97.531744 -102.484212)
			(xy 97.477565 -102.476396) (xy 97.425062 -102.460908) (xy 97.375315 -102.438067) (xy 97.329348 -102.408343)
			(xy 97.308416 -102.390702) (xy 97.308162 -102.390448) (xy 97.301066 -102.384875) (xy 97.284156 -102.378621)
			(xy 97.275142 -102.378256) (xy 97.208086 -102.378256) (xy 97.199067 -102.378594) (xy 97.18215 -102.384854)
			(xy 97.175066 -102.390448) (xy 97.175066 -102.390702) (xy 97.174812 -102.390702) (xy 97.153886 -102.408349)
			(xy 97.107912 -102.43806) (xy 97.058163 -102.460894) (xy 97.005661 -102.476383) (xy 96.951484 -102.484209)
			(xy 96.924114 -102.484682) (xy 96.896859 -102.484272) (xy 96.842902 -102.476516) (xy 96.790599 -102.46116)
			(xy 96.741014 -102.438517) (xy 96.695156 -102.409047) (xy 96.653959 -102.373351) (xy 96.618261 -102.332155)
			(xy 96.58879 -102.286298) (xy 96.566145 -102.236714) (xy 96.550787 -102.184411) (xy 96.543029 -102.130455)
			(xy 93.899978 -102.130455) (xy 93.886247 -102.14578) (xy 93.843379 -102.181455) (xy 93.795773 -102.210509)
			(xy 93.744444 -102.232321) (xy 93.690487 -102.246427) (xy 93.63505 -102.252527) (xy 93.579316 -102.25049)
			(xy 93.524473 -102.24036) (xy 93.471689 -102.222353) (xy 93.422089 -102.196852) (xy 93.376731 -102.164401)
			(xy 93.336582 -102.125692) (xy 93.302496 -102.081549) (xy 93.2752 -102.032914) (xy 93.255277 -101.980823)
			(xy 93.243151 -101.926386) (xy 93.23908 -101.870764) (xy 88.397963 -101.870764) (xy 88.375013 -101.889863)
			(xy 88.327407 -101.918917) (xy 88.276078 -101.940729) (xy 88.222121 -101.954835) (xy 88.166684 -101.960935)
			(xy 88.11095 -101.958898) (xy 88.056107 -101.948768) (xy 88.003323 -101.930761) (xy 87.953723 -101.90526)
			(xy 87.908365 -101.872809) (xy 87.868216 -101.8341) (xy 87.83413 -101.789957) (xy 87.806834 -101.741322)
			(xy 87.786911 -101.689231) (xy 87.774785 -101.634794) (xy 87.770714 -101.579172) (xy 84.002003 -101.579172)
			(xy 83.692477 -103.13924) (xy 89.507058 -103.13924) (xy 89.511129 -103.083618) (xy 89.523255 -103.029181)
			(xy 89.543178 -102.97709) (xy 89.570474 -102.928455) (xy 89.60456 -102.884312) (xy 89.644709 -102.845603)
			(xy 89.690067 -102.813152) (xy 89.739667 -102.787651) (xy 89.792451 -102.769644) (xy 89.847294 -102.759514)
			(xy 89.903028 -102.757477) (xy 89.958465 -102.763577) (xy 90.012422 -102.777683) (xy 90.063751 -102.799495)
			(xy 90.111357 -102.828549) (xy 90.154225 -102.864224) (xy 90.191442 -102.905761) (xy 90.222215 -102.952274)
			(xy 90.245887 -103.002771) (xy 90.261955 -103.056178) (xy 90.270075 -103.111354) (xy 90.270584 -103.13924)
			(xy 90.270075 -103.167126) (xy 90.261955 -103.222302) (xy 90.245887 -103.275709) (xy 90.222215 -103.326206)
			(xy 90.191442 -103.372719) (xy 90.154225 -103.414256) (xy 90.111357 -103.449931) (xy 90.063751 -103.478985)
			(xy 90.012422 -103.500797) (xy 89.958465 -103.514903) (xy 89.903028 -103.521003) (xy 89.847294 -103.518966)
			(xy 89.792451 -103.508836) (xy 89.739667 -103.490829) (xy 89.690067 -103.465328) (xy 89.644709 -103.432877)
			(xy 89.60456 -103.394168) (xy 89.570474 -103.350025) (xy 89.543178 -103.30139) (xy 89.523255 -103.249299)
			(xy 89.511129 -103.194862) (xy 89.507058 -103.13924) (xy 83.692477 -103.13924) (xy 83.387789 -104.674924)
			(xy 88.559384 -104.674924) (xy 88.563455 -104.619302) (xy 88.575581 -104.564865) (xy 88.595504 -104.512774)
			(xy 88.6228 -104.464139) (xy 88.656886 -104.419996) (xy 88.697035 -104.381287) (xy 88.742393 -104.348836)
			(xy 88.791993 -104.323335) (xy 88.844777 -104.305328) (xy 88.89962 -104.295198) (xy 88.955354 -104.293161)
			(xy 89.010791 -104.299261) (xy 89.064748 -104.313367) (xy 89.116077 -104.335179) (xy 89.163683 -104.364233)
			(xy 89.206551 -104.399908) (xy 89.243768 -104.441445) (xy 89.274541 -104.487958) (xy 89.298213 -104.538455)
			(xy 89.314281 -104.591862) (xy 89.322401 -104.647038) (xy 89.32291 -104.674924) (xy 89.322401 -104.70281)
			(xy 89.314281 -104.757986) (xy 89.298213 -104.811393) (xy 89.274541 -104.86189) (xy 89.243768 -104.908403)
			(xy 89.206551 -104.94994) (xy 89.163683 -104.985615) (xy 89.116077 -105.014669) (xy 89.064748 -105.036481)
			(xy 89.010791 -105.050587) (xy 88.955354 -105.056687) (xy 88.89962 -105.05465) (xy 88.844777 -105.04452)
			(xy 88.791993 -105.026513) (xy 88.742393 -105.001012) (xy 88.697035 -104.968561) (xy 88.656886 -104.929852)
			(xy 88.6228 -104.885709) (xy 88.595504 -104.837074) (xy 88.575581 -104.784983) (xy 88.563455 -104.730546)
			(xy 88.559384 -104.674924) (xy 83.387789 -104.674924) (xy 82.884746 -107.210352) (xy 85.74278 -107.210352)
			(xy 85.74328 -107.181612) (xy 85.751909 -107.124784) (xy 85.768965 -107.069893) (xy 85.794062 -107.018182)
			(xy 85.826631 -106.97082) (xy 85.845904 -106.949494) (xy 85.852508 -106.942636) (xy 85.85962 -106.924602)
			(xy 85.85962 -106.835702) (xy 85.852508 -106.817668) (xy 85.845904 -106.81081) (xy 85.826587 -106.789524)
			(xy 85.794025 -106.742154) (xy 85.768937 -106.690435) (xy 85.751891 -106.635539) (xy 85.743274 -106.578706)
			(xy 85.743279 -106.521224) (xy 85.751907 -106.464393) (xy 85.768963 -106.409499) (xy 85.79406 -106.357785)
			(xy 85.826631 -106.310421) (xy 85.845904 -106.289094) (xy 85.852508 -106.282236) (xy 85.85962 -106.264202)
			(xy 85.85962 -106.175302) (xy 85.852508 -106.157268) (xy 85.845904 -106.15041) (xy 85.826622 -106.129093)
			(xy 85.794055 -106.081729) (xy 85.768963 -106.030015) (xy 85.751916 -105.975122) (xy 85.743298 -105.918292)
			(xy 85.74278 -105.889552) (xy 85.743266 -105.862301) (xy 85.751022 -105.808353) (xy 85.766377 -105.756058)
			(xy 85.789019 -105.706481) (xy 85.818485 -105.660631) (xy 85.854176 -105.61944) (xy 85.895367 -105.583749)
			(xy 85.941217 -105.554283) (xy 85.990794 -105.531641) (xy 86.043089 -105.516286) (xy 86.097037 -105.50853)
			(xy 86.151539 -105.50853) (xy 86.205487 -105.516286) (xy 86.257782 -105.531641) (xy 86.307359 -105.554283)
			(xy 86.353209 -105.583749) (xy 86.3944 -105.61944) (xy 86.430091 -105.660631) (xy 86.459557 -105.706481)
			(xy 86.482199 -105.756058) (xy 86.497554 -105.808353) (xy 86.50531 -105.862301) (xy 86.505796 -105.889552)
			(xy 86.505305 -105.918292) (xy 86.496675 -105.975121) (xy 86.479617 -106.030012) (xy 86.454518 -106.081723)
			(xy 86.421946 -106.129084) (xy 86.402672 -106.15041) (xy 86.396068 -106.157268) (xy 86.388956 -106.175302)
			(xy 86.388956 -106.264202) (xy 86.396068 -106.282236) (xy 86.402672 -106.289094) (xy 86.421895 -106.310462)
			(xy 86.454463 -106.357817) (xy 86.479557 -106.409522) (xy 86.496611 -106.464407) (xy 86.505238 -106.521229)
			(xy 86.505243 -106.578702) (xy 86.496626 -106.635525) (xy 86.479583 -106.690412) (xy 86.454498 -106.742122)
			(xy 86.421939 -106.789483) (xy 86.402672 -106.81081) (xy 86.396068 -106.817668) (xy 86.388956 -106.835702)
			(xy 86.388956 -106.924602) (xy 86.396068 -106.942636) (xy 86.402672 -106.949494) (xy 86.421969 -106.970798)
			(xy 86.454531 -107.018167) (xy 86.473954 -107.058206) (xy 89.573862 -107.058206) (xy 89.5744 -107.029468)
			(xy 89.58302 -106.972641) (xy 89.600068 -106.917751) (xy 89.625156 -106.866039) (xy 89.657717 -106.818676)
			(xy 89.676986 -106.797348) (xy 89.68359 -106.79049) (xy 89.690702 -106.772456) (xy 89.690702 -106.683556)
			(xy 89.68359 -106.665522) (xy 89.676986 -106.658664) (xy 89.657723 -106.637331) (xy 89.625161 -106.589969)
			(xy 89.600071 -106.538258) (xy 89.583023 -106.483368) (xy 89.5744 -106.426542) (xy 89.5744 -106.369066)
			(xy 89.583021 -106.31224) (xy 89.600068 -106.257351) (xy 89.625156 -106.205639) (xy 89.657717 -106.158276)
			(xy 89.676986 -106.136948) (xy 89.68359 -106.13009) (xy 89.690702 -106.112056) (xy 89.690702 -106.023156)
			(xy 89.68359 -106.005122) (xy 89.676986 -105.998264) (xy 89.657726 -105.976927) (xy 89.625156 -105.929569)
			(xy 89.600061 -105.87786) (xy 89.583008 -105.822971) (xy 89.574384 -105.766145) (xy 89.573862 -105.737406)
			(xy 89.574348 -105.710155) (xy 89.582104 -105.656207) (xy 89.597459 -105.603912) (xy 89.620101 -105.554335)
			(xy 89.649567 -105.508485) (xy 89.685258 -105.467294) (xy 89.726449 -105.431603) (xy 89.772299 -105.402137)
			(xy 89.821876 -105.379495) (xy 89.874171 -105.36414) (xy 89.928119 -105.356384) (xy 89.982621 -105.356384)
			(xy 90.036569 -105.36414) (xy 90.088864 -105.379495) (xy 90.138441 -105.402137) (xy 90.184291 -105.431603)
			(xy 90.225482 -105.467294) (xy 90.261173 -105.508485) (xy 90.290639 -105.554335) (xy 90.313281 -105.603912)
			(xy 90.328636 -105.656207) (xy 90.336392 -105.710155) (xy 90.336878 -105.737406) (xy 90.336337 -105.766144)
			(xy 90.327715 -105.82297) (xy 90.310668 -105.877859) (xy 90.285581 -105.929571) (xy 90.253022 -105.976936)
			(xy 90.233754 -105.998264) (xy 90.22715 -106.005122) (xy 90.220038 -106.023156) (xy 90.220038 -106.112056)
			(xy 90.22715 -106.13009) (xy 90.233754 -106.136948) (xy 90.253032 -106.158269) (xy 90.285599 -106.205632)
			(xy 90.310691 -106.257344) (xy 90.327742 -106.312236) (xy 90.336365 -106.369065) (xy 90.336364 -106.426544)
			(xy 90.32774 -106.483372) (xy 90.310688 -106.538264) (xy 90.285594 -106.589976) (xy 90.253026 -106.637338)
			(xy 90.233754 -106.658664) (xy 90.22715 -106.665522) (xy 90.220038 -106.683556) (xy 90.220038 -106.772456)
			(xy 90.22715 -106.79049) (xy 90.233754 -106.797348) (xy 90.253026 -106.818674) (xy 90.285593 -106.866036)
			(xy 90.310685 -106.917748) (xy 90.327735 -106.972639) (xy 90.336357 -107.029467) (xy 90.336878 -107.058206)
			(xy 90.336392 -107.085457) (xy 90.328636 -107.139405) (xy 90.313281 -107.1917) (xy 90.290639 -107.241277)
			(xy 90.261173 -107.287127) (xy 90.225482 -107.328318) (xy 90.184291 -107.364009) (xy 90.138441 -107.393475)
			(xy 90.088864 -107.416117) (xy 90.036569 -107.431472) (xy 89.982621 -107.439228) (xy 89.928119 -107.439228)
			(xy 89.874171 -107.431472) (xy 89.821876 -107.416117) (xy 89.772299 -107.393475) (xy 89.726449 -107.364009)
			(xy 89.685258 -107.328318) (xy 89.649567 -107.287127) (xy 89.620101 -107.241277) (xy 89.597459 -107.1917)
			(xy 89.582104 -107.139405) (xy 89.574348 -107.085457) (xy 89.573862 -107.058206) (xy 86.473954 -107.058206)
			(xy 86.479619 -107.069884) (xy 86.496663 -107.12478) (xy 86.505279 -107.181611) (xy 86.505796 -107.210352)
			(xy 86.50531 -107.237603) (xy 86.497554 -107.291551) (xy 86.482199 -107.343846) (xy 86.459557 -107.393423)
			(xy 86.430091 -107.439273) (xy 86.3944 -107.480464) (xy 86.353209 -107.516155) (xy 86.307359 -107.545621)
			(xy 86.257782 -107.568263) (xy 86.205487 -107.583618) (xy 86.151539 -107.591374) (xy 86.097037 -107.591374)
			(xy 86.043089 -107.583618) (xy 85.990794 -107.568263) (xy 85.941217 -107.545621) (xy 85.895367 -107.516155)
			(xy 85.854176 -107.480464) (xy 85.818485 -107.439273) (xy 85.789019 -107.393423) (xy 85.766377 -107.343846)
			(xy 85.751022 -107.291551) (xy 85.743266 -107.237603) (xy 85.74278 -107.210352) (xy 82.884746 -107.210352)
			(xy 82.652879 -108.379006) (xy 90.462862 -108.379006) (xy 90.4634 -108.350268) (xy 90.47202 -108.293441)
			(xy 90.489068 -108.238551) (xy 90.514156 -108.186839) (xy 90.546717 -108.139476) (xy 90.565986 -108.118148)
			(xy 90.57259 -108.11129) (xy 90.579702 -108.093256) (xy 90.579702 -108.004356) (xy 90.57259 -107.986322)
			(xy 90.565986 -107.979464) (xy 90.546723 -107.958131) (xy 90.514161 -107.910769) (xy 90.489071 -107.859058)
			(xy 90.472023 -107.804168) (xy 90.4634 -107.747342) (xy 90.4634 -107.689866) (xy 90.472021 -107.63304)
			(xy 90.489068 -107.578151) (xy 90.514156 -107.526439) (xy 90.546717 -107.479076) (xy 90.565986 -107.457748)
			(xy 90.57259 -107.45089) (xy 90.579702 -107.432856) (xy 90.579702 -107.343956) (xy 90.57259 -107.325922)
			(xy 90.565986 -107.319064) (xy 90.546723 -107.297731) (xy 90.514161 -107.250369) (xy 90.489071 -107.198658)
			(xy 90.472023 -107.143768) (xy 90.4634 -107.086942) (xy 90.4634 -107.029466) (xy 90.472021 -106.97264)
			(xy 90.489068 -106.917751) (xy 90.514156 -106.866039) (xy 90.546717 -106.818676) (xy 90.565986 -106.797348)
			(xy 90.57259 -106.79049) (xy 90.579702 -106.772456) (xy 90.579702 -106.683556) (xy 90.57259 -106.665522)
			(xy 90.565986 -106.658664) (xy 90.546723 -106.637331) (xy 90.514161 -106.589969) (xy 90.489071 -106.538258)
			(xy 90.472023 -106.483368) (xy 90.4634 -106.426542) (xy 90.4634 -106.369066) (xy 90.472021 -106.31224)
			(xy 90.489068 -106.257351) (xy 90.514156 -106.205639) (xy 90.546717 -106.158276) (xy 90.565986 -106.136948)
			(xy 90.57259 -106.13009) (xy 90.579702 -106.112056) (xy 90.579702 -106.023156) (xy 90.57259 -106.005122)
			(xy 90.565986 -105.998264) (xy 90.546723 -105.976931) (xy 90.514161 -105.929569) (xy 90.489071 -105.877858)
			(xy 90.472023 -105.822968) (xy 90.4634 -105.766142) (xy 90.4634 -105.708666) (xy 90.472021 -105.65184)
			(xy 90.489068 -105.596951) (xy 90.514156 -105.545239) (xy 90.546717 -105.497876) (xy 90.565986 -105.476548)
			(xy 90.57259 -105.46969) (xy 90.579702 -105.451656) (xy 90.579702 -105.362756) (xy 90.57259 -105.344722)
			(xy 90.565986 -105.337864) (xy 90.546723 -105.316531) (xy 90.514161 -105.269169) (xy 90.489071 -105.217458)
			(xy 90.472023 -105.162568) (xy 90.4634 -105.105742) (xy 90.4634 -105.048266) (xy 90.472021 -104.99144)
			(xy 90.489068 -104.936551) (xy 90.514156 -104.884839) (xy 90.546717 -104.837476) (xy 90.565986 -104.816148)
			(xy 90.57259 -104.80929) (xy 90.579702 -104.791256) (xy 90.579702 -104.702356) (xy 90.57259 -104.684322)
			(xy 90.565986 -104.677464) (xy 90.546723 -104.656131) (xy 90.514161 -104.608769) (xy 90.489071 -104.557058)
			(xy 90.472023 -104.502168) (xy 90.4634 -104.445342) (xy 90.4634 -104.387866) (xy 90.472021 -104.33104)
			(xy 90.489068 -104.276151) (xy 90.514156 -104.224439) (xy 90.546717 -104.177076) (xy 90.565986 -104.155748)
			(xy 90.57259 -104.14889) (xy 90.579702 -104.130856) (xy 90.579702 -104.041956) (xy 90.57259 -104.023922)
			(xy 90.565986 -104.017064) (xy 90.546723 -103.995731) (xy 90.514161 -103.948369) (xy 90.489071 -103.896658)
			(xy 90.472023 -103.841768) (xy 90.4634 -103.784942) (xy 90.4634 -103.727466) (xy 90.472021 -103.67064)
			(xy 90.489068 -103.615751) (xy 90.514156 -103.564039) (xy 90.546717 -103.516676) (xy 90.565986 -103.495348)
			(xy 90.57259 -103.48849) (xy 90.579702 -103.470456) (xy 90.579702 -103.381556) (xy 90.57259 -103.363522)
			(xy 90.565986 -103.356664) (xy 90.546726 -103.335327) (xy 90.514156 -103.287969) (xy 90.489061 -103.23626)
			(xy 90.472008 -103.181371) (xy 90.463384 -103.124545) (xy 90.462862 -103.095806) (xy 90.463323 -103.068599)
			(xy 90.471046 -103.014737) (xy 90.486351 -102.962521) (xy 90.508926 -102.913012) (xy 90.538312 -102.867217)
			(xy 90.573912 -102.826066) (xy 90.615003 -102.790397) (xy 90.637614 -102.775258) (xy 90.645996 -102.769924)
			(xy 90.657172 -102.753668) (xy 90.67546 -102.674674) (xy 90.67726 -102.665044) (xy 90.674266 -102.645705)
			(xy 90.669618 -102.637082) (xy 90.669364 -102.637082) (xy 90.669364 -102.636574) (xy 90.656155 -102.614065)
			(xy 90.635301 -102.566222) (xy 90.621152 -102.515987) (xy 90.613969 -102.464294) (xy 90.613484 -102.4382)
			(xy 90.61397 -102.410949) (xy 90.621726 -102.357001) (xy 90.637081 -102.304706) (xy 90.659723 -102.255129)
			(xy 90.689189 -102.209279) (xy 90.72488 -102.168088) (xy 90.766071 -102.132397) (xy 90.811921 -102.102931)
			(xy 90.861498 -102.080289) (xy 90.913793 -102.064934) (xy 90.967741 -102.057178) (xy 91.022243 -102.057178)
			(xy 91.076191 -102.064934) (xy 91.128486 -102.080289) (xy 91.178063 -102.102931) (xy 91.223913 -102.132397)
			(xy 91.265104 -102.168088) (xy 91.300795 -102.209279) (xy 91.330261 -102.255129) (xy 91.352903 -102.304706)
			(xy 91.368258 -102.357001) (xy 91.376014 -102.410949) (xy 91.3765 -102.4382) (xy 91.376061 -102.465408)
			(xy 91.368336 -102.519271) (xy 91.353029 -102.571489) (xy 91.330451 -102.620999) (xy 91.301061 -102.666794)
			(xy 91.265456 -102.707943) (xy 91.224361 -102.743611) (xy 91.201748 -102.758748) (xy 91.193366 -102.764082)
			(xy 91.18219 -102.780338) (xy 91.163902 -102.859332) (xy 91.16209 -102.868961) (xy 91.16509 -102.888303)
			(xy 91.169744 -102.896924) (xy 91.169998 -102.896924) (xy 91.169998 -102.897432) (xy 91.183206 -102.919942)
			(xy 91.204061 -102.967784) (xy 91.218211 -103.018019) (xy 91.225393 -103.069712) (xy 91.225878 -103.095806)
			(xy 91.225337 -103.124544) (xy 91.216715 -103.18137) (xy 91.199668 -103.236259) (xy 91.174581 -103.287971)
			(xy 91.142022 -103.335336) (xy 91.122754 -103.356664) (xy 91.11615 -103.363522) (xy 91.109038 -103.381556)
			(xy 91.109038 -103.470456) (xy 91.11615 -103.48849) (xy 91.122754 -103.495348) (xy 91.142032 -103.516669)
			(xy 91.174599 -103.564032) (xy 91.199691 -103.615744) (xy 91.216742 -103.670636) (xy 91.225365 -103.727465)
			(xy 91.225364 -103.784944) (xy 91.21674 -103.841772) (xy 91.199688 -103.896664) (xy 91.174594 -103.948376)
			(xy 91.142026 -103.995738) (xy 91.122754 -104.017064) (xy 91.117128 -104.022906) (xy 95.86595 -104.022906)
			(xy 95.866405 -103.996591) (xy 95.873641 -103.944462) (xy 95.887961 -103.893818) (xy 95.909095 -103.845619)
			(xy 95.936644 -103.800776) (xy 95.970087 -103.760138) (xy 95.98914 -103.741982) (xy 95.996543 -103.734461)
			(xy 96.005069 -103.715181) (xy 96.00565 -103.704644) (xy 96.00565 -103.629968) (xy 96.005083 -103.619423)
			(xy 95.996573 -103.600128) (xy 95.98914 -103.59263) (xy 95.970095 -103.574465) (xy 95.936639 -103.533836)
			(xy 95.90908 -103.488997) (xy 95.88794 -103.440798) (xy 95.87362 -103.390153) (xy 95.866391 -103.338021)
			(xy 95.86595 -103.311706) (xy 95.866483 -103.284457) (xy 95.874238 -103.230513) (xy 95.88959 -103.178222)
			(xy 95.912227 -103.128647) (xy 95.941689 -103.082799) (xy 95.977376 -103.04161) (xy 96.01856 -103.005918)
			(xy 96.064405 -102.97645) (xy 96.113977 -102.953807) (xy 96.166266 -102.938448) (xy 96.220209 -102.930687)
			(xy 96.247458 -102.930198) (xy 96.275122 -102.930744) (xy 96.329869 -102.938737) (xy 96.38289 -102.954548)
			(xy 96.433074 -102.977846) (xy 96.47937 -103.008142) (xy 96.520809 -103.044802) (xy 96.556524 -103.087059)
			(xy 96.571562 -103.110284) (xy 96.578207 -103.119953) (xy 96.598063 -103.1324) (xy 96.609662 -103.13416)
			(xy 96.689672 -103.142034) (xy 96.70131 -103.142646) (xy 96.723146 -103.13458) (xy 96.731582 -103.12654)
			(xy 96.731836 -103.126286) (xy 96.749915 -103.107703) (xy 96.790247 -103.075125) (xy 96.834622 -103.048312)
			(xy 96.882221 -103.02776) (xy 96.932166 -103.013847) (xy 96.983535 -103.00683) (xy 97.009458 -103.006398)
			(xy 97.03671 -103.006894) (xy 97.09066 -103.014646) (xy 97.142958 -103.029997) (xy 97.192538 -103.052635)
			(xy 97.238392 -103.082099) (xy 97.279585 -103.117789) (xy 97.315279 -103.158979) (xy 97.344748 -103.20483)
			(xy 97.367391 -103.254408) (xy 97.382747 -103.306705) (xy 97.390503 -103.360654) (xy 97.390966 -103.387906)
			(xy 97.390512 -103.415277) (xy 97.382692 -103.469457) (xy 97.367201 -103.52196) (xy 97.344356 -103.571707)
			(xy 97.314629 -103.617673) (xy 97.296986 -103.638604) (xy 97.296732 -103.638858) (xy 97.291149 -103.645947)
			(xy 97.284902 -103.662862) (xy 97.28454 -103.671878) (xy 97.28454 -103.68565) (xy 108.492794 -103.68565)
			(xy 108.492794 -103.63115) (xy 108.50055 -103.577205) (xy 108.515905 -103.524912) (xy 108.538545 -103.475338)
			(xy 108.56801 -103.429489) (xy 108.603699 -103.388301) (xy 108.644888 -103.352611) (xy 108.690736 -103.323146)
			(xy 108.740311 -103.300505) (xy 108.792603 -103.285151) (xy 108.846548 -103.277394) (xy 108.873798 -103.276908)
			(xy 108.900112 -103.277374) (xy 108.952241 -103.284609) (xy 109.002884 -103.298928) (xy 109.051083 -103.320061)
			(xy 109.095926 -103.347607) (xy 109.136566 -103.381046) (xy 109.154722 -103.400098) (xy 109.162234 -103.407511)
			(xy 109.181521 -103.416029) (xy 109.19206 -103.416608) (xy 109.266736 -103.416608) (xy 109.277283 -103.416056)
			(xy 109.296579 -103.407537) (xy 109.304074 -103.400098) (xy 109.323894 -103.37931) (xy 109.368666 -103.343335)
			(xy 109.418324 -103.314475) (xy 109.471746 -103.293382) (xy 109.527725 -103.280533) (xy 109.584998 -103.276218)
			(xy 109.642271 -103.280533) (xy 109.69825 -103.293382) (xy 109.751672 -103.314475) (xy 109.80133 -103.343335)
			(xy 109.846102 -103.37931) (xy 109.865922 -103.400098) (xy 109.873434 -103.407511) (xy 109.892721 -103.416029)
			(xy 109.90326 -103.416608) (xy 109.977936 -103.416608) (xy 109.988483 -103.416056) (xy 110.007779 -103.407537)
			(xy 110.015274 -103.400098) (xy 110.033449 -103.381062) (xy 110.074074 -103.347603) (xy 110.118911 -103.320041)
			(xy 110.167108 -103.2989) (xy 110.217752 -103.284578) (xy 110.269883 -103.277349) (xy 110.296198 -103.276908)
			(xy 110.323452 -103.277339) (xy 110.377406 -103.285096) (xy 110.429706 -103.300452) (xy 110.479288 -103.323096)
			(xy 110.525144 -103.352565) (xy 110.566338 -103.38826) (xy 110.602034 -103.429455) (xy 110.631503 -103.47531)
			(xy 110.654147 -103.524892) (xy 110.669504 -103.577192) (xy 110.677261 -103.631146) (xy 110.677261 -103.685654)
			(xy 110.669504 -103.739608) (xy 110.654147 -103.791908) (xy 110.631503 -103.84149) (xy 110.602034 -103.887345)
			(xy 110.566338 -103.92854) (xy 110.525144 -103.964235) (xy 110.479288 -103.993704) (xy 110.429706 -104.016348)
			(xy 110.377406 -104.031704) (xy 110.323452 -104.039461) (xy 110.296198 -104.039924) (xy 110.269884 -104.03945)
			(xy 110.217756 -104.032216) (xy 110.167114 -104.017897) (xy 110.118915 -103.996766) (xy 110.074072 -103.969221)
			(xy 110.033431 -103.935785) (xy 110.015274 -103.916734) (xy 110.00776 -103.909324) (xy 109.988474 -103.900803)
			(xy 109.977936 -103.900224) (xy 109.90326 -103.900224) (xy 109.892712 -103.900765) (xy 109.873416 -103.909291)
			(xy 109.865922 -103.916734) (xy 109.846102 -103.937522) (xy 109.80133 -103.973497) (xy 109.751672 -104.002357)
			(xy 109.69825 -104.02345) (xy 109.642271 -104.036299) (xy 109.584998 -104.040614) (xy 109.527725 -104.036299)
			(xy 109.471746 -104.02345) (xy 109.418324 -104.002357) (xy 109.368666 -103.973497) (xy 109.323894 -103.937522)
			(xy 109.304074 -103.916734) (xy 109.29656 -103.909324) (xy 109.277274 -103.900803) (xy 109.266736 -103.900224)
			(xy 109.19206 -103.900224) (xy 109.181512 -103.900765) (xy 109.162216 -103.909291) (xy 109.154722 -103.916734)
			(xy 109.136555 -103.935778) (xy 109.095927 -103.969235) (xy 109.051089 -103.996795) (xy 109.002891 -104.017935)
			(xy 108.952245 -104.032255) (xy 108.900113 -104.039483) (xy 108.873798 -104.039924) (xy 108.846548 -104.039406)
			(xy 108.792603 -104.031649) (xy 108.740311 -104.016295) (xy 108.690736 -103.993654) (xy 108.644888 -103.964189)
			(xy 108.603699 -103.928499) (xy 108.56801 -103.887311) (xy 108.538545 -103.841462) (xy 108.515905 -103.791888)
			(xy 108.50055 -103.739595) (xy 108.492794 -103.68565) (xy 97.28454 -103.68565) (xy 97.28454 -103.738934)
			(xy 97.284872 -103.747954) (xy 97.291136 -103.764871) (xy 97.296732 -103.771954) (xy 97.296986 -103.771954)
			(xy 97.296986 -103.772208) (xy 97.31464 -103.793128) (xy 97.34435 -103.839104) (xy 97.367183 -103.888854)
			(xy 97.382671 -103.941358) (xy 97.390495 -103.995536) (xy 97.390966 -104.022906) (xy 97.39055 -104.050161)
			(xy 97.382791 -104.104116) (xy 97.367432 -104.156417) (xy 97.344786 -104.206) (xy 97.315314 -104.251855)
			(xy 97.279615 -104.293049) (xy 97.238417 -104.328742) (xy 97.192558 -104.358209) (xy 97.142972 -104.380849)
			(xy 97.090669 -104.396201) (xy 97.036713 -104.403954) (xy 97.009458 -104.404414) (xy 96.980541 -104.403886)
			(xy 96.923369 -104.395164) (xy 96.868169 -104.37791) (xy 96.816206 -104.35252) (xy 96.768673 -104.319576)
			(xy 96.726657 -104.279834) (xy 96.708468 -104.257348) (xy 96.700874 -104.248527) (xy 96.679963 -104.238353)
			(xy 96.668336 -104.23779) (xy 96.58858 -104.23779) (xy 96.576949 -104.238336) (xy 96.55604 -104.24852)
			(xy 96.548448 -104.257348) (xy 96.530242 -104.279818) (xy 96.488224 -104.319552) (xy 96.440692 -104.352491)
			(xy 96.388734 -104.377882) (xy 96.333539 -104.395141) (xy 96.276373 -104.403876) (xy 96.247458 -104.404414)
			(xy 96.220206 -104.403961) (xy 96.166257 -104.396199) (xy 96.113962 -104.380839) (xy 96.064385 -104.358193)
			(xy 96.018536 -104.328723) (xy 95.977346 -104.293029) (xy 95.941655 -104.251836) (xy 95.912189 -104.205983)
			(xy 95.889548 -104.156404) (xy 95.874193 -104.104107) (xy 95.866436 -104.050158) (xy 95.86595 -104.022906)
			(xy 91.117128 -104.022906) (xy 91.11615 -104.023922) (xy 91.109038 -104.041956) (xy 91.109038 -104.130856)
			(xy 91.11615 -104.14889) (xy 91.122754 -104.155748) (xy 91.142032 -104.177069) (xy 91.174599 -104.224432)
			(xy 91.199691 -104.276144) (xy 91.216742 -104.331036) (xy 91.225365 -104.387865) (xy 91.225364 -104.445344)
			(xy 91.21674 -104.502172) (xy 91.199688 -104.557064) (xy 91.174594 -104.608776) (xy 91.142026 -104.656138)
			(xy 91.122754 -104.677464) (xy 91.11615 -104.684322) (xy 91.109038 -104.702356) (xy 91.109038 -104.791256)
			(xy 91.11615 -104.80929) (xy 91.122754 -104.816148) (xy 91.142032 -104.837469) (xy 91.174599 -104.884832)
			(xy 91.199691 -104.936544) (xy 91.216742 -104.991436) (xy 91.225365 -105.048265) (xy 91.225364 -105.084455)
			(xy 95.743949 -105.084455) (xy 95.743949 -105.029945) (xy 95.751707 -104.975991) (xy 95.767065 -104.92369)
			(xy 95.78971 -104.874107) (xy 95.819181 -104.828252) (xy 95.854879 -104.787058) (xy 95.896076 -104.751363)
			(xy 95.941933 -104.721896) (xy 95.991518 -104.699255) (xy 96.04382 -104.683901) (xy 96.097775 -104.676147)
			(xy 96.12503 -104.675686) (xy 96.152401 -104.676138) (xy 96.20658 -104.68396) (xy 96.259083 -104.699452)
			(xy 96.30883 -104.722297) (xy 96.354796 -104.752024) (xy 96.375728 -104.769666) (xy 96.375982 -104.76992)
			(xy 96.383068 -104.775507) (xy 96.399985 -104.781753) (xy 96.409002 -104.782112) (xy 96.476058 -104.782112)
			(xy 96.485073 -104.781732) (xy 96.50199 -104.7755) (xy 96.509078 -104.76992) (xy 96.509078 -104.769666)
			(xy 96.509332 -104.769666) (xy 96.530265 -104.752025) (xy 96.576233 -104.722301) (xy 96.625979 -104.699455)
			(xy 96.678481 -104.683959) (xy 96.732659 -104.67613) (xy 96.787401 -104.67613) (xy 96.841579 -104.683959)
			(xy 96.894081 -104.699455) (xy 96.943827 -104.722301) (xy 96.989795 -104.752025) (xy 97.010728 -104.769666)
			(xy 97.010982 -104.76992) (xy 97.018068 -104.775507) (xy 97.034985 -104.781753) (xy 97.044002 -104.782112)
			(xy 97.111058 -104.782112) (xy 97.120073 -104.781732) (xy 97.13699 -104.7755) (xy 97.144078 -104.76992)
			(xy 97.144078 -104.769666) (xy 97.144332 -104.769666) (xy 97.165265 -104.752025) (xy 97.211233 -104.722301)
			(xy 97.260979 -104.699455) (xy 97.313481 -104.683959) (xy 97.367659 -104.67613) (xy 97.422401 -104.67613)
			(xy 97.476579 -104.683959) (xy 97.529081 -104.699455) (xy 97.578827 -104.722301) (xy 97.624795 -104.752025)
			(xy 97.645728 -104.769666) (xy 97.645982 -104.76992) (xy 97.653068 -104.775507) (xy 97.669985 -104.781753)
			(xy 97.679002 -104.782112) (xy 97.746058 -104.782112) (xy 97.755073 -104.781732) (xy 97.77199 -104.7755)
			(xy 97.779078 -104.76992) (xy 97.779078 -104.769666) (xy 97.779332 -104.769666) (xy 97.800275 -104.75204)
			(xy 97.846245 -104.722327) (xy 97.89599 -104.699489) (xy 97.948488 -104.683995) (xy 98.002662 -104.676163)
			(xy 98.03003 -104.675686) (xy 98.057279 -104.676186) (xy 98.111223 -104.683946) (xy 98.163513 -104.699303)
			(xy 98.213086 -104.721946) (xy 98.258932 -104.751412) (xy 98.300118 -104.787103) (xy 98.335806 -104.828292)
			(xy 98.365269 -104.87414) (xy 98.387907 -104.923715) (xy 98.403261 -104.976006) (xy 98.411016 -105.029951)
			(xy 98.411016 -105.084449) (xy 98.403261 -105.138394) (xy 98.387907 -105.190685) (xy 98.365269 -105.24026)
			(xy 98.335806 -105.286108) (xy 98.300118 -105.327297) (xy 98.258932 -105.362988) (xy 98.213086 -105.392454)
			(xy 98.163513 -105.415097) (xy 98.111223 -105.430454) (xy 98.057279 -105.438214) (xy 98.03003 -105.438702)
			(xy 98.00266 -105.438218) (xy 97.948482 -105.430404) (xy 97.895979 -105.414919) (xy 97.846232 -105.392082)
			(xy 97.800264 -105.362361) (xy 97.779332 -105.344722) (xy 97.779078 -105.344468) (xy 97.772005 -105.338863)
			(xy 97.755078 -105.332628) (xy 97.746058 -105.332276) (xy 97.679002 -105.332276) (xy 97.669986 -105.332639)
			(xy 97.653069 -105.338883) (xy 97.645982 -105.344468) (xy 97.645728 -105.344722) (xy 97.624795 -105.362363)
			(xy 97.578827 -105.392087) (xy 97.529081 -105.414933) (xy 97.476579 -105.430429) (xy 97.422401 -105.438258)
			(xy 97.367659 -105.438258) (xy 97.313481 -105.430429) (xy 97.260979 -105.414933) (xy 97.211233 -105.392087)
			(xy 97.165265 -105.362363) (xy 97.144332 -105.344722) (xy 97.144078 -105.344468) (xy 97.137005 -105.338863)
			(xy 97.120078 -105.332628) (xy 97.111058 -105.332276) (xy 97.044002 -105.332276) (xy 97.034986 -105.332639)
			(xy 97.018069 -105.338883) (xy 97.010982 -105.344468) (xy 97.010982 -105.344722) (xy 97.010728 -105.344722)
			(xy 96.989795 -105.362363) (xy 96.943827 -105.392087) (xy 96.894081 -105.414933) (xy 96.841579 -105.430429)
			(xy 96.787401 -105.438258) (xy 96.732659 -105.438258) (xy 96.678481 -105.430429) (xy 96.625979 -105.414933)
			(xy 96.576233 -105.392087) (xy 96.530265 -105.362363) (xy 96.509332 -105.344722) (xy 96.509078 -105.344468)
			(xy 96.502005 -105.338863) (xy 96.485078 -105.332628) (xy 96.476058 -105.332276) (xy 96.409002 -105.332276)
			(xy 96.399986 -105.332639) (xy 96.383069 -105.338883) (xy 96.375982 -105.344468) (xy 96.375982 -105.344722)
			(xy 96.375728 -105.344722) (xy 96.354799 -105.362365) (xy 96.308825 -105.392075) (xy 96.259077 -105.41491)
			(xy 96.206575 -105.4304) (xy 96.152399 -105.438228) (xy 96.12503 -105.438702) (xy 96.097775 -105.438253)
			(xy 96.04382 -105.430499) (xy 95.991518 -105.415145) (xy 95.941933 -105.392504) (xy 95.896076 -105.363037)
			(xy 95.854879 -105.327342) (xy 95.819181 -105.286148) (xy 95.78971 -105.240293) (xy 95.767065 -105.19071)
			(xy 95.751707 -105.138409) (xy 95.743949 -105.084455) (xy 91.225364 -105.084455) (xy 91.225364 -105.105744)
			(xy 91.21674 -105.162572) (xy 91.199688 -105.217464) (xy 91.174594 -105.269176) (xy 91.142026 -105.316538)
			(xy 91.122754 -105.337864) (xy 91.11615 -105.344722) (xy 91.109038 -105.362756) (xy 91.109038 -105.451656)
			(xy 91.11615 -105.46969) (xy 91.122754 -105.476548) (xy 91.142032 -105.497869) (xy 91.174599 -105.545232)
			(xy 91.199691 -105.596944) (xy 91.216742 -105.651836) (xy 91.225365 -105.708665) (xy 91.225364 -105.766144)
			(xy 91.21674 -105.822972) (xy 91.199688 -105.877864) (xy 91.174594 -105.929576) (xy 91.142026 -105.976938)
			(xy 91.122754 -105.998264) (xy 91.11615 -106.005122) (xy 91.109038 -106.023156) (xy 91.109038 -106.112056)
			(xy 91.11615 -106.13009) (xy 91.122754 -106.136948) (xy 91.142032 -106.158269) (xy 91.174599 -106.205632)
			(xy 91.199691 -106.257344) (xy 91.216742 -106.312236) (xy 91.225365 -106.369065) (xy 91.225364 -106.426544)
			(xy 91.21674 -106.483372) (xy 91.199688 -106.538264) (xy 91.174594 -106.589976) (xy 91.142026 -106.637338)
			(xy 91.122754 -106.658664) (xy 91.11615 -106.665522) (xy 91.109038 -106.683556) (xy 91.109038 -106.772456)
			(xy 91.11615 -106.79049) (xy 91.122754 -106.797348) (xy 91.127367 -106.80245) (xy 108.420905 -106.80245)
			(xy 108.420905 -106.74795) (xy 108.428662 -106.694005) (xy 108.444016 -106.641712) (xy 108.466657 -106.592138)
			(xy 108.496123 -106.54629) (xy 108.531814 -106.505102) (xy 108.573003 -106.469413) (xy 108.618852 -106.439949)
			(xy 108.668427 -106.417311) (xy 108.72072 -106.401958) (xy 108.774666 -106.394204) (xy 108.801916 -106.393742)
			(xy 108.828231 -106.394185) (xy 108.880361 -106.401423) (xy 108.931005 -106.415746) (xy 108.979204 -106.436883)
			(xy 109.024047 -106.464434) (xy 109.064685 -106.497878) (xy 109.08284 -106.516932) (xy 109.090354 -106.524343)
			(xy 109.109639 -106.532865) (xy 109.120178 -106.533442) (xy 109.194854 -106.533442) (xy 109.205401 -106.532889)
			(xy 109.224695 -106.524369) (xy 109.232192 -106.516932) (xy 109.252012 -106.496144) (xy 109.296784 -106.460169)
			(xy 109.346442 -106.431309) (xy 109.399864 -106.410216) (xy 109.455843 -106.397367) (xy 109.513116 -106.393052)
			(xy 109.570389 -106.397367) (xy 109.626368 -106.410216) (xy 109.67979 -106.431309) (xy 109.729448 -106.460169)
			(xy 109.77422 -106.496144) (xy 109.79404 -106.516932) (xy 109.801554 -106.524343) (xy 109.820839 -106.532865)
			(xy 109.831378 -106.533442) (xy 109.906054 -106.533442) (xy 109.916601 -106.532889) (xy 109.935895 -106.524369)
			(xy 109.943392 -106.516932) (xy 109.961565 -106.497893) (xy 110.00219 -106.464434) (xy 110.047026 -106.436871)
			(xy 110.095224 -106.41573) (xy 110.145869 -106.401409) (xy 110.198001 -106.394182) (xy 110.224316 -106.393742)
			(xy 110.25157 -106.394129) (xy 110.305523 -106.401888) (xy 110.357823 -106.417247) (xy 110.407405 -106.439892)
			(xy 110.453259 -106.469362) (xy 110.494453 -106.505059) (xy 110.530147 -106.546254) (xy 110.559616 -106.59211)
			(xy 110.582259 -106.641692) (xy 110.597615 -106.693993) (xy 110.605372 -106.747946) (xy 110.605372 -106.802454)
			(xy 110.597615 -106.856407) (xy 110.582259 -106.908708) (xy 110.559616 -106.95829) (xy 110.530147 -107.004146)
			(xy 110.494453 -107.045341) (xy 110.453259 -107.081038) (xy 110.407405 -107.110508) (xy 110.357823 -107.133153)
			(xy 110.305523 -107.148512) (xy 110.25157 -107.156271) (xy 110.224316 -107.156758) (xy 110.198002 -107.156293)
			(xy 110.145873 -107.14906) (xy 110.095229 -107.134741) (xy 110.04703 -107.113608) (xy 110.002187 -107.086061)
			(xy 109.961548 -107.052621) (xy 109.943392 -107.033568) (xy 109.935866 -107.026171) (xy 109.91659 -107.017642)
			(xy 109.906054 -107.017058) (xy 109.831378 -107.017058) (xy 109.820833 -107.017628) (xy 109.801538 -107.026136)
			(xy 109.79404 -107.033568) (xy 109.77422 -107.054356) (xy 109.729448 -107.090331) (xy 109.67979 -107.119191)
			(xy 109.626368 -107.140284) (xy 109.570389 -107.153133) (xy 109.513116 -107.157448) (xy 109.455843 -107.153133)
			(xy 109.399864 -107.140284) (xy 109.346442 -107.119191) (xy 109.296784 -107.090331) (xy 109.252012 -107.054356)
			(xy 109.232192 -107.033568) (xy 109.224666 -107.026171) (xy 109.20539 -107.017642) (xy 109.194854 -107.017058)
			(xy 109.120178 -107.017058) (xy 109.109633 -107.017628) (xy 109.090338 -107.026136) (xy 109.08284 -107.033568)
			(xy 109.0647 -107.05264) (xy 109.024068 -107.086096) (xy 108.979225 -107.113654) (xy 108.931021 -107.13479)
			(xy 108.88037 -107.149103) (xy 108.828233 -107.156323) (xy 108.801916 -107.156758) (xy 108.774666 -107.156196)
			(xy 108.72072 -107.148442) (xy 108.668427 -107.133089) (xy 108.618852 -107.110451) (xy 108.573003 -107.080987)
			(xy 108.531813 -107.045298) (xy 108.496123 -107.00411) (xy 108.466657 -106.958262) (xy 108.444016 -106.908688)
			(xy 108.428662 -106.856395) (xy 108.420905 -106.80245) (xy 91.127367 -106.80245) (xy 91.142032 -106.818669)
			(xy 91.174599 -106.866032) (xy 91.199691 -106.917744) (xy 91.216742 -106.972636) (xy 91.225365 -107.029465)
			(xy 91.225364 -107.086944) (xy 91.21674 -107.143772) (xy 91.199688 -107.198664) (xy 91.174594 -107.250376)
			(xy 91.142026 -107.297738) (xy 91.122754 -107.319064) (xy 91.11615 -107.325922) (xy 91.109038 -107.343956)
			(xy 91.109038 -107.432856) (xy 91.11615 -107.45089) (xy 91.122754 -107.457748) (xy 91.142032 -107.479069)
			(xy 91.174599 -107.526432) (xy 91.199691 -107.578144) (xy 91.216742 -107.633036) (xy 91.225365 -107.689865)
			(xy 91.225364 -107.740253) (xy 95.684273 -107.740253) (xy 95.684273 -107.685747) (xy 95.692031 -107.631795)
			(xy 95.707388 -107.579496) (xy 95.730033 -107.529916) (xy 95.759503 -107.484063) (xy 95.795199 -107.442871)
			(xy 95.836395 -107.407179) (xy 95.882251 -107.377714) (xy 95.931834 -107.355074) (xy 95.984134 -107.339723)
			(xy 96.038087 -107.331971) (xy 96.06534 -107.33151) (xy 96.092709 -107.332009) (xy 96.146887 -107.339818)
			(xy 96.19939 -107.3553) (xy 96.249137 -107.378134) (xy 96.295105 -107.407852) (xy 96.316038 -107.42549)
			(xy 96.316292 -107.425744) (xy 96.323373 -107.431339) (xy 96.340294 -107.437579) (xy 96.349312 -107.437936)
			(xy 96.416368 -107.437936) (xy 96.425382 -107.437556) (xy 96.442299 -107.431323) (xy 96.449388 -107.425744)
			(xy 96.449388 -107.42549) (xy 96.449642 -107.42549) (xy 96.470575 -107.407849) (xy 96.516543 -107.378125)
			(xy 96.566289 -107.355279) (xy 96.618791 -107.339783) (xy 96.672969 -107.331954) (xy 96.727711 -107.331954)
			(xy 96.781889 -107.339783) (xy 96.834391 -107.355279) (xy 96.884137 -107.378125) (xy 96.930105 -107.407849)
			(xy 96.951038 -107.42549) (xy 96.951292 -107.425744) (xy 96.958373 -107.431339) (xy 96.975294 -107.437579)
			(xy 96.984312 -107.437936) (xy 97.051368 -107.437936) (xy 97.060382 -107.437556) (xy 97.077299 -107.431323)
			(xy 97.084388 -107.425744) (xy 97.084388 -107.42549) (xy 97.084642 -107.42549) (xy 97.105575 -107.407849)
			(xy 97.151543 -107.378125) (xy 97.201289 -107.355279) (xy 97.253791 -107.339783) (xy 97.307969 -107.331954)
			(xy 97.362711 -107.331954) (xy 97.416889 -107.339783) (xy 97.469391 -107.355279) (xy 97.519137 -107.378125)
			(xy 97.565105 -107.407849) (xy 97.586038 -107.42549) (xy 97.586292 -107.425744) (xy 97.593373 -107.431339)
			(xy 97.610294 -107.437579) (xy 97.619312 -107.437936) (xy 97.686368 -107.437936) (xy 97.695382 -107.437556)
			(xy 97.712299 -107.431323) (xy 97.719388 -107.425744) (xy 97.719388 -107.42549) (xy 97.719642 -107.42549)
			(xy 97.740584 -107.407863) (xy 97.786554 -107.37815) (xy 97.836299 -107.355312) (xy 97.888798 -107.339818)
			(xy 97.942972 -107.331986) (xy 97.97034 -107.33151) (xy 97.997591 -107.331963) (xy 98.051537 -107.339724)
			(xy 98.103829 -107.355083) (xy 98.153404 -107.377728) (xy 98.199251 -107.407197) (xy 98.240438 -107.44289)
			(xy 98.276127 -107.484081) (xy 98.305591 -107.529932) (xy 98.328231 -107.579508) (xy 98.343584 -107.631803)
			(xy 98.35134 -107.685749) (xy 98.35134 -107.740251) (xy 98.343584 -107.794197) (xy 98.328231 -107.846492)
			(xy 98.305591 -107.896068) (xy 98.276127 -107.941919) (xy 98.240438 -107.98311) (xy 98.199251 -108.018803)
			(xy 98.153404 -108.048272) (xy 98.103829 -108.070917) (xy 98.051537 -108.086276) (xy 97.997591 -108.094037)
			(xy 97.97034 -108.094526) (xy 97.94297 -108.094055) (xy 97.88879 -108.086241) (xy 97.836286 -108.070754)
			(xy 97.786539 -108.047913) (xy 97.740573 -108.018188) (xy 97.719642 -108.000546) (xy 97.719388 -108.000292)
			(xy 97.71231 -107.994693) (xy 97.695387 -107.988454) (xy 97.686368 -107.9881) (xy 97.619312 -107.9881)
			(xy 97.610296 -107.988463) (xy 97.593379 -107.994706) (xy 97.586292 -108.000292) (xy 97.586038 -108.000546)
			(xy 97.565105 -108.018187) (xy 97.519137 -108.047911) (xy 97.469391 -108.070757) (xy 97.416889 -108.086253)
			(xy 97.362711 -108.094082) (xy 97.307969 -108.094082) (xy 97.253791 -108.086253) (xy 97.201289 -108.070757)
			(xy 97.151543 -108.047911) (xy 97.105575 -108.018187) (xy 97.084642 -108.000546) (xy 97.084388 -108.000292)
			(xy 97.07731 -107.994693) (xy 97.060387 -107.988454) (xy 97.051368 -107.9881) (xy 96.984312 -107.9881)
			(xy 96.975296 -107.988463) (xy 96.958379 -107.994706) (xy 96.951292 -108.000292) (xy 96.951292 -108.000546)
			(xy 96.951038 -108.000546) (xy 96.930105 -108.018187) (xy 96.884137 -108.047911) (xy 96.834391 -108.070757)
			(xy 96.781889 -108.086253) (xy 96.727711 -108.094082) (xy 96.672969 -108.094082) (xy 96.618791 -108.086253)
			(xy 96.566289 -108.070757) (xy 96.516543 -108.047911) (xy 96.470575 -108.018187) (xy 96.449642 -108.000546)
			(xy 96.449388 -108.000292) (xy 96.44231 -107.994693) (xy 96.425387 -107.988454) (xy 96.416368 -107.9881)
			(xy 96.349312 -107.9881) (xy 96.340296 -107.988463) (xy 96.323379 -107.994706) (xy 96.316292 -108.000292)
			(xy 96.316292 -108.000546) (xy 96.316038 -108.000546) (xy 96.295095 -108.018172) (xy 96.249126 -108.047888)
			(xy 96.199382 -108.070727) (xy 96.146883 -108.086221) (xy 96.092709 -108.094051) (xy 96.06534 -108.094526)
			(xy 96.038087 -108.094029) (xy 95.984134 -108.086277) (xy 95.931834 -108.070926) (xy 95.882251 -108.048286)
			(xy 95.836395 -108.018821) (xy 95.795199 -107.983129) (xy 95.759503 -107.941937) (xy 95.730033 -107.896084)
			(xy 95.707388 -107.846504) (xy 95.692031 -107.794205) (xy 95.684273 -107.740253) (xy 91.225364 -107.740253)
			(xy 91.225364 -107.747344) (xy 91.21674 -107.804172) (xy 91.199688 -107.859064) (xy 91.174594 -107.910776)
			(xy 91.142026 -107.958138) (xy 91.122754 -107.979464) (xy 91.11615 -107.986322) (xy 91.109038 -108.004356)
			(xy 91.109038 -108.093256) (xy 91.11615 -108.11129) (xy 91.122754 -108.118148) (xy 91.142026 -108.139474)
			(xy 91.174593 -108.186836) (xy 91.199685 -108.238548) (xy 91.216735 -108.293439) (xy 91.225357 -108.350267)
			(xy 91.225878 -108.379006) (xy 91.225392 -108.406257) (xy 91.217636 -108.460205) (xy 91.202281 -108.5125)
			(xy 91.179639 -108.562077) (xy 91.174865 -108.569506) (xy 106.861102 -108.569506) (xy 106.861571 -108.542136)
			(xy 106.869388 -108.487957) (xy 106.884876 -108.435454) (xy 106.907718 -108.385707) (xy 106.937441 -108.33974)
			(xy 106.955082 -108.318808) (xy 106.955336 -108.318554) (xy 106.96091 -108.311459) (xy 106.967163 -108.294549)
			(xy 106.967528 -108.285534) (xy 106.967528 -108.218478) (xy 106.967176 -108.209461) (xy 106.960924 -108.192544)
			(xy 106.955336 -108.185458) (xy 106.955082 -108.185458) (xy 106.955082 -108.185204) (xy 106.937429 -108.164284)
			(xy 106.907719 -108.118307) (xy 106.884887 -108.068557) (xy 106.869399 -108.016054) (xy 106.861574 -107.961876)
			(xy 106.861102 -107.934506) (xy 106.861588 -107.907255) (xy 106.869344 -107.853307) (xy 106.884699 -107.801012)
			(xy 106.907341 -107.751435) (xy 106.936807 -107.705585) (xy 106.972498 -107.664394) (xy 107.013689 -107.628703)
			(xy 107.059539 -107.599237) (xy 107.109116 -107.576595) (xy 107.161411 -107.56124) (xy 107.215359 -107.553484)
			(xy 107.269861 -107.553484) (xy 107.323809 -107.56124) (xy 107.376104 -107.576595) (xy 107.425681 -107.599237)
			(xy 107.471531 -107.628703) (xy 107.512722 -107.664394) (xy 107.548413 -107.705585) (xy 107.577879 -107.751435)
			(xy 107.600521 -107.801012) (xy 107.615876 -107.853307) (xy 107.623632 -107.907255) (xy 107.624118 -107.934506)
			(xy 107.623675 -107.961877) (xy 107.615855 -108.016058) (xy 107.600362 -108.068562) (xy 107.577514 -108.118309)
			(xy 107.547783 -108.164274) (xy 107.530138 -108.185204) (xy 107.529884 -108.185458) (xy 107.524307 -108.192551)
			(xy 107.518055 -108.209463) (xy 107.517692 -108.218478) (xy 107.517692 -108.285534) (xy 107.518035 -108.294552)
			(xy 107.524293 -108.311469) (xy 107.529884 -108.318554) (xy 107.530138 -108.318554) (xy 107.530138 -108.318808)
			(xy 107.547801 -108.339721) (xy 107.577508 -108.3857) (xy 107.600339 -108.435452) (xy 107.615824 -108.487957)
			(xy 107.623647 -108.542136) (xy 107.624118 -108.569506) (xy 107.623632 -108.596757) (xy 107.615876 -108.650705)
			(xy 107.600521 -108.703) (xy 107.577879 -108.752577) (xy 107.548413 -108.798427) (xy 107.512722 -108.839618)
			(xy 107.471531 -108.875309) (xy 107.425681 -108.904775) (xy 107.376104 -108.927417) (xy 107.323809 -108.942772)
			(xy 107.269861 -108.950528) (xy 107.215359 -108.950528) (xy 107.161411 -108.942772) (xy 107.109116 -108.927417)
			(xy 107.059539 -108.904775) (xy 107.013689 -108.875309) (xy 106.972498 -108.839618) (xy 106.936807 -108.798427)
			(xy 106.907341 -108.752577) (xy 106.884699 -108.703) (xy 106.869344 -108.650705) (xy 106.861588 -108.596757)
			(xy 106.861102 -108.569506) (xy 91.174865 -108.569506) (xy 91.150173 -108.607927) (xy 91.114482 -108.649118)
			(xy 91.073291 -108.684809) (xy 91.027441 -108.714275) (xy 90.977864 -108.736917) (xy 90.925569 -108.752272)
			(xy 90.871621 -108.760028) (xy 90.817119 -108.760028) (xy 90.763171 -108.752272) (xy 90.710876 -108.736917)
			(xy 90.661299 -108.714275) (xy 90.615449 -108.684809) (xy 90.574258 -108.649118) (xy 90.538567 -108.607927)
			(xy 90.509101 -108.562077) (xy 90.486459 -108.5125) (xy 90.471104 -108.460205) (xy 90.463348 -108.406257)
			(xy 90.462862 -108.379006) (xy 82.652879 -108.379006) (xy 82.429982 -109.502448) (xy 109.414562 -109.502448)
			(xy 109.418633 -109.446826) (xy 109.430759 -109.392389) (xy 109.450682 -109.340298) (xy 109.477978 -109.291663)
			(xy 109.512064 -109.24752) (xy 109.552213 -109.208811) (xy 109.597571 -109.17636) (xy 109.647171 -109.150859)
			(xy 109.699955 -109.132852) (xy 109.754798 -109.122722) (xy 109.810532 -109.120685) (xy 109.865969 -109.126785)
			(xy 109.919926 -109.140891) (xy 109.971255 -109.162703) (xy 110.018861 -109.191757) (xy 110.061729 -109.227432)
			(xy 110.098946 -109.268969) (xy 110.129719 -109.315482) (xy 110.153391 -109.365979) (xy 110.169459 -109.419386)
			(xy 110.177579 -109.474562) (xy 110.178088 -109.502448) (xy 110.177579 -109.530334) (xy 110.169459 -109.58551)
			(xy 110.153391 -109.638917) (xy 110.129719 -109.689414) (xy 110.098946 -109.735927) (xy 110.061729 -109.777464)
			(xy 110.018861 -109.813139) (xy 109.971255 -109.842193) (xy 109.919926 -109.864005) (xy 109.865969 -109.878111)
			(xy 109.810532 -109.884211) (xy 109.754798 -109.882174) (xy 109.699955 -109.872044) (xy 109.647171 -109.854037)
			(xy 109.597571 -109.828536) (xy 109.552213 -109.796085) (xy 109.512064 -109.757376) (xy 109.477978 -109.713233)
			(xy 109.450682 -109.664598) (xy 109.430759 -109.612507) (xy 109.418633 -109.55807) (xy 109.414562 -109.502448)
			(xy 82.429982 -109.502448) (xy 82.207942 -110.621572) (xy 90.56116 -110.621572) (xy 90.56159 -110.595257)
			(xy 90.568829 -110.543126) (xy 90.583155 -110.492481) (xy 90.604294 -110.444282) (xy 90.631848 -110.39944)
			(xy 90.665294 -110.358803) (xy 90.68435 -110.340648) (xy 90.691769 -110.333141) (xy 90.700285 -110.31385)
			(xy 90.70086 -110.30331) (xy 90.70086 -110.228634) (xy 90.700338 -110.218083) (xy 90.691799 -110.198787)
			(xy 90.68435 -110.191296) (xy 90.66529 -110.173145) (xy 90.631835 -110.132513) (xy 90.604278 -110.087672)
			(xy 90.583141 -110.03947) (xy 90.568824 -109.988822) (xy 90.561599 -109.936688) (xy 90.56116 -109.910372)
			(xy 90.561646 -109.883121) (xy 90.569402 -109.829173) (xy 90.584757 -109.776878) (xy 90.607399 -109.727301)
			(xy 90.636865 -109.681451) (xy 90.672556 -109.64026) (xy 90.713747 -109.604569) (xy 90.759597 -109.575103)
			(xy 90.809174 -109.552461) (xy 90.861469 -109.537106) (xy 90.915417 -109.52935) (xy 90.969919 -109.52935)
			(xy 91.023867 -109.537106) (xy 91.076162 -109.552461) (xy 91.125739 -109.575103) (xy 91.171589 -109.604569)
			(xy 91.21278 -109.64026) (xy 91.248471 -109.681451) (xy 91.277937 -109.727301) (xy 91.300579 -109.776878)
			(xy 91.315934 -109.829173) (xy 91.32369 -109.883121) (xy 91.324176 -109.910372) (xy 91.323764 -109.936688)
			(xy 91.316519 -109.988819) (xy 91.30219 -110.039463) (xy 91.281047 -110.087662) (xy 91.253491 -110.132504)
			(xy 91.220042 -110.173141) (xy 91.200986 -110.191296) (xy 91.193582 -110.198815) (xy 91.185059 -110.218097)
			(xy 91.184476 -110.228634) (xy 91.184476 -110.30331) (xy 91.184993 -110.313861) (xy 91.193538 -110.333156)
			(xy 91.200986 -110.340648) (xy 91.220055 -110.35879) (xy 91.253512 -110.399422) (xy 91.281069 -110.444265)
			(xy 91.302205 -110.492469) (xy 91.316519 -110.543119) (xy 91.32374 -110.595255) (xy 91.324176 -110.621572)
			(xy 91.32369 -110.648823) (xy 91.315934 -110.702771) (xy 91.300579 -110.755066) (xy 91.277937 -110.804643)
			(xy 91.248471 -110.850493) (xy 91.21278 -110.891684) (xy 91.171589 -110.927375) (xy 91.125739 -110.956841)
			(xy 91.076162 -110.979483) (xy 91.023867 -110.994838) (xy 90.969919 -111.002594) (xy 90.915417 -111.002594)
			(xy 90.861469 -110.994838) (xy 90.809174 -110.979483) (xy 90.759597 -110.956841) (xy 90.713747 -110.927375)
			(xy 90.672556 -110.891684) (xy 90.636865 -110.850493) (xy 90.607399 -110.804643) (xy 90.584757 -110.755066)
			(xy 90.569402 -110.702771) (xy 90.561646 -110.648823) (xy 90.56116 -110.621572) (xy 82.207942 -110.621572)
			(xy 81.875335 -112.297972) (xy 93.069918 -112.297972) (xy 93.070361 -112.271657) (xy 93.0776 -112.219527)
			(xy 93.091924 -112.168884) (xy 93.113061 -112.120685) (xy 93.140611 -112.075842) (xy 93.174054 -112.035204)
			(xy 93.193108 -112.017048) (xy 93.200536 -112.009549) (xy 93.209045 -111.990252) (xy 93.209618 -111.97971)
			(xy 93.209618 -111.905034) (xy 93.209079 -111.894486) (xy 93.20055 -111.875191) (xy 93.193108 -111.867696)
			(xy 93.174059 -111.849534) (xy 93.140601 -111.808906) (xy 93.113041 -111.764067) (xy 93.091901 -111.715867)
			(xy 93.077583 -111.665221) (xy 93.070357 -111.613088) (xy 93.069918 -111.586772) (xy 93.070404 -111.559521)
			(xy 93.07816 -111.505573) (xy 93.093515 -111.453278) (xy 93.116157 -111.403701) (xy 93.145623 -111.357851)
			(xy 93.181314 -111.31666) (xy 93.222505 -111.280969) (xy 93.268355 -111.251503) (xy 93.317932 -111.228861)
			(xy 93.370227 -111.213506) (xy 93.424175 -111.20575) (xy 93.478677 -111.20575) (xy 93.532625 -111.213506)
			(xy 93.58492 -111.228861) (xy 93.634497 -111.251503) (xy 93.680347 -111.280969) (xy 93.721538 -111.31666)
			(xy 93.757229 -111.357851) (xy 93.786695 -111.403701) (xy 93.809337 -111.453278) (xy 93.824692 -111.505573)
			(xy 93.832448 -111.559521) (xy 93.832934 -111.586772) (xy 93.832504 -111.613087) (xy 93.82526 -111.665217)
			(xy 93.810933 -111.71586) (xy 93.789793 -111.764058) (xy 93.762241 -111.808901) (xy 93.728798 -111.84954)
			(xy 93.709744 -111.867696) (xy 93.702349 -111.875223) (xy 93.693819 -111.894499) (xy 93.693234 -111.905034)
			(xy 93.693234 -111.97971) (xy 93.693734 -111.990263) (xy 93.702289 -112.009559) (xy 93.709744 -112.017048)
			(xy 93.728824 -112.035179) (xy 93.762277 -112.075815) (xy 93.789832 -112.12066) (xy 93.810966 -112.168866)
			(xy 93.825278 -112.219517) (xy 93.832498 -112.271655) (xy 93.832934 -112.297972) (xy 95.101918 -112.297972)
			(xy 95.102361 -112.271657) (xy 95.1096 -112.219527) (xy 95.123924 -112.168884) (xy 95.145061 -112.120685)
			(xy 95.172611 -112.075842) (xy 95.206054 -112.035204) (xy 95.225108 -112.017048) (xy 95.232536 -112.009549)
			(xy 95.241045 -111.990252) (xy 95.241618 -111.97971) (xy 95.241618 -111.905034) (xy 95.241079 -111.894486)
			(xy 95.23255 -111.875191) (xy 95.225108 -111.867696) (xy 95.206059 -111.849534) (xy 95.172601 -111.808906)
			(xy 95.145041 -111.764067) (xy 95.123901 -111.715867) (xy 95.109583 -111.665221) (xy 95.102357 -111.613088)
			(xy 95.101918 -111.586772) (xy 95.102404 -111.559521) (xy 95.11016 -111.505573) (xy 95.125515 -111.453278)
			(xy 95.148157 -111.403701) (xy 95.177623 -111.357851) (xy 95.213314 -111.31666) (xy 95.254505 -111.280969)
			(xy 95.300355 -111.251503) (xy 95.349932 -111.228861) (xy 95.402227 -111.213506) (xy 95.456175 -111.20575)
			(xy 95.510677 -111.20575) (xy 95.564625 -111.213506) (xy 95.61692 -111.228861) (xy 95.666497 -111.251503)
			(xy 95.712347 -111.280969) (xy 95.753538 -111.31666) (xy 95.789229 -111.357851) (xy 95.818695 -111.403701)
			(xy 95.841337 -111.453278) (xy 95.856692 -111.505573) (xy 95.864448 -111.559521) (xy 95.864934 -111.586772)
			(xy 95.864504 -111.613087) (xy 95.85726 -111.665217) (xy 95.842933 -111.71586) (xy 95.821793 -111.764058)
			(xy 95.794241 -111.808901) (xy 95.760798 -111.84954) (xy 95.741744 -111.867696) (xy 95.734349 -111.875223)
			(xy 95.725819 -111.894499) (xy 95.725234 -111.905034) (xy 95.725234 -111.97971) (xy 95.725734 -111.990263)
			(xy 95.734289 -112.009559) (xy 95.741744 -112.017048) (xy 95.760824 -112.035179) (xy 95.762829 -112.037615)
			(xy 97.556142 -112.037615) (xy 97.560456 -111.980343) (xy 97.573304 -111.924365) (xy 97.594396 -111.870944)
			(xy 97.623255 -111.821288) (xy 97.65923 -111.776517) (xy 97.680018 -111.756698) (xy 97.687425 -111.749182)
			(xy 97.695946 -111.729897) (xy 97.696528 -111.71936) (xy 97.696528 -111.644684) (xy 97.696013 -111.634133)
			(xy 97.687467 -111.614838) (xy 97.680018 -111.607346) (xy 97.660947 -111.589206) (xy 97.62749 -111.548573)
			(xy 97.599933 -111.50373) (xy 97.578797 -111.455526) (xy 97.564484 -111.404876) (xy 97.557264 -111.352739)
			(xy 97.556828 -111.326422) (xy 97.557314 -111.299171) (xy 97.56507 -111.245223) (xy 97.580425 -111.192928)
			(xy 97.603067 -111.143351) (xy 97.632533 -111.097501) (xy 97.668224 -111.05631) (xy 97.709415 -111.020619)
			(xy 97.755265 -110.991153) (xy 97.804842 -110.968511) (xy 97.857137 -110.953156) (xy 97.911085 -110.9454)
			(xy 97.965587 -110.9454) (xy 98.019535 -110.953156) (xy 98.07183 -110.968511) (xy 98.121407 -110.991153)
			(xy 98.167257 -111.020619) (xy 98.208448 -111.05631) (xy 98.244139 -111.097501) (xy 98.273605 -111.143351)
			(xy 98.296247 -111.192928) (xy 98.311602 -111.245223) (xy 98.319358 -111.299171) (xy 98.319844 -111.326422)
			(xy 98.319409 -111.352737) (xy 98.31217 -111.404868) (xy 98.297846 -111.455512) (xy 98.276707 -111.503711)
			(xy 98.249155 -111.548554) (xy 98.215709 -111.589191) (xy 98.196654 -111.607346) (xy 98.189238 -111.614856)
			(xy 98.18072 -111.634144) (xy 98.180144 -111.644684) (xy 98.180144 -111.71936) (xy 98.180668 -111.729911)
			(xy 98.189206 -111.749207) (xy 98.196654 -111.756698) (xy 98.217462 -111.776497) (xy 98.253434 -111.821274)
			(xy 98.28229 -111.870935) (xy 98.303379 -111.924359) (xy 98.316226 -111.980341) (xy 98.320539 -112.037615)
			(xy 100.09439 -112.037615) (xy 100.098702 -111.980346) (xy 100.111547 -111.924369) (xy 100.132634 -111.87095)
			(xy 100.161488 -111.821292) (xy 100.197456 -111.776519) (xy 100.21824 -111.756698) (xy 100.225636 -111.749171)
			(xy 100.234165 -111.729895) (xy 100.23475 -111.71936) (xy 100.23475 -111.644684) (xy 100.234228 -111.634134)
			(xy 100.225686 -111.614839) (xy 100.21824 -111.607346) (xy 100.199154 -111.589222) (xy 100.165702 -111.548584)
			(xy 100.138148 -111.503737) (xy 100.117016 -111.45553) (xy 100.102704 -111.404878) (xy 100.095486 -111.35274)
			(xy 100.09505 -111.326422) (xy 100.095536 -111.299171) (xy 100.103292 -111.245223) (xy 100.118647 -111.192928)
			(xy 100.141289 -111.143351) (xy 100.170755 -111.097501) (xy 100.206446 -111.05631) (xy 100.247637 -111.020619)
			(xy 100.293487 -110.991153) (xy 100.343064 -110.968511) (xy 100.395359 -110.953156) (xy 100.449307 -110.9454)
			(xy 100.503809 -110.9454) (xy 100.557757 -110.953156) (xy 100.610052 -110.968511) (xy 100.659629 -110.991153)
			(xy 100.705479 -111.020619) (xy 100.74667 -111.05631) (xy 100.782361 -111.097501) (xy 100.811827 -111.143351)
			(xy 100.834469 -111.192928) (xy 100.849824 -111.245223) (xy 100.85758 -111.299171) (xy 100.858066 -111.326422)
			(xy 100.857624 -111.352737) (xy 100.850386 -111.404867) (xy 100.836062 -111.455511) (xy 100.814925 -111.50371)
			(xy 100.787374 -111.548553) (xy 100.75393 -111.589191) (xy 100.734876 -111.607346) (xy 100.727463 -111.614859)
			(xy 100.718942 -111.634145) (xy 100.718366 -111.644684) (xy 100.718366 -111.71936) (xy 100.718913 -111.729907)
			(xy 100.727437 -111.749202) (xy 100.734876 -111.756698) (xy 100.755688 -111.776495) (xy 100.791667 -111.821269)
			(xy 100.820529 -111.87093) (xy 100.841623 -111.924355) (xy 100.854472 -111.980338) (xy 100.855495 -111.993923)
			(xy 104.297324 -111.993923) (xy 104.301636 -111.936654) (xy 104.314481 -111.880678) (xy 104.335569 -111.827258)
			(xy 104.364423 -111.777602) (xy 104.400393 -111.73283) (xy 104.421178 -111.71301) (xy 104.428574 -111.705484)
			(xy 104.437102 -111.686207) (xy 104.437688 -111.675672) (xy 104.437688 -111.600996) (xy 104.437178 -111.590444)
			(xy 104.42863 -111.571149) (xy 104.421178 -111.563658) (xy 104.400424 -111.543804) (xy 104.364449 -111.499036)
			(xy 104.335589 -111.449383) (xy 104.314494 -111.395966) (xy 104.301643 -111.339992) (xy 104.297324 -111.282723)
			(xy 104.301636 -111.225454) (xy 104.314481 -111.169478) (xy 104.335569 -111.116058) (xy 104.364423 -111.066402)
			(xy 104.400393 -111.02163) (xy 104.421178 -111.00181) (xy 104.428574 -110.994284) (xy 104.437102 -110.975007)
			(xy 104.437688 -110.964472) (xy 104.437688 -110.889796) (xy 104.437178 -110.879244) (xy 104.42863 -110.859949)
			(xy 104.421178 -110.852458) (xy 104.402105 -110.83432) (xy 104.36865 -110.793686) (xy 104.341094 -110.748842)
			(xy 104.319959 -110.700638) (xy 104.305645 -110.649987) (xy 104.298424 -110.597851) (xy 104.297988 -110.571534)
			(xy 104.298487 -110.544282) (xy 104.306239 -110.490333) (xy 104.321591 -110.438036) (xy 104.344229 -110.388456)
			(xy 104.373693 -110.342603) (xy 104.409383 -110.30141) (xy 104.450572 -110.265716) (xy 104.496423 -110.236247)
			(xy 104.546 -110.213604) (xy 104.598296 -110.198247) (xy 104.652244 -110.19049) (xy 104.679496 -110.190026)
			(xy 104.70581 -110.190488) (xy 104.757939 -110.197723) (xy 104.808583 -110.212042) (xy 104.856782 -110.233176)
			(xy 104.901625 -110.260723) (xy 104.942264 -110.294164) (xy 104.96042 -110.313216) (xy 104.96793 -110.320631)
			(xy 104.987219 -110.329147) (xy 104.997758 -110.329726) (xy 105.072434 -110.329726) (xy 105.08298 -110.329167)
			(xy 105.102275 -110.320652) (xy 105.109772 -110.313216) (xy 105.127951 -110.294184) (xy 105.168576 -110.260724)
			(xy 105.213411 -110.233162) (xy 105.261607 -110.212019) (xy 105.31225 -110.197697) (xy 105.364381 -110.190467)
			(xy 105.390696 -110.190026) (xy 105.41795 -110.190459) (xy 105.471904 -110.198216) (xy 105.524205 -110.213574)
			(xy 105.573787 -110.236218) (xy 105.613417 -110.261688) (xy 106.914421 -110.261688) (xy 106.914421 -110.209712)
			(xy 106.922553 -110.158377) (xy 106.938615 -110.108946) (xy 106.962213 -110.062636) (xy 106.992766 -110.020588)
			(xy 107.02952 -109.983839) (xy 107.071572 -109.953291) (xy 107.117884 -109.929699) (xy 107.167318 -109.913643)
			(xy 107.218654 -109.905518) (xy 107.244642 -109.905038) (xy 107.271287 -109.905526) (xy 107.323889 -109.914057)
			(xy 107.374439 -109.930922) (xy 107.421625 -109.955684) (xy 107.464224 -109.987701) (xy 107.50113 -110.026141)
			(xy 107.516676 -110.047786) (xy 107.52504 -110.059072) (xy 107.546713 -110.076927) (xy 107.572427 -110.08821)
			(xy 107.600242 -110.092068) (xy 107.628057 -110.08821) (xy 107.653771 -110.076927) (xy 107.675444 -110.059072)
			(xy 107.683808 -110.047786) (xy 107.699397 -110.026178) (xy 107.73631 -109.987761) (xy 107.778906 -109.95576)
			(xy 107.826082 -109.931002) (xy 107.876617 -109.914129) (xy 107.929203 -109.905578) (xy 107.955842 -109.905038)
			(xy 107.981831 -109.905459) (xy 108.033167 -109.913596) (xy 108.082599 -109.929663) (xy 108.128909 -109.953264)
			(xy 108.170957 -109.983819) (xy 108.207709 -110.020575) (xy 108.238258 -110.062627) (xy 108.261853 -110.10894)
			(xy 108.277914 -110.158374) (xy 108.286044 -110.209711) (xy 108.286044 -110.261689) (xy 108.277914 -110.313026)
			(xy 108.261853 -110.36246) (xy 108.238258 -110.408773) (xy 108.207709 -110.450825) (xy 108.170957 -110.487581)
			(xy 108.132325 -110.515654) (xy 110.828072 -110.515654) (xy 110.832143 -110.460032) (xy 110.844269 -110.405595)
			(xy 110.864192 -110.353504) (xy 110.891488 -110.304869) (xy 110.925574 -110.260726) (xy 110.965723 -110.222017)
			(xy 111.011081 -110.189566) (xy 111.060681 -110.164065) (xy 111.113465 -110.146058) (xy 111.168308 -110.135928)
			(xy 111.224042 -110.133891) (xy 111.279479 -110.139991) (xy 111.333436 -110.154097) (xy 111.384765 -110.175909)
			(xy 111.432371 -110.204963) (xy 111.475239 -110.240638) (xy 111.512456 -110.282175) (xy 111.543229 -110.328688)
			(xy 111.566901 -110.379185) (xy 111.582969 -110.432592) (xy 111.591089 -110.487768) (xy 111.591598 -110.515654)
			(xy 111.591089 -110.54354) (xy 111.582969 -110.598716) (xy 111.566901 -110.652123) (xy 111.543229 -110.70262)
			(xy 111.512456 -110.749133) (xy 111.475239 -110.79067) (xy 111.432371 -110.826345) (xy 111.384765 -110.855399)
			(xy 111.333436 -110.877211) (xy 111.279479 -110.891317) (xy 111.224042 -110.897417) (xy 111.168308 -110.89538)
			(xy 111.113465 -110.88525) (xy 111.060681 -110.867243) (xy 111.011081 -110.841742) (xy 110.965723 -110.809291)
			(xy 110.925574 -110.770582) (xy 110.891488 -110.726439) (xy 110.864192 -110.677804) (xy 110.844269 -110.625713)
			(xy 110.832143 -110.571276) (xy 110.828072 -110.515654) (xy 108.132325 -110.515654) (xy 108.128909 -110.518136)
			(xy 108.082599 -110.541737) (xy 108.033167 -110.557804) (xy 107.981831 -110.565941) (xy 107.955842 -110.566454)
			(xy 107.929197 -110.565981) (xy 107.876594 -110.557448) (xy 107.826043 -110.54058) (xy 107.778857 -110.515815)
			(xy 107.736259 -110.483795) (xy 107.699354 -110.445352) (xy 107.683808 -110.423706) (xy 107.675444 -110.41242)
			(xy 107.653771 -110.394565) (xy 107.628057 -110.383282) (xy 107.600242 -110.379424) (xy 107.572427 -110.383282)
			(xy 107.546713 -110.394565) (xy 107.52504 -110.41242) (xy 107.516676 -110.423706) (xy 107.501095 -110.44532)
			(xy 107.46418 -110.483737) (xy 107.421583 -110.515738) (xy 107.374405 -110.540494) (xy 107.323869 -110.557366)
			(xy 107.271281 -110.565916) (xy 107.244642 -110.566454) (xy 107.218654 -110.565882) (xy 107.167318 -110.557757)
			(xy 107.117884 -110.541701) (xy 107.071572 -110.518109) (xy 107.02952 -110.487561) (xy 106.992766 -110.450812)
			(xy 106.962213 -110.408764) (xy 106.938615 -110.362454) (xy 106.922553 -110.313023) (xy 106.914421 -110.261688)
			(xy 105.613417 -110.261688) (xy 105.619642 -110.265689) (xy 105.660835 -110.301386) (xy 105.696529 -110.342582)
			(xy 105.725996 -110.388439) (xy 105.748637 -110.438024) (xy 105.76399 -110.490325) (xy 105.771743 -110.54428)
			(xy 105.772204 -110.571534) (xy 105.771758 -110.597849) (xy 105.764519 -110.649978) (xy 105.750195 -110.700621)
			(xy 105.729059 -110.74882) (xy 105.701509 -110.793663) (xy 105.668067 -110.834302) (xy 105.649014 -110.852458)
			(xy 105.641631 -110.859995) (xy 105.633095 -110.879263) (xy 105.632504 -110.889796) (xy 105.632504 -110.964472)
			(xy 105.633034 -110.975022) (xy 105.641568 -110.994317) (xy 105.649014 -111.00181) (xy 105.669836 -111.021596)
			(xy 105.705811 -111.066373) (xy 105.73467 -111.116036) (xy 105.752772 -111.16189) (xy 106.914397 -111.16189)
			(xy 106.914397 -111.10991) (xy 106.922529 -111.058571) (xy 106.938593 -111.009136) (xy 106.962193 -110.962823)
			(xy 106.992748 -110.920773) (xy 107.029505 -110.88402) (xy 107.071559 -110.853471) (xy 107.117875 -110.829877)
			(xy 107.167312 -110.813819) (xy 107.218652 -110.805694) (xy 107.244642 -110.805214) (xy 107.271286 -110.805713)
			(xy 107.323887 -110.814242) (xy 107.374436 -110.831106) (xy 107.421622 -110.855866) (xy 107.464222 -110.887881)
			(xy 107.501129 -110.926319) (xy 107.516676 -110.947962) (xy 107.52504 -110.959248) (xy 107.546713 -110.977103)
			(xy 107.572427 -110.988386) (xy 107.600242 -110.992244) (xy 107.628057 -110.988386) (xy 107.653771 -110.977103)
			(xy 107.675444 -110.959248) (xy 107.683808 -110.947962) (xy 107.69939 -110.926349) (xy 107.736306 -110.887933)
			(xy 107.778903 -110.855933) (xy 107.82608 -110.831177) (xy 107.876616 -110.814305) (xy 107.929203 -110.805754)
			(xy 107.955842 -110.805214) (xy 107.981829 -110.805683) (xy 108.033162 -110.813819) (xy 108.08259 -110.829885)
			(xy 108.128897 -110.853484) (xy 108.170942 -110.884037) (xy 108.20769 -110.92079) (xy 108.238238 -110.962839)
			(xy 108.261831 -111.009149) (xy 108.277891 -111.058579) (xy 108.286021 -111.109913) (xy 108.286021 -111.161887)
			(xy 108.277891 -111.213221) (xy 108.261831 -111.262651) (xy 108.238238 -111.308961) (xy 108.20769 -111.35101)
			(xy 108.170942 -111.387763) (xy 108.128897 -111.418316) (xy 108.08259 -111.441915) (xy 108.033162 -111.457981)
			(xy 107.981829 -111.466117) (xy 107.955842 -111.46663) (xy 107.929196 -111.466167) (xy 107.876592 -111.457633)
			(xy 107.826041 -111.440764) (xy 107.778855 -111.415997) (xy 107.736257 -111.383975) (xy 107.699353 -111.345529)
			(xy 107.683808 -111.323882) (xy 107.675444 -111.312596) (xy 107.653771 -111.294741) (xy 107.628057 -111.283458)
			(xy 107.600242 -111.2796) (xy 107.572427 -111.283458) (xy 107.546713 -111.294741) (xy 107.52504 -111.312596)
			(xy 107.516676 -111.323882) (xy 107.501117 -111.345512) (xy 107.464195 -111.383925) (xy 107.421592 -111.415922)
			(xy 107.374411 -111.440675) (xy 107.323872 -111.457543) (xy 107.271282 -111.466092) (xy 107.244642 -111.46663)
			(xy 107.218652 -111.466106) (xy 107.167312 -111.457981) (xy 107.117875 -111.441923) (xy 107.071559 -111.418329)
			(xy 107.029505 -111.38778) (xy 106.992748 -111.351027) (xy 106.962193 -111.308977) (xy 106.938593 -111.262664)
			(xy 106.922529 -111.213229) (xy 106.914397 -111.16189) (xy 105.752772 -111.16189) (xy 105.755761 -111.169462)
			(xy 105.768608 -111.225446) (xy 105.77292 -111.282723) (xy 105.768601 -111.339999) (xy 105.755748 -111.395982)
			(xy 105.73465 -111.449406) (xy 105.705785 -111.499065) (xy 105.669805 -111.543838) (xy 105.649014 -111.563658)
			(xy 105.641631 -111.571195) (xy 105.633095 -111.590463) (xy 105.632504 -111.600996) (xy 105.632504 -111.675672)
			(xy 105.633034 -111.686222) (xy 105.641568 -111.705517) (xy 105.649014 -111.71301) (xy 105.669836 -111.732796)
			(xy 105.705811 -111.777573) (xy 105.73467 -111.827236) (xy 105.755761 -111.880662) (xy 105.768608 -111.936646)
			(xy 105.77292 -111.993923) (xy 105.768601 -112.051199) (xy 105.76617 -112.061788) (xy 106.914419 -112.061788)
			(xy 106.914419 -112.009812) (xy 106.922551 -111.958476) (xy 106.938613 -111.909045) (xy 106.962212 -111.862735)
			(xy 106.992764 -111.820687) (xy 107.029519 -111.783937) (xy 107.071571 -111.75339) (xy 107.117884 -111.729797)
			(xy 107.167317 -111.713741) (xy 107.218654 -111.705616) (xy 107.244642 -111.705136) (xy 107.271287 -111.705625)
			(xy 107.323888 -111.714156) (xy 107.374438 -111.73102) (xy 107.421625 -111.755782) (xy 107.464224 -111.787799)
			(xy 107.501129 -111.826239) (xy 107.516676 -111.847884) (xy 107.52504 -111.85917) (xy 107.546713 -111.877025)
			(xy 107.572427 -111.888308) (xy 107.600242 -111.892166) (xy 107.628057 -111.888308) (xy 107.653771 -111.877025)
			(xy 107.675444 -111.85917) (xy 107.683808 -111.847884) (xy 107.699396 -111.826275) (xy 107.73631 -111.787859)
			(xy 107.778906 -111.755857) (xy 107.826082 -111.7311) (xy 107.876617 -111.714227) (xy 107.929203 -111.705676)
			(xy 107.955842 -111.705136) (xy 107.98183 -111.705561) (xy 108.033167 -111.713698) (xy 108.082598 -111.729765)
			(xy 108.128908 -111.753366) (xy 108.170956 -111.78392) (xy 108.17269 -111.785654) (xy 109.457742 -111.785654)
			(xy 109.461813 -111.730032) (xy 109.473939 -111.675595) (xy 109.493862 -111.623504) (xy 109.521158 -111.574869)
			(xy 109.555244 -111.530726) (xy 109.595393 -111.492017) (xy 109.640751 -111.459566) (xy 109.690351 -111.434065)
			(xy 109.743135 -111.416058) (xy 109.797978 -111.405928) (xy 109.853712 -111.403891) (xy 109.909149 -111.409991)
			(xy 109.963106 -111.424097) (xy 110.014435 -111.445909) (xy 110.062041 -111.474963) (xy 110.104909 -111.510638)
			(xy 110.142126 -111.552175) (xy 110.172899 -111.598688) (xy 110.196571 -111.649185) (xy 110.212639 -111.702592)
			(xy 110.220759 -111.757768) (xy 110.221268 -111.785654) (xy 110.220759 -111.81354) (xy 110.212639 -111.868716)
			(xy 110.196571 -111.922123) (xy 110.172899 -111.97262) (xy 110.142126 -112.019133) (xy 110.104909 -112.06067)
			(xy 110.062041 -112.096345) (xy 110.014435 -112.125399) (xy 109.963106 -112.147211) (xy 109.909149 -112.161317)
			(xy 109.853712 -112.167417) (xy 109.797978 -112.16538) (xy 109.743135 -112.15525) (xy 109.690351 -112.137243)
			(xy 109.640751 -112.111742) (xy 109.595393 -112.079291) (xy 109.555244 -112.040582) (xy 109.521158 -111.996439)
			(xy 109.493862 -111.947804) (xy 109.473939 -111.895713) (xy 109.461813 -111.841276) (xy 109.457742 -111.785654)
			(xy 108.17269 -111.785654) (xy 108.207707 -111.820676) (xy 108.238256 -111.862728) (xy 108.261852 -111.909041)
			(xy 108.277912 -111.958474) (xy 108.286042 -112.009811) (xy 108.286042 -112.061789) (xy 108.277912 -112.113126)
			(xy 108.261852 -112.162559) (xy 108.238256 -112.208872) (xy 108.207707 -112.250924) (xy 108.170956 -112.28768)
			(xy 108.15819 -112.296956) (xy 110.894874 -112.296956) (xy 110.898945 -112.241334) (xy 110.911071 -112.186897)
			(xy 110.930994 -112.134806) (xy 110.95829 -112.086171) (xy 110.992376 -112.042028) (xy 111.032525 -112.003319)
			(xy 111.077883 -111.970868) (xy 111.127483 -111.945367) (xy 111.180267 -111.92736) (xy 111.23511 -111.91723)
			(xy 111.290844 -111.915193) (xy 111.346281 -111.921293) (xy 111.400238 -111.935399) (xy 111.451567 -111.957211)
			(xy 111.499173 -111.986265) (xy 111.542041 -112.02194) (xy 111.579258 -112.063477) (xy 111.610031 -112.10999)
			(xy 111.633703 -112.160487) (xy 111.649771 -112.213894) (xy 111.657891 -112.26907) (xy 111.6584 -112.296956)
			(xy 111.657891 -112.324842) (xy 111.649771 -112.380018) (xy 111.633703 -112.433425) (xy 111.610031 -112.483922)
			(xy 111.579258 -112.530435) (xy 111.542041 -112.571972) (xy 111.499173 -112.607647) (xy 111.451567 -112.636701)
			(xy 111.400238 -112.658513) (xy 111.346281 -112.672619) (xy 111.290844 -112.678719) (xy 111.23511 -112.676682)
			(xy 111.180267 -112.666552) (xy 111.127483 -112.648545) (xy 111.077883 -112.623044) (xy 111.032525 -112.590593)
			(xy 110.992376 -112.551884) (xy 110.95829 -112.507741) (xy 110.930994 -112.459106) (xy 110.911071 -112.407015)
			(xy 110.898945 -112.352578) (xy 110.894874 -112.296956) (xy 108.15819 -112.296956) (xy 108.128908 -112.318234)
			(xy 108.082598 -112.341835) (xy 108.033167 -112.357902) (xy 107.98183 -112.366039) (xy 107.955842 -112.366552)
			(xy 107.929197 -112.36608) (xy 107.876594 -112.357547) (xy 107.826043 -112.340679) (xy 107.778857 -112.315913)
			(xy 107.736259 -112.283894) (xy 107.699354 -112.24545) (xy 107.683808 -112.223804) (xy 107.675444 -112.212518)
			(xy 107.653771 -112.194663) (xy 107.628057 -112.18338) (xy 107.600242 -112.179522) (xy 107.572427 -112.18338)
			(xy 107.546713 -112.194663) (xy 107.52504 -112.212518) (xy 107.516676 -112.223804) (xy 107.501094 -112.245417)
			(xy 107.46418 -112.283835) (xy 107.421582 -112.315836) (xy 107.374405 -112.340592) (xy 107.323869 -112.357464)
			(xy 107.271281 -112.366014) (xy 107.244642 -112.366552) (xy 107.218654 -112.365984) (xy 107.167317 -112.357859)
			(xy 107.117884 -112.341803) (xy 107.071571 -112.31821) (xy 107.029519 -112.287663) (xy 106.992764 -112.250913)
			(xy 106.962212 -112.208865) (xy 106.938613 -112.162555) (xy 106.922551 -112.113124) (xy 106.914419 -112.061788)
			(xy 105.76617 -112.061788) (xy 105.755748 -112.107182) (xy 105.73465 -112.160606) (xy 105.705785 -112.210265)
			(xy 105.669805 -112.255038) (xy 105.649014 -112.274858) (xy 105.641631 -112.282395) (xy 105.633095 -112.301663)
			(xy 105.632504 -112.312196) (xy 105.632504 -112.386872) (xy 105.633034 -112.397422) (xy 105.641568 -112.416717)
			(xy 105.649014 -112.42421) (xy 105.66807 -112.442365) (xy 105.701527 -112.482995) (xy 105.729085 -112.527836)
			(xy 105.750224 -112.576036) (xy 105.764541 -112.626684) (xy 105.771765 -112.678818) (xy 105.772204 -112.705134)
			(xy 105.771754 -112.732386) (xy 105.763993 -112.786335) (xy 105.748633 -112.838631) (xy 105.725988 -112.888209)
			(xy 105.696517 -112.934059) (xy 105.672482 -112.961794) (xy 106.914341 -112.961794) (xy 106.914341 -112.909806)
			(xy 106.922475 -112.858458) (xy 106.938541 -112.809015) (xy 106.962145 -112.762694) (xy 106.992705 -112.720636)
			(xy 107.029468 -112.683878) (xy 107.07153 -112.653323) (xy 107.117854 -112.629725) (xy 107.167299 -112.613665)
			(xy 107.218648 -112.605538) (xy 107.244642 -112.605058) (xy 107.271287 -112.605538) (xy 107.32389 -112.614069)
			(xy 107.37444 -112.630935) (xy 107.421627 -112.655699) (xy 107.464225 -112.687717) (xy 107.50113 -112.72616)
			(xy 107.516676 -112.747806) (xy 107.52504 -112.759092) (xy 107.546713 -112.776947) (xy 107.572427 -112.78823)
			(xy 107.600242 -112.792088) (xy 107.628057 -112.78823) (xy 107.653771 -112.776947) (xy 107.675444 -112.759092)
			(xy 107.683808 -112.747806) (xy 107.699373 -112.72618) (xy 107.736294 -112.687768) (xy 107.778896 -112.655771)
			(xy 107.826076 -112.631018) (xy 107.876614 -112.614148) (xy 107.929202 -112.605598) (xy 107.955842 -112.605058)
			(xy 107.981824 -112.605639) (xy 108.033148 -112.613774) (xy 108.082568 -112.629837) (xy 108.128867 -112.653432)
			(xy 108.170905 -112.68398) (xy 108.207648 -112.720727) (xy 108.23819 -112.762769) (xy 108.26178 -112.809071)
			(xy 108.277836 -112.858492) (xy 108.285965 -112.909818) (xy 108.285965 -112.961782) (xy 108.277836 -113.013108)
			(xy 108.26178 -113.062529) (xy 108.23819 -113.108831) (xy 108.207648 -113.150873) (xy 108.170905 -113.18762)
			(xy 108.128867 -113.218168) (xy 108.082568 -113.241763) (xy 108.033148 -113.257826) (xy 107.981824 -113.265961)
			(xy 107.955842 -113.266474) (xy 107.929197 -113.265992) (xy 107.876595 -113.25746) (xy 107.826045 -113.240593)
			(xy 107.778859 -113.21583) (xy 107.73626 -113.183812) (xy 107.699355 -113.145371) (xy 107.683808 -113.123726)
			(xy 107.675444 -113.11244) (xy 107.653771 -113.094585) (xy 107.628057 -113.083302) (xy 107.600242 -113.079444)
			(xy 107.572427 -113.083302) (xy 107.546713 -113.094585) (xy 107.52504 -113.11244) (xy 107.516676 -113.123726)
			(xy 107.501101 -113.145344) (xy 107.464184 -113.18376) (xy 107.421585 -113.21576) (xy 107.374407 -113.240516)
			(xy 107.32387 -113.257386) (xy 107.271281 -113.265936) (xy 107.244642 -113.266474) (xy 107.218648 -113.266062)
			(xy 107.167299 -113.257935) (xy 107.117854 -113.241875) (xy 107.07153 -113.218277) (xy 107.029468 -113.187722)
			(xy 106.992705 -113.150964) (xy 106.962145 -113.108906) (xy 106.938541 -113.062585) (xy 106.922475 -113.013142)
			(xy 106.914341 -112.961794) (xy 105.672482 -112.961794) (xy 105.660822 -112.975249) (xy 105.619629 -113.01094)
			(xy 105.573775 -113.040406) (xy 105.524195 -113.063046) (xy 105.471898 -113.078401) (xy 105.417948 -113.086157)
			(xy 105.390696 -113.086642) (xy 105.364381 -113.086196) (xy 105.312251 -113.078959) (xy 105.261607 -113.064637)
			(xy 105.213408 -113.043501) (xy 105.168565 -113.01595) (xy 105.127927 -112.982506) (xy 105.109772 -112.963452)
			(xy 105.102256 -112.956044) (xy 105.082972 -112.947521) (xy 105.072434 -112.946942) (xy 104.997758 -112.946942)
			(xy 104.987209 -112.947477) (xy 104.967912 -112.956007) (xy 104.96042 -112.963452) (xy 104.942258 -112.982501)
			(xy 104.901628 -113.015957) (xy 104.856789 -113.043515) (xy 104.80859 -113.064654) (xy 104.757944 -113.078974)
			(xy 104.705812 -113.086202) (xy 104.679496 -113.086642) (xy 104.652246 -113.086126) (xy 104.598301 -113.07837)
			(xy 104.546009 -113.063016) (xy 104.496434 -113.040377) (xy 104.450585 -113.010913) (xy 104.409396 -112.975225)
			(xy 104.373705 -112.934039) (xy 104.344238 -112.888192) (xy 104.321595 -112.838619) (xy 104.306237 -112.786328)
			(xy 104.298476 -112.732384) (xy 104.297988 -112.705134) (xy 104.298415 -112.678819) (xy 104.305659 -112.626689)
			(xy 104.319986 -112.576045) (xy 104.341126 -112.527847) (xy 104.368679 -112.483004) (xy 104.402124 -112.442366)
			(xy 104.421178 -112.42421) (xy 104.428574 -112.416684) (xy 104.437102 -112.397407) (xy 104.437688 -112.386872)
			(xy 104.437688 -112.312196) (xy 104.437178 -112.301644) (xy 104.42863 -112.282349) (xy 104.421178 -112.274858)
			(xy 104.400424 -112.255004) (xy 104.364449 -112.210236) (xy 104.335589 -112.160583) (xy 104.314494 -112.107166)
			(xy 104.301643 -112.051192) (xy 104.297324 -111.993923) (xy 100.855495 -111.993923) (xy 100.858786 -112.037615)
			(xy 100.854467 -112.094891) (xy 100.841614 -112.150873) (xy 100.820516 -112.204297) (xy 100.79165 -112.253956)
			(xy 100.755667 -112.298727) (xy 100.734876 -112.318546) (xy 100.727463 -112.326059) (xy 100.718942 -112.345345)
			(xy 100.718366 -112.355884) (xy 100.718366 -112.43056) (xy 100.718913 -112.441107) (xy 100.727437 -112.460402)
			(xy 100.734876 -112.467898) (xy 100.753919 -112.486066) (xy 100.787378 -112.526693) (xy 100.814939 -112.57153)
			(xy 100.83608 -112.619729) (xy 100.8504 -112.670374) (xy 100.857627 -112.722506) (xy 100.858066 -112.748822)
			(xy 100.85758 -112.776073) (xy 100.849824 -112.830021) (xy 100.834469 -112.882316) (xy 100.811827 -112.931893)
			(xy 100.782361 -112.977743) (xy 100.74667 -113.018934) (xy 100.705479 -113.054625) (xy 100.659629 -113.084091)
			(xy 100.610052 -113.106733) (xy 100.557757 -113.122088) (xy 100.503809 -113.129844) (xy 100.449307 -113.129844)
			(xy 100.395359 -113.122088) (xy 100.343064 -113.106733) (xy 100.293487 -113.084091) (xy 100.247637 -113.054625)
			(xy 100.206446 -113.018934) (xy 100.170755 -112.977743) (xy 100.141289 -112.931893) (xy 100.118647 -112.882316)
			(xy 100.103292 -112.830021) (xy 100.095536 -112.776073) (xy 100.09505 -112.748822) (xy 100.095516 -112.722508)
			(xy 100.102749 -112.670379) (xy 100.117067 -112.619735) (xy 100.1382 -112.571536) (xy 100.165747 -112.526693)
			(xy 100.199187 -112.486054) (xy 100.21824 -112.467898) (xy 100.225636 -112.460371) (xy 100.234165 -112.441095)
			(xy 100.23475 -112.43056) (xy 100.23475 -112.355884) (xy 100.234228 -112.345334) (xy 100.225686 -112.326039)
			(xy 100.21824 -112.318546) (xy 100.197476 -112.298703) (xy 100.161505 -112.253932) (xy 100.132647 -112.204277)
			(xy 100.111556 -112.150859) (xy 100.098707 -112.094884) (xy 100.09439 -112.037615) (xy 98.320539 -112.037615)
			(xy 98.316221 -112.094889) (xy 98.303371 -112.150869) (xy 98.282277 -112.204292) (xy 98.253417 -112.253951)
			(xy 98.217442 -112.298725) (xy 98.196654 -112.318546) (xy 98.189238 -112.326056) (xy 98.18072 -112.345344)
			(xy 98.180144 -112.355884) (xy 98.180144 -112.43056) (xy 98.180668 -112.441111) (xy 98.189206 -112.460407)
			(xy 98.196654 -112.467898) (xy 98.215712 -112.486051) (xy 98.249167 -112.526682) (xy 98.276724 -112.571524)
			(xy 98.297862 -112.619725) (xy 98.312179 -112.670372) (xy 98.319405 -112.722506) (xy 98.319844 -112.748822)
			(xy 98.319358 -112.776073) (xy 98.311602 -112.830021) (xy 98.296247 -112.882316) (xy 98.273605 -112.931893)
			(xy 98.244139 -112.977743) (xy 98.208448 -113.018934) (xy 98.167257 -113.054625) (xy 98.121407 -113.084091)
			(xy 98.07183 -113.106733) (xy 98.019535 -113.122088) (xy 97.965587 -113.129844) (xy 97.911085 -113.129844)
			(xy 97.857137 -113.122088) (xy 97.804842 -113.106733) (xy 97.755265 -113.084091) (xy 97.709415 -113.054625)
			(xy 97.668224 -113.018934) (xy 97.632533 -112.977743) (xy 97.603067 -112.931893) (xy 97.580425 -112.882316)
			(xy 97.56507 -112.830021) (xy 97.557314 -112.776073) (xy 97.556828 -112.748822) (xy 97.557301 -112.722508)
			(xy 97.564534 -112.67038) (xy 97.578851 -112.619737) (xy 97.599982 -112.571537) (xy 97.627528 -112.526694)
			(xy 97.660966 -112.486054) (xy 97.680018 -112.467898) (xy 97.687425 -112.460382) (xy 97.695946 -112.441097)
			(xy 97.696528 -112.43056) (xy 97.696528 -112.355884) (xy 97.696013 -112.345333) (xy 97.687467 -112.326038)
			(xy 97.680018 -112.318546) (xy 97.65925 -112.298705) (xy 97.623272 -112.253937) (xy 97.594409 -112.204283)
			(xy 97.573313 -112.150863) (xy 97.560461 -112.094886) (xy 97.556142 -112.037615) (xy 95.762829 -112.037615)
			(xy 95.794277 -112.075815) (xy 95.821832 -112.12066) (xy 95.842966 -112.168866) (xy 95.857278 -112.219517)
			(xy 95.864498 -112.271655) (xy 95.864934 -112.297972) (xy 95.864448 -112.325223) (xy 95.856692 -112.379171)
			(xy 95.841337 -112.431466) (xy 95.818695 -112.481043) (xy 95.789229 -112.526893) (xy 95.753538 -112.568084)
			(xy 95.712347 -112.603775) (xy 95.666497 -112.633241) (xy 95.61692 -112.655883) (xy 95.564625 -112.671238)
			(xy 95.510677 -112.678994) (xy 95.456175 -112.678994) (xy 95.402227 -112.671238) (xy 95.349932 -112.655883)
			(xy 95.300355 -112.633241) (xy 95.254505 -112.603775) (xy 95.213314 -112.568084) (xy 95.177623 -112.526893)
			(xy 95.148157 -112.481043) (xy 95.125515 -112.431466) (xy 95.11016 -112.379171) (xy 95.102404 -112.325223)
			(xy 95.101918 -112.297972) (xy 93.832934 -112.297972) (xy 93.832448 -112.325223) (xy 93.824692 -112.379171)
			(xy 93.809337 -112.431466) (xy 93.786695 -112.481043) (xy 93.757229 -112.526893) (xy 93.721538 -112.568084)
			(xy 93.680347 -112.603775) (xy 93.634497 -112.633241) (xy 93.58492 -112.655883) (xy 93.532625 -112.671238)
			(xy 93.478677 -112.678994) (xy 93.424175 -112.678994) (xy 93.370227 -112.671238) (xy 93.317932 -112.655883)
			(xy 93.268355 -112.633241) (xy 93.222505 -112.603775) (xy 93.181314 -112.568084) (xy 93.145623 -112.526893)
			(xy 93.116157 -112.481043) (xy 93.093515 -112.431466) (xy 93.07816 -112.379171) (xy 93.070404 -112.325223)
			(xy 93.069918 -112.297972) (xy 81.875335 -112.297972) (xy 81.79435 -112.70615) (xy 81.793468 -112.716661)
			(xy 81.799255 -112.736923) (xy 81.81265 -112.753189) (xy 81.821782 -112.758474) (xy 81.824576 -112.759744)
			(xy 81.849861 -112.771198) (xy 81.897102 -112.800341) (xy 81.939622 -112.836021) (xy 81.976524 -112.877486)
			(xy 82.007028 -112.92386) (xy 82.030492 -112.974164) (xy 82.04642 -113.027337) (xy 82.054475 -113.082256)
			(xy 82.054954 -113.11001) (xy 82.054487 -113.136985) (xy 82.046886 -113.190398) (xy 82.031837 -113.242207)
			(xy 82.00964 -113.291379) (xy 81.980738 -113.336935) (xy 81.945706 -113.377965) (xy 81.905244 -113.413651)
			(xy 81.860159 -113.443282) (xy 81.81135 -113.466266) (xy 81.759789 -113.482146) (xy 81.706506 -113.490604)
			(xy 81.679542 -113.491518) (xy 81.679288 -113.491518) (xy 81.670715 -113.492026) (xy 81.654623 -113.497997)
			(xy 81.647792 -113.503202) (xy 81.640934 -113.50879) (xy 81.632044 -113.523522) (xy 81.520759 -114.084637)
			(xy 89.449407 -114.084637) (xy 89.449409 -114.03014) (xy 89.457166 -113.976198) (xy 89.472521 -113.923908)
			(xy 89.495161 -113.874336) (xy 89.524626 -113.828491) (xy 89.560315 -113.787305) (xy 89.601502 -113.751618)
			(xy 89.647348 -113.722155) (xy 89.696921 -113.699517) (xy 89.749211 -113.684163) (xy 89.803153 -113.676408)
			(xy 89.830402 -113.675922) (xy 89.83091 -113.675922) (xy 89.854668 -113.676301) (xy 89.901812 -113.682246)
			(xy 89.947855 -113.693991) (xy 89.970102 -113.702338) (xy 89.982802 -113.707418) (xy 90.009472 -113.703354)
			(xy 90.088974 -113.640108) (xy 90.095629 -113.634331) (xy 90.10491 -113.619367) (xy 90.108586 -113.602146)
			(xy 90.10777 -113.593372) (xy 90.10777 -113.592864) (xy 90.105906 -113.579288) (xy 90.103869 -113.551957)
			(xy 90.103706 -113.538254) (xy 90.104135 -113.511001) (xy 90.111898 -113.45705) (xy 90.12726 -113.404754)
			(xy 90.149907 -113.355176) (xy 90.17938 -113.309325) (xy 90.215077 -113.268135) (xy 90.256273 -113.232444)
			(xy 90.302128 -113.202979) (xy 90.35171 -113.180339) (xy 90.404009 -113.164985) (xy 90.457961 -113.157231)
			(xy 90.485214 -113.156746) (xy 90.514129 -113.157309) (xy 90.571299 -113.166026) (xy 90.626498 -113.183274)
			(xy 90.67846 -113.208657) (xy 90.725995 -113.241594) (xy 90.768013 -113.281329) (xy 90.786204 -113.303812)
			(xy 90.793817 -113.312613) (xy 90.814713 -113.322799) (xy 90.826336 -113.32337) (xy 90.906092 -113.32337)
			(xy 90.917723 -113.322822) (xy 90.938633 -113.312641) (xy 90.946224 -113.303812) (xy 90.964405 -113.28132)
			(xy 91.006426 -113.241584) (xy 91.053963 -113.208646) (xy 91.105926 -113.183259) (xy 91.161126 -113.166005)
			(xy 91.218297 -113.157279) (xy 91.247214 -113.156746) (xy 91.274464 -113.157265) (xy 91.328408 -113.165022)
			(xy 91.380699 -113.180376) (xy 91.430273 -113.203016) (xy 91.476121 -113.232479) (xy 91.51731 -113.268167)
			(xy 91.553001 -113.309353) (xy 91.582469 -113.355199) (xy 91.605112 -113.404771) (xy 91.620471 -113.457061)
			(xy 91.628233 -113.511005) (xy 91.628722 -113.538254) (xy 91.628284 -113.565013) (xy 91.627758 -113.568734)
			(xy 110.889794 -113.568734) (xy 110.893865 -113.513112) (xy 110.905991 -113.458675) (xy 110.925914 -113.406584)
			(xy 110.95321 -113.357949) (xy 110.987296 -113.313806) (xy 111.027445 -113.275097) (xy 111.072803 -113.242646)
			(xy 111.122403 -113.217145) (xy 111.175187 -113.199138) (xy 111.23003 -113.189008) (xy 111.285764 -113.186971)
			(xy 111.341201 -113.193071) (xy 111.395158 -113.207177) (xy 111.446487 -113.228989) (xy 111.494093 -113.258043)
			(xy 111.536961 -113.293718) (xy 111.574178 -113.335255) (xy 111.604951 -113.381768) (xy 111.628623 -113.432265)
			(xy 111.644691 -113.485672) (xy 111.652811 -113.540848) (xy 111.65332 -113.568734) (xy 111.652811 -113.59662)
			(xy 111.644691 -113.651796) (xy 111.628623 -113.705203) (xy 111.604951 -113.7557) (xy 111.574178 -113.802213)
			(xy 111.536961 -113.84375) (xy 111.494093 -113.879425) (xy 111.446487 -113.908479) (xy 111.395158 -113.930291)
			(xy 111.341201 -113.944397) (xy 111.285764 -113.950497) (xy 111.23003 -113.94846) (xy 111.175187 -113.93833)
			(xy 111.122403 -113.920323) (xy 111.072803 -113.894822) (xy 111.027445 -113.862371) (xy 110.987296 -113.823662)
			(xy 110.95321 -113.779519) (xy 110.925914 -113.730884) (xy 110.905991 -113.678793) (xy 110.893865 -113.624356)
			(xy 110.889794 -113.568734) (xy 91.627758 -113.568734) (xy 91.620797 -113.618004) (xy 91.605979 -113.669429)
			(xy 91.58412 -113.718279) (xy 91.555649 -113.763594) (xy 91.521125 -113.804487) (xy 91.481225 -113.840153)
			(xy 91.436732 -113.869894) (xy 91.412822 -113.881916) (xy 91.412568 -113.881916) (xy 91.40182 -113.888029)
			(xy 91.387212 -113.907926) (xy 91.384628 -113.920016) (xy 91.369642 -114.015012) (xy 91.37777 -114.03838)
			(xy 91.38666 -114.047016) (xy 91.396783 -114.05681) (xy 91.415729 -114.077656) (xy 91.424506 -114.088672)
			(xy 91.432057 -114.097444) (xy 91.452825 -114.107619) (xy 91.464384 -114.10823) (xy 91.544394 -114.10823)
			(xy 91.556027 -114.107697) (xy 91.576938 -114.097506) (xy 91.584526 -114.088672) (xy 91.602695 -114.06617)
			(xy 91.64472 -114.026437) (xy 91.69226 -113.993501) (xy 91.744225 -113.968116) (xy 91.799426 -113.950864)
			(xy 91.856599 -113.942139) (xy 91.885516 -113.941606) (xy 91.912768 -113.942065) (xy 91.966715 -113.949824)
			(xy 92.01901 -113.965181) (xy 92.068587 -113.987824) (xy 92.114437 -114.017291) (xy 92.127342 -114.028474)
			(xy 105.005122 -114.028474) (xy 105.009193 -113.972852) (xy 105.021319 -113.918415) (xy 105.041242 -113.866324)
			(xy 105.068538 -113.817689) (xy 105.102624 -113.773546) (xy 105.142773 -113.734837) (xy 105.188131 -113.702386)
			(xy 105.237731 -113.676885) (xy 105.290515 -113.658878) (xy 105.345358 -113.648748) (xy 105.401092 -113.646711)
			(xy 105.456529 -113.652811) (xy 105.510486 -113.666917) (xy 105.561815 -113.688729) (xy 105.609421 -113.717783)
			(xy 105.652289 -113.753458) (xy 105.689506 -113.794995) (xy 105.720279 -113.841508) (xy 105.743951 -113.892005)
			(xy 105.760019 -113.945412) (xy 105.768139 -114.000588) (xy 105.768648 -114.028474) (xy 105.768139 -114.05636)
			(xy 105.760019 -114.111536) (xy 105.743951 -114.164943) (xy 105.720279 -114.21544) (xy 105.689506 -114.261953)
			(xy 105.652289 -114.30349) (xy 105.609421 -114.339165) (xy 105.561815 -114.368219) (xy 105.510486 -114.390031)
			(xy 105.456529 -114.404137) (xy 105.401092 -114.410237) (xy 105.345358 -114.4082) (xy 105.290515 -114.39807)
			(xy 105.237731 -114.380063) (xy 105.188131 -114.354562) (xy 105.142773 -114.322111) (xy 105.102624 -114.283402)
			(xy 105.068538 -114.239259) (xy 105.041242 -114.190624) (xy 105.021319 -114.138533) (xy 105.009193 -114.084096)
			(xy 105.005122 -114.028474) (xy 92.127342 -114.028474) (xy 92.155627 -114.052984) (xy 92.191318 -114.094175)
			(xy 92.220784 -114.140027) (xy 92.243425 -114.189605) (xy 92.25878 -114.2419) (xy 92.266536 -114.295848)
			(xy 92.266536 -114.350352) (xy 92.25878 -114.4043) (xy 92.243425 -114.456595) (xy 92.220784 -114.506173)
			(xy 92.191318 -114.552025) (xy 92.155627 -114.593216) (xy 92.114437 -114.628909) (xy 92.068587 -114.658376)
			(xy 92.01901 -114.681019) (xy 91.966715 -114.696376) (xy 91.912767 -114.704135) (xy 91.885516 -114.704622)
			(xy 91.856598 -114.704122) (xy 91.799425 -114.695393) (xy 91.744224 -114.678134) (xy 91.692262 -114.652739)
			(xy 91.644729 -114.619791) (xy 91.602714 -114.580044) (xy 91.584526 -114.557556) (xy 91.576905 -114.548763)
			(xy 91.556015 -114.538574) (xy 91.544394 -114.537998) (xy 91.464638 -114.537998) (xy 91.453004 -114.538516)
			(xy 91.432094 -114.54872) (xy 91.424506 -114.557556) (xy 91.4063 -114.580027) (xy 91.364285 -114.619765)
			(xy 91.316754 -114.652707) (xy 91.264795 -114.678098) (xy 91.209599 -114.695356) (xy 91.152431 -114.704087)
			(xy 91.123516 -114.704622) (xy 91.096264 -114.70413) (xy 91.042315 -114.696375) (xy 90.990019 -114.681022)
			(xy 90.940439 -114.658383) (xy 90.894587 -114.628917) (xy 90.853394 -114.593227) (xy 90.817701 -114.552037)
			(xy 90.788232 -114.506187) (xy 90.765588 -114.45661) (xy 90.750231 -114.404314) (xy 90.742472 -114.350366)
			(xy 90.742008 -114.323114) (xy 90.742459 -114.296356) (xy 90.749948 -114.243367) (xy 90.764767 -114.191945)
			(xy 90.786626 -114.143097) (xy 90.815095 -114.097782) (xy 90.849616 -114.056889) (xy 90.889512 -114.021221)
			(xy 90.934 -113.991476) (xy 90.957908 -113.979452) (xy 90.958162 -113.979452) (xy 90.968927 -113.973364)
			(xy 90.983526 -113.953449) (xy 90.986102 -113.941352) (xy 91.001088 -113.846356) (xy 90.99296 -113.822988)
			(xy 90.98407 -113.814352) (xy 90.973942 -113.804563) (xy 90.954999 -113.783714) (xy 90.946224 -113.772696)
			(xy 90.938648 -113.763949) (xy 90.9179 -113.753757) (xy 90.906346 -113.753138) (xy 90.826336 -113.753138)
			(xy 90.814699 -113.753642) (xy 90.793789 -113.763854) (xy 90.786204 -113.772696) (xy 90.76801 -113.795177)
			(xy 90.725991 -113.834912) (xy 90.678457 -113.867852) (xy 90.626496 -113.893241) (xy 90.571299 -113.910497)
			(xy 90.51413 -113.919227) (xy 90.485214 -113.919762) (xy 90.484706 -113.919762) (xy 90.460948 -113.919379)
			(xy 90.413804 -113.913436) (xy 90.367761 -113.901692) (xy 90.345514 -113.893346) (xy 90.332814 -113.888266)
			(xy 90.306144 -113.89233) (xy 90.226642 -113.955576) (xy 90.219982 -113.961347) (xy 90.210709 -113.976316)
			(xy 90.207033 -113.993537) (xy 90.207846 -114.002312) (xy 90.207846 -114.00282) (xy 90.209719 -114.016395)
			(xy 90.21175 -114.043727) (xy 90.21191 -114.05743) (xy 90.21139 -114.084679) (xy 90.20363 -114.138621)
			(xy 90.188272 -114.190909) (xy 90.16563 -114.24048) (xy 90.136163 -114.286324) (xy 90.100472 -114.327508)
			(xy 90.059283 -114.363193) (xy 90.013436 -114.392654) (xy 89.963862 -114.41529) (xy 89.911571 -114.430641)
			(xy 89.857628 -114.438393) (xy 89.803131 -114.43839) (xy 89.749189 -114.430632) (xy 89.6969 -114.415276)
			(xy 89.647328 -114.392634) (xy 89.601483 -114.363169) (xy 89.560299 -114.327479) (xy 89.524612 -114.286291)
			(xy 89.49515 -114.240444) (xy 89.472513 -114.19087) (xy 89.457161 -114.13858) (xy 89.449407 -114.084637)
			(xy 81.520759 -114.084637) (xy 81.25972 -115.400836) (xy 87.260682 -115.400836) (xy 87.264753 -115.345214)
			(xy 87.276879 -115.290777) (xy 87.296802 -115.238686) (xy 87.324098 -115.190051) (xy 87.358184 -115.145908)
			(xy 87.398333 -115.107199) (xy 87.443691 -115.074748) (xy 87.493291 -115.049247) (xy 87.546075 -115.03124)
			(xy 87.600918 -115.02111) (xy 87.656652 -115.019073) (xy 87.712089 -115.025173) (xy 87.766046 -115.039279)
			(xy 87.817375 -115.061091) (xy 87.864981 -115.090145) (xy 87.907849 -115.12582) (xy 87.945066 -115.167357)
			(xy 87.975839 -115.21387) (xy 87.999511 -115.264367) (xy 88.015579 -115.317774) (xy 88.023317 -115.370356)
			(xy 89.361262 -115.370356) (xy 89.365333 -115.314734) (xy 89.377459 -115.260297) (xy 89.397382 -115.208206)
			(xy 89.424678 -115.159571) (xy 89.458764 -115.115428) (xy 89.498913 -115.076719) (xy 89.544271 -115.044268)
			(xy 89.593871 -115.018767) (xy 89.646655 -115.00076) (xy 89.701498 -114.99063) (xy 89.757232 -114.988593)
			(xy 89.812669 -114.994693) (xy 89.866626 -115.008799) (xy 89.871678 -115.010946) (xy 106.6198 -115.010946)
			(xy 106.623871 -114.955324) (xy 106.635997 -114.900887) (xy 106.65592 -114.848796) (xy 106.683216 -114.800161)
			(xy 106.717302 -114.756018) (xy 106.757451 -114.717309) (xy 106.802809 -114.684858) (xy 106.852409 -114.659357)
			(xy 106.905193 -114.64135) (xy 106.960036 -114.63122) (xy 107.01577 -114.629183) (xy 107.071207 -114.635283)
			(xy 107.125164 -114.649389) (xy 107.176493 -114.671201) (xy 107.224099 -114.700255) (xy 107.266967 -114.73593)
			(xy 107.304184 -114.777467) (xy 107.334957 -114.82398) (xy 107.358629 -114.874477) (xy 107.374697 -114.927884)
			(xy 107.382817 -114.98306) (xy 107.383326 -115.010946) (xy 107.382817 -115.038832) (xy 107.379893 -115.058698)
			(xy 107.98632 -115.058698) (xy 107.990391 -115.003076) (xy 108.002517 -114.948639) (xy 108.02244 -114.896548)
			(xy 108.049736 -114.847913) (xy 108.083822 -114.80377) (xy 108.123971 -114.765061) (xy 108.169329 -114.73261)
			(xy 108.218929 -114.707109) (xy 108.271713 -114.689102) (xy 108.326556 -114.678972) (xy 108.38229 -114.676935)
			(xy 108.437727 -114.683035) (xy 108.491684 -114.697141) (xy 108.543013 -114.718953) (xy 108.590619 -114.748007)
			(xy 108.633487 -114.783682) (xy 108.670704 -114.825219) (xy 108.701477 -114.871732) (xy 108.725149 -114.922229)
			(xy 108.741217 -114.975636) (xy 108.743386 -114.990372) (xy 109.365032 -114.990372) (xy 109.369103 -114.93475)
			(xy 109.381229 -114.880313) (xy 109.401152 -114.828222) (xy 109.428448 -114.779587) (xy 109.462534 -114.735444)
			(xy 109.502683 -114.696735) (xy 109.548041 -114.664284) (xy 109.597641 -114.638783) (xy 109.650425 -114.620776)
			(xy 109.705268 -114.610646) (xy 109.761002 -114.608609) (xy 109.816439 -114.614709) (xy 109.870396 -114.628815)
			(xy 109.921725 -114.650627) (xy 109.969331 -114.679681) (xy 110.012199 -114.715356) (xy 110.049416 -114.756893)
			(xy 110.080189 -114.803406) (xy 110.103861 -114.853903) (xy 110.119929 -114.90731) (xy 110.127779 -114.960654)
			(xy 110.891826 -114.960654) (xy 110.895897 -114.905032) (xy 110.908023 -114.850595) (xy 110.927946 -114.798504)
			(xy 110.955242 -114.749869) (xy 110.989328 -114.705726) (xy 111.029477 -114.667017) (xy 111.074835 -114.634566)
			(xy 111.124435 -114.609065) (xy 111.177219 -114.591058) (xy 111.232062 -114.580928) (xy 111.287796 -114.578891)
			(xy 111.343233 -114.584991) (xy 111.39719 -114.599097) (xy 111.448519 -114.620909) (xy 111.496125 -114.649963)
			(xy 111.538993 -114.685638) (xy 111.57621 -114.727175) (xy 111.606983 -114.773688) (xy 111.630655 -114.824185)
			(xy 111.646723 -114.877592) (xy 111.654843 -114.932768) (xy 111.655352 -114.960654) (xy 111.654843 -114.98854)
			(xy 111.646723 -115.043716) (xy 111.630655 -115.097123) (xy 111.606983 -115.14762) (xy 111.57621 -115.194133)
			(xy 111.538993 -115.23567) (xy 111.496125 -115.271345) (xy 111.448519 -115.300399) (xy 111.39719 -115.322211)
			(xy 111.343233 -115.336317) (xy 111.287796 -115.342417) (xy 111.232062 -115.34038) (xy 111.177219 -115.33025)
			(xy 111.124435 -115.312243) (xy 111.074835 -115.286742) (xy 111.029477 -115.254291) (xy 110.989328 -115.215582)
			(xy 110.955242 -115.171439) (xy 110.927946 -115.122804) (xy 110.908023 -115.070713) (xy 110.895897 -115.016276)
			(xy 110.891826 -114.960654) (xy 110.127779 -114.960654) (xy 110.128049 -114.962486) (xy 110.128558 -114.990372)
			(xy 110.128049 -115.018258) (xy 110.119929 -115.073434) (xy 110.103861 -115.126841) (xy 110.080189 -115.177338)
			(xy 110.049416 -115.223851) (xy 110.012199 -115.265388) (xy 109.969331 -115.301063) (xy 109.921725 -115.330117)
			(xy 109.870396 -115.351929) (xy 109.816439 -115.366035) (xy 109.761002 -115.372135) (xy 109.705268 -115.370098)
			(xy 109.650425 -115.359968) (xy 109.597641 -115.341961) (xy 109.548041 -115.31646) (xy 109.502683 -115.284009)
			(xy 109.462534 -115.2453) (xy 109.428448 -115.201157) (xy 109.401152 -115.152522) (xy 109.381229 -115.100431)
			(xy 109.369103 -115.045994) (xy 109.365032 -114.990372) (xy 108.743386 -114.990372) (xy 108.749337 -115.030812)
			(xy 108.749846 -115.058698) (xy 108.749337 -115.086584) (xy 108.741217 -115.14176) (xy 108.725149 -115.195167)
			(xy 108.701477 -115.245664) (xy 108.670704 -115.292177) (xy 108.633487 -115.333714) (xy 108.590619 -115.369389)
			(xy 108.543013 -115.398443) (xy 108.491684 -115.420255) (xy 108.437727 -115.434361) (xy 108.38229 -115.440461)
			(xy 108.326556 -115.438424) (xy 108.271713 -115.428294) (xy 108.218929 -115.410287) (xy 108.169329 -115.384786)
			(xy 108.123971 -115.352335) (xy 108.083822 -115.313626) (xy 108.049736 -115.269483) (xy 108.02244 -115.220848)
			(xy 108.002517 -115.168757) (xy 107.990391 -115.11432) (xy 107.98632 -115.058698) (xy 107.379893 -115.058698)
			(xy 107.374697 -115.094008) (xy 107.358629 -115.147415) (xy 107.334957 -115.197912) (xy 107.304184 -115.244425)
			(xy 107.266967 -115.285962) (xy 107.224099 -115.321637) (xy 107.176493 -115.350691) (xy 107.125164 -115.372503)
			(xy 107.071207 -115.386609) (xy 107.01577 -115.392709) (xy 106.960036 -115.390672) (xy 106.905193 -115.380542)
			(xy 106.852409 -115.362535) (xy 106.802809 -115.337034) (xy 106.757451 -115.304583) (xy 106.717302 -115.265874)
			(xy 106.683216 -115.221731) (xy 106.65592 -115.173096) (xy 106.635997 -115.121005) (xy 106.623871 -115.066568)
			(xy 106.6198 -115.010946) (xy 89.871678 -115.010946) (xy 89.917955 -115.030611) (xy 89.965561 -115.059665)
			(xy 90.008429 -115.09534) (xy 90.045646 -115.136877) (xy 90.076419 -115.18339) (xy 90.100091 -115.233887)
			(xy 90.116159 -115.287294) (xy 90.124279 -115.34247) (xy 90.124788 -115.370356) (xy 90.124279 -115.398242)
			(xy 90.116159 -115.453418) (xy 90.100091 -115.506825) (xy 90.076419 -115.557322) (xy 90.045646 -115.603835)
			(xy 90.008429 -115.645372) (xy 89.965561 -115.681047) (xy 89.917955 -115.710101) (xy 89.866626 -115.731913)
			(xy 89.812669 -115.746019) (xy 89.757232 -115.752119) (xy 89.701498 -115.750082) (xy 89.646655 -115.739952)
			(xy 89.593871 -115.721945) (xy 89.544271 -115.696444) (xy 89.498913 -115.663993) (xy 89.458764 -115.625284)
			(xy 89.424678 -115.581141) (xy 89.397382 -115.532506) (xy 89.377459 -115.480415) (xy 89.365333 -115.425978)
			(xy 89.361262 -115.370356) (xy 88.023317 -115.370356) (xy 88.023699 -115.37295) (xy 88.024208 -115.400836)
			(xy 88.023699 -115.428722) (xy 88.015579 -115.483898) (xy 87.999511 -115.537305) (xy 87.975839 -115.587802)
			(xy 87.945066 -115.634315) (xy 87.907849 -115.675852) (xy 87.864981 -115.711527) (xy 87.817375 -115.740581)
			(xy 87.766046 -115.762393) (xy 87.712089 -115.776499) (xy 87.656652 -115.782599) (xy 87.600918 -115.780562)
			(xy 87.546075 -115.770432) (xy 87.493291 -115.752425) (xy 87.443691 -115.726924) (xy 87.398333 -115.694473)
			(xy 87.358184 -115.655764) (xy 87.324098 -115.611621) (xy 87.296802 -115.562986) (xy 87.276879 -115.510895)
			(xy 87.264753 -115.456458) (xy 87.260682 -115.400836) (xy 81.25972 -115.400836) (xy 81.23428 -115.529106)
			(xy 81.174051 -115.832636) (xy 92.979238 -115.832636) (xy 92.983309 -115.777014) (xy 92.995435 -115.722577)
			(xy 93.015358 -115.670486) (xy 93.042654 -115.621851) (xy 93.07674 -115.577708) (xy 93.116889 -115.538999)
			(xy 93.162247 -115.506548) (xy 93.211847 -115.481047) (xy 93.264631 -115.46304) (xy 93.319474 -115.45291)
			(xy 93.375208 -115.450873) (xy 93.430645 -115.456973) (xy 93.484602 -115.471079) (xy 93.535931 -115.492891)
			(xy 93.583537 -115.521945) (xy 93.626405 -115.55762) (xy 93.663622 -115.599157) (xy 93.694395 -115.64567)
			(xy 93.718067 -115.696167) (xy 93.734135 -115.749574) (xy 93.742255 -115.80475) (xy 93.742764 -115.832636)
			(xy 93.742255 -115.860522) (xy 93.734135 -115.915698) (xy 93.718067 -115.969105) (xy 93.694395 -116.019602)
			(xy 93.663622 -116.066115) (xy 93.626405 -116.107652) (xy 93.583537 -116.143327) (xy 93.535931 -116.172381)
			(xy 93.484602 -116.194193) (xy 93.430645 -116.208299) (xy 93.375208 -116.214399) (xy 93.319474 -116.212362)
			(xy 93.264631 -116.202232) (xy 93.211847 -116.184225) (xy 93.162247 -116.158724) (xy 93.116889 -116.126273)
			(xy 93.07674 -116.087564) (xy 93.042654 -116.043421) (xy 93.015358 -115.994786) (xy 92.995435 -115.942695)
			(xy 92.983309 -115.888258) (xy 92.979238 -115.832636) (xy 81.174051 -115.832636) (xy 81.007928 -116.66982)
			(xy 89.3732 -116.66982) (xy 89.377271 -116.614198) (xy 89.389397 -116.559761) (xy 89.40932 -116.50767)
			(xy 89.436616 -116.459035) (xy 89.470702 -116.414892) (xy 89.510851 -116.376183) (xy 89.556209 -116.343732)
			(xy 89.605809 -116.318231) (xy 89.658593 -116.300224) (xy 89.713436 -116.290094) (xy 89.76917 -116.288057)
			(xy 89.824607 -116.294157) (xy 89.878564 -116.308263) (xy 89.929893 -116.330075) (xy 89.977499 -116.359129)
			(xy 90.020367 -116.394804) (xy 90.057584 -116.436341) (xy 90.088357 -116.482854) (xy 90.112029 -116.533351)
			(xy 90.128097 -116.586758) (xy 90.13434 -116.62918) (xy 105.137964 -116.62918) (xy 105.142035 -116.573558)
			(xy 105.154161 -116.519121) (xy 105.174084 -116.46703) (xy 105.20138 -116.418395) (xy 105.235466 -116.374252)
			(xy 105.275615 -116.335543) (xy 105.320973 -116.303092) (xy 105.370573 -116.277591) (xy 105.423357 -116.259584)
			(xy 105.4782 -116.249454) (xy 105.533934 -116.247417) (xy 105.589371 -116.253517) (xy 105.643328 -116.267623)
			(xy 105.694657 -116.289435) (xy 105.742263 -116.318489) (xy 105.785131 -116.354164) (xy 105.822348 -116.395701)
			(xy 105.853121 -116.442214) (xy 105.876793 -116.492711) (xy 105.892861 -116.546118) (xy 105.900981 -116.601294)
			(xy 105.90149 -116.62918) (xy 105.900981 -116.657066) (xy 105.892861 -116.712242) (xy 105.876793 -116.765649)
			(xy 105.853121 -116.816146) (xy 105.822348 -116.862659) (xy 105.785131 -116.904196) (xy 105.742263 -116.939871)
			(xy 105.694657 -116.968925) (xy 105.643328 -116.990737) (xy 105.589371 -117.004843) (xy 105.533934 -117.010943)
			(xy 105.4782 -117.008906) (xy 105.423357 -116.998776) (xy 105.370573 -116.980769) (xy 105.320973 -116.955268)
			(xy 105.275615 -116.922817) (xy 105.235466 -116.884108) (xy 105.20138 -116.839965) (xy 105.174084 -116.79133)
			(xy 105.154161 -116.739239) (xy 105.142035 -116.684802) (xy 105.137964 -116.62918) (xy 90.13434 -116.62918)
			(xy 90.136217 -116.641934) (xy 90.136726 -116.66982) (xy 90.136217 -116.697706) (xy 90.128097 -116.752882)
			(xy 90.112029 -116.806289) (xy 90.088357 -116.856786) (xy 90.057584 -116.903299) (xy 90.020367 -116.944836)
			(xy 89.977499 -116.980511) (xy 89.929893 -117.009565) (xy 89.878564 -117.031377) (xy 89.824607 -117.045483)
			(xy 89.76917 -117.051583) (xy 89.713436 -117.049546) (xy 89.658593 -117.039416) (xy 89.605809 -117.021409)
			(xy 89.556209 -116.995908) (xy 89.510851 -116.963457) (xy 89.470702 -116.924748) (xy 89.436616 -116.880605)
			(xy 89.40932 -116.83197) (xy 89.389397 -116.779879) (xy 89.377271 -116.725442) (xy 89.3732 -116.66982)
			(xy 81.007928 -116.66982) (xy 80.964532 -116.888514) (xy 80.963516 -116.897658) (xy 80.957865 -117.390451)
			(xy 90.742495 -117.390451) (xy 90.742495 -117.335949) (xy 90.750252 -117.282003) (xy 90.765607 -117.229709)
			(xy 90.788248 -117.180133) (xy 90.817715 -117.134284) (xy 90.853406 -117.093095) (xy 90.894597 -117.057405)
			(xy 90.940447 -117.027941) (xy 90.990024 -117.005301) (xy 91.042318 -116.989948) (xy 91.096265 -116.982194)
			(xy 91.123516 -116.981732) (xy 91.152431 -116.982299) (xy 91.209601 -116.991016) (xy 91.264799 -117.008264)
			(xy 91.316761 -117.033646) (xy 91.364296 -117.066582) (xy 91.406315 -117.106316) (xy 91.424506 -117.128798)
			(xy 91.432121 -117.137598) (xy 91.453016 -117.147786) (xy 91.464638 -117.148356) (xy 91.544394 -117.148356)
			(xy 91.556026 -117.147815) (xy 91.576937 -117.137629) (xy 91.584526 -117.128798) (xy 91.602702 -117.106302)
			(xy 91.644725 -117.066567) (xy 91.692263 -117.03363) (xy 91.744227 -117.008244) (xy 91.799427 -116.99099)
			(xy 91.856599 -116.982265) (xy 91.885516 -116.981732) (xy 91.912769 -116.982139) (xy 91.966721 -116.989898)
			(xy 92.019019 -117.005256) (xy 92.0686 -117.027901) (xy 92.114453 -117.057371) (xy 92.155646 -117.093066)
			(xy 92.163938 -117.102636) (xy 92.979238 -117.102636) (xy 92.983309 -117.047014) (xy 92.995435 -116.992577)
			(xy 93.015358 -116.940486) (xy 93.042654 -116.891851) (xy 93.07674 -116.847708) (xy 93.116889 -116.808999)
			(xy 93.162247 -116.776548) (xy 93.211847 -116.751047) (xy 93.264631 -116.73304) (xy 93.319474 -116.72291)
			(xy 93.375208 -116.720873) (xy 93.430645 -116.726973) (xy 93.484602 -116.741079) (xy 93.535931 -116.762891)
			(xy 93.583537 -116.791945) (xy 93.626405 -116.82762) (xy 93.663622 -116.869157) (xy 93.694395 -116.91567)
			(xy 93.718067 -116.966167) (xy 93.734135 -117.019574) (xy 93.742255 -117.07475) (xy 93.742764 -117.102636)
			(xy 93.742255 -117.130522) (xy 93.734135 -117.185698) (xy 93.718067 -117.239105) (xy 93.713814 -117.248178)
			(xy 107.738924 -117.248178) (xy 107.742995 -117.192556) (xy 107.755121 -117.138119) (xy 107.775044 -117.086028)
			(xy 107.80234 -117.037393) (xy 107.836426 -116.99325) (xy 107.876575 -116.954541) (xy 107.921933 -116.92209)
			(xy 107.971533 -116.896589) (xy 108.024317 -116.878582) (xy 108.07916 -116.868452) (xy 108.134894 -116.866415)
			(xy 108.190331 -116.872515) (xy 108.244288 -116.886621) (xy 108.295617 -116.908433) (xy 108.343223 -116.937487)
			(xy 108.386091 -116.973162) (xy 108.423308 -117.014699) (xy 108.454081 -117.061212) (xy 108.477753 -117.111709)
			(xy 108.493821 -117.165116) (xy 108.501941 -117.220292) (xy 108.50245 -117.248178) (xy 108.501941 -117.276064)
			(xy 108.493821 -117.33124) (xy 108.477753 -117.384647) (xy 108.454081 -117.435144) (xy 108.423308 -117.481657)
			(xy 108.386091 -117.523194) (xy 108.343223 -117.558869) (xy 108.295617 -117.587923) (xy 108.244288 -117.609735)
			(xy 108.190331 -117.623841) (xy 108.134894 -117.629941) (xy 108.07916 -117.627904) (xy 108.024317 -117.617774)
			(xy 107.971533 -117.599767) (xy 107.921933 -117.574266) (xy 107.876575 -117.541815) (xy 107.836426 -117.503106)
			(xy 107.80234 -117.458963) (xy 107.775044 -117.410328) (xy 107.755121 -117.358237) (xy 107.742995 -117.3038)
			(xy 107.738924 -117.248178) (xy 93.713814 -117.248178) (xy 93.694395 -117.289602) (xy 93.663622 -117.336115)
			(xy 93.626405 -117.377652) (xy 93.583537 -117.413327) (xy 93.535931 -117.442381) (xy 93.484602 -117.464193)
			(xy 93.430645 -117.478299) (xy 93.375208 -117.484399) (xy 93.319474 -117.482362) (xy 93.264631 -117.472232)
			(xy 93.211847 -117.454225) (xy 93.162247 -117.428724) (xy 93.116889 -117.396273) (xy 93.07674 -117.357564)
			(xy 93.042654 -117.313421) (xy 93.015358 -117.264786) (xy 92.995435 -117.212695) (xy 92.983309 -117.158258)
			(xy 92.979238 -117.102636) (xy 92.163938 -117.102636) (xy 92.191339 -117.13426) (xy 92.220807 -117.180114)
			(xy 92.243449 -117.229696) (xy 92.258805 -117.281995) (xy 92.266562 -117.335947) (xy 92.266562 -117.390453)
			(xy 92.258805 -117.444405) (xy 92.243449 -117.496704) (xy 92.220807 -117.546286) (xy 92.191339 -117.59214)
			(xy 92.155646 -117.633334) (xy 92.114453 -117.66903) (xy 92.0686 -117.698499) (xy 92.019019 -117.721144)
			(xy 91.974969 -117.73408) (xy 116.39626 -117.73408) (xy 116.400331 -117.678458) (xy 116.412457 -117.624021)
			(xy 116.43238 -117.57193) (xy 116.459676 -117.523295) (xy 116.493762 -117.479152) (xy 116.533911 -117.440443)
			(xy 116.579269 -117.407992) (xy 116.628869 -117.382491) (xy 116.681653 -117.364484) (xy 116.736496 -117.354354)
			(xy 116.79223 -117.352317) (xy 116.847667 -117.358417) (xy 116.901624 -117.372523) (xy 116.952953 -117.394335)
			(xy 117.000559 -117.423389) (xy 117.043427 -117.459064) (xy 117.080644 -117.500601) (xy 117.111417 -117.547114)
			(xy 117.135089 -117.597611) (xy 117.151157 -117.651018) (xy 117.159277 -117.706194) (xy 117.159786 -117.73408)
			(xy 117.159277 -117.761966) (xy 117.151157 -117.817142) (xy 117.135089 -117.870549) (xy 117.111417 -117.921046)
			(xy 117.080644 -117.967559) (xy 117.043427 -118.009096) (xy 117.021849 -118.027053) (xy 117.690342 -118.027053)
			(xy 117.690342 -117.972547) (xy 117.698099 -117.918594) (xy 117.713455 -117.866295) (xy 117.736098 -117.816714)
			(xy 117.765566 -117.77086) (xy 117.80126 -117.729666) (xy 117.842453 -117.693971) (xy 117.888307 -117.664502)
			(xy 117.937888 -117.641858) (xy 117.990187 -117.626501) (xy 118.044139 -117.618742) (xy 118.071392 -117.618256)
			(xy 118.10031 -117.618759) (xy 118.157483 -117.627488) (xy 118.212683 -117.644748) (xy 118.264645 -117.670142)
			(xy 118.312178 -117.703089) (xy 118.354193 -117.742834) (xy 118.372382 -117.765322) (xy 118.380003 -117.774115)
			(xy 118.400893 -117.784306) (xy 118.412514 -117.78488) (xy 118.49227 -117.78488) (xy 118.503899 -117.784316)
			(xy 118.524809 -117.774146) (xy 118.532402 -117.765322) (xy 118.550597 -117.742842) (xy 118.592616 -117.703106)
			(xy 118.640149 -117.670166) (xy 118.69211 -117.644776) (xy 118.747307 -117.62752) (xy 118.804476 -117.618791)
			(xy 118.833392 -117.618256) (xy 118.860643 -117.618791) (xy 118.914589 -117.626546) (xy 118.966883 -117.6419)
			(xy 119.01646 -117.66454) (xy 119.062309 -117.694005) (xy 119.103499 -117.729695) (xy 119.13919 -117.770884)
			(xy 119.168656 -117.816733) (xy 119.191297 -117.866309) (xy 119.206652 -117.918603) (xy 119.214409 -117.972549)
			(xy 119.214409 -118.027051) (xy 119.206652 -118.080997) (xy 119.191297 -118.133291) (xy 119.168656 -118.182867)
			(xy 119.13919 -118.228716) (xy 119.103499 -118.269905) (xy 119.062309 -118.305595) (xy 119.01646 -118.33506)
			(xy 118.966883 -118.3577) (xy 118.914589 -118.373054) (xy 118.860643 -118.380809) (xy 118.833392 -118.381272)
			(xy 118.804477 -118.380698) (xy 118.747308 -118.371982) (xy 118.69211 -118.354736) (xy 118.640148 -118.329355)
			(xy 118.592612 -118.29642) (xy 118.550594 -118.256687) (xy 118.532402 -118.234206) (xy 118.524783 -118.225411)
			(xy 118.503891 -118.21522) (xy 118.49227 -118.214648) (xy 118.412514 -118.214648) (xy 118.400882 -118.215193)
			(xy 118.379972 -118.225376) (xy 118.372382 -118.234206) (xy 118.354203 -118.256699) (xy 118.31218 -118.296434)
			(xy 118.264643 -118.329371) (xy 118.212679 -118.354758) (xy 118.15748 -118.372012) (xy 118.100309 -118.380738)
			(xy 118.071392 -118.381272) (xy 118.044139 -118.380858) (xy 117.990187 -118.373099) (xy 117.937888 -118.357742)
			(xy 117.888307 -118.335098) (xy 117.842453 -118.305629) (xy 117.80126 -118.269934) (xy 117.765566 -118.22874)
			(xy 117.736098 -118.182886) (xy 117.713455 -118.133305) (xy 117.698099 -118.081006) (xy 117.690342 -118.027053)
			(xy 117.021849 -118.027053) (xy 117.000559 -118.044771) (xy 116.952953 -118.073825) (xy 116.901624 -118.095637)
			(xy 116.847667 -118.109743) (xy 116.79223 -118.115843) (xy 116.736496 -118.113806) (xy 116.681653 -118.103676)
			(xy 116.628869 -118.085669) (xy 116.579269 -118.060168) (xy 116.533911 -118.027717) (xy 116.493762 -117.989008)
			(xy 116.459676 -117.944865) (xy 116.43238 -117.89623) (xy 116.412457 -117.844139) (xy 116.400331 -117.789702)
			(xy 116.39626 -117.73408) (xy 91.974969 -117.73408) (xy 91.966721 -117.736502) (xy 91.912769 -117.744261)
			(xy 91.885516 -117.744748) (xy 91.856599 -117.744238) (xy 91.799426 -117.73551) (xy 91.744226 -117.718252)
			(xy 91.692264 -117.692859) (xy 91.644731 -117.659913) (xy 91.602715 -117.620169) (xy 91.584526 -117.597682)
			(xy 91.576901 -117.588893) (xy 91.556014 -117.5787) (xy 91.544394 -117.578124) (xy 91.464638 -117.578124)
			(xy 91.453002 -117.578633) (xy 91.432092 -117.588842) (xy 91.424506 -117.597682) (xy 91.406307 -117.620159)
			(xy 91.364289 -117.659895) (xy 91.316756 -117.692836) (xy 91.264797 -117.718225) (xy 91.2096 -117.735483)
			(xy 91.152432 -117.744213) (xy 91.123516 -117.744748) (xy 91.096265 -117.744206) (xy 91.042318 -117.736452)
			(xy 90.990024 -117.721099) (xy 90.940447 -117.698459) (xy 90.894597 -117.668995) (xy 90.853406 -117.633305)
			(xy 90.817715 -117.592116) (xy 90.788248 -117.546267) (xy 90.765607 -117.496691) (xy 90.750252 -117.444397)
			(xy 90.742495 -117.390451) (xy 80.957865 -117.390451) (xy 80.950054 -118.071646) (xy 80.950054 -118.077742)
			(xy 80.950294 -118.086303) (xy 80.955734 -118.102532) (xy 80.960722 -118.109492) (xy 80.965802 -118.116096)
			(xy 80.980026 -118.12524) (xy 80.988662 -118.127526) (xy 81.014074 -118.134185) (xy 81.062916 -118.153526)
			(xy 81.108649 -118.179372) (xy 81.150414 -118.211236) (xy 81.187422 -118.248519) (xy 81.203546 -118.269258)
			(xy 81.206251 -118.272707) (xy 81.21264 -118.278705) (xy 81.216246 -118.281196) (xy 81.230978 -118.291102)
			(xy 81.234932 -118.293528) (xy 81.243494 -118.297096) (xy 81.247996 -118.298214) (xy 81.271618 -118.303548)
			(xy 81.279536 -118.304556) (xy 81.295316 -118.302226) (xy 81.302606 -118.298976) (xy 81.328831 -118.284392)
			(xy 81.384263 -118.261413) (xy 81.44222 -118.245863) (xy 81.501711 -118.238009) (xy 81.531714 -118.237508)
			(xy 81.532222 -118.237508) (xy 81.562206 -118.237999) (xy 81.621661 -118.245829) (xy 81.679585 -118.261352)
			(xy 81.734988 -118.284302) (xy 81.786922 -118.314286) (xy 81.834498 -118.350793) (xy 81.876902 -118.393196)
			(xy 81.913409 -118.440771) (xy 81.929065 -118.467886) (xy 97.482404 -118.467886) (xy 97.486475 -118.412264)
			(xy 97.498601 -118.357827) (xy 97.518524 -118.305736) (xy 97.54582 -118.257101) (xy 97.579906 -118.212958)
			(xy 97.620055 -118.174249) (xy 97.665413 -118.141798) (xy 97.715013 -118.116297) (xy 97.767797 -118.09829)
			(xy 97.82264 -118.08816) (xy 97.878374 -118.086123) (xy 97.933811 -118.092223) (xy 97.987768 -118.106329)
			(xy 98.039097 -118.128141) (xy 98.086703 -118.157195) (xy 98.129571 -118.19287) (xy 98.166788 -118.234407)
			(xy 98.197561 -118.28092) (xy 98.221233 -118.331417) (xy 98.237301 -118.384824) (xy 98.245421 -118.44)
			(xy 98.24593 -118.467886) (xy 98.245421 -118.495772) (xy 98.237301 -118.550948) (xy 98.221233 -118.604355)
			(xy 98.197561 -118.654852) (xy 98.166788 -118.701365) (xy 98.129571 -118.742902) (xy 98.108737 -118.76024)
			(xy 102.564436 -118.76024) (xy 102.568507 -118.704618) (xy 102.580633 -118.650181) (xy 102.600556 -118.59809)
			(xy 102.627852 -118.549455) (xy 102.661938 -118.505312) (xy 102.702087 -118.466603) (xy 102.747445 -118.434152)
			(xy 102.797045 -118.408651) (xy 102.849829 -118.390644) (xy 102.904672 -118.380514) (xy 102.960406 -118.378477)
			(xy 103.015843 -118.384577) (xy 103.0698 -118.398683) (xy 103.121129 -118.420495) (xy 103.168735 -118.449549)
			(xy 103.211603 -118.485224) (xy 103.24882 -118.526761) (xy 103.279593 -118.573274) (xy 103.303265 -118.623771)
			(xy 103.319333 -118.677178) (xy 103.327453 -118.732354) (xy 103.327962 -118.76024) (xy 103.327453 -118.788126)
			(xy 103.319333 -118.843302) (xy 103.303265 -118.896709) (xy 103.279593 -118.947206) (xy 103.24882 -118.993719)
			(xy 103.211603 -119.035256) (xy 103.168735 -119.070931) (xy 103.157994 -119.077486) (xy 114.208558 -119.077486)
			(xy 114.212629 -119.021864) (xy 114.224755 -118.967427) (xy 114.244678 -118.915336) (xy 114.271974 -118.866701)
			(xy 114.30606 -118.822558) (xy 114.346209 -118.783849) (xy 114.391567 -118.751398) (xy 114.441167 -118.725897)
			(xy 114.493951 -118.70789) (xy 114.548794 -118.69776) (xy 114.604528 -118.695723) (xy 114.659965 -118.701823)
			(xy 114.713922 -118.715929) (xy 114.765251 -118.737741) (xy 114.812857 -118.766795) (xy 114.855725 -118.80247)
			(xy 114.892942 -118.844007) (xy 114.923715 -118.89052) (xy 114.947387 -118.941017) (xy 114.963455 -118.994424)
			(xy 114.971193 -119.047006) (xy 116.309138 -119.047006) (xy 116.313209 -118.991384) (xy 116.325335 -118.936947)
			(xy 116.345258 -118.884856) (xy 116.372554 -118.836221) (xy 116.40664 -118.792078) (xy 116.446789 -118.753369)
			(xy 116.492147 -118.720918) (xy 116.541747 -118.695417) (xy 116.594531 -118.67741) (xy 116.649374 -118.66728)
			(xy 116.705108 -118.665243) (xy 116.760545 -118.671343) (xy 116.814502 -118.685449) (xy 116.865831 -118.707261)
			(xy 116.913437 -118.736315) (xy 116.956305 -118.77199) (xy 116.993522 -118.813527) (xy 117.024295 -118.86004)
			(xy 117.047967 -118.910537) (xy 117.064035 -118.963944) (xy 117.072155 -119.01912) (xy 117.072664 -119.047006)
			(xy 117.072155 -119.074892) (xy 117.064035 -119.130068) (xy 117.047967 -119.183475) (xy 117.024295 -119.233972)
			(xy 116.993522 -119.280485) (xy 116.956305 -119.322022) (xy 116.913437 -119.357697) (xy 116.865831 -119.386751)
			(xy 116.814502 -119.408563) (xy 116.760545 -119.422669) (xy 116.705108 -119.428769) (xy 116.649374 -119.426732)
			(xy 116.594531 -119.416602) (xy 116.541747 -119.398595) (xy 116.492147 -119.373094) (xy 116.446789 -119.340643)
			(xy 116.40664 -119.301934) (xy 116.372554 -119.257791) (xy 116.345258 -119.209156) (xy 116.325335 -119.157065)
			(xy 116.313209 -119.102628) (xy 116.309138 -119.047006) (xy 114.971193 -119.047006) (xy 114.971575 -119.0496)
			(xy 114.972084 -119.077486) (xy 114.971575 -119.105372) (xy 114.963455 -119.160548) (xy 114.947387 -119.213955)
			(xy 114.923715 -119.264452) (xy 114.892942 -119.310965) (xy 114.855725 -119.352502) (xy 114.812857 -119.388177)
			(xy 114.765251 -119.417231) (xy 114.713922 -119.439043) (xy 114.659965 -119.453149) (xy 114.604528 -119.459249)
			(xy 114.548794 -119.457212) (xy 114.493951 -119.447082) (xy 114.441167 -119.429075) (xy 114.391567 -119.403574)
			(xy 114.346209 -119.371123) (xy 114.30606 -119.332414) (xy 114.271974 -119.288271) (xy 114.244678 -119.239636)
			(xy 114.224755 -119.187545) (xy 114.212629 -119.133108) (xy 114.208558 -119.077486) (xy 103.157994 -119.077486)
			(xy 103.121129 -119.099985) (xy 103.0698 -119.121797) (xy 103.015843 -119.135903) (xy 102.960406 -119.142003)
			(xy 102.904672 -119.139966) (xy 102.849829 -119.129836) (xy 102.797045 -119.111829) (xy 102.747445 -119.086328)
			(xy 102.702087 -119.053877) (xy 102.661938 -119.015168) (xy 102.627852 -118.971025) (xy 102.600556 -118.92239)
			(xy 102.580633 -118.870299) (xy 102.568507 -118.815862) (xy 102.564436 -118.76024) (xy 98.108737 -118.76024)
			(xy 98.086703 -118.778577) (xy 98.039097 -118.807631) (xy 97.987768 -118.829443) (xy 97.933811 -118.843549)
			(xy 97.878374 -118.849649) (xy 97.82264 -118.847612) (xy 97.767797 -118.837482) (xy 97.715013 -118.819475)
			(xy 97.665413 -118.793974) (xy 97.620055 -118.761523) (xy 97.579906 -118.722814) (xy 97.54582 -118.678671)
			(xy 97.518524 -118.630036) (xy 97.498601 -118.577945) (xy 97.486475 -118.523508) (xy 97.482404 -118.467886)
			(xy 81.929065 -118.467886) (xy 81.943395 -118.492705) (xy 81.966346 -118.548107) (xy 81.981869 -118.606031)
			(xy 81.9897 -118.665486) (xy 81.990184 -118.69547) (xy 81.990184 -119.407554) (xy 94.499632 -119.407554)
			(xy 94.499632 -119.353046) (xy 94.507389 -119.299093) (xy 94.522745 -119.246794) (xy 94.545388 -119.197211)
			(xy 94.574856 -119.151356) (xy 94.61055 -119.110162) (xy 94.651743 -119.074466) (xy 94.697597 -119.044995)
			(xy 94.747179 -119.022351) (xy 94.799478 -119.006992) (xy 94.85343 -118.999233) (xy 94.880684 -118.998746)
			(xy 94.908054 -118.99921) (xy 94.962234 -119.007027) (xy 95.014738 -119.022516) (xy 95.064484 -119.045358)
			(xy 95.110451 -119.075084) (xy 95.131382 -119.092726) (xy 95.131636 -119.09298) (xy 95.13873 -119.098555)
			(xy 95.155641 -119.104807) (xy 95.164656 -119.105172) (xy 95.231712 -119.105172) (xy 95.24073 -119.104827)
			(xy 95.257647 -119.098572) (xy 95.264732 -119.09298) (xy 95.264732 -119.092726) (xy 95.264986 -119.092726)
			(xy 95.285916 -119.075084) (xy 95.331889 -119.045372) (xy 95.381637 -119.022536) (xy 95.434138 -119.007046)
			(xy 95.488315 -118.999219) (xy 95.515684 -118.998746) (xy 95.542934 -118.9993) (xy 95.59688 -119.007054)
			(xy 95.649174 -119.022407) (xy 95.69875 -119.045046) (xy 95.7446 -119.07451) (xy 95.785789 -119.110199)
			(xy 95.82148 -119.151387) (xy 95.850946 -119.197236) (xy 95.873587 -119.246811) (xy 95.888942 -119.299104)
			(xy 95.896699 -119.35305) (xy 95.896699 -119.40755) (xy 95.888942 -119.461496) (xy 95.884381 -119.477028)
			(xy 99.60813 -119.477028) (xy 99.612201 -119.421406) (xy 99.624327 -119.366969) (xy 99.64425 -119.314878)
			(xy 99.671546 -119.266243) (xy 99.705632 -119.2221) (xy 99.745781 -119.183391) (xy 99.791139 -119.15094)
			(xy 99.840739 -119.125439) (xy 99.893523 -119.107432) (xy 99.948366 -119.097302) (xy 100.0041 -119.095265)
			(xy 100.059537 -119.101365) (xy 100.113494 -119.115471) (xy 100.164823 -119.137283) (xy 100.212429 -119.166337)
			(xy 100.255297 -119.202012) (xy 100.292514 -119.243549) (xy 100.323287 -119.290062) (xy 100.346959 -119.340559)
			(xy 100.363027 -119.393966) (xy 100.371147 -119.449142) (xy 100.371656 -119.477028) (xy 100.371147 -119.504914)
			(xy 100.363027 -119.56009) (xy 100.346959 -119.613497) (xy 100.323287 -119.663994) (xy 100.292514 -119.710507)
			(xy 100.255297 -119.752044) (xy 100.226222 -119.77624) (xy 100.535992 -119.77624) (xy 100.540063 -119.720618)
			(xy 100.552189 -119.666181) (xy 100.572112 -119.61409) (xy 100.599408 -119.565455) (xy 100.633494 -119.521312)
			(xy 100.673643 -119.482603) (xy 100.719001 -119.450152) (xy 100.768601 -119.424651) (xy 100.821385 -119.406644)
			(xy 100.876228 -119.396514) (xy 100.931962 -119.394477) (xy 100.987399 -119.400577) (xy 101.041356 -119.414683)
			(xy 101.092685 -119.436495) (xy 101.140291 -119.465549) (xy 101.183159 -119.501224) (xy 101.220376 -119.542761)
			(xy 101.251149 -119.589274) (xy 101.274821 -119.639771) (xy 101.290889 -119.693178) (xy 101.294665 -119.718836)
			(xy 107.536486 -119.718836) (xy 107.540557 -119.663214) (xy 107.552683 -119.608777) (xy 107.572606 -119.556686)
			(xy 107.599902 -119.508051) (xy 107.633988 -119.463908) (xy 107.674137 -119.425199) (xy 107.719495 -119.392748)
			(xy 107.769095 -119.367247) (xy 107.821879 -119.34924) (xy 107.876722 -119.33911) (xy 107.932456 -119.337073)
			(xy 107.987893 -119.343173) (xy 108.04185 -119.357279) (xy 108.093179 -119.379091) (xy 108.140785 -119.408145)
			(xy 108.183653 -119.44382) (xy 108.22087 -119.485357) (xy 108.251643 -119.53187) (xy 108.275315 -119.582367)
			(xy 108.291383 -119.635774) (xy 108.299503 -119.69095) (xy 108.300012 -119.718836) (xy 108.299503 -119.746722)
			(xy 108.291383 -119.801898) (xy 108.275315 -119.855305) (xy 108.251643 -119.905802) (xy 108.22087 -119.952315)
			(xy 108.183653 -119.993852) (xy 108.140785 -120.029527) (xy 108.093179 -120.058581) (xy 108.04185 -120.080393)
			(xy 107.987893 -120.094499) (xy 107.932456 -120.100599) (xy 107.876722 -120.098562) (xy 107.821879 -120.088432)
			(xy 107.769095 -120.070425) (xy 107.719495 -120.044924) (xy 107.674137 -120.012473) (xy 107.633988 -119.973764)
			(xy 107.599902 -119.929621) (xy 107.572606 -119.880986) (xy 107.552683 -119.828895) (xy 107.540557 -119.774458)
			(xy 107.536486 -119.718836) (xy 101.294665 -119.718836) (xy 101.299009 -119.748354) (xy 101.299518 -119.77624)
			(xy 101.299009 -119.804126) (xy 101.290889 -119.859302) (xy 101.274821 -119.912709) (xy 101.251149 -119.963206)
			(xy 101.220376 -120.009719) (xy 101.183159 -120.051256) (xy 101.140291 -120.086931) (xy 101.092685 -120.115985)
			(xy 101.041356 -120.137797) (xy 100.987399 -120.151903) (xy 100.931962 -120.158003) (xy 100.876228 -120.155966)
			(xy 100.821385 -120.145836) (xy 100.768601 -120.127829) (xy 100.719001 -120.102328) (xy 100.673643 -120.069877)
			(xy 100.633494 -120.031168) (xy 100.599408 -119.987025) (xy 100.572112 -119.93839) (xy 100.552189 -119.886299)
			(xy 100.540063 -119.831862) (xy 100.535992 -119.77624) (xy 100.226222 -119.77624) (xy 100.212429 -119.787719)
			(xy 100.164823 -119.816773) (xy 100.113494 -119.838585) (xy 100.059537 -119.852691) (xy 100.0041 -119.858791)
			(xy 99.948366 -119.856754) (xy 99.893523 -119.846624) (xy 99.840739 -119.828617) (xy 99.791139 -119.803116)
			(xy 99.745781 -119.770665) (xy 99.705632 -119.731956) (xy 99.671546 -119.687813) (xy 99.64425 -119.639178)
			(xy 99.624327 -119.587087) (xy 99.612201 -119.53265) (xy 99.60813 -119.477028) (xy 95.884381 -119.477028)
			(xy 95.873587 -119.513789) (xy 95.850946 -119.563364) (xy 95.82148 -119.609213) (xy 95.785789 -119.650401)
			(xy 95.7446 -119.68609) (xy 95.69875 -119.715554) (xy 95.649174 -119.738193) (xy 95.59688 -119.753546)
			(xy 95.542934 -119.7613) (xy 95.515684 -119.761762) (xy 95.488313 -119.761315) (xy 95.434133 -119.753494)
			(xy 95.381629 -119.738001) (xy 95.331882 -119.715155) (xy 95.285917 -119.685426) (xy 95.264986 -119.667782)
			(xy 95.264732 -119.667528) (xy 95.257647 -119.66194) (xy 95.240729 -119.655696) (xy 95.231712 -119.655336)
			(xy 95.164656 -119.655336) (xy 95.155641 -119.655712) (xy 95.138723 -119.661946) (xy 95.131636 -119.667528)
			(xy 95.131636 -119.667782) (xy 95.131382 -119.667782) (xy 95.110428 -119.685393) (xy 95.064461 -119.71511)
			(xy 95.014719 -119.737952) (xy 94.962224 -119.753449) (xy 94.908052 -119.761284) (xy 94.880684 -119.761762)
			(xy 94.85343 -119.761367) (xy 94.799478 -119.753608) (xy 94.747179 -119.738249) (xy 94.697597 -119.715605)
			(xy 94.651743 -119.686134) (xy 94.61055 -119.650438) (xy 94.574856 -119.609244) (xy 94.545388 -119.563389)
			(xy 94.522745 -119.513806) (xy 94.507389 -119.461507) (xy 94.499632 -119.407554) (xy 81.990184 -119.407554)
			(xy 81.990184 -119.55907) (xy 81.989717 -119.589057) (xy 81.981892 -119.64852) (xy 81.966373 -119.706452)
			(xy 81.943425 -119.761863) (xy 81.913441 -119.813805) (xy 81.876933 -119.861388) (xy 81.845245 -119.89308)
			(xy 97.569018 -119.89308) (xy 97.573089 -119.837458) (xy 97.585215 -119.783021) (xy 97.605138 -119.73093)
			(xy 97.632434 -119.682295) (xy 97.66652 -119.638152) (xy 97.706669 -119.599443) (xy 97.752027 -119.566992)
			(xy 97.801627 -119.541491) (xy 97.854411 -119.523484) (xy 97.909254 -119.513354) (xy 97.964988 -119.511317)
			(xy 98.020425 -119.517417) (xy 98.074382 -119.531523) (xy 98.125711 -119.553335) (xy 98.173317 -119.582389)
			(xy 98.216185 -119.618064) (xy 98.253402 -119.659601) (xy 98.284175 -119.706114) (xy 98.307847 -119.756611)
			(xy 98.323915 -119.810018) (xy 98.332035 -119.865194) (xy 98.332544 -119.89308) (xy 98.332035 -119.920966)
			(xy 98.323915 -119.976142) (xy 98.307847 -120.029549) (xy 98.284175 -120.080046) (xy 98.253402 -120.126559)
			(xy 98.216185 -120.168096) (xy 98.173317 -120.203771) (xy 98.125711 -120.232825) (xy 98.074382 -120.254637)
			(xy 98.020425 -120.268743) (xy 97.964988 -120.274843) (xy 97.909254 -120.272806) (xy 97.854411 -120.262676)
			(xy 97.801627 -120.244669) (xy 97.752027 -120.219168) (xy 97.706669 -120.186717) (xy 97.66652 -120.148008)
			(xy 97.632434 -120.103865) (xy 97.605138 -120.05523) (xy 97.585215 -120.003139) (xy 97.573089 -119.948702)
			(xy 97.569018 -119.89308) (xy 81.845245 -119.89308) (xy 81.834527 -119.903799) (xy 81.786948 -119.940312)
			(xy 81.73501 -119.970302) (xy 81.679601 -119.993257) (xy 81.621671 -120.008782) (xy 81.562209 -120.016613)
			(xy 81.532222 -120.017032) (xy 81.531968 -120.017032) (xy 81.503133 -120.016559) (xy 81.445922 -120.009292)
			(xy 81.390072 -119.994914) (xy 81.336464 -119.973652) (xy 81.310988 -119.960136) (xy 81.3054 -119.957088)
			(xy 81.280762 -119.950484) (xy 81.269332 -119.951754) (xy 81.239106 -119.958612) (xy 81.230547 -119.960893)
			(xy 81.215611 -119.970386) (xy 81.209896 -119.977154) (xy 81.20634 -119.98198) (xy 81.205578 -119.982996)
			(xy 81.188092 -120.005886) (xy 81.147376 -120.046629) (xy 81.100994 -120.080782) (xy 81.05 -120.107566)
			(xy 80.995557 -120.126373) (xy 80.967326 -120.132094) (xy 80.967072 -120.132094) (xy 80.960722 -120.133618)
			(xy 80.950823 -120.137406) (xy 80.935041 -120.151519) (xy 80.926277 -120.170791) (xy 80.92567 -120.18137)
			(xy 80.911947 -121.365772) (xy 83.716368 -121.365772) (xy 83.716368 -120.502172) (xy 83.716858 -120.472188)
			(xy 83.724686 -120.412732) (xy 83.740207 -120.354807) (xy 83.763156 -120.299403) (xy 83.79314 -120.247469)
			(xy 83.829646 -120.199893) (xy 83.872051 -120.157488) (xy 83.919627 -120.120982) (xy 83.971561 -120.090998)
			(xy 84.026965 -120.068049) (xy 84.08489 -120.052528) (xy 84.144346 -120.0447) (xy 84.204314 -120.0447)
			(xy 84.26377 -120.052528) (xy 84.321695 -120.068049) (xy 84.377099 -120.090998) (xy 84.429033 -120.120982)
			(xy 84.476609 -120.157488) (xy 84.519014 -120.199893) (xy 84.55552 -120.247469) (xy 84.585504 -120.299403)
			(xy 84.608453 -120.354807) (xy 84.623974 -120.412732) (xy 84.631802 -120.472188) (xy 84.632292 -120.502172)
			(xy 84.632292 -121.365772) (xy 84.631802 -121.395756) (xy 84.623974 -121.455212) (xy 84.608453 -121.513137)
			(xy 84.585504 -121.568541) (xy 84.55552 -121.620475) (xy 84.519014 -121.668051) (xy 84.476609 -121.710456)
			(xy 84.429033 -121.746962) (xy 84.377099 -121.776946) (xy 84.321695 -121.799895) (xy 84.26377 -121.815416)
			(xy 84.204314 -121.823244) (xy 84.144346 -121.823244) (xy 84.08489 -121.815416) (xy 84.026965 -121.799895)
			(xy 83.971561 -121.776946) (xy 83.919627 -121.746962) (xy 83.872051 -121.710456) (xy 83.829646 -121.668051)
			(xy 83.79314 -121.620475) (xy 83.763156 -121.568541) (xy 83.740207 -121.513137) (xy 83.724686 -121.455212)
			(xy 83.716858 -121.395756) (xy 83.716368 -121.365772) (xy 80.911947 -121.365772) (xy 80.908398 -121.672096)
			(xy 80.90917 -121.680926) (xy 80.91592 -121.697301) (xy 80.921606 -121.7041) (xy 80.951832 -121.720356)
			(xy 80.952086 -121.720356) (xy 80.977277 -121.724395) (xy 81.026366 -121.738294) (xy 81.073168 -121.758604)
			(xy 81.116849 -121.784965) (xy 81.156631 -121.816907) (xy 81.191806 -121.853861) (xy 81.207102 -121.87428)
			(xy 81.20888 -121.876566) (xy 81.231486 -121.891298) (xy 81.235321 -121.893691) (xy 81.243625 -121.897259)
			(xy 81.247996 -121.89841) (xy 81.268824 -121.903236) (xy 81.273842 -121.904261) (xy 81.28408 -121.904513)
			(xy 81.289144 -121.903744) (xy 81.293419 -121.902855) (xy 81.301593 -121.899786) (xy 81.3054 -121.897648)
			(xy 81.331358 -121.883406) (xy 81.386161 -121.860993) (xy 81.443397 -121.845835) (xy 81.50211 -121.838187)
			(xy 81.531714 -121.837704) (xy 81.532222 -121.837704) (xy 81.562206 -121.838195) (xy 81.621661 -121.846025)
			(xy 81.679586 -121.861548) (xy 81.734989 -121.884498) (xy 81.786923 -121.914482) (xy 81.834499 -121.950988)
			(xy 81.876904 -121.993392) (xy 81.913411 -122.040967) (xy 81.943397 -122.0929) (xy 81.966348 -122.148303)
			(xy 81.978069 -122.192034) (xy 89.450672 -122.192034) (xy 89.45114 -122.164664) (xy 89.458955 -122.110484)
			(xy 89.474443 -122.05798) (xy 89.497284 -122.008233) (xy 89.52701 -121.962267) (xy 89.544652 -121.941336)
			(xy 89.544906 -121.941082) (xy 89.550507 -121.934005) (xy 89.556745 -121.917081) (xy 89.557098 -121.908062)
			(xy 89.557098 -121.841006) (xy 89.556739 -121.831989) (xy 89.550493 -121.815072) (xy 89.544906 -121.807986)
			(xy 89.544652 -121.807986) (xy 89.544652 -121.807732) (xy 89.527044 -121.786773) (xy 89.497316 -121.74081)
			(xy 89.474467 -121.691068) (xy 89.458967 -121.63857) (xy 89.451134 -121.584395) (xy 89.451131 -121.529656)
			(xy 89.458956 -121.47548) (xy 89.474449 -121.42298) (xy 89.497291 -121.373235) (xy 89.527013 -121.327268)
			(xy 89.544652 -121.306336) (xy 89.544906 -121.306082) (xy 89.550507 -121.299005) (xy 89.556745 -121.282081)
			(xy 89.557098 -121.273062) (xy 89.557098 -121.206006) (xy 89.556739 -121.196989) (xy 89.550493 -121.180072)
			(xy 89.544906 -121.172986) (xy 89.544652 -121.172986) (xy 89.544652 -121.172732) (xy 89.527044 -121.151773)
			(xy 89.497316 -121.10581) (xy 89.474467 -121.056068) (xy 89.458967 -121.00357) (xy 89.451134 -120.949395)
			(xy 89.451131 -120.894656) (xy 89.458956 -120.84048) (xy 89.474449 -120.78798) (xy 89.497291 -120.738235)
			(xy 89.527013 -120.692268) (xy 89.544652 -120.671336) (xy 89.544906 -120.671082) (xy 89.550507 -120.664005)
			(xy 89.556745 -120.647081) (xy 89.557098 -120.638062) (xy 89.557098 -120.571006) (xy 89.556739 -120.561989)
			(xy 89.550493 -120.545072) (xy 89.544906 -120.537986) (xy 89.544652 -120.537986) (xy 89.544652 -120.537732)
			(xy 89.527023 -120.516792) (xy 89.497307 -120.470822) (xy 89.474469 -120.421077) (xy 89.458976 -120.368578)
			(xy 89.451146 -120.314403) (xy 89.450672 -120.287034) (xy 89.451158 -120.259783) (xy 89.458914 -120.205835)
			(xy 89.474269 -120.15354) (xy 89.496911 -120.103963) (xy 89.526377 -120.058113) (xy 89.562068 -120.016922)
			(xy 89.603259 -119.981231) (xy 89.649109 -119.951765) (xy 89.698686 -119.929123) (xy 89.750981 -119.913768)
			(xy 89.804929 -119.906012) (xy 89.859431 -119.906012) (xy 89.913379 -119.913768) (xy 89.965674 -119.929123)
			(xy 90.015251 -119.951765) (xy 90.061101 -119.981231) (xy 90.102292 -120.016922) (xy 90.137983 -120.058113)
			(xy 90.167449 -120.103963) (xy 90.190091 -120.15354) (xy 90.205446 -120.205835) (xy 90.213202 -120.259783)
			(xy 90.213688 -120.287034) (xy 90.213245 -120.314405) (xy 90.205422 -120.368585) (xy 90.189928 -120.421089)
			(xy 90.167081 -120.470835) (xy 90.152727 -120.493028) (xy 99.604066 -120.493028) (xy 99.608137 -120.437406)
			(xy 99.620263 -120.382969) (xy 99.640186 -120.330878) (xy 99.667482 -120.282243) (xy 99.701568 -120.2381)
			(xy 99.741717 -120.199391) (xy 99.787075 -120.16694) (xy 99.836675 -120.141439) (xy 99.889459 -120.123432)
			(xy 99.944302 -120.113302) (xy 100.000036 -120.111265) (xy 100.055473 -120.117365) (xy 100.10943 -120.131471)
			(xy 100.160759 -120.153283) (xy 100.208365 -120.182337) (xy 100.251233 -120.218012) (xy 100.28845 -120.259549)
			(xy 100.319223 -120.306062) (xy 100.342895 -120.356559) (xy 100.358963 -120.409966) (xy 100.367083 -120.465142)
			(xy 100.367592 -120.493028) (xy 100.367083 -120.520914) (xy 100.358963 -120.57609) (xy 100.342895 -120.629497)
			(xy 100.319223 -120.679994) (xy 100.28845 -120.726507) (xy 100.251233 -120.768044) (xy 100.222158 -120.79224)
			(xy 100.535992 -120.79224) (xy 100.540063 -120.736618) (xy 100.552189 -120.682181) (xy 100.572112 -120.63009)
			(xy 100.599408 -120.581455) (xy 100.633494 -120.537312) (xy 100.673643 -120.498603) (xy 100.719001 -120.466152)
			(xy 100.768601 -120.440651) (xy 100.821385 -120.422644) (xy 100.876228 -120.412514) (xy 100.931962 -120.410477)
			(xy 100.987399 -120.416577) (xy 101.041356 -120.430683) (xy 101.092685 -120.452495) (xy 101.140291 -120.481549)
			(xy 101.183159 -120.517224) (xy 101.220376 -120.558761) (xy 101.251149 -120.605274) (xy 101.274821 -120.655771)
			(xy 101.290889 -120.709178) (xy 101.299009 -120.764354) (xy 101.299518 -120.79224) (xy 102.691436 -120.79224)
			(xy 102.695507 -120.736618) (xy 102.707633 -120.682181) (xy 102.727556 -120.63009) (xy 102.754852 -120.581455)
			(xy 102.788938 -120.537312) (xy 102.829087 -120.498603) (xy 102.874445 -120.466152) (xy 102.924045 -120.440651)
			(xy 102.976829 -120.422644) (xy 103.031672 -120.412514) (xy 103.087406 -120.410477) (xy 103.142843 -120.416577)
			(xy 103.1968 -120.430683) (xy 103.248129 -120.452495) (xy 103.295735 -120.481549) (xy 103.338603 -120.517224)
			(xy 103.346737 -120.526302) (xy 105.993436 -120.526302) (xy 105.997507 -120.47068) (xy 106.009633 -120.416243)
			(xy 106.029556 -120.364152) (xy 106.056852 -120.315517) (xy 106.090938 -120.271374) (xy 106.131087 -120.232665)
			(xy 106.176445 -120.200214) (xy 106.226045 -120.174713) (xy 106.278829 -120.156706) (xy 106.333672 -120.146576)
			(xy 106.389406 -120.144539) (xy 106.444843 -120.150639) (xy 106.4988 -120.164745) (xy 106.550129 -120.186557)
			(xy 106.597735 -120.215611) (xy 106.640603 -120.251286) (xy 106.67782 -120.292823) (xy 106.708593 -120.339336)
			(xy 106.711937 -120.34647) (xy 116.321076 -120.34647) (xy 116.325147 -120.290848) (xy 116.337273 -120.236411)
			(xy 116.357196 -120.18432) (xy 116.384492 -120.135685) (xy 116.418578 -120.091542) (xy 116.458727 -120.052833)
			(xy 116.504085 -120.020382) (xy 116.553685 -119.994881) (xy 116.606469 -119.976874) (xy 116.661312 -119.966744)
			(xy 116.717046 -119.964707) (xy 116.772483 -119.970807) (xy 116.82644 -119.984913) (xy 116.877769 -120.006725)
			(xy 116.925375 -120.035779) (xy 116.968243 -120.071454) (xy 117.00546 -120.112991) (xy 117.036233 -120.159504)
			(xy 117.059905 -120.210001) (xy 117.075973 -120.263408) (xy 117.084093 -120.318584) (xy 117.084602 -120.34647)
			(xy 117.084093 -120.374356) (xy 117.075973 -120.429532) (xy 117.059905 -120.482939) (xy 117.036233 -120.533436)
			(xy 117.00546 -120.579949) (xy 116.968243 -120.621486) (xy 116.925375 -120.657161) (xy 116.877769 -120.686215)
			(xy 116.82644 -120.708027) (xy 116.772483 -120.722133) (xy 116.717046 -120.728233) (xy 116.661312 -120.726196)
			(xy 116.606469 -120.716066) (xy 116.553685 -120.698059) (xy 116.504085 -120.672558) (xy 116.458727 -120.640107)
			(xy 116.418578 -120.601398) (xy 116.384492 -120.557255) (xy 116.357196 -120.50862) (xy 116.337273 -120.456529)
			(xy 116.325147 -120.402092) (xy 116.321076 -120.34647) (xy 106.711937 -120.34647) (xy 106.732265 -120.389833)
			(xy 106.748333 -120.44324) (xy 106.756453 -120.498416) (xy 106.756962 -120.526302) (xy 106.756453 -120.554188)
			(xy 106.748333 -120.609364) (xy 106.732265 -120.662771) (xy 106.708593 -120.713268) (xy 106.67782 -120.759781)
			(xy 106.640603 -120.801318) (xy 106.597735 -120.836993) (xy 106.550129 -120.866047) (xy 106.4988 -120.887859)
			(xy 106.444843 -120.901965) (xy 106.389406 -120.908065) (xy 106.333672 -120.906028) (xy 106.278829 -120.895898)
			(xy 106.226045 -120.877891) (xy 106.176445 -120.85239) (xy 106.131087 -120.819939) (xy 106.090938 -120.78123)
			(xy 106.056852 -120.737087) (xy 106.029556 -120.688452) (xy 106.009633 -120.636361) (xy 105.997507 -120.581924)
			(xy 105.993436 -120.526302) (xy 103.346737 -120.526302) (xy 103.37582 -120.558761) (xy 103.406593 -120.605274)
			(xy 103.430265 -120.655771) (xy 103.446333 -120.709178) (xy 103.454453 -120.764354) (xy 103.454962 -120.79224)
			(xy 103.454453 -120.820126) (xy 103.446333 -120.875302) (xy 103.430265 -120.928709) (xy 103.406593 -120.979206)
			(xy 103.37582 -121.025719) (xy 103.338696 -121.067152) (xy 117.690368 -121.067152) (xy 117.690368 -121.012648)
			(xy 117.698124 -120.9587) (xy 117.713479 -120.906404) (xy 117.736121 -120.856826) (xy 117.765587 -120.810975)
			(xy 117.801278 -120.769784) (xy 117.842469 -120.734092) (xy 117.888319 -120.704624) (xy 117.937897 -120.681982)
			(xy 117.990192 -120.666626) (xy 118.04414 -120.658868) (xy 118.071392 -120.658382) (xy 118.10031 -120.658875)
			(xy 118.157484 -120.667605) (xy 118.212685 -120.684866) (xy 118.264647 -120.710262) (xy 118.31218 -120.743212)
			(xy 118.354194 -120.782959) (xy 118.372382 -120.805448) (xy 118.379999 -120.814245) (xy 118.400892 -120.824432)
			(xy 118.412514 -120.825006) (xy 118.49227 -120.825006) (xy 118.503898 -120.824433) (xy 118.524807 -120.814268)
			(xy 118.532402 -120.805448) (xy 118.550579 -120.782953) (xy 118.592603 -120.743221) (xy 118.640141 -120.710285)
			(xy 118.692105 -120.684899) (xy 118.747305 -120.667644) (xy 118.804475 -120.658917) (xy 118.833392 -120.658382)
			(xy 118.860645 -120.658865) (xy 118.914595 -120.666621) (xy 118.966892 -120.681976) (xy 119.016472 -120.704617)
			(xy 119.062325 -120.734084) (xy 119.103518 -120.769777) (xy 119.139211 -120.810969) (xy 119.168679 -120.856821)
			(xy 119.191322 -120.9064) (xy 119.206678 -120.958697) (xy 119.214435 -121.012647) (xy 119.214435 -121.067153)
			(xy 119.206678 -121.121103) (xy 119.191322 -121.1734) (xy 119.168679 -121.222979) (xy 119.139211 -121.268831)
			(xy 119.103518 -121.310023) (xy 119.062325 -121.345716) (xy 119.016472 -121.375183) (xy 118.966892 -121.397824)
			(xy 118.914595 -121.413179) (xy 118.860645 -121.420935) (xy 118.833392 -121.421398) (xy 118.804477 -121.420815)
			(xy 118.747309 -121.412099) (xy 118.692112 -121.394854) (xy 118.64015 -121.369475) (xy 118.592614 -121.336543)
			(xy 118.550594 -121.296812) (xy 118.532402 -121.274332) (xy 118.524796 -121.265524) (xy 118.503894 -121.255344)
			(xy 118.49227 -121.254774) (xy 118.412514 -121.254774) (xy 118.400881 -121.25531) (xy 118.37997 -121.265498)
			(xy 118.372382 -121.274332) (xy 118.354209 -121.296831) (xy 118.312185 -121.336564) (xy 118.264646 -121.3695)
			(xy 118.212681 -121.394885) (xy 118.157481 -121.412139) (xy 118.100309 -121.420865) (xy 118.071392 -121.421398)
			(xy 118.04414 -121.420932) (xy 117.990192 -121.413174) (xy 117.937897 -121.397818) (xy 117.888319 -121.375176)
			(xy 117.842469 -121.345708) (xy 117.801278 -121.310016) (xy 117.765587 -121.268825) (xy 117.736121 -121.222974)
			(xy 117.713479 -121.173396) (xy 117.698124 -121.1211) (xy 117.690368 -121.067152) (xy 103.338696 -121.067152)
			(xy 103.338603 -121.067256) (xy 103.295735 -121.102931) (xy 103.248129 -121.131985) (xy 103.1968 -121.153797)
			(xy 103.142843 -121.167903) (xy 103.087406 -121.174003) (xy 103.031672 -121.171966) (xy 102.976829 -121.161836)
			(xy 102.924045 -121.143829) (xy 102.874445 -121.118328) (xy 102.829087 -121.085877) (xy 102.788938 -121.047168)
			(xy 102.754852 -121.003025) (xy 102.727556 -120.95439) (xy 102.707633 -120.902299) (xy 102.695507 -120.847862)
			(xy 102.691436 -120.79224) (xy 101.299518 -120.79224) (xy 101.299009 -120.820126) (xy 101.290889 -120.875302)
			(xy 101.274821 -120.928709) (xy 101.251149 -120.979206) (xy 101.220376 -121.025719) (xy 101.183159 -121.067256)
			(xy 101.140291 -121.102931) (xy 101.092685 -121.131985) (xy 101.041356 -121.153797) (xy 100.987399 -121.167903)
			(xy 100.931962 -121.174003) (xy 100.876228 -121.171966) (xy 100.821385 -121.161836) (xy 100.768601 -121.143829)
			(xy 100.719001 -121.118328) (xy 100.673643 -121.085877) (xy 100.633494 -121.047168) (xy 100.599408 -121.003025)
			(xy 100.572112 -120.95439) (xy 100.552189 -120.902299) (xy 100.540063 -120.847862) (xy 100.535992 -120.79224)
			(xy 100.222158 -120.79224) (xy 100.208365 -120.803719) (xy 100.160759 -120.832773) (xy 100.10943 -120.854585)
			(xy 100.055473 -120.868691) (xy 100.000036 -120.874791) (xy 99.944302 -120.872754) (xy 99.889459 -120.862624)
			(xy 99.836675 -120.844617) (xy 99.787075 -120.819116) (xy 99.741717 -120.786665) (xy 99.701568 -120.747956)
			(xy 99.667482 -120.703813) (xy 99.640186 -120.655178) (xy 99.620263 -120.603087) (xy 99.608137 -120.54865)
			(xy 99.604066 -120.493028) (xy 90.152727 -120.493028) (xy 90.137351 -120.516801) (xy 90.119708 -120.537732)
			(xy 90.119454 -120.537986) (xy 90.113862 -120.545068) (xy 90.10762 -120.561989) (xy 90.107262 -120.571006)
			(xy 90.107262 -120.638062) (xy 90.107645 -120.647076) (xy 90.113876 -120.663993) (xy 90.119454 -120.671082)
			(xy 90.119708 -120.671082) (xy 90.119708 -120.671336) (xy 90.137381 -120.692242) (xy 90.167101 -120.738216)
			(xy 90.189943 -120.787966) (xy 90.205435 -120.840472) (xy 90.213259 -120.894654) (xy 90.213256 -120.949397)
			(xy 90.205424 -121.003578) (xy 90.189925 -121.056082) (xy 90.167077 -121.105829) (xy 90.13735 -121.151799)
			(xy 90.119708 -121.172732) (xy 90.119454 -121.172986) (xy 90.113862 -121.180068) (xy 90.10762 -121.196989)
			(xy 90.10755 -121.198753) (xy 90.48544 -121.198753) (xy 90.48544 -121.144247) (xy 90.493196 -121.090297)
			(xy 90.508551 -121.038) (xy 90.531192 -120.98842) (xy 90.560659 -120.942566) (xy 90.59635 -120.901373)
			(xy 90.637541 -120.865678) (xy 90.683392 -120.836208) (xy 90.73297 -120.813562) (xy 90.785266 -120.798203)
			(xy 90.839216 -120.790442) (xy 90.866468 -120.789954) (xy 90.893838 -120.790426) (xy 90.948018 -120.79824)
			(xy 91.000521 -120.813727) (xy 91.050268 -120.836568) (xy 91.096235 -120.866293) (xy 91.117166 -120.883934)
			(xy 91.11742 -120.884188) (xy 91.124498 -120.889788) (xy 91.141421 -120.896027) (xy 91.15044 -120.89638)
			(xy 91.217496 -120.89638) (xy 91.226513 -120.896026) (xy 91.24343 -120.889777) (xy 91.250516 -120.884188)
			(xy 91.250516 -120.883934) (xy 91.25077 -120.883934) (xy 91.271707 -120.866301) (xy 91.317678 -120.836587)
			(xy 91.367424 -120.813749) (xy 91.419924 -120.798257) (xy 91.474099 -120.790428) (xy 91.501468 -120.789954)
			(xy 91.52872 -120.790491) (xy 91.582669 -120.798244) (xy 91.634965 -120.813595) (xy 91.684544 -120.836234)
			(xy 91.730397 -120.865698) (xy 91.771589 -120.901388) (xy 91.807283 -120.942577) (xy 91.836751 -120.988428)
			(xy 91.859394 -121.038005) (xy 91.87475 -121.0903) (xy 91.882507 -121.144248) (xy 91.882507 -121.198752)
			(xy 91.87475 -121.2527) (xy 91.859394 -121.304995) (xy 91.836751 -121.354572) (xy 91.807283 -121.400423)
			(xy 91.771589 -121.441612) (xy 91.730397 -121.477302) (xy 91.684544 -121.506766) (xy 91.634965 -121.529405)
			(xy 91.582669 -121.544756) (xy 91.52872 -121.552509) (xy 91.501468 -121.55297) (xy 91.474097 -121.55253)
			(xy 91.419916 -121.544707) (xy 91.367413 -121.529212) (xy 91.317666 -121.506365) (xy 91.271701 -121.476634)
			(xy 91.25077 -121.45899) (xy 91.250516 -121.458736) (xy 91.243435 -121.453142) (xy 91.226514 -121.446902)
			(xy 91.217496 -121.446544) (xy 91.15044 -121.446544) (xy 91.141424 -121.446911) (xy 91.124506 -121.45315)
			(xy 91.11742 -121.458736) (xy 91.11742 -121.45899) (xy 91.117166 -121.45899) (xy 91.096219 -121.47661)
			(xy 91.05025 -121.506325) (xy 91.000507 -121.529165) (xy 90.948009 -121.54466) (xy 90.893836 -121.552493)
			(xy 90.866468 -121.55297) (xy 90.839216 -121.552558) (xy 90.785266 -121.544797) (xy 90.73297 -121.529438)
			(xy 90.683392 -121.506792) (xy 90.637541 -121.477322) (xy 90.59635 -121.441627) (xy 90.560659 -121.400434)
			(xy 90.531192 -121.35458) (xy 90.508551 -121.305) (xy 90.493196 -121.252703) (xy 90.48544 -121.198753)
			(xy 90.10755 -121.198753) (xy 90.107262 -121.206006) (xy 90.107262 -121.273062) (xy 90.107645 -121.282076)
			(xy 90.113876 -121.298993) (xy 90.119454 -121.306082) (xy 90.119708 -121.306082) (xy 90.119708 -121.306336)
			(xy 90.137381 -121.327242) (xy 90.167101 -121.373216) (xy 90.189943 -121.422966) (xy 90.205435 -121.475472)
			(xy 90.213259 -121.529654) (xy 90.213256 -121.581672) (xy 91.994736 -121.581672) (xy 91.995177 -121.554301)
			(xy 92.002999 -121.50012) (xy 92.018494 -121.447617) (xy 92.041341 -121.39787) (xy 92.071072 -121.351905)
			(xy 92.088716 -121.330974) (xy 92.08897 -121.33072) (xy 92.094563 -121.323638) (xy 92.100804 -121.306717)
			(xy 92.101162 -121.2977) (xy 92.101162 -121.230644) (xy 92.100792 -121.221628) (xy 92.094554 -121.204711)
			(xy 92.08897 -121.197624) (xy 92.088716 -121.197624) (xy 92.088716 -121.19737) (xy 92.071099 -121.17642)
			(xy 92.041383 -121.130453) (xy 92.018543 -121.08071) (xy 92.003047 -121.028213) (xy 91.995213 -120.97404)
			(xy 91.994736 -120.946672) (xy 91.995129 -120.919416) (xy 92.002891 -120.865461) (xy 92.018253 -120.813159)
			(xy 92.040902 -120.763576) (xy 92.070377 -120.71772) (xy 92.106078 -120.676527) (xy 92.147278 -120.640834)
			(xy 92.193139 -120.611367) (xy 92.242726 -120.588728) (xy 92.295031 -120.573376) (xy 92.348988 -120.565624)
			(xy 92.376244 -120.565164) (xy 92.405365 -120.565735) (xy 92.462934 -120.574566) (xy 92.518491 -120.592047)
			(xy 92.570744 -120.617772) (xy 92.618478 -120.651142) (xy 92.660584 -120.691381) (xy 92.696083 -120.737554)
			(xy 92.724149 -120.788588) (xy 92.74413 -120.843295) (xy 92.750386 -120.871742) (xy 92.752672 -120.883426)
			(xy 92.76715 -120.902222) (xy 92.851224 -120.942608) (xy 92.862036 -120.947177) (xy 92.885477 -120.946915)
			(xy 92.896182 -120.9421) (xy 92.89669 -120.9421) (xy 92.923744 -120.928808) (xy 92.981022 -120.910034)
			(xy 93.040542 -120.900519) (xy 93.07068 -120.899936) (xy 93.097934 -120.900374) (xy 93.151888 -120.908129)
			(xy 93.20419 -120.923485) (xy 93.253772 -120.946129) (xy 93.299628 -120.975599) (xy 93.340822 -121.011295)
			(xy 93.376516 -121.052491) (xy 93.405983 -121.098349) (xy 93.428623 -121.147933) (xy 93.443976 -121.200235)
			(xy 93.449513 -121.238772) (xy 97.584258 -121.238772) (xy 97.588329 -121.18315) (xy 97.600455 -121.128713)
			(xy 97.620378 -121.076622) (xy 97.647674 -121.027987) (xy 97.68176 -120.983844) (xy 97.721909 -120.945135)
			(xy 97.767267 -120.912684) (xy 97.816867 -120.887183) (xy 97.869651 -120.869176) (xy 97.924494 -120.859046)
			(xy 97.980228 -120.857009) (xy 98.035665 -120.863109) (xy 98.089622 -120.877215) (xy 98.140951 -120.899027)
			(xy 98.188557 -120.928081) (xy 98.231425 -120.963756) (xy 98.268642 -121.005293) (xy 98.299415 -121.051806)
			(xy 98.323087 -121.102303) (xy 98.339155 -121.15571) (xy 98.347275 -121.210886) (xy 98.347784 -121.238772)
			(xy 98.347275 -121.266658) (xy 98.339155 -121.321834) (xy 98.323087 -121.375241) (xy 98.299415 -121.425738)
			(xy 98.268642 -121.472251) (xy 98.231425 -121.513788) (xy 98.188557 -121.549463) (xy 98.140951 -121.578517)
			(xy 98.089622 -121.600329) (xy 98.035665 -121.614435) (xy 97.980228 -121.620535) (xy 97.924494 -121.618498)
			(xy 97.869651 -121.608368) (xy 97.816867 -121.590361) (xy 97.767267 -121.56486) (xy 97.721909 -121.532409)
			(xy 97.68176 -121.4937) (xy 97.647674 -121.449557) (xy 97.620378 -121.400922) (xy 97.600455 -121.348831)
			(xy 97.588329 -121.294394) (xy 97.584258 -121.238772) (xy 93.449513 -121.238772) (xy 93.451728 -121.25419)
			(xy 93.452188 -121.281444) (xy 93.451692 -121.308813) (xy 93.443882 -121.362991) (xy 93.4284 -121.415494)
			(xy 93.405565 -121.465241) (xy 93.375846 -121.511209) (xy 93.358208 -121.532142) (xy 93.357954 -121.532396)
			(xy 93.352357 -121.539476) (xy 93.346118 -121.556398) (xy 93.345762 -121.565416) (xy 93.345762 -121.632472)
			(xy 93.346141 -121.641486) (xy 93.352374 -121.658403) (xy 93.357954 -121.665492) (xy 93.358208 -121.665492)
			(xy 93.358208 -121.665746) (xy 93.375836 -121.686687) (xy 93.40555 -121.732657) (xy 93.428387 -121.782403)
			(xy 93.443881 -121.834901) (xy 93.451712 -121.889075) (xy 93.452188 -121.916444) (xy 93.451763 -121.943697)
			(xy 93.444 -121.997648) (xy 93.428638 -122.049945) (xy 93.405991 -122.099524) (xy 93.376518 -122.145375)
			(xy 93.34082 -122.186565) (xy 93.299624 -122.222256) (xy 93.253768 -122.251721) (xy 93.204185 -122.274361)
			(xy 93.151886 -122.289714) (xy 93.097933 -122.297468) (xy 93.07068 -122.297952) (xy 93.041557 -122.297438)
			(xy 92.983987 -122.288596) (xy 92.928429 -122.271105) (xy 92.876177 -122.245372) (xy 92.828443 -122.211995)
			(xy 92.786338 -122.171749) (xy 92.75084 -122.125571) (xy 92.722774 -122.074533) (xy 92.702793 -122.019822)
			(xy 92.696538 -121.991374) (xy 92.694252 -121.97969) (xy 92.679774 -121.960894) (xy 92.5957 -121.920508)
			(xy 92.584883 -121.915953) (xy 92.561446 -121.916206) (xy 92.550742 -121.921016) (xy 92.550234 -121.921016)
			(xy 92.523177 -121.934301) (xy 92.4659 -121.953077) (xy 92.406381 -121.962596) (xy 92.376244 -121.96318)
			(xy 92.348991 -121.962704) (xy 92.295039 -121.954952) (xy 92.24274 -121.9396) (xy 92.193158 -121.916961)
			(xy 92.147303 -121.887495) (xy 92.106109 -121.851802) (xy 92.070415 -121.81061) (xy 92.040947 -121.764756)
			(xy 92.018305 -121.715175) (xy 92.002951 -121.662877) (xy 91.995197 -121.608925) (xy 91.994736 -121.581672)
			(xy 90.213256 -121.581672) (xy 90.213256 -121.584397) (xy 90.205424 -121.638578) (xy 90.189925 -121.691082)
			(xy 90.167077 -121.740829) (xy 90.13735 -121.786799) (xy 90.119708 -121.807732) (xy 90.119454 -121.807986)
			(xy 90.113862 -121.815068) (xy 90.10762 -121.831989) (xy 90.107262 -121.841006) (xy 90.107262 -121.908062)
			(xy 90.107645 -121.917076) (xy 90.113876 -121.933993) (xy 90.119454 -121.941082) (xy 90.119708 -121.941082)
			(xy 90.119708 -121.941336) (xy 90.137332 -121.96228) (xy 90.167046 -122.00825) (xy 90.189884 -122.057994)
			(xy 90.205379 -122.110492) (xy 90.213212 -122.164666) (xy 90.213688 -122.192034) (xy 90.213202 -122.219285)
			(xy 90.205446 -122.273233) (xy 90.190091 -122.325528) (xy 90.167449 -122.375105) (xy 90.137983 -122.420955)
			(xy 90.102292 -122.462146) (xy 90.061101 -122.497837) (xy 90.015251 -122.527303) (xy 89.965674 -122.549945)
			(xy 89.913379 -122.5653) (xy 89.859431 -122.573056) (xy 89.804929 -122.573056) (xy 89.750981 -122.5653)
			(xy 89.698686 -122.549945) (xy 89.649109 -122.527303) (xy 89.603259 -122.497837) (xy 89.562068 -122.462146)
			(xy 89.526377 -122.420955) (xy 89.496911 -122.375105) (xy 89.474269 -122.325528) (xy 89.458914 -122.273233)
			(xy 89.451158 -122.219285) (xy 89.450672 -122.192034) (xy 81.978069 -122.192034) (xy 81.981873 -122.206227)
			(xy 81.989704 -122.265682) (xy 81.990184 -122.295666) (xy 81.990184 -123.159266) (xy 81.989694 -123.18925)
			(xy 81.981866 -123.248706) (xy 81.966345 -123.306631) (xy 81.943396 -123.362035) (xy 81.941942 -123.364553)
			(xy 94.064275 -123.364553) (xy 94.064275 -123.310047) (xy 94.072033 -123.256097) (xy 94.087389 -123.203799)
			(xy 94.110033 -123.15422) (xy 94.139502 -123.108368) (xy 94.175197 -123.067177) (xy 94.21639 -123.031485)
			(xy 94.262245 -123.002019) (xy 94.311826 -122.97938) (xy 94.364124 -122.964027) (xy 94.418075 -122.956273)
			(xy 94.445328 -122.955812) (xy 94.472699 -122.956259) (xy 94.526879 -122.964081) (xy 94.579382 -122.979574)
			(xy 94.629129 -123.00242) (xy 94.675095 -123.032149) (xy 94.696026 -123.049792) (xy 94.69628 -123.050046)
			(xy 94.703364 -123.055636) (xy 94.720283 -123.061879) (xy 94.7293 -123.062238) (xy 94.796356 -123.062238)
			(xy 94.80537 -123.061852) (xy 94.822286 -123.055624) (xy 94.829376 -123.050046) (xy 94.829376 -123.049792)
			(xy 94.82963 -123.049792) (xy 94.850563 -123.032151) (xy 94.896531 -123.002427) (xy 94.946277 -122.979581)
			(xy 94.998779 -122.964085) (xy 95.052957 -122.956256) (xy 95.107699 -122.956256) (xy 95.161877 -122.964085)
			(xy 95.214379 -122.979581) (xy 95.264125 -123.002427) (xy 95.310093 -123.032151) (xy 95.331026 -123.049792)
			(xy 95.33128 -123.050046) (xy 95.338364 -123.055636) (xy 95.355283 -123.061879) (xy 95.3643 -123.062238)
			(xy 95.431356 -123.062238) (xy 95.44037 -123.061852) (xy 95.457286 -123.055624) (xy 95.464376 -123.050046)
			(xy 95.464376 -123.049792) (xy 95.46463 -123.049792) (xy 95.485577 -123.032171) (xy 95.531546 -123.002457)
			(xy 95.581289 -122.979617) (xy 95.633787 -122.964122) (xy 95.68796 -122.956289) (xy 95.715328 -122.955812)
			(xy 95.742579 -122.95626) (xy 95.796527 -122.96402) (xy 95.848821 -122.979378) (xy 95.898397 -123.002022)
			(xy 95.944247 -123.031491) (xy 95.985436 -123.067184) (xy 96.021126 -123.108376) (xy 96.050591 -123.154227)
			(xy 96.073232 -123.203805) (xy 96.088586 -123.256101) (xy 96.096342 -123.310049) (xy 96.096342 -123.364551)
			(xy 96.088586 -123.4185) (xy 96.073232 -123.470795) (xy 96.050591 -123.520373) (xy 96.021126 -123.566224)
			(xy 95.985436 -123.607416) (xy 95.944247 -123.643109) (xy 95.898397 -123.672578) (xy 95.848821 -123.695222)
			(xy 95.796527 -123.71058) (xy 95.742579 -123.71834) (xy 95.715328 -123.718828) (xy 95.687958 -123.718363)
			(xy 95.633778 -123.710548) (xy 95.581274 -123.695059) (xy 95.531527 -123.672217) (xy 95.485561 -123.64249)
			(xy 95.46463 -123.624848) (xy 95.464376 -123.624594) (xy 95.457301 -123.618991) (xy 95.440375 -123.612754)
			(xy 95.431356 -123.612402) (xy 95.3643 -123.612402) (xy 95.355283 -123.612759) (xy 95.338366 -123.619006)
			(xy 95.33128 -123.624594) (xy 95.331026 -123.624848) (xy 95.310093 -123.642489) (xy 95.264125 -123.672213)
			(xy 95.214379 -123.695059) (xy 95.161877 -123.710555) (xy 95.107699 -123.718384) (xy 95.052957 -123.718384)
			(xy 94.998779 -123.710555) (xy 94.946277 -123.695059) (xy 94.896531 -123.672213) (xy 94.850563 -123.642489)
			(xy 94.82963 -123.624848) (xy 94.829376 -123.624594) (xy 94.822301 -123.618991) (xy 94.805375 -123.612754)
			(xy 94.796356 -123.612402) (xy 94.7293 -123.612402) (xy 94.720283 -123.612759) (xy 94.703366 -123.619006)
			(xy 94.69628 -123.624594) (xy 94.69628 -123.624848) (xy 94.696026 -123.624848) (xy 94.675088 -123.64248)
			(xy 94.629118 -123.672195) (xy 94.579372 -123.695033) (xy 94.526872 -123.710525) (xy 94.472697 -123.718354)
			(xy 94.445328 -123.718828) (xy 94.418075 -123.718327) (xy 94.364124 -123.710573) (xy 94.311826 -123.69522)
			(xy 94.262245 -123.672581) (xy 94.21639 -123.643115) (xy 94.175197 -123.607423) (xy 94.139502 -123.566232)
			(xy 94.110033 -123.52038) (xy 94.087389 -123.470801) (xy 94.072033 -123.418503) (xy 94.064275 -123.364553)
			(xy 81.941942 -123.364553) (xy 81.913412 -123.413969) (xy 81.876906 -123.461545) (xy 81.834501 -123.50395)
			(xy 81.786925 -123.540456) (xy 81.734991 -123.57044) (xy 81.679587 -123.593389) (xy 81.621662 -123.60891)
			(xy 81.562206 -123.616738) (xy 81.502238 -123.616738) (xy 81.442782 -123.60891) (xy 81.384857 -123.593389)
			(xy 81.329453 -123.57044) (xy 81.277519 -123.540456) (xy 81.229943 -123.50395) (xy 81.187538 -123.461545)
			(xy 81.151032 -123.413969) (xy 81.121048 -123.362035) (xy 81.098099 -123.306631) (xy 81.082578 -123.248706)
			(xy 81.07475 -123.18925) (xy 81.07426 -123.159266) (xy 81.07426 -122.57532) (xy 81.07426 -122.574812)
			(xy 81.07364 -122.563924) (xy 81.064427 -122.54418) (xy 81.05648 -122.536712) (xy 80.99806 -122.486674)
			(xy 80.990864 -122.481017) (xy 80.97368 -122.474757) (xy 80.964532 -122.474482) (xy 80.957166 -122.47499)
			(xy 80.943196 -122.477022) (xy 80.934146 -122.478526) (xy 80.917891 -122.487001) (xy 80.911446 -122.493532)
			(xy 80.905096 -122.50039) (xy 80.898746 -122.517154) (xy 80.870439 -124.965714) (xy 83.716368 -124.965714)
			(xy 83.716368 -124.102114) (xy 83.716858 -124.07213) (xy 83.724686 -124.012674) (xy 83.740207 -123.954749)
			(xy 83.763156 -123.899345) (xy 83.79314 -123.847411) (xy 83.829646 -123.799835) (xy 83.872051 -123.75743)
			(xy 83.919627 -123.720924) (xy 83.971561 -123.69094) (xy 84.026965 -123.667991) (xy 84.08489 -123.65247)
			(xy 84.144346 -123.644642) (xy 84.204314 -123.644642) (xy 84.26377 -123.65247) (xy 84.321695 -123.667991)
			(xy 84.377099 -123.69094) (xy 84.429033 -123.720924) (xy 84.476609 -123.75743) (xy 84.486939 -123.76776)
			(xy 97.442306 -123.76776) (xy 97.45006 -123.713817) (xy 97.465412 -123.661528) (xy 97.488049 -123.611955)
			(xy 97.51751 -123.566108) (xy 97.553197 -123.524921) (xy 97.594381 -123.489231) (xy 97.640225 -123.459765)
			(xy 97.689796 -123.437124) (xy 97.742084 -123.421767) (xy 97.796026 -123.414008) (xy 97.823274 -123.41352)
			(xy 97.823782 -123.41352) (xy 97.834154 -123.413603) (xy 97.854866 -123.414745) (xy 97.865184 -123.415806)
			(xy 97.879729 -123.41691) (xy 97.908422 -123.411704) (xy 97.934478 -123.398612) (xy 97.955781 -123.378698)
			(xy 97.970599 -123.353583) (xy 97.977727 -123.325307) (xy 97.976586 -123.296168) (xy 97.972372 -123.282202)
			(xy 97.963011 -123.252595) (xy 97.952934 -123.191327) (xy 97.952306 -123.160282) (xy 97.952306 -123.160028)
			(xy 97.952725 -123.132773) (xy 97.960479 -123.078817) (xy 97.975832 -123.026514) (xy 97.998473 -122.976928)
			(xy 98.02794 -122.931069) (xy 98.063634 -122.889871) (xy 98.104828 -122.854171) (xy 98.150683 -122.824698)
			(xy 98.200266 -122.80205) (xy 98.252567 -122.78669) (xy 98.306522 -122.778929) (xy 98.361032 -122.778925)
			(xy 98.414988 -122.78668) (xy 98.467291 -122.802034) (xy 98.516876 -122.824675) (xy 98.562735 -122.854143)
			(xy 98.603933 -122.889837) (xy 98.639632 -122.931032) (xy 98.669105 -122.976887) (xy 98.691751 -123.02647)
			(xy 98.707111 -123.078771) (xy 98.714872 -123.132726) (xy 98.714874 -123.187236) (xy 98.707119 -123.241192)
			(xy 98.691765 -123.293495) (xy 98.669122 -123.34308) (xy 98.639654 -123.388939) (xy 98.603959 -123.430136)
			(xy 98.562765 -123.465834) (xy 98.516909 -123.495307) (xy 98.467326 -123.517953) (xy 98.415024 -123.533312)
			(xy 98.361069 -123.541072) (xy 98.333814 -123.541536) (xy 98.333306 -123.541536) (xy 98.322934 -123.541454)
			(xy 98.302222 -123.540311) (xy 98.291904 -123.53925) (xy 98.277358 -123.538193) (xy 98.248676 -123.5434)
			(xy 98.222628 -123.556487) (xy 98.20133 -123.576392) (xy 98.186512 -123.601496) (xy 98.179379 -123.629761)
			(xy 98.18051 -123.658891) (xy 98.184716 -123.672854) (xy 98.194067 -123.702464) (xy 98.204151 -123.763729)
			(xy 98.204782 -123.794774) (xy 98.204782 -123.795028) (xy 98.204292 -123.822276) (xy 98.196532 -123.876218)
			(xy 98.181176 -123.928506) (xy 98.158534 -123.978077) (xy 98.129068 -124.023921) (xy 98.093378 -124.065105)
			(xy 98.05219 -124.100791) (xy 98.006343 -124.130252) (xy 97.956771 -124.152889) (xy 97.904481 -124.168241)
			(xy 97.850538 -124.175995) (xy 97.796042 -124.175993) (xy 97.7421 -124.168236) (xy 97.689811 -124.152882)
			(xy 97.640239 -124.130242) (xy 97.594394 -124.100779) (xy 97.553208 -124.065091) (xy 97.51752 -124.023905)
			(xy 97.488057 -123.978059) (xy 97.465417 -123.928487) (xy 97.450063 -123.876198) (xy 97.442307 -123.822256)
			(xy 97.442306 -123.76776) (xy 84.486939 -123.76776) (xy 84.519014 -123.799835) (xy 84.55552 -123.847411)
			(xy 84.585504 -123.899345) (xy 84.608453 -123.954749) (xy 84.623974 -124.012674) (xy 84.631802 -124.07213)
			(xy 84.632292 -124.102114) (xy 84.632292 -124.215144) (xy 94.606616 -124.215144) (xy 94.610687 -124.159522)
			(xy 94.622813 -124.105085) (xy 94.642736 -124.052994) (xy 94.670032 -124.004359) (xy 94.704118 -123.960216)
			(xy 94.744267 -123.921507) (xy 94.789625 -123.889056) (xy 94.839225 -123.863555) (xy 94.892009 -123.845548)
			(xy 94.946852 -123.835418) (xy 95.002586 -123.833381) (xy 95.058023 -123.839481) (xy 95.11198 -123.853587)
			(xy 95.163309 -123.875399) (xy 95.210915 -123.904453) (xy 95.253783 -123.940128) (xy 95.291 -123.981665)
			(xy 95.321773 -124.028178) (xy 95.345445 -124.078675) (xy 95.361513 -124.132082) (xy 95.369633 -124.187258)
			(xy 95.370142 -124.215144) (xy 95.369633 -124.24303) (xy 95.361513 -124.298206) (xy 95.345445 -124.351613)
			(xy 95.321773 -124.40211) (xy 95.291 -124.448623) (xy 95.253783 -124.49016) (xy 95.210915 -124.525835)
			(xy 95.163309 -124.554889) (xy 95.11198 -124.576701) (xy 95.058023 -124.590807) (xy 95.002586 -124.596907)
			(xy 94.946852 -124.59487) (xy 94.892009 -124.58474) (xy 94.839225 -124.566733) (xy 94.789625 -124.541232)
			(xy 94.744267 -124.508781) (xy 94.704118 -124.470072) (xy 94.670032 -124.425929) (xy 94.642736 -124.377294)
			(xy 94.622813 -124.325203) (xy 94.610687 -124.270766) (xy 94.606616 -124.215144) (xy 84.632292 -124.215144)
			(xy 84.632292 -124.965714) (xy 84.631802 -124.995698) (xy 84.623974 -125.055154) (xy 84.608453 -125.113079)
			(xy 84.585504 -125.168483) (xy 84.55552 -125.220417) (xy 84.519014 -125.267993) (xy 84.476609 -125.310398)
			(xy 84.429033 -125.346904) (xy 84.377099 -125.376888) (xy 84.321695 -125.399837) (xy 84.26377 -125.415358)
			(xy 84.204314 -125.423186) (xy 84.144346 -125.423186) (xy 84.08489 -125.415358) (xy 84.026965 -125.399837)
			(xy 83.971561 -125.376888) (xy 83.919627 -125.346904) (xy 83.872051 -125.310398) (xy 83.829646 -125.267993)
			(xy 83.79314 -125.220417) (xy 83.763156 -125.168483) (xy 83.740207 -125.113079) (xy 83.724686 -125.055154)
			(xy 83.716858 -124.995698) (xy 83.716368 -124.965714) (xy 80.870439 -124.965714) (xy 80.859736 -125.891544)
			(xy 95.17507 -125.891544) (xy 95.17551 -125.865229) (xy 95.182752 -125.8131) (xy 95.197077 -125.762457)
			(xy 95.218214 -125.714258) (xy 95.245765 -125.669415) (xy 95.279207 -125.628776) (xy 95.29826 -125.61062)
			(xy 95.305649 -125.603087) (xy 95.314182 -125.583816) (xy 95.31477 -125.573282) (xy 95.31477 -125.498606)
			(xy 95.31426 -125.488054) (xy 95.305712 -125.468758) (xy 95.29826 -125.461268) (xy 95.279188 -125.443129)
			(xy 95.245734 -125.402495) (xy 95.218178 -125.357651) (xy 95.197043 -125.309447) (xy 95.182729 -125.258797)
			(xy 95.175507 -125.206661) (xy 95.17507 -125.180344) (xy 95.175556 -125.153093) (xy 95.183312 -125.099145)
			(xy 95.198667 -125.04685) (xy 95.221309 -124.997273) (xy 95.250775 -124.951423) (xy 95.286466 -124.910232)
			(xy 95.327657 -124.874541) (xy 95.373507 -124.845075) (xy 95.423084 -124.822433) (xy 95.475379 -124.807078)
			(xy 95.529327 -124.799322) (xy 95.583829 -124.799322) (xy 95.637777 -124.807078) (xy 95.690072 -124.822433)
			(xy 95.739649 -124.845075) (xy 95.785499 -124.874541) (xy 95.82669 -124.910232) (xy 95.862381 -124.951423)
			(xy 95.891847 -124.997273) (xy 95.914489 -125.04685) (xy 95.929844 -125.099145) (xy 95.9376 -125.153093)
			(xy 95.938086 -125.180344) (xy 95.937652 -125.206659) (xy 95.930411 -125.258789) (xy 95.916086 -125.309433)
			(xy 95.894947 -125.357632) (xy 95.867395 -125.402474) (xy 95.83395 -125.443112) (xy 95.814896 -125.461268)
			(xy 95.807506 -125.468799) (xy 95.798975 -125.488072) (xy 95.798386 -125.498606) (xy 95.798386 -125.573282)
			(xy 95.798916 -125.583831) (xy 95.807451 -125.603127) (xy 95.814896 -125.61062) (xy 95.833953 -125.628774)
			(xy 95.867411 -125.669404) (xy 95.894969 -125.714244) (xy 95.916108 -125.762445) (xy 95.930424 -125.813093)
			(xy 95.937648 -125.865228) (xy 95.938086 -125.891544) (xy 95.9376 -125.918795) (xy 95.929844 -125.972743)
			(xy 95.914489 -126.025038) (xy 95.891847 -126.074615) (xy 95.862381 -126.120465) (xy 95.82669 -126.161656)
			(xy 95.785499 -126.197347) (xy 95.739649 -126.226813) (xy 95.690072 -126.249455) (xy 95.637777 -126.26481)
			(xy 95.583829 -126.272566) (xy 95.529327 -126.272566) (xy 95.475379 -126.26481) (xy 95.423084 -126.249455)
			(xy 95.373507 -126.226813) (xy 95.327657 -126.197347) (xy 95.286466 -126.161656) (xy 95.250775 -126.120465)
			(xy 95.221309 -126.074615) (xy 95.198667 -126.025038) (xy 95.183312 -125.972743) (xy 95.175556 -125.918795)
			(xy 95.17507 -125.891544) (xy 80.859736 -125.891544) (xy 80.847012 -126.992126) (xy 104.844342 -126.992126)
			(xy 104.844813 -126.964756) (xy 104.852628 -126.910577) (xy 104.868115 -126.858073) (xy 104.890956 -126.808326)
			(xy 104.920681 -126.762359) (xy 104.938322 -126.741428) (xy 104.938576 -126.741174) (xy 104.944147 -126.734077)
			(xy 104.950401 -126.717168) (xy 104.950768 -126.708154) (xy 104.950768 -126.641098) (xy 104.950419 -126.63208)
			(xy 104.944167 -126.615163) (xy 104.938576 -126.608078) (xy 104.938322 -126.608078) (xy 104.938322 -126.607824)
			(xy 104.920707 -126.586871) (xy 104.890982 -126.540906) (xy 104.868135 -126.491163) (xy 104.852637 -126.438664)
			(xy 104.844806 -126.384489) (xy 104.844803 -126.32975) (xy 104.852629 -126.275574) (xy 104.868121 -126.223073)
			(xy 104.890963 -126.173328) (xy 104.920683 -126.127361) (xy 104.938322 -126.106428) (xy 104.938576 -126.106174)
			(xy 104.944147 -126.099077) (xy 104.950401 -126.082168) (xy 104.950768 -126.073154) (xy 104.950768 -126.006098)
			(xy 104.950419 -125.99708) (xy 104.944167 -125.980163) (xy 104.938576 -125.973078) (xy 104.938322 -125.973078)
			(xy 104.938322 -125.972824) (xy 104.920707 -125.951871) (xy 104.890982 -125.905906) (xy 104.868135 -125.856163)
			(xy 104.852637 -125.803664) (xy 104.844806 -125.749489) (xy 104.844803 -125.69475) (xy 104.852629 -125.640574)
			(xy 104.868121 -125.588073) (xy 104.890963 -125.538328) (xy 104.920683 -125.492361) (xy 104.938322 -125.471428)
			(xy 104.938576 -125.471174) (xy 104.944147 -125.464077) (xy 104.950401 -125.447168) (xy 104.950768 -125.438154)
			(xy 104.950768 -125.371098) (xy 104.950419 -125.36208) (xy 104.944167 -125.345163) (xy 104.938576 -125.338078)
			(xy 104.938322 -125.338078) (xy 104.938322 -125.337824) (xy 104.920684 -125.316891) (xy 104.890971 -125.270919)
			(xy 104.868135 -125.221172) (xy 104.852644 -125.168671) (xy 104.844816 -125.114495) (xy 104.844342 -125.087126)
			(xy 104.844828 -125.059875) (xy 104.852584 -125.005927) (xy 104.867939 -124.953632) (xy 104.890581 -124.904055)
			(xy 104.920047 -124.858205) (xy 104.955738 -124.817014) (xy 104.996929 -124.781323) (xy 105.042779 -124.751857)
			(xy 105.092356 -124.729215) (xy 105.144651 -124.71386) (xy 105.198599 -124.706104) (xy 105.253101 -124.706104)
			(xy 105.307049 -124.71386) (xy 105.359344 -124.729215) (xy 105.408921 -124.751857) (xy 105.454771 -124.781323)
			(xy 105.495962 -124.817014) (xy 105.531653 -124.858205) (xy 105.561119 -124.904055) (xy 105.583761 -124.953632)
			(xy 105.599116 -125.005927) (xy 105.606872 -125.059875) (xy 105.607358 -125.087126) (xy 105.606917 -125.114497)
			(xy 105.599095 -125.168678) (xy 105.583601 -125.221182) (xy 105.560753 -125.270928) (xy 105.531022 -125.316893)
			(xy 105.513378 -125.337824) (xy 105.513124 -125.338078) (xy 105.507532 -125.34516) (xy 105.50129 -125.362081)
			(xy 105.500932 -125.371098) (xy 105.500932 -125.438154) (xy 105.501304 -125.447169) (xy 105.50754 -125.464087)
			(xy 105.513124 -125.471174) (xy 105.513378 -125.471174) (xy 105.513378 -125.471428) (xy 105.531044 -125.49234)
			(xy 105.560767 -125.538312) (xy 105.583611 -125.588061) (xy 105.599105 -125.640567) (xy 105.606931 -125.694748)
			(xy 105.606928 -125.749491) (xy 105.599097 -125.803672) (xy 105.583597 -125.856175) (xy 105.560748 -125.905923)
			(xy 105.53102 -125.951891) (xy 105.513378 -125.972824) (xy 105.513124 -125.973078) (xy 105.507532 -125.98016)
			(xy 105.50129 -125.997081) (xy 105.500932 -126.006098) (xy 105.500932 -126.073154) (xy 105.501304 -126.082169)
			(xy 105.50754 -126.099087) (xy 105.513124 -126.106174) (xy 105.513378 -126.106174) (xy 105.513378 -126.106428)
			(xy 105.531044 -126.12734) (xy 105.560767 -126.173312) (xy 105.583611 -126.223061) (xy 105.599105 -126.275567)
			(xy 105.606931 -126.329748) (xy 105.606928 -126.384491) (xy 105.599097 -126.438672) (xy 105.583597 -126.491175)
			(xy 105.560748 -126.540923) (xy 105.53102 -126.586891) (xy 105.513378 -126.607824) (xy 105.513124 -126.608078)
			(xy 105.507532 -126.61516) (xy 105.50129 -126.632081) (xy 105.500932 -126.641098) (xy 105.500932 -126.708154)
			(xy 105.501304 -126.717169) (xy 105.50754 -126.734087) (xy 105.513124 -126.741174) (xy 105.513378 -126.741174)
			(xy 105.513378 -126.741428) (xy 105.530993 -126.762379) (xy 105.56071 -126.808346) (xy 105.58355 -126.858089)
			(xy 105.599047 -126.910586) (xy 105.606881 -126.964758) (xy 105.607358 -126.992126) (xy 105.606872 -127.019377)
			(xy 105.602208 -127.051816) (xy 107.500166 -127.051816) (xy 107.500625 -127.024445) (xy 107.508442 -126.970265)
			(xy 107.523932 -126.917762) (xy 107.546776 -126.868015) (xy 107.576503 -126.822049) (xy 107.594146 -126.801118)
			(xy 107.5944 -126.800864) (xy 107.599966 -126.793763) (xy 107.606225 -126.776857) (xy 107.606592 -126.767844)
			(xy 107.606592 -126.700788) (xy 107.606242 -126.69177) (xy 107.59999 -126.674853) (xy 107.5944 -126.667768)
			(xy 107.594146 -126.667768) (xy 107.594146 -126.667514) (xy 107.57652 -126.646569) (xy 107.546793 -126.600604)
			(xy 107.523946 -126.55086) (xy 107.508448 -126.498359) (xy 107.500617 -126.444182) (xy 107.500615 -126.389442)
			(xy 107.508442 -126.335264) (xy 107.523937 -126.282763) (xy 107.546782 -126.233017) (xy 107.576506 -126.18705)
			(xy 107.594146 -126.166118) (xy 107.5944 -126.165864) (xy 107.599966 -126.158763) (xy 107.606225 -126.141857)
			(xy 107.606592 -126.132844) (xy 107.606592 -126.065788) (xy 107.606242 -126.05677) (xy 107.59999 -126.039853)
			(xy 107.5944 -126.032768) (xy 107.594146 -126.032768) (xy 107.594146 -126.032514) (xy 107.57652 -126.011569)
			(xy 107.546793 -125.965604) (xy 107.523946 -125.91586) (xy 107.508448 -125.863359) (xy 107.500617 -125.809182)
			(xy 107.500615 -125.754442) (xy 107.508442 -125.700264) (xy 107.523937 -125.647763) (xy 107.546782 -125.598017)
			(xy 107.576506 -125.55205) (xy 107.594146 -125.531118) (xy 107.5944 -125.530864) (xy 107.599966 -125.523763)
			(xy 107.606225 -125.506857) (xy 107.606592 -125.497844) (xy 107.606592 -125.430788) (xy 107.606242 -125.42177)
			(xy 107.59999 -125.404853) (xy 107.5944 -125.397768) (xy 107.594146 -125.397768) (xy 107.594146 -125.397514)
			(xy 107.576507 -125.376582) (xy 107.546794 -125.33061) (xy 107.523957 -125.280862) (xy 107.508466 -125.228361)
			(xy 107.500639 -125.174185) (xy 107.500166 -125.146816) (xy 107.500652 -125.119565) (xy 107.508408 -125.065617)
			(xy 107.523763 -125.013322) (xy 107.546405 -124.963745) (xy 107.575871 -124.917895) (xy 107.611562 -124.876704)
			(xy 107.652753 -124.841013) (xy 107.698603 -124.811547) (xy 107.74818 -124.788905) (xy 107.800475 -124.77355)
			(xy 107.854423 -124.765794) (xy 107.908925 -124.765794) (xy 107.962873 -124.77355) (xy 108.015168 -124.788905)
			(xy 108.064745 -124.811547) (xy 108.110595 -124.841013) (xy 108.151786 -124.876704) (xy 108.158044 -124.883926)
			(xy 116.439948 -124.883926) (xy 116.444019 -124.828304) (xy 116.456145 -124.773867) (xy 116.476068 -124.721776)
			(xy 116.503364 -124.673141) (xy 116.53745 -124.628998) (xy 116.577599 -124.590289) (xy 116.622957 -124.557838)
			(xy 116.672557 -124.532337) (xy 116.725341 -124.51433) (xy 116.780184 -124.5042) (xy 116.835918 -124.502163)
			(xy 116.891355 -124.508263) (xy 116.945312 -124.522369) (xy 116.996641 -124.544181) (xy 117.044247 -124.573235)
			(xy 117.087115 -124.60891) (xy 117.124332 -124.650447) (xy 117.155105 -124.69696) (xy 117.178777 -124.747457)
			(xy 117.194845 -124.800864) (xy 117.202965 -124.85604) (xy 117.203474 -124.883926) (xy 117.202965 -124.911812)
			(xy 117.194845 -124.966988) (xy 117.178777 -125.020395) (xy 117.155105 -125.070892) (xy 117.124332 -125.117405)
			(xy 117.087115 -125.158942) (xy 117.044247 -125.194617) (xy 116.996641 -125.223671) (xy 116.945312 -125.245483)
			(xy 116.891355 -125.259589) (xy 116.835918 -125.265689) (xy 116.780184 -125.263652) (xy 116.725341 -125.253522)
			(xy 116.672557 -125.235515) (xy 116.622957 -125.210014) (xy 116.577599 -125.177563) (xy 116.53745 -125.138854)
			(xy 116.503364 -125.094711) (xy 116.476068 -125.046076) (xy 116.456145 -124.993985) (xy 116.444019 -124.939548)
			(xy 116.439948 -124.883926) (xy 108.158044 -124.883926) (xy 108.187477 -124.917895) (xy 108.216943 -124.963745)
			(xy 108.239585 -125.013322) (xy 108.25494 -125.065617) (xy 108.262696 -125.119565) (xy 108.263182 -125.146816)
			(xy 108.26273 -125.174187) (xy 108.254909 -125.228367) (xy 108.239417 -125.28087) (xy 108.216572 -125.330617)
			(xy 108.186845 -125.376583) (xy 108.169202 -125.397514) (xy 108.168948 -125.397768) (xy 108.163362 -125.404855)
			(xy 108.157116 -125.421772) (xy 108.156756 -125.430788) (xy 108.156756 -125.497844) (xy 108.157128 -125.50686)
			(xy 108.163364 -125.523777) (xy 108.168948 -125.530864) (xy 108.169202 -125.530864) (xy 108.169202 -125.531118)
			(xy 108.186857 -125.552039) (xy 108.216579 -125.598009) (xy 108.239422 -125.647758) (xy 108.254916 -125.700261)
			(xy 108.262742 -125.754441) (xy 108.26274 -125.809183) (xy 108.25491 -125.863362) (xy 108.239413 -125.915865)
			(xy 108.216567 -125.965612) (xy 108.186843 -126.011581) (xy 108.169202 -126.032514) (xy 108.168948 -126.032768)
			(xy 108.163362 -126.039855) (xy 108.157116 -126.056772) (xy 108.156756 -126.065788) (xy 108.156756 -126.132844)
			(xy 108.157128 -126.14186) (xy 108.163364 -126.158777) (xy 108.168948 -126.165864) (xy 108.169202 -126.166118)
			(xy 108.186022 -126.186075) (xy 108.193742 -126.197868) (xy 116.44579 -126.197868) (xy 116.449861 -126.142246)
			(xy 116.461987 -126.087809) (xy 116.48191 -126.035718) (xy 116.509206 -125.987083) (xy 116.543292 -125.94294)
			(xy 116.583441 -125.904231) (xy 116.628799 -125.87178) (xy 116.678399 -125.846279) (xy 116.731183 -125.828272)
			(xy 116.786026 -125.818142) (xy 116.84176 -125.816105) (xy 116.897197 -125.822205) (xy 116.951154 -125.836311)
			(xy 117.002483 -125.858123) (xy 117.050089 -125.887177) (xy 117.065409 -125.899926) (xy 118.631714 -125.899926)
			(xy 118.635785 -125.844304) (xy 118.647911 -125.789867) (xy 118.667834 -125.737776) (xy 118.69513 -125.689141)
			(xy 118.729216 -125.644998) (xy 118.769365 -125.606289) (xy 118.814723 -125.573838) (xy 118.864323 -125.548337)
			(xy 118.917107 -125.53033) (xy 118.97195 -125.5202) (xy 119.027684 -125.518163) (xy 119.083121 -125.524263)
			(xy 119.137078 -125.538369) (xy 119.188407 -125.560181) (xy 119.236013 -125.589235) (xy 119.278881 -125.62491)
			(xy 119.316098 -125.666447) (xy 119.346871 -125.71296) (xy 119.370543 -125.763457) (xy 119.386611 -125.816864)
			(xy 119.394731 -125.87204) (xy 119.39524 -125.899926) (xy 119.394731 -125.927812) (xy 119.386611 -125.982988)
			(xy 119.370543 -126.036395) (xy 119.346871 -126.086892) (xy 119.316098 -126.133405) (xy 119.278881 -126.174942)
			(xy 119.236013 -126.210617) (xy 119.188407 -126.239671) (xy 119.137078 -126.261483) (xy 119.083121 -126.275589)
			(xy 119.027684 -126.281689) (xy 118.97195 -126.279652) (xy 118.917107 -126.269522) (xy 118.864323 -126.251515)
			(xy 118.814723 -126.226014) (xy 118.769365 -126.193563) (xy 118.729216 -126.154854) (xy 118.69513 -126.110711)
			(xy 118.667834 -126.062076) (xy 118.647911 -126.009985) (xy 118.635785 -125.955548) (xy 118.631714 -125.899926)
			(xy 117.065409 -125.899926) (xy 117.092957 -125.922852) (xy 117.130174 -125.964389) (xy 117.160947 -126.010902)
			(xy 117.184619 -126.061399) (xy 117.200687 -126.114806) (xy 117.208807 -126.169982) (xy 117.209316 -126.197868)
			(xy 117.208807 -126.225754) (xy 117.200687 -126.28093) (xy 117.184619 -126.334337) (xy 117.160947 -126.384834)
			(xy 117.130174 -126.431347) (xy 117.092957 -126.472884) (xy 117.050089 -126.508559) (xy 117.002483 -126.537613)
			(xy 116.951154 -126.559425) (xy 116.897197 -126.573531) (xy 116.84176 -126.579631) (xy 116.786026 -126.577594)
			(xy 116.731183 -126.567464) (xy 116.678399 -126.549457) (xy 116.628799 -126.523956) (xy 116.583441 -126.491505)
			(xy 116.543292 -126.452796) (xy 116.509206 -126.408653) (xy 116.48191 -126.360018) (xy 116.461987 -126.307927)
			(xy 116.449861 -126.25349) (xy 116.44579 -126.197868) (xy 108.193742 -126.197868) (xy 108.214608 -126.229744)
			(xy 108.236986 -126.276896) (xy 108.252738 -126.326655) (xy 108.257594 -126.3523) (xy 108.257594 -126.352554)
			(xy 108.259428 -126.360829) (xy 108.267719 -126.375599) (xy 108.280376 -126.386856) (xy 108.288074 -126.3904)
			(xy 108.379514 -126.429008) (xy 108.405168 -126.426214) (xy 108.415836 -126.418594) (xy 108.439986 -126.402441)
			(xy 108.492126 -126.376812) (xy 108.547549 -126.359386) (xy 108.604973 -126.350564) (xy 108.634022 -126.350014)
			(xy 108.661275 -126.350457) (xy 108.715225 -126.358217) (xy 108.767522 -126.373577) (xy 108.817101 -126.396222)
			(xy 108.862952 -126.425692) (xy 108.904143 -126.461388) (xy 108.939834 -126.502583) (xy 108.969299 -126.548438)
			(xy 108.991939 -126.598019) (xy 109.007292 -126.650318) (xy 109.015046 -126.704269) (xy 109.01553 -126.731522)
			(xy 109.015096 -126.758152) (xy 109.00769 -126.810896) (xy 108.993024 -126.862097) (xy 108.971382 -126.910763)
			(xy 108.943187 -126.955948) (xy 108.908984 -126.996776) (xy 108.869437 -127.032452) (xy 108.847636 -127.047752)
			(xy 108.837476 -127.05461) (xy 108.825792 -127.075438) (xy 108.821474 -127.18161) (xy 108.83138 -127.203454)
			(xy 108.841032 -127.211074) (xy 108.862881 -127.229325) (xy 108.901486 -127.27116) (xy 108.933453 -127.318263)
			(xy 108.95807 -127.369591) (xy 108.963528 -127.38735) (xy 110.308898 -127.38735) (xy 110.309418 -127.357979)
			(xy 110.318417 -127.29993) (xy 110.336209 -127.243946) (xy 110.362374 -127.191353) (xy 110.396293 -127.143393)
			(xy 110.41634 -127.12192) (xy 110.42272 -127.114735) (xy 110.430017 -127.096971) (xy 110.430564 -127.087376)
			(xy 110.431834 -127.008128) (xy 110.424976 -126.990094) (xy 110.418626 -126.982982) (xy 110.400068 -126.961814)
			(xy 110.368766 -126.915023) (xy 110.344678 -126.864142) (xy 110.328326 -126.810275) (xy 110.320065 -126.754589)
			(xy 110.319566 -126.726442) (xy 110.320094 -126.699191) (xy 110.327845 -126.645244) (xy 110.343194 -126.592949)
			(xy 110.36583 -126.543371) (xy 110.395291 -126.497519) (xy 110.430978 -126.456326) (xy 110.472164 -126.420632)
			(xy 110.518011 -126.391163) (xy 110.567585 -126.368518) (xy 110.619878 -126.353159) (xy 110.673823 -126.345399)
			(xy 110.701074 -126.344934) (xy 110.729754 -126.345504) (xy 110.786466 -126.35411) (xy 110.841253 -126.371103)
			(xy 110.892881 -126.3961) (xy 110.940189 -126.428538) (xy 110.982113 -126.467688) (xy 111.017708 -126.512669)
			(xy 111.046175 -126.562468) (xy 111.066872 -126.615966) (xy 111.079333 -126.671957) (xy 111.08182 -126.700534)
			(xy 111.082582 -126.713488) (xy 111.096552 -126.735332) (xy 111.194596 -126.788926) (xy 111.220504 -126.788926)
			(xy 111.231934 -126.782576) (xy 111.260181 -126.767818) (xy 111.320372 -126.746883) (xy 111.383205 -126.736248)
			(xy 111.415068 -126.735586) (xy 111.415576 -126.735586) (xy 111.44283 -126.73606) (xy 111.496782 -126.743814)
			(xy 111.549082 -126.759167) (xy 111.598664 -126.781808) (xy 111.64452 -126.811275) (xy 111.685715 -126.846968)
			(xy 111.72141 -126.888161) (xy 111.75088 -126.934014) (xy 111.773524 -126.983595) (xy 111.788881 -127.035894)
			(xy 111.796639 -127.089846) (xy 111.796639 -127.144354) (xy 111.788881 -127.198306) (xy 111.773524 -127.250605)
			(xy 111.75088 -127.300186) (xy 111.72141 -127.346039) (xy 111.685715 -127.387232) (xy 111.64452 -127.422925)
			(xy 111.598664 -127.452392) (xy 111.549082 -127.475033) (xy 111.518979 -127.48387) (xy 116.59438 -127.48387)
			(xy 116.598451 -127.428248) (xy 116.610577 -127.373811) (xy 116.6305 -127.32172) (xy 116.657796 -127.273085)
			(xy 116.691882 -127.228942) (xy 116.732031 -127.190233) (xy 116.777389 -127.157782) (xy 116.826989 -127.132281)
			(xy 116.879773 -127.114274) (xy 116.934616 -127.104144) (xy 116.99035 -127.102107) (xy 117.045787 -127.108207)
			(xy 117.099744 -127.122313) (xy 117.151073 -127.144125) (xy 117.198679 -127.173179) (xy 117.241547 -127.208854)
			(xy 117.278764 -127.250391) (xy 117.309537 -127.296904) (xy 117.333209 -127.347401) (xy 117.349277 -127.400808)
			(xy 117.357397 -127.455984) (xy 117.357906 -127.48387) (xy 117.357397 -127.511756) (xy 117.349277 -127.566932)
			(xy 117.333209 -127.620339) (xy 117.309537 -127.670836) (xy 117.278764 -127.717349) (xy 117.241547 -127.758886)
			(xy 117.198679 -127.794561) (xy 117.151073 -127.823615) (xy 117.099744 -127.845427) (xy 117.045787 -127.859533)
			(xy 116.99035 -127.865633) (xy 116.934616 -127.863596) (xy 116.879773 -127.853466) (xy 116.826989 -127.835459)
			(xy 116.777389 -127.809958) (xy 116.732031 -127.777507) (xy 116.691882 -127.738798) (xy 116.657796 -127.694655)
			(xy 116.6305 -127.64602) (xy 116.610577 -127.593929) (xy 116.598451 -127.539492) (xy 116.59438 -127.48387)
			(xy 111.518979 -127.48387) (xy 111.496782 -127.490386) (xy 111.44283 -127.49814) (xy 111.415576 -127.498602)
			(xy 111.388288 -127.498128) (xy 111.334267 -127.49036) (xy 111.281905 -127.47497) (xy 111.232272 -127.452274)
			(xy 111.209074 -127.437896) (xy 111.20882 -127.437642) (xy 111.198527 -127.431896) (xy 111.175101 -127.429514)
			(xy 111.163862 -127.43307) (xy 111.087408 -127.461264) (xy 111.076556 -127.465943) (xy 111.060406 -127.483158)
			(xy 111.05642 -127.494284) (xy 111.05642 -127.494792) (xy 111.048249 -127.520795) (xy 111.025627 -127.570382)
			(xy 110.996177 -127.616243) (xy 110.960498 -127.657445) (xy 110.919317 -127.693147) (xy 110.873472 -127.722623)
			(xy 110.823899 -127.745273) (xy 110.771605 -127.760634) (xy 110.717657 -127.768394) (xy 110.690406 -127.768858)
			(xy 110.663151 -127.768439) (xy 110.609196 -127.760681) (xy 110.556894 -127.745324) (xy 110.507311 -127.722678)
			(xy 110.461455 -127.693206) (xy 110.420261 -127.657508) (xy 110.384567 -127.61631) (xy 110.355101 -127.570451)
			(xy 110.332461 -127.520865) (xy 110.317109 -127.468561) (xy 110.309358 -127.414605) (xy 110.308898 -127.38735)
			(xy 108.963528 -127.38735) (xy 108.974793 -127.424005) (xy 108.983252 -127.480299) (xy 108.98378 -127.508762)
			(xy 108.983294 -127.536013) (xy 108.975538 -127.589961) (xy 108.960183 -127.642256) (xy 108.937541 -127.691833)
			(xy 108.908075 -127.737683) (xy 108.872384 -127.778874) (xy 108.831193 -127.814565) (xy 108.785343 -127.844031)
			(xy 108.735766 -127.866673) (xy 108.683471 -127.882028) (xy 108.629523 -127.889784) (xy 108.575021 -127.889784)
			(xy 108.521073 -127.882028) (xy 108.468778 -127.866673) (xy 108.419201 -127.844031) (xy 108.373351 -127.814565)
			(xy 108.33216 -127.778874) (xy 108.296469 -127.737683) (xy 108.267003 -127.691833) (xy 108.244361 -127.642256)
			(xy 108.229006 -127.589961) (xy 108.22125 -127.536013) (xy 108.220764 -127.508762) (xy 108.22178 -127.479552)
			(xy 108.22305 -127.465582) (xy 108.21035 -127.440182) (xy 108.110528 -127.376936) (xy 108.082588 -127.376428)
			(xy 108.070396 -127.383286) (xy 108.048743 -127.395152) (xy 108.003045 -127.413849) (xy 107.955319 -127.426507)
			(xy 107.906361 -127.432913) (xy 107.881674 -127.433324) (xy 107.854423 -127.432846) (xy 107.800476 -127.425087)
			(xy 107.748182 -127.409729) (xy 107.698605 -127.387086) (xy 107.652756 -127.357619) (xy 107.611566 -127.321926)
			(xy 107.575875 -127.280736) (xy 107.546409 -127.234886) (xy 107.523767 -127.185309) (xy 107.508411 -127.133015)
			(xy 107.500653 -127.079067) (xy 107.500166 -127.051816) (xy 105.602208 -127.051816) (xy 105.599116 -127.073325)
			(xy 105.583761 -127.12562) (xy 105.561119 -127.175197) (xy 105.531653 -127.221047) (xy 105.495962 -127.262238)
			(xy 105.454771 -127.297929) (xy 105.408921 -127.327395) (xy 105.359344 -127.350037) (xy 105.307049 -127.365392)
			(xy 105.253101 -127.373148) (xy 105.198599 -127.373148) (xy 105.144651 -127.365392) (xy 105.092356 -127.350037)
			(xy 105.042779 -127.327395) (xy 104.996929 -127.297929) (xy 104.955738 -127.262238) (xy 104.920047 -127.221047)
			(xy 104.890581 -127.175197) (xy 104.867939 -127.12562) (xy 104.852584 -127.073325) (xy 104.844828 -127.019377)
			(xy 104.844342 -126.992126) (xy 80.847012 -126.992126) (xy 80.827669 -128.665246) (xy 112.888324 -128.665246)
			(xy 112.888324 -128.610754) (xy 112.896079 -128.556815) (xy 112.91143 -128.504529) (xy 112.934066 -128.45496)
			(xy 112.963526 -128.409117) (xy 112.99921 -128.367933) (xy 113.040391 -128.332245) (xy 113.086232 -128.302782)
			(xy 113.135799 -128.280142) (xy 113.188084 -128.264786) (xy 113.242022 -128.257026) (xy 113.269268 -128.256538)
			(xy 113.296638 -128.257014) (xy 113.350817 -128.264828) (xy 113.40332 -128.280314) (xy 113.453067 -128.303154)
			(xy 113.499034 -128.332877) (xy 113.519966 -128.350518) (xy 113.52022 -128.350772) (xy 113.527291 -128.356382)
			(xy 113.54422 -128.362612) (xy 113.55324 -128.362964) (xy 113.620296 -128.362964) (xy 113.629314 -128.362613)
			(xy 113.646231 -128.356362) (xy 113.653316 -128.350772) (xy 113.653316 -128.350518) (xy 113.65357 -128.350518)
			(xy 113.674503 -128.332877) (xy 113.720471 -128.303153) (xy 113.770217 -128.280307) (xy 113.822719 -128.264811)
			(xy 113.876897 -128.256982) (xy 113.931639 -128.256982) (xy 113.985817 -128.264811) (xy 114.038319 -128.280307)
			(xy 114.088065 -128.303153) (xy 114.134033 -128.332877) (xy 114.154966 -128.350518) (xy 114.15522 -128.350772)
			(xy 114.162291 -128.356382) (xy 114.17922 -128.362612) (xy 114.18824 -128.362964) (xy 114.255296 -128.362964)
			(xy 114.264314 -128.362613) (xy 114.281231 -128.356362) (xy 114.288316 -128.350772) (xy 114.288316 -128.350518)
			(xy 114.28857 -128.350518) (xy 114.309505 -128.332882) (xy 114.355477 -128.303169) (xy 114.405223 -128.280332)
			(xy 114.457724 -128.264841) (xy 114.511899 -128.257012) (xy 114.539268 -128.256538) (xy 114.566526 -128.256907)
			(xy 114.620487 -128.264661) (xy 114.672795 -128.280016) (xy 114.722385 -128.30266) (xy 114.768248 -128.33213)
			(xy 114.809449 -128.367828) (xy 114.845151 -128.409027) (xy 114.874625 -128.454887) (xy 114.897273 -128.504475)
			(xy 114.912632 -128.556782) (xy 114.920391 -128.610742) (xy 114.920391 -128.665258) (xy 114.912632 -128.719218)
			(xy 114.897273 -128.771525) (xy 114.874625 -128.821113) (xy 114.845151 -128.866973) (xy 114.809449 -128.908172)
			(xy 114.768248 -128.94387) (xy 114.722385 -128.97334) (xy 114.672795 -128.995984) (xy 114.620487 -129.011339)
			(xy 114.566526 -129.019093) (xy 114.539268 -129.019554) (xy 114.511897 -129.019118) (xy 114.457716 -129.011295)
			(xy 114.405212 -128.995799) (xy 114.355465 -128.97295) (xy 114.3095 -128.943219) (xy 114.28857 -128.925574)
			(xy 114.288316 -128.92532) (xy 114.281236 -128.919725) (xy 114.264314 -128.913485) (xy 114.255296 -128.913128)
			(xy 114.18824 -128.913128) (xy 114.179224 -128.913498) (xy 114.162307 -128.919736) (xy 114.15522 -128.92532)
			(xy 114.154966 -128.925574) (xy 114.134033 -128.943215) (xy 114.088065 -128.972939) (xy 114.038319 -128.995785)
			(xy 113.985817 -129.011281) (xy 113.931639 -129.01911) (xy 113.876897 -129.01911) (xy 113.822719 -129.011281)
			(xy 113.770217 -128.995785) (xy 113.720471 -128.972939) (xy 113.674503 -128.943215) (xy 113.65357 -128.925574)
			(xy 113.653316 -128.92532) (xy 113.646236 -128.919725) (xy 113.629314 -128.913485) (xy 113.620296 -128.913128)
			(xy 113.55324 -128.913128) (xy 113.544224 -128.913498) (xy 113.527307 -128.919736) (xy 113.52022 -128.92532)
			(xy 113.52022 -128.925574) (xy 113.519966 -128.925574) (xy 113.499017 -128.943192) (xy 113.453049 -128.972908)
			(xy 113.403306 -128.995748) (xy 113.350809 -129.011244) (xy 113.296636 -129.019077) (xy 113.269268 -129.019554)
			(xy 113.242022 -129.018974) (xy 113.188084 -129.011214) (xy 113.135799 -128.995858) (xy 113.086232 -128.973218)
			(xy 113.040391 -128.943755) (xy 112.99921 -128.908067) (xy 112.963526 -128.866883) (xy 112.934067 -128.82104)
			(xy 112.91143 -128.771471) (xy 112.896079 -128.719185) (xy 112.888324 -128.665246) (xy 80.827669 -128.665246)
			(xy 80.803347 -130.769106) (xy 81.07426 -130.769106) (xy 81.07426 -129.905506) (xy 81.07475 -129.875522)
			(xy 81.082578 -129.816066) (xy 81.098099 -129.758141) (xy 81.121048 -129.702737) (xy 81.151032 -129.650803)
			(xy 81.187538 -129.603227) (xy 81.229943 -129.560822) (xy 81.277519 -129.524316) (xy 81.329453 -129.494332)
			(xy 81.384857 -129.471383) (xy 81.442782 -129.455862) (xy 81.502238 -129.448034) (xy 81.562206 -129.448034)
			(xy 81.621662 -129.455862) (xy 81.679587 -129.471383) (xy 81.734991 -129.494332) (xy 81.786925 -129.524316)
			(xy 81.834501 -129.560822) (xy 81.876906 -129.603227) (xy 81.913412 -129.650803) (xy 81.943396 -129.702737)
			(xy 81.966345 -129.758141) (xy 81.981866 -129.816066) (xy 81.989694 -129.875522) (xy 81.990184 -129.905506)
			(xy 81.990184 -129.951246) (xy 112.909426 -129.951246) (xy 112.909426 -129.896754) (xy 112.91718 -129.842818)
			(xy 112.932531 -129.790534) (xy 112.955166 -129.740966) (xy 112.984623 -129.695124) (xy 113.020305 -129.65394)
			(xy 113.061484 -129.618253) (xy 113.107322 -129.58879) (xy 113.156887 -129.566148) (xy 113.209169 -129.550791)
			(xy 113.263105 -129.54303) (xy 113.29035 -129.54254) (xy 113.31772 -129.543026) (xy 113.371898 -129.550837)
			(xy 113.424402 -129.566321) (xy 113.474149 -129.589159) (xy 113.520116 -129.61888) (xy 113.541048 -129.63652)
			(xy 113.541302 -129.636774) (xy 113.548378 -129.642376) (xy 113.565303 -129.648612) (xy 113.574322 -129.648966)
			(xy 113.641378 -129.648966) (xy 113.650395 -129.648606) (xy 113.667312 -129.642361) (xy 113.674398 -129.636774)
			(xy 113.674398 -129.63652) (xy 113.674652 -129.63652) (xy 113.695594 -129.618893) (xy 113.741564 -129.589179)
			(xy 113.791309 -129.56634) (xy 113.843807 -129.550846) (xy 113.897981 -129.543015) (xy 113.92535 -129.54254)
			(xy 113.952609 -129.542904) (xy 114.006572 -129.550656) (xy 114.058882 -129.566009) (xy 114.108475 -129.588652)
			(xy 114.15434 -129.618122) (xy 114.195544 -129.65382) (xy 114.231248 -129.69502) (xy 114.260724 -129.740881)
			(xy 114.283373 -129.790471) (xy 114.298734 -129.842779) (xy 114.306493 -129.896741) (xy 114.306493 -129.951259)
			(xy 114.298734 -130.005221) (xy 114.283373 -130.057529) (xy 114.260724 -130.107119) (xy 114.231248 -130.15298)
			(xy 114.195544 -130.19418) (xy 114.15434 -130.229878) (xy 114.108475 -130.259348) (xy 114.058882 -130.281991)
			(xy 114.006572 -130.297344) (xy 113.952609 -130.305096) (xy 113.92535 -130.305556) (xy 113.89798 -130.305071)
			(xy 113.843802 -130.29726) (xy 113.791298 -130.281776) (xy 113.741551 -130.258938) (xy 113.695584 -130.229216)
			(xy 113.674652 -130.211576) (xy 113.674398 -130.211322) (xy 113.667323 -130.205719) (xy 113.650397 -130.199484)
			(xy 113.641378 -130.19913) (xy 113.574322 -130.19913) (xy 113.565305 -130.199491) (xy 113.548388 -130.205735)
			(xy 113.541302 -130.211322) (xy 113.541302 -130.211576) (xy 113.541048 -130.211576) (xy 113.520106 -130.229202)
			(xy 113.474136 -130.258917) (xy 113.424391 -130.281756) (xy 113.371893 -130.29725) (xy 113.317719 -130.305081)
			(xy 113.29035 -130.305556) (xy 113.263105 -130.30497) (xy 113.209169 -130.297209) (xy 113.156887 -130.281852)
			(xy 113.107322 -130.259211) (xy 113.061484 -130.229747) (xy 113.020305 -130.19406) (xy 112.984623 -130.152876)
			(xy 112.955166 -130.107034) (xy 112.932531 -130.057466) (xy 112.91718 -130.005182) (xy 112.909426 -129.951246)
			(xy 81.990184 -129.951246) (xy 81.990184 -130.769106) (xy 81.989694 -130.79909) (xy 81.981866 -130.858546)
			(xy 81.966345 -130.916471) (xy 81.943396 -130.971875) (xy 81.913412 -131.023809) (xy 81.876906 -131.071385)
			(xy 81.834501 -131.11379) (xy 81.786925 -131.150296) (xy 81.734991 -131.18028) (xy 81.679587 -131.203229)
			(xy 81.621662 -131.21875) (xy 81.562206 -131.226578) (xy 81.502238 -131.226578) (xy 81.442782 -131.21875)
			(xy 81.384857 -131.203229) (xy 81.329453 -131.18028) (xy 81.277519 -131.150296) (xy 81.229943 -131.11379)
			(xy 81.187538 -131.071385) (xy 81.151032 -131.023809) (xy 81.121048 -130.971875) (xy 81.098099 -130.916471)
			(xy 81.082578 -130.858546) (xy 81.07475 -130.79909) (xy 81.07426 -130.769106) (xy 80.803347 -130.769106)
			(xy 80.78246 -132.575808) (xy 83.716368 -132.575808) (xy 83.716368 -131.712208) (xy 83.716858 -131.682224)
			(xy 83.724686 -131.622768) (xy 83.740207 -131.564843) (xy 83.763156 -131.509439) (xy 83.79314 -131.457505)
			(xy 83.829646 -131.409929) (xy 83.872051 -131.367524) (xy 83.919627 -131.331018) (xy 83.971561 -131.301034)
			(xy 84.026965 -131.278085) (xy 84.08489 -131.262564) (xy 84.144346 -131.254736) (xy 84.204314 -131.254736)
			(xy 84.26377 -131.262564) (xy 84.321695 -131.278085) (xy 84.377099 -131.301034) (xy 84.429033 -131.331018)
			(xy 84.476609 -131.367524) (xy 84.519014 -131.409929) (xy 84.55552 -131.457505) (xy 84.585504 -131.509439)
			(xy 84.608453 -131.564843) (xy 84.623974 -131.622768) (xy 84.631802 -131.682224) (xy 84.632292 -131.712208)
			(xy 84.632292 -132.575808) (xy 84.631802 -132.605792) (xy 84.623974 -132.665248) (xy 84.608453 -132.723173)
			(xy 84.585504 -132.778577) (xy 84.55552 -132.830511) (xy 84.519014 -132.878087) (xy 84.476609 -132.920492)
			(xy 84.429033 -132.956998) (xy 84.377099 -132.986982) (xy 84.321695 -133.009931) (xy 84.26377 -133.025452)
			(xy 84.204314 -133.03328) (xy 84.144346 -133.03328) (xy 84.08489 -133.025452) (xy 84.026965 -133.009931)
			(xy 83.971561 -132.986982) (xy 83.919627 -132.956998) (xy 83.872051 -132.920492) (xy 83.829646 -132.878087)
			(xy 83.79314 -132.830511) (xy 83.763156 -132.778577) (xy 83.740207 -132.723173) (xy 83.724686 -132.665248)
			(xy 83.716858 -132.605792) (xy 83.716368 -132.575808) (xy 80.78246 -132.575808) (xy 80.761726 -134.369302)
			(xy 81.07426 -134.369302) (xy 81.07426 -133.505702) (xy 81.07475 -133.475718) (xy 81.082578 -133.416262)
			(xy 81.098099 -133.358337) (xy 81.121048 -133.302933) (xy 81.151032 -133.250999) (xy 81.187538 -133.203423)
			(xy 81.229943 -133.161018) (xy 81.277519 -133.124512) (xy 81.329453 -133.094528) (xy 81.384857 -133.071579)
			(xy 81.442782 -133.056058) (xy 81.502238 -133.04823) (xy 81.562206 -133.04823) (xy 81.621662 -133.056058)
			(xy 81.679587 -133.071579) (xy 81.734991 -133.094528) (xy 81.786925 -133.124512) (xy 81.834501 -133.161018)
			(xy 81.876906 -133.203423) (xy 81.913412 -133.250999) (xy 81.943396 -133.302933) (xy 81.966345 -133.358337)
			(xy 81.981866 -133.416262) (xy 81.989694 -133.475718) (xy 81.990184 -133.505702) (xy 81.990184 -134.369302)
			(xy 81.989694 -134.399286) (xy 81.981866 -134.458742) (xy 81.966345 -134.516667) (xy 81.943396 -134.572071)
			(xy 81.913412 -134.624005) (xy 81.876906 -134.671581) (xy 81.834501 -134.713986) (xy 81.786925 -134.750492)
			(xy 81.734991 -134.780476) (xy 81.679587 -134.803425) (xy 81.621662 -134.818946) (xy 81.562206 -134.826774)
			(xy 81.502238 -134.826774) (xy 81.442782 -134.818946) (xy 81.384857 -134.803425) (xy 81.329453 -134.780476)
			(xy 81.277519 -134.750492) (xy 81.229943 -134.713986) (xy 81.187538 -134.671581) (xy 81.151032 -134.624005)
			(xy 81.121048 -134.572071) (xy 81.098099 -134.516667) (xy 81.082578 -134.458742) (xy 81.07475 -134.399286)
			(xy 81.07426 -134.369302) (xy 80.761726 -134.369302) (xy 80.740842 -136.17575) (xy 83.716368 -136.17575)
			(xy 83.716368 -135.31215) (xy 83.716858 -135.282166) (xy 83.724686 -135.22271) (xy 83.740207 -135.164785)
			(xy 83.763156 -135.109381) (xy 83.79314 -135.057447) (xy 83.829646 -135.009871) (xy 83.872051 -134.967466)
			(xy 83.919627 -134.93096) (xy 83.971561 -134.900976) (xy 84.026965 -134.878027) (xy 84.08489 -134.862506)
			(xy 84.144346 -134.854678) (xy 84.204314 -134.854678) (xy 84.26377 -134.862506) (xy 84.321695 -134.878027)
			(xy 84.377099 -134.900976) (xy 84.429033 -134.93096) (xy 84.476609 -134.967466) (xy 84.519014 -135.009871)
			(xy 84.55552 -135.057447) (xy 84.585504 -135.109381) (xy 84.608453 -135.164785) (xy 84.623974 -135.22271)
			(xy 84.631802 -135.282166) (xy 84.632292 -135.31215) (xy 84.632292 -136.17575) (xy 84.631802 -136.205734)
			(xy 84.623974 -136.26519) (xy 84.608453 -136.323115) (xy 84.585504 -136.378519) (xy 84.55552 -136.430453)
			(xy 84.519014 -136.478029) (xy 84.476609 -136.520434) (xy 84.429033 -136.55694) (xy 84.377099 -136.586924)
			(xy 84.321695 -136.609873) (xy 84.26377 -136.625394) (xy 84.204314 -136.633222) (xy 84.144346 -136.633222)
			(xy 84.08489 -136.625394) (xy 84.026965 -136.609873) (xy 83.971561 -136.586924) (xy 83.919627 -136.55694)
			(xy 83.872051 -136.520434) (xy 83.829646 -136.478029) (xy 83.79314 -136.430453) (xy 83.763156 -136.378519)
			(xy 83.740207 -136.323115) (xy 83.724686 -136.26519) (xy 83.716858 -136.205734) (xy 83.716368 -136.17575)
			(xy 80.740842 -136.17575) (xy 80.736948 -136.512554) (xy 80.737339 -136.522929) (xy 80.745337 -136.542068)
			(xy 80.752442 -136.549638) (xy 80.75549 -136.552432) (xy 80.816958 -136.602724) (xy 80.821323 -136.606126)
			(xy 80.831189 -136.611131) (xy 80.836516 -136.61263) (xy 80.847692 -136.615424) (xy 80.859376 -136.612884)
			(xy 80.879019 -136.608974) (xy 80.918852 -136.604779) (xy 80.938878 -136.604502) (xy 80.946498 -136.604502)
			(xy 80.973429 -136.605447) (xy 81.026638 -136.61398) (xy 81.078115 -136.629917) (xy 81.126837 -136.652941)
			(xy 81.171835 -136.682592) (xy 81.212211 -136.71828) (xy 81.247162 -136.759296) (xy 81.275994 -136.804823)
			(xy 81.298131 -136.853954) (xy 81.313133 -136.905712) (xy 81.320702 -136.959066) (xy 81.321148 -136.98601)
			(xy 81.320662 -137.013262) (xy 81.312904 -137.067211) (xy 81.297549 -137.119506) (xy 81.274907 -137.169085)
			(xy 81.245441 -137.214937) (xy 81.209751 -137.256129) (xy 81.168561 -137.291823) (xy 81.122711 -137.321293)
			(xy 81.073135 -137.343938) (xy 81.02084 -137.359298) (xy 80.966892 -137.367059) (xy 80.93964 -137.367518)
			(xy 80.931258 -137.367518) (xy 80.903741 -137.366469) (xy 80.849424 -137.357417) (xy 80.823054 -137.349484)
			(xy 80.815434 -137.346944) (xy 80.800448 -137.341864) (xy 80.795368 -137.339578) (xy 80.78724 -137.335768)
			(xy 80.774032 -137.329926) (xy 80.747616 -137.346436) (xy 80.738516 -137.353902) (xy 80.727791 -137.374822)
			(xy 80.727042 -137.386568) (xy 80.700032 -139.71651) (xy 82.792316 -139.71651) (xy 82.792813 -139.6896)
			(xy 82.800389 -139.636317) (xy 82.815376 -139.584627) (xy 82.837479 -139.535555) (xy 82.866258 -139.490077)
			(xy 82.901143 -139.449094) (xy 82.94144 -139.41342) (xy 82.98635 -139.383762) (xy 83.034982 -139.360709)
			(xy 83.06054 -139.352274) (xy 83.060794 -139.352274) (xy 83.06648 -139.350277) (xy 83.076759 -139.343993)
			(xy 83.081114 -139.339828) (xy 83.410298 -139.010644) (xy 83.417111 -139.003223) (xy 83.424847 -138.98464)
			(xy 83.425284 -138.974576) (xy 83.425284 -138.61161) (xy 83.425767 -138.585523) (xy 83.433934 -138.533991)
			(xy 83.450066 -138.484373) (xy 83.473768 -138.437892) (xy 83.504453 -138.395695) (xy 83.522566 -138.376914)
			(xy 86.960456 -134.939024) (xy 86.979219 -134.920983) (xy 87.02134 -134.890407) (xy 87.067718 -134.866783)
			(xy 87.117216 -134.85069) (xy 87.16862 -134.842524) (xy 87.194644 -134.841996) (xy 92.110814 -134.841996)
			(xy 92.120888 -134.841606) (xy 92.139487 -134.833863) (xy 92.146882 -134.82701) (xy 95.351092 -131.622546)
			(xy 95.355212 -131.618156) (xy 95.361495 -131.607889) (xy 95.363538 -131.602226) (xy 95.363538 -131.601718)
			(xy 95.371993 -131.576177) (xy 95.395064 -131.527574) (xy 95.424734 -131.482695) (xy 95.460414 -131.442428)
			(xy 95.501397 -131.407573) (xy 95.54687 -131.37882) (xy 95.595931 -131.356741) (xy 95.647607 -131.341772)
			(xy 95.700874 -131.334211) (xy 95.727774 -131.333748) (xy 95.755023 -131.334302) (xy 95.808966 -131.342054)
			(xy 95.861256 -131.357404) (xy 95.91083 -131.380039) (xy 95.956679 -131.409498) (xy 95.997868 -131.445182)
			(xy 96.03356 -131.486365) (xy 96.063028 -131.532208) (xy 96.085672 -131.581778) (xy 96.101031 -131.634066)
			(xy 96.108793 -131.688008) (xy 96.109282 -131.715256) (xy 96.108845 -131.742167) (xy 96.10126 -131.795454)
			(xy 96.086264 -131.847145) (xy 96.064153 -131.896217) (xy 96.035366 -131.941695) (xy 96.000475 -131.982678)
			(xy 95.960171 -132.018351) (xy 95.941398 -132.030746) (xy 112.909424 -132.030746) (xy 112.909424 -131.976254)
			(xy 112.917178 -131.922318) (xy 112.932529 -131.870033) (xy 112.955164 -131.820465) (xy 112.984622 -131.774623)
			(xy 113.020304 -131.733439) (xy 113.061483 -131.697752) (xy 113.107321 -131.668288) (xy 113.156886 -131.645647)
			(xy 113.209169 -131.630289) (xy 113.263104 -131.622528) (xy 113.29035 -131.622038) (xy 113.31772 -131.622524)
			(xy 113.371898 -131.630336) (xy 113.424401 -131.64582) (xy 113.474149 -131.668657) (xy 113.520116 -131.698378)
			(xy 113.541048 -131.716018) (xy 113.541302 -131.716272) (xy 113.548378 -131.721874) (xy 113.565303 -131.728109)
			(xy 113.574322 -131.728464) (xy 113.641378 -131.728464) (xy 113.650395 -131.728104) (xy 113.667312 -131.721859)
			(xy 113.674398 -131.716272) (xy 113.674398 -131.716018) (xy 113.674652 -131.716018) (xy 113.695594 -131.698391)
			(xy 113.741564 -131.668677) (xy 113.791309 -131.645838) (xy 113.843807 -131.630344) (xy 113.897981 -131.622513)
			(xy 113.92535 -131.622038) (xy 113.952608 -131.622406) (xy 114.006571 -131.630158) (xy 114.058882 -131.645511)
			(xy 114.108474 -131.668154) (xy 114.154339 -131.697624) (xy 114.195543 -131.733322) (xy 114.231246 -131.774521)
			(xy 114.260722 -131.820382) (xy 114.283371 -131.869971) (xy 114.298732 -131.92228) (xy 114.306491 -131.976242)
			(xy 114.306491 -132.030758) (xy 114.298732 -132.08472) (xy 114.283371 -132.137029) (xy 114.260722 -132.186618)
			(xy 114.231246 -132.232479) (xy 114.195543 -132.273678) (xy 114.154339 -132.309376) (xy 114.108474 -132.338846)
			(xy 114.058882 -132.361489) (xy 114.006571 -132.376842) (xy 113.952609 -132.384594) (xy 113.92535 -132.385054)
			(xy 113.89798 -132.38457) (xy 113.843802 -132.376758) (xy 113.791298 -132.361274) (xy 113.741551 -132.338436)
			(xy 113.695584 -132.308714) (xy 113.674652 -132.291074) (xy 113.674398 -132.29082) (xy 113.667323 -132.285217)
			(xy 113.650397 -132.278982) (xy 113.641378 -132.278628) (xy 113.574322 -132.278628) (xy 113.565305 -132.27899)
			(xy 113.548388 -132.285233) (xy 113.541302 -132.29082) (xy 113.541302 -132.291074) (xy 113.541048 -132.291074)
			(xy 113.520105 -132.3087) (xy 113.474136 -132.338415) (xy 113.424391 -132.361254) (xy 113.371893 -132.376748)
			(xy 113.317719 -132.384579) (xy 113.29035 -132.385054) (xy 113.263104 -132.384472) (xy 113.209169 -132.376711)
			(xy 113.156886 -132.361353) (xy 113.107321 -132.338712) (xy 113.061483 -132.309248) (xy 113.020304 -132.273561)
			(xy 112.984622 -132.232377) (xy 112.955164 -132.186535) (xy 112.932529 -132.136967) (xy 112.917178 -132.084682)
			(xy 112.909424 -132.030746) (xy 95.941398 -132.030746) (xy 95.915255 -132.048007) (xy 95.866618 -132.071057)
			(xy 95.841058 -132.079492) (xy 95.840804 -132.079492) (xy 95.83512 -132.081495) (xy 95.82484 -132.087775)
			(xy 95.820484 -132.091938) (xy 92.504006 -135.408416) (xy 92.48525 -135.426464) (xy 92.443129 -135.457042)
			(xy 92.396749 -135.480666) (xy 92.347248 -135.496756) (xy 92.295843 -135.504919) (xy 92.269818 -135.505444)
			(xy 87.353648 -135.505444) (xy 87.34358 -135.505883) (xy 87.324981 -135.513593) (xy 87.31758 -135.52043)
			(xy 84.479862 -138.358372) (xy 84.809328 -138.358372) (xy 84.813399 -138.30275) (xy 84.825525 -138.248313)
			(xy 84.845448 -138.196222) (xy 84.872744 -138.147587) (xy 84.90683 -138.103444) (xy 84.946979 -138.064735)
			(xy 84.992337 -138.032284) (xy 85.041937 -138.006783) (xy 85.094721 -137.988776) (xy 85.149564 -137.978646)
			(xy 85.205298 -137.976609) (xy 85.260735 -137.982709) (xy 85.314692 -137.996815) (xy 85.366021 -138.018627)
			(xy 85.413627 -138.047681) (xy 85.456495 -138.083356) (xy 85.493712 -138.124893) (xy 85.524485 -138.171406)
			(xy 85.548157 -138.221903) (xy 85.564225 -138.27531) (xy 85.572345 -138.330486) (xy 85.572854 -138.358372)
			(xy 85.572345 -138.386258) (xy 85.564225 -138.441434) (xy 85.548157 -138.494841) (xy 85.524485 -138.545338)
			(xy 85.493712 -138.591851) (xy 85.456495 -138.633388) (xy 85.413627 -138.669063) (xy 85.366021 -138.698117)
			(xy 85.314692 -138.719929) (xy 85.260735 -138.734035) (xy 85.205298 -138.740135) (xy 85.149564 -138.738098)
			(xy 85.094721 -138.727968) (xy 85.041937 -138.709961) (xy 84.992337 -138.68446) (xy 84.946979 -138.652009)
			(xy 84.90683 -138.6133) (xy 84.872744 -138.569157) (xy 84.845448 -138.520522) (xy 84.825525 -138.468431)
			(xy 84.813399 -138.413994) (xy 84.809328 -138.358372) (xy 84.479862 -138.358372) (xy 84.104226 -138.734038)
			(xy 84.097381 -138.741434) (xy 84.089663 -138.760036) (xy 84.08924 -138.770106) (xy 84.08924 -139.03706)
			(xy 106.080052 -139.03706) (xy 106.080564 -139.008321) (xy 106.089192 -138.951494) (xy 106.106245 -138.896603)
			(xy 106.131339 -138.844892) (xy 106.163905 -138.797529) (xy 106.183176 -138.776202) (xy 106.18978 -138.769344)
			(xy 106.196892 -138.75131) (xy 106.196892 -138.66241) (xy 106.18978 -138.644376) (xy 106.183176 -138.637518)
			(xy 106.163893 -138.616202) (xy 106.131327 -138.568838) (xy 106.106236 -138.517123) (xy 106.089188 -138.46223)
			(xy 106.08057 -138.4054) (xy 106.080052 -138.37666) (xy 106.080538 -138.349409) (xy 106.088294 -138.295461)
			(xy 106.103649 -138.243166) (xy 106.126291 -138.193589) (xy 106.155757 -138.147739) (xy 106.191448 -138.106548)
			(xy 106.232639 -138.070857) (xy 106.278489 -138.041391) (xy 106.328066 -138.018749) (xy 106.380361 -138.003394)
			(xy 106.434309 -137.995638) (xy 106.488811 -137.995638) (xy 106.542759 -138.003394) (xy 106.595054 -138.018749)
			(xy 106.644631 -138.041391) (xy 106.690481 -138.070857) (xy 106.731672 -138.106548) (xy 106.767363 -138.147739)
			(xy 106.796829 -138.193589) (xy 106.819471 -138.243166) (xy 106.834826 -138.295461) (xy 106.842582 -138.349409)
			(xy 106.843068 -138.37666) (xy 106.842563 -138.405399) (xy 106.833933 -138.462227) (xy 106.816877 -138.517117)
			(xy 106.791782 -138.568828) (xy 106.759215 -138.616191) (xy 106.739944 -138.637518) (xy 106.73334 -138.644376)
			(xy 106.726228 -138.66241) (xy 106.726228 -138.75131) (xy 106.73334 -138.769344) (xy 106.739944 -138.776202)
			(xy 106.759193 -138.797548) (xy 106.791763 -138.844905) (xy 106.81686 -138.896611) (xy 106.833916 -138.951498)
			(xy 106.842544 -139.008322) (xy 106.843068 -139.03706) (xy 106.842617 -139.062965) (xy 106.835599 -139.114299)
			(xy 106.821702 -139.164211) (xy 106.80118 -139.211785) (xy 106.774411 -139.256145) (xy 106.758486 -139.276582)
			(xy 106.752749 -139.284343) (xy 106.747003 -139.30275) (xy 106.74731 -139.312396) (xy 106.752898 -139.381992)
			(xy 106.753985 -139.391424) (xy 106.76222 -139.408518) (xy 106.7689 -139.415266) (xy 106.769408 -139.415774)
			(xy 106.788658 -139.433887) (xy 106.822417 -139.474559) (xy 106.85024 -139.5195) (xy 106.871596 -139.56785)
			(xy 106.886076 -139.618685) (xy 106.893402 -139.671032) (xy 106.893868 -139.69746) (xy 106.893363 -139.726199)
			(xy 106.884733 -139.783027) (xy 106.867677 -139.837917) (xy 106.842582 -139.889628) (xy 106.810015 -139.936991)
			(xy 106.790744 -139.958318) (xy 106.78414 -139.965176) (xy 106.777028 -139.98321) (xy 106.777028 -140.07211)
			(xy 106.78414 -140.090144) (xy 106.790744 -140.097002) (xy 106.809977 -140.118362) (xy 106.842546 -140.165718)
			(xy 106.867642 -140.217424) (xy 106.884696 -140.27231) (xy 106.893323 -140.329134) (xy 106.893328 -140.386608)
			(xy 106.884709 -140.443433) (xy 106.867663 -140.498321) (xy 106.842575 -140.550031) (xy 106.810013 -140.597392)
			(xy 106.790744 -140.618718) (xy 106.78414 -140.625576) (xy 106.777028 -140.64361) (xy 106.777028 -140.73251)
			(xy 106.78414 -140.750544) (xy 106.790744 -140.757402) (xy 106.809993 -140.778748) (xy 106.842563 -140.826105)
			(xy 106.86766 -140.877811) (xy 106.884716 -140.932698) (xy 106.893344 -140.989522) (xy 106.893868 -141.01826)
			(xy 108.518452 -141.01826) (xy 108.518964 -140.989521) (xy 108.527592 -140.932694) (xy 108.544645 -140.877803)
			(xy 108.569739 -140.826092) (xy 108.602305 -140.778729) (xy 108.621576 -140.757402) (xy 108.62818 -140.750544)
			(xy 108.635292 -140.73251) (xy 108.635292 -140.64361) (xy 108.62818 -140.625576) (xy 108.621576 -140.618718)
			(xy 108.602268 -140.597425) (xy 108.569708 -140.550055) (xy 108.544622 -140.498337) (xy 108.527577 -140.443442)
			(xy 108.518959 -140.386611) (xy 108.518963 -140.329131) (xy 108.52759 -140.272301) (xy 108.544643 -140.217408)
			(xy 108.569737 -140.165694) (xy 108.602304 -140.11833) (xy 108.621576 -140.097002) (xy 108.62818 -140.090144)
			(xy 108.635292 -140.07211) (xy 108.635292 -139.98321) (xy 108.62818 -139.965176) (xy 108.621576 -139.958318)
			(xy 108.602293 -139.937002) (xy 108.569727 -139.889638) (xy 108.544636 -139.837923) (xy 108.527588 -139.78303)
			(xy 108.51897 -139.7262) (xy 108.518452 -139.69746) (xy 108.518993 -139.668544) (xy 108.527715 -139.611373)
			(xy 108.544967 -139.556173) (xy 108.570354 -139.504211) (xy 108.603295 -139.456677) (xy 108.643033 -139.41466)
			(xy 108.665518 -139.39647) (xy 108.674332 -139.388869) (xy 108.684511 -139.367964) (xy 108.685076 -139.356338)
			(xy 108.685076 -139.276582) (xy 108.684541 -139.264949) (xy 108.67435 -139.244039) (xy 108.665518 -139.23645)
			(xy 108.643062 -139.218226) (xy 108.603324 -139.176214) (xy 108.570382 -139.128686) (xy 108.544988 -139.076731)
			(xy 108.527726 -139.021539) (xy 108.518991 -138.964374) (xy 108.518452 -138.93546) (xy 108.518964 -138.906721)
			(xy 108.527592 -138.849894) (xy 108.544645 -138.795003) (xy 108.569739 -138.743292) (xy 108.602305 -138.695929)
			(xy 108.621576 -138.674602) (xy 108.62818 -138.667744) (xy 108.635292 -138.64971) (xy 108.635292 -138.56081)
			(xy 108.62818 -138.542776) (xy 108.621576 -138.535918) (xy 108.602293 -138.514602) (xy 108.569727 -138.467238)
			(xy 108.544636 -138.415523) (xy 108.527588 -138.36063) (xy 108.51897 -138.3038) (xy 108.518452 -138.27506)
			(xy 108.51894 -138.24781) (xy 108.526701 -138.193864) (xy 108.54206 -138.141572) (xy 108.564702 -138.091997)
			(xy 108.594169 -138.046149) (xy 108.62986 -138.00496) (xy 108.671049 -137.969269) (xy 108.716897 -137.939802)
			(xy 108.766472 -137.91716) (xy 108.818764 -137.901801) (xy 108.87271 -137.89404) (xy 108.89996 -137.893552)
			(xy 108.929295 -137.894104) (xy 108.987274 -137.903069) (xy 109.043197 -137.920808) (xy 109.095742 -137.946903)
			(xy 109.143671 -137.980739) (xy 109.165136 -138.00074) (xy 109.172502 -138.007852) (xy 109.190282 -138.014964)
			(xy 109.281214 -138.014964) (xy 109.298994 -138.007852) (xy 109.30636 -138.00074) (xy 109.327833 -137.980749)
			(xy 109.375767 -137.946923) (xy 109.42831 -137.920828) (xy 109.484228 -137.903079) (xy 109.542203 -137.894094)
			(xy 109.571536 -137.893552) (xy 109.598786 -137.894044) (xy 109.652732 -137.901805) (xy 109.705024 -137.917162)
			(xy 109.754599 -137.939805) (xy 109.800447 -137.969271) (xy 109.841636 -138.004962) (xy 109.877327 -138.04615)
			(xy 109.906793 -138.091998) (xy 109.929436 -138.141572) (xy 109.944795 -138.193864) (xy 109.952556 -138.24781)
			(xy 109.953044 -138.27506) (xy 109.952545 -138.3038) (xy 109.943915 -138.360628) (xy 109.926858 -138.415518)
			(xy 109.901761 -138.467229) (xy 109.869192 -138.514591) (xy 109.84992 -138.535918) (xy 109.843316 -138.542776)
			(xy 109.836204 -138.56081) (xy 109.836204 -138.64971) (xy 109.843316 -138.667744) (xy 109.84992 -138.674602)
			(xy 109.869165 -138.695952) (xy 109.901736 -138.743307) (xy 109.926834 -138.795013) (xy 109.943891 -138.849899)
			(xy 109.95252 -138.906722) (xy 109.953044 -138.93546) (xy 112.090708 -138.93546) (xy 112.091205 -138.90672)
			(xy 112.099834 -138.849891) (xy 112.11689 -138.795) (xy 112.141988 -138.743289) (xy 112.174559 -138.695928)
			(xy 112.193832 -138.674602) (xy 112.200436 -138.667744) (xy 112.207548 -138.64971) (xy 112.207548 -138.56081)
			(xy 112.200436 -138.542776) (xy 112.193832 -138.535918) (xy 112.174541 -138.514608) (xy 112.141978 -138.467241)
			(xy 112.116889 -138.415525) (xy 112.099844 -138.360631) (xy 112.091226 -138.3038) (xy 112.090708 -138.27506)
			(xy 112.091194 -138.247809) (xy 112.09895 -138.193861) (xy 112.114305 -138.141566) (xy 112.136947 -138.091989)
			(xy 112.166413 -138.046139) (xy 112.202104 -138.004948) (xy 112.243295 -137.969257) (xy 112.289145 -137.939791)
			(xy 112.338722 -137.917149) (xy 112.391017 -137.901794) (xy 112.444965 -137.894038) (xy 112.499467 -137.894038)
			(xy 112.553415 -137.901794) (xy 112.60571 -137.917149) (xy 112.655287 -137.939791) (xy 112.701137 -137.969257)
			(xy 112.742328 -138.004948) (xy 112.778019 -138.046139) (xy 112.807485 -138.091989) (xy 112.830127 -138.141566)
			(xy 112.845482 -138.193861) (xy 112.853238 -138.247809) (xy 112.853724 -138.27506) (xy 112.85323 -138.3038)
			(xy 112.844599 -138.360628) (xy 112.827542 -138.415519) (xy 112.802444 -138.46723) (xy 112.769873 -138.514592)
			(xy 112.7506 -138.535918) (xy 112.743996 -138.542776) (xy 112.736884 -138.56081) (xy 112.736884 -138.64971)
			(xy 112.743996 -138.667744) (xy 112.7506 -138.674602) (xy 112.769841 -138.695955) (xy 112.802414 -138.743309)
			(xy 112.827513 -138.795014) (xy 112.84457 -138.849899) (xy 112.853199 -138.906723) (xy 112.853724 -138.93546)
			(xy 112.85327 -138.960927) (xy 112.84647 -139.011406) (xy 112.833011 -139.060531) (xy 112.813134 -139.107427)
			(xy 112.787191 -139.15126) (xy 112.755645 -139.19125) (xy 112.737646 -139.209272) (xy 112.73007 -139.217369)
			(xy 112.72217 -139.238063) (xy 112.722406 -139.24915) (xy 112.727994 -139.32662) (xy 112.729248 -139.337683)
			(xy 112.739929 -139.357188) (xy 112.748568 -139.364212) (xy 112.772282 -139.382359) (xy 112.81434 -139.42474)
			(xy 112.849289 -139.473152) (xy 112.876276 -139.526413) (xy 112.894644 -139.583226) (xy 112.903944 -139.642206)
			(xy 112.904524 -139.67206) (xy 112.90403 -139.7008) (xy 112.895399 -139.757628) (xy 112.878342 -139.812519)
			(xy 112.853244 -139.86423) (xy 112.820673 -139.911592) (xy 112.8014 -139.932918) (xy 112.794796 -139.939776)
			(xy 112.787684 -139.95781) (xy 112.787684 -140.04671) (xy 112.794796 -140.064744) (xy 112.8014 -140.071602)
			(xy 112.82063 -140.092964) (xy 112.853195 -140.140321) (xy 112.878287 -140.192027) (xy 112.895339 -140.246912)
			(xy 112.903964 -140.303734) (xy 112.903969 -140.361207) (xy 112.895352 -140.418031) (xy 112.878308 -140.472919)
			(xy 112.853224 -140.524629) (xy 112.820667 -140.571991) (xy 112.8014 -140.593318) (xy 112.794796 -140.600176)
			(xy 112.787684 -140.61821) (xy 112.787684 -140.70711) (xy 112.794796 -140.725144) (xy 112.8014 -140.732002)
			(xy 112.820641 -140.753355) (xy 112.853214 -140.800709) (xy 112.878313 -140.852414) (xy 112.89537 -140.907299)
			(xy 112.903999 -140.964123) (xy 112.90406 -140.96746) (xy 114.529108 -140.96746) (xy 114.529605 -140.93872)
			(xy 114.538234 -140.881891) (xy 114.55529 -140.827) (xy 114.580388 -140.775289) (xy 114.612959 -140.727928)
			(xy 114.632232 -140.706602) (xy 114.638836 -140.699744) (xy 114.645948 -140.68171) (xy 114.645948 -140.59281)
			(xy 114.638836 -140.574776) (xy 114.632232 -140.567918) (xy 114.612921 -140.546626) (xy 114.580357 -140.499258)
			(xy 114.555267 -140.44754) (xy 114.538219 -140.392644) (xy 114.5296 -140.335812) (xy 114.529605 -140.27833)
			(xy 114.538232 -140.221499) (xy 114.555288 -140.166605) (xy 114.580386 -140.114892) (xy 114.612958 -140.067529)
			(xy 114.632232 -140.046202) (xy 114.638836 -140.039344) (xy 114.645948 -140.02131) (xy 114.645948 -139.93241)
			(xy 114.638836 -139.914376) (xy 114.632232 -139.907518) (xy 114.612941 -139.886208) (xy 114.580378 -139.838841)
			(xy 114.555289 -139.787125) (xy 114.538244 -139.732231) (xy 114.529626 -139.6754) (xy 114.529108 -139.64666)
			(xy 114.529546 -139.620345) (xy 114.536787 -139.568215) (xy 114.551111 -139.517572) (xy 114.572249 -139.469373)
			(xy 114.599801 -139.42453) (xy 114.633244 -139.383892) (xy 114.652298 -139.365736) (xy 114.659685 -139.358203)
			(xy 114.668218 -139.338931) (xy 114.668808 -139.328398) (xy 114.668808 -139.253722) (xy 114.668278 -139.243173)
			(xy 114.659743 -139.223877) (xy 114.652298 -139.216384) (xy 114.633241 -139.19823) (xy 114.599784 -139.1576)
			(xy 114.572226 -139.112759) (xy 114.551087 -139.064558) (xy 114.53677 -139.01391) (xy 114.529546 -138.961776)
			(xy 114.529108 -138.93546) (xy 114.529605 -138.90672) (xy 114.538234 -138.849891) (xy 114.55529 -138.795)
			(xy 114.580388 -138.743289) (xy 114.612959 -138.695928) (xy 114.632232 -138.674602) (xy 114.638836 -138.667744)
			(xy 114.645948 -138.64971) (xy 114.645948 -138.56081) (xy 114.638836 -138.542776) (xy 114.632232 -138.535918)
			(xy 114.612941 -138.514608) (xy 114.580378 -138.467241) (xy 114.555289 -138.415525) (xy 114.538244 -138.360631)
			(xy 114.529626 -138.3038) (xy 114.529108 -138.27506) (xy 114.529541 -138.247807) (xy 114.537303 -138.193857)
			(xy 114.552664 -138.14156) (xy 114.575311 -138.091981) (xy 114.604783 -138.04613) (xy 114.64048 -138.00494)
			(xy 114.681675 -137.969249) (xy 114.727531 -137.939784) (xy 114.777112 -137.917144) (xy 114.829411 -137.901791)
			(xy 114.883363 -137.894037) (xy 114.910616 -137.893552) (xy 114.93829 -137.894058) (xy 114.993059 -137.902052)
			(xy 115.046094 -137.917884) (xy 115.096283 -137.94122) (xy 115.142567 -137.971571) (xy 115.1636 -137.989564)
			(xy 115.170966 -137.996168) (xy 115.188746 -138.002518) (xy 115.278154 -137.999724) (xy 115.295934 -137.992104)
			(xy 115.302792 -137.985246) (xy 115.32441 -137.964521) (xy 115.372875 -137.929347) (xy 115.426241 -137.90218)
			(xy 115.483198 -137.883689) (xy 115.542344 -137.874327) (xy 115.572286 -137.87374) (xy 115.599541 -137.874169)
			(xy 115.653495 -137.881925) (xy 115.705797 -137.897281) (xy 115.75538 -137.919926) (xy 115.801236 -137.949397)
			(xy 115.84243 -137.985094) (xy 115.878124 -138.026292) (xy 115.90759 -138.07215) (xy 115.93023 -138.121735)
			(xy 115.945582 -138.174038) (xy 115.953334 -138.227993) (xy 115.953794 -138.255248) (xy 115.953301 -138.283988)
			(xy 115.944671 -138.340817) (xy 115.927614 -138.395708) (xy 115.902516 -138.447419) (xy 115.869944 -138.49478)
			(xy 115.85067 -138.516106) (xy 115.844066 -138.522964) (xy 115.836954 -138.540998) (xy 115.836954 -138.629898)
			(xy 115.844066 -138.647932) (xy 115.85067 -138.65479) (xy 115.869965 -138.676096) (xy 115.902527 -138.723464)
			(xy 115.927615 -138.775181) (xy 115.94466 -138.830076) (xy 115.953277 -138.886908) (xy 115.953794 -138.915648)
			(xy 115.95336 -138.941963) (xy 115.946119 -138.994093) (xy 115.931793 -139.044737) (xy 115.910655 -139.092936)
			(xy 115.883102 -139.137778) (xy 115.849658 -139.178416) (xy 115.830604 -139.196572) (xy 115.823213 -139.204103)
			(xy 115.814683 -139.223376) (xy 115.814094 -139.23391) (xy 115.814094 -139.308586) (xy 115.814619 -139.319136)
			(xy 115.823157 -139.338431) (xy 115.830604 -139.345924) (xy 115.849665 -139.364074) (xy 115.883121 -139.404705)
			(xy 115.91068 -139.449547) (xy 115.931817 -139.497748) (xy 115.946133 -139.548397) (xy 115.953356 -139.600532)
			(xy 115.953794 -139.626848) (xy 115.953301 -139.655588) (xy 115.944671 -139.712417) (xy 115.927614 -139.767308)
			(xy 115.902516 -139.819019) (xy 115.869944 -139.86638) (xy 115.85067 -139.887706) (xy 115.844066 -139.894564)
			(xy 115.836954 -139.912598) (xy 115.836954 -140.001498) (xy 115.844066 -140.019532) (xy 115.85067 -140.02639)
			(xy 115.869989 -140.047675) (xy 115.902553 -140.095045) (xy 115.927642 -140.146763) (xy 115.944689 -140.20166)
			(xy 115.953307 -140.258494) (xy 115.953302 -140.315976) (xy 115.944673 -140.372808) (xy 115.927616 -140.427702)
			(xy 115.902518 -140.479416) (xy 115.869945 -140.526779) (xy 115.85067 -140.548106) (xy 115.844066 -140.554964)
			(xy 115.836954 -140.572998) (xy 115.836954 -140.661898) (xy 115.844066 -140.679932) (xy 115.85067 -140.68679)
			(xy 115.869965 -140.708096) (xy 115.902527 -140.755464) (xy 115.927615 -140.807181) (xy 115.94466 -140.862076)
			(xy 115.953277 -140.918908) (xy 115.953794 -140.947648) (xy 115.953367 -140.974901) (xy 115.945603 -141.028852)
			(xy 115.930241 -141.081148) (xy 115.907594 -141.130727) (xy 115.878121 -141.176577) (xy 115.842424 -141.217767)
			(xy 115.801228 -141.253458) (xy 115.755372 -141.282923) (xy 115.70579 -141.305563) (xy 115.653491 -141.320917)
			(xy 115.599539 -141.328671) (xy 115.572286 -141.329156) (xy 115.544612 -141.328647) (xy 115.489844 -141.320653)
			(xy 115.436808 -141.304822) (xy 115.38662 -141.281486) (xy 115.340335 -141.251136) (xy 115.319302 -141.233144)
			(xy 115.311936 -141.22654) (xy 115.294156 -141.22019) (xy 115.204748 -141.222984) (xy 115.186968 -141.230604)
			(xy 115.18011 -141.237462) (xy 115.158536 -141.258235) (xy 115.11006 -141.293403) (xy 115.056682 -141.32056)
			(xy 114.999716 -141.33904) (xy 114.940561 -141.348388) (xy 114.910616 -141.348968) (xy 114.883362 -141.34853)
			(xy 114.829408 -141.340774) (xy 114.777107 -141.325418) (xy 114.727524 -141.302774) (xy 114.681669 -141.273304)
			(xy 114.640475 -141.237608) (xy 114.604781 -141.196412) (xy 114.575314 -141.150555) (xy 114.552674 -141.10097)
			(xy 114.537321 -141.048669) (xy 114.529569 -140.994714) (xy 114.529108 -140.96746) (xy 112.90406 -140.96746)
			(xy 112.904524 -140.99286) (xy 112.904038 -141.020111) (xy 112.896282 -141.074059) (xy 112.880927 -141.126354)
			(xy 112.858285 -141.175931) (xy 112.828819 -141.221781) (xy 112.793128 -141.262972) (xy 112.751937 -141.298663)
			(xy 112.706087 -141.328129) (xy 112.65651 -141.350771) (xy 112.604215 -141.366126) (xy 112.550267 -141.373882)
			(xy 112.495765 -141.373882) (xy 112.441817 -141.366126) (xy 112.389522 -141.350771) (xy 112.339945 -141.328129)
			(xy 112.294095 -141.298663) (xy 112.252904 -141.262972) (xy 112.217213 -141.221781) (xy 112.187747 -141.175931)
			(xy 112.165105 -141.126354) (xy 112.14975 -141.074059) (xy 112.141994 -141.020111) (xy 112.141508 -140.99286)
			(xy 112.142005 -140.96412) (xy 112.150634 -140.907291) (xy 112.16769 -140.8524) (xy 112.192788 -140.800689)
			(xy 112.225359 -140.753328) (xy 112.244632 -140.732002) (xy 112.251236 -140.725144) (xy 112.258348 -140.70711)
			(xy 112.258348 -140.61821) (xy 112.251236 -140.600176) (xy 112.244632 -140.593318) (xy 112.225321 -140.572026)
			(xy 112.192757 -140.524658) (xy 112.167667 -140.47294) (xy 112.150619 -140.418044) (xy 112.142 -140.361212)
			(xy 112.142005 -140.30373) (xy 112.150632 -140.246899) (xy 112.167688 -140.192005) (xy 112.192786 -140.140292)
			(xy 112.225358 -140.092929) (xy 112.244632 -140.071602) (xy 112.251236 -140.064744) (xy 112.258348 -140.04671)
			(xy 112.258348 -139.95781) (xy 112.251236 -139.939776) (xy 112.244632 -139.932918) (xy 112.225341 -139.911608)
			(xy 112.192778 -139.864241) (xy 112.167689 -139.812525) (xy 112.150644 -139.757631) (xy 112.142026 -139.7008)
			(xy 112.141508 -139.67206) (xy 112.141965 -139.646593) (xy 112.148764 -139.596114) (xy 112.162221 -139.546989)
			(xy 112.182098 -139.500093) (xy 112.20804 -139.456259) (xy 112.239586 -139.41627) (xy 112.257586 -139.398248)
			(xy 112.265156 -139.390147) (xy 112.273059 -139.369456) (xy 112.272826 -139.35837) (xy 112.267238 -139.2809)
			(xy 112.265962 -139.269842) (xy 112.255296 -139.250335) (xy 112.246664 -139.243308) (xy 112.222945 -139.225168)
			(xy 112.18089 -139.182783) (xy 112.145944 -139.134369) (xy 112.118958 -139.081107) (xy 112.100591 -139.024294)
			(xy 112.091289 -138.965314) (xy 112.090708 -138.93546) (xy 109.953044 -138.93546) (xy 109.952518 -138.964377)
			(xy 109.943794 -139.021549) (xy 109.926539 -139.076748) (xy 109.901149 -139.128711) (xy 109.868205 -139.176245)
			(xy 109.828464 -139.218261) (xy 109.805978 -139.23645) (xy 109.7972 -139.244085) (xy 109.787001 -139.264965)
			(xy 109.78642 -139.276582) (xy 109.78642 -139.356338) (xy 109.786945 -139.367972) (xy 109.797143 -139.388882)
			(xy 109.805978 -139.39647) (xy 109.828443 -139.414684) (xy 109.86818 -139.456698) (xy 109.901122 -139.504228)
			(xy 109.926514 -139.556185) (xy 109.943774 -139.611379) (xy 109.952507 -139.668545) (xy 109.953044 -139.69746)
			(xy 109.952545 -139.7262) (xy 109.943915 -139.783028) (xy 109.926858 -139.837918) (xy 109.901761 -139.889629)
			(xy 109.869192 -139.936991) (xy 109.84992 -139.958318) (xy 109.843316 -139.965176) (xy 109.836204 -139.98321)
			(xy 109.836204 -140.07211) (xy 109.843316 -140.090144) (xy 109.84992 -140.097002) (xy 109.869149 -140.118364)
			(xy 109.901712 -140.165722) (xy 109.926803 -140.217428) (xy 109.943854 -140.272313) (xy 109.952479 -140.329135)
			(xy 109.952483 -140.386607) (xy 109.943867 -140.44343) (xy 109.926824 -140.498318) (xy 109.901741 -140.550028)
			(xy 109.869186 -140.59739) (xy 109.84992 -140.618718) (xy 109.843316 -140.625576) (xy 109.836204 -140.64361)
			(xy 109.836204 -140.73251) (xy 109.843316 -140.750544) (xy 109.84992 -140.757402) (xy 109.869165 -140.778752)
			(xy 109.901736 -140.826107) (xy 109.926834 -140.877813) (xy 109.943891 -140.932699) (xy 109.95252 -140.989522)
			(xy 109.953044 -141.01826) (xy 109.952508 -141.04551) (xy 109.944757 -141.099457) (xy 109.929408 -141.151751)
			(xy 109.906773 -141.201329) (xy 109.877312 -141.24718) (xy 109.841626 -141.288372) (xy 109.800441 -141.324067)
			(xy 109.754595 -141.353536) (xy 109.705022 -141.376181) (xy 109.652731 -141.391541) (xy 109.598786 -141.399302)
			(xy 109.571536 -141.399768) (xy 109.542202 -141.399213) (xy 109.484222 -141.390248) (xy 109.4283 -141.372509)
			(xy 109.375755 -141.346415) (xy 109.327825 -141.312581) (xy 109.30636 -141.29258) (xy 109.298994 -141.285468)
			(xy 109.281214 -141.278356) (xy 109.190282 -141.278356) (xy 109.172502 -141.285468) (xy 109.165136 -141.29258)
			(xy 109.143652 -141.312559) (xy 109.095723 -141.34639) (xy 109.043182 -141.372489) (xy 108.987266 -141.39024)
			(xy 108.929293 -141.399226) (xy 108.89996 -141.399768) (xy 108.872706 -141.399359) (xy 108.818753 -141.391596)
			(xy 108.766455 -141.376234) (xy 108.716875 -141.353585) (xy 108.671023 -141.324111) (xy 108.629832 -141.288412)
			(xy 108.594141 -141.247213) (xy 108.564676 -141.201355) (xy 108.542038 -141.15177) (xy 108.526687 -141.099468)
			(xy 108.518935 -141.045514) (xy 108.518452 -141.01826) (xy 106.893868 -141.01826) (xy 106.893382 -141.045511)
			(xy 106.885626 -141.099459) (xy 106.870271 -141.151754) (xy 106.847629 -141.201331) (xy 106.818163 -141.247181)
			(xy 106.782472 -141.288372) (xy 106.741281 -141.324063) (xy 106.695431 -141.353529) (xy 106.645854 -141.376171)
			(xy 106.593559 -141.391526) (xy 106.539611 -141.399282) (xy 106.485109 -141.399282) (xy 106.431161 -141.391526)
			(xy 106.378866 -141.376171) (xy 106.329289 -141.353529) (xy 106.283439 -141.324063) (xy 106.242248 -141.288372)
			(xy 106.206557 -141.247181) (xy 106.177091 -141.201331) (xy 106.154449 -141.151754) (xy 106.139094 -141.099459)
			(xy 106.131338 -141.045511) (xy 106.130852 -141.01826) (xy 106.131364 -140.989521) (xy 106.139992 -140.932694)
			(xy 106.157045 -140.877803) (xy 106.182139 -140.826092) (xy 106.214705 -140.778729) (xy 106.233976 -140.757402)
			(xy 106.24058 -140.750544) (xy 106.247692 -140.73251) (xy 106.247692 -140.64361) (xy 106.24058 -140.625576)
			(xy 106.233976 -140.618718) (xy 106.214668 -140.597425) (xy 106.182108 -140.550055) (xy 106.157022 -140.498337)
			(xy 106.139977 -140.443442) (xy 106.131359 -140.386611) (xy 106.131363 -140.329131) (xy 106.13999 -140.272301)
			(xy 106.157043 -140.217408) (xy 106.182137 -140.165694) (xy 106.214704 -140.11833) (xy 106.233976 -140.097002)
			(xy 106.24058 -140.090144) (xy 106.247692 -140.07211) (xy 106.247692 -139.98321) (xy 106.24058 -139.965176)
			(xy 106.233976 -139.958318) (xy 106.214693 -139.937002) (xy 106.182127 -139.889638) (xy 106.157036 -139.837923)
			(xy 106.139988 -139.78303) (xy 106.13137 -139.7262) (xy 106.130852 -139.69746) (xy 106.13131 -139.671555)
			(xy 106.138325 -139.620221) (xy 106.152221 -139.570309) (xy 106.172741 -139.522735) (xy 106.199509 -139.478375)
			(xy 106.215434 -139.457938) (xy 106.221153 -139.450166) (xy 106.226912 -139.431767) (xy 106.22661 -139.422124)
			(xy 106.221022 -139.352528) (xy 106.21992 -139.343099) (xy 106.211695 -139.326005) (xy 106.20502 -139.319254)
			(xy 106.204512 -139.318746) (xy 106.185276 -139.300619) (xy 106.151515 -139.259951) (xy 106.123689 -139.215013)
			(xy 106.102331 -139.166665) (xy 106.087848 -139.115832) (xy 106.080519 -139.063487) (xy 106.080052 -139.03706)
			(xy 84.08924 -139.03706) (xy 84.08924 -139.133072) (xy 84.088767 -139.15916) (xy 84.080602 -139.210693)
			(xy 84.064468 -139.260312) (xy 84.040763 -139.306793) (xy 84.010073 -139.348989) (xy 83.991958 -139.367768)
			(xy 83.550506 -139.80922) (xy 83.546394 -139.813617) (xy 83.540106 -139.823879) (xy 83.53806 -139.82954)
			(xy 83.53806 -139.830048) (xy 83.529587 -139.855583) (xy 83.506519 -139.904186) (xy 83.476853 -139.949067)
			(xy 83.441175 -139.989335) (xy 83.400194 -140.024191) (xy 83.358155 -140.050774) (xy 85.235794 -140.050774)
			(xy 85.239865 -139.995152) (xy 85.251991 -139.940715) (xy 85.271914 -139.888624) (xy 85.29921 -139.839989)
			(xy 85.333296 -139.795846) (xy 85.373445 -139.757137) (xy 85.418803 -139.724686) (xy 85.468403 -139.699185)
			(xy 85.521187 -139.681178) (xy 85.57603 -139.671048) (xy 85.631764 -139.669011) (xy 85.687201 -139.675111)
			(xy 85.741158 -139.689217) (xy 85.792487 -139.711029) (xy 85.840093 -139.740083) (xy 85.882961 -139.775758)
			(xy 85.920178 -139.817295) (xy 85.950951 -139.863808) (xy 85.974623 -139.914305) (xy 85.990691 -139.967712)
			(xy 85.998811 -140.022888) (xy 85.99932 -140.050774) (xy 85.998811 -140.07866) (xy 85.990691 -140.133836)
			(xy 85.974623 -140.187243) (xy 85.950951 -140.23774) (xy 85.920178 -140.284253) (xy 85.882961 -140.32579)
			(xy 85.840093 -140.361465) (xy 85.792487 -140.390519) (xy 85.741158 -140.412331) (xy 85.687201 -140.426437)
			(xy 85.631764 -140.432537) (xy 85.57603 -140.4305) (xy 85.521187 -140.42037) (xy 85.468403 -140.402363)
			(xy 85.418803 -140.376862) (xy 85.373445 -140.344411) (xy 85.333296 -140.305702) (xy 85.29921 -140.261559)
			(xy 85.271914 -140.212924) (xy 85.251991 -140.160833) (xy 85.239865 -140.106396) (xy 85.235794 -140.050774)
			(xy 83.358155 -140.050774) (xy 83.354723 -140.052944) (xy 83.305664 -140.075025) (xy 83.253989 -140.089994)
			(xy 83.200724 -140.097556) (xy 83.173824 -140.098018) (xy 83.146572 -140.097522) (xy 83.092623 -140.089769)
			(xy 83.040326 -140.074416) (xy 82.990747 -140.051777) (xy 82.944894 -140.022313) (xy 82.903701 -139.986623)
			(xy 82.868007 -139.945433) (xy 82.838539 -139.899583) (xy 82.815895 -139.850006) (xy 82.800538 -139.79771)
			(xy 82.79278 -139.743762) (xy 82.792316 -139.71651) (xy 80.700032 -139.71651) (xy 80.690545 -140.534898)
			(xy 81.097372 -140.534898) (xy 81.101443 -140.479276) (xy 81.113569 -140.424839) (xy 81.133492 -140.372748)
			(xy 81.160788 -140.324113) (xy 81.194874 -140.27997) (xy 81.235023 -140.241261) (xy 81.280381 -140.20881)
			(xy 81.329981 -140.183309) (xy 81.382765 -140.165302) (xy 81.437608 -140.155172) (xy 81.493342 -140.153135)
			(xy 81.548779 -140.159235) (xy 81.602736 -140.173341) (xy 81.654065 -140.195153) (xy 81.701671 -140.224207)
			(xy 81.744539 -140.259882) (xy 81.781756 -140.301419) (xy 81.812529 -140.347932) (xy 81.836201 -140.398429)
			(xy 81.852269 -140.451836) (xy 81.860389 -140.507012) (xy 81.860898 -140.534898) (xy 81.860389 -140.562784)
			(xy 81.852269 -140.61796) (xy 81.836201 -140.671367) (xy 81.812529 -140.721864) (xy 81.781756 -140.768377)
			(xy 81.744539 -140.809914) (xy 81.701671 -140.845589) (xy 81.654065 -140.874643) (xy 81.602736 -140.896455)
			(xy 81.548779 -140.910561) (xy 81.493342 -140.916661) (xy 81.437608 -140.914624) (xy 81.382765 -140.904494)
			(xy 81.329981 -140.886487) (xy 81.280381 -140.860986) (xy 81.235023 -140.828535) (xy 81.194874 -140.789826)
			(xy 81.160788 -140.745683) (xy 81.133492 -140.697048) (xy 81.113569 -140.644957) (xy 81.101443 -140.59052)
			(xy 81.097372 -140.534898) (xy 80.690545 -140.534898) (xy 80.656412 -143.479266) (xy 81.07426 -143.479266)
			(xy 81.07426 -142.615666) (xy 81.07475 -142.585682) (xy 81.082578 -142.526226) (xy 81.098099 -142.468301)
			(xy 81.121048 -142.412897) (xy 81.151032 -142.360963) (xy 81.187538 -142.313387) (xy 81.229943 -142.270982)
			(xy 81.277519 -142.234476) (xy 81.329453 -142.204492) (xy 81.384857 -142.181543) (xy 81.442782 -142.166022)
			(xy 81.502238 -142.158194) (xy 81.562206 -142.158194) (xy 81.621662 -142.166022) (xy 81.679587 -142.181543)
			(xy 81.734991 -142.204492) (xy 81.786925 -142.234476) (xy 81.834501 -142.270982) (xy 81.876906 -142.313387)
			(xy 81.913412 -142.360963) (xy 81.943396 -142.412897) (xy 81.966345 -142.468301) (xy 81.981866 -142.526226)
			(xy 81.989694 -142.585682) (xy 81.990184 -142.615666) (xy 81.990184 -143.479266) (xy 81.989694 -143.50925)
			(xy 81.981866 -143.568706) (xy 81.966345 -143.626631) (xy 81.943396 -143.682035) (xy 81.913412 -143.733969)
			(xy 81.876906 -143.781545) (xy 81.834501 -143.82395) (xy 81.786925 -143.860456) (xy 81.734991 -143.89044)
			(xy 81.679587 -143.913389) (xy 81.621662 -143.92891) (xy 81.562206 -143.936738) (xy 81.502238 -143.936738)
			(xy 81.442782 -143.92891) (xy 81.384857 -143.913389) (xy 81.329453 -143.89044) (xy 81.277519 -143.860456)
			(xy 81.229943 -143.82395) (xy 81.187538 -143.781545) (xy 81.151032 -143.733969) (xy 81.121048 -143.682035)
			(xy 81.098099 -143.626631) (xy 81.082578 -143.568706) (xy 81.07475 -143.50925) (xy 81.07426 -143.479266)
			(xy 80.656412 -143.479266) (xy 80.649572 -144.069308) (xy 80.648891 -144.103028) (xy 80.643552 -144.170269)
			(xy 80.638904 -144.203674) (xy 80.638904 -144.203928) (xy 80.499539 -145.285714) (xy 83.716368 -145.285714)
			(xy 83.716368 -144.422114) (xy 83.716858 -144.39213) (xy 83.724686 -144.332674) (xy 83.740207 -144.274749)
			(xy 83.763156 -144.219345) (xy 83.79314 -144.167411) (xy 83.829646 -144.119835) (xy 83.872051 -144.07743)
			(xy 83.919627 -144.040924) (xy 83.971561 -144.01094) (xy 84.026965 -143.987991) (xy 84.08489 -143.97247)
			(xy 84.144346 -143.964642) (xy 84.204314 -143.964642) (xy 84.26377 -143.97247) (xy 84.321695 -143.987991)
			(xy 84.377099 -144.01094) (xy 84.429033 -144.040924) (xy 84.476609 -144.07743) (xy 84.519014 -144.119835)
			(xy 84.55552 -144.167411) (xy 84.585504 -144.219345) (xy 84.608453 -144.274749) (xy 84.623974 -144.332674)
			(xy 84.631802 -144.39213) (xy 84.632292 -144.422114) (xy 84.632292 -145.285714) (xy 84.631802 -145.315698)
			(xy 84.623974 -145.375154) (xy 84.608453 -145.433079) (xy 84.585504 -145.488483) (xy 84.55552 -145.540417)
			(xy 84.519014 -145.587993) (xy 84.476609 -145.630398) (xy 84.429033 -145.666904) (xy 84.377099 -145.696888)
			(xy 84.321695 -145.719837) (xy 84.26377 -145.735358) (xy 84.204314 -145.743186) (xy 84.144346 -145.743186)
			(xy 84.08489 -145.735358) (xy 84.026965 -145.719837) (xy 83.971561 -145.696888) (xy 83.919627 -145.666904)
			(xy 83.872051 -145.630398) (xy 83.829646 -145.587993) (xy 83.79314 -145.540417) (xy 83.763156 -145.488483)
			(xy 83.740207 -145.433079) (xy 83.724686 -145.375154) (xy 83.716858 -145.315698) (xy 83.716368 -145.285714)
			(xy 80.499539 -145.285714) (xy 80.268486 -147.079208) (xy 81.07426 -147.079208) (xy 81.07426 -146.215608)
			(xy 81.07475 -146.185624) (xy 81.082578 -146.126168) (xy 81.098099 -146.068243) (xy 81.121048 -146.012839)
			(xy 81.151032 -145.960905) (xy 81.187538 -145.913329) (xy 81.229943 -145.870924) (xy 81.277519 -145.834418)
			(xy 81.329453 -145.804434) (xy 81.384857 -145.781485) (xy 81.442782 -145.765964) (xy 81.502238 -145.758136)
			(xy 81.562206 -145.758136) (xy 81.621662 -145.765964) (xy 81.679587 -145.781485) (xy 81.734991 -145.804434)
			(xy 81.786925 -145.834418) (xy 81.834501 -145.870924) (xy 81.876906 -145.913329) (xy 81.913412 -145.960905)
			(xy 81.943396 -146.012839) (xy 81.966345 -146.068243) (xy 81.981866 -146.126168) (xy 81.989694 -146.185624)
			(xy 81.990184 -146.215608) (xy 81.990184 -147.079208) (xy 81.989694 -147.109192) (xy 81.981866 -147.168648)
			(xy 81.966345 -147.226573) (xy 81.943396 -147.281977) (xy 81.913412 -147.333911) (xy 81.876906 -147.381487)
			(xy 81.834501 -147.423892) (xy 81.786925 -147.460398) (xy 81.734991 -147.490382) (xy 81.679587 -147.513331)
			(xy 81.621662 -147.528852) (xy 81.562206 -147.53668) (xy 81.502238 -147.53668) (xy 81.442782 -147.528852)
			(xy 81.384857 -147.513331) (xy 81.329453 -147.490382) (xy 81.277519 -147.460398) (xy 81.229943 -147.423892)
			(xy 81.187538 -147.381487) (xy 81.151032 -147.333911) (xy 81.121048 -147.281977) (xy 81.098099 -147.226573)
			(xy 81.082578 -147.168648) (xy 81.07475 -147.109192) (xy 81.07426 -147.079208) (xy 80.268486 -147.079208)
			(xy 80.035732 -148.88591) (xy 83.716368 -148.88591) (xy 83.716368 -148.02231) (xy 83.716858 -147.992326)
			(xy 83.724686 -147.93287) (xy 83.740207 -147.874945) (xy 83.763156 -147.819541) (xy 83.79314 -147.767607)
			(xy 83.829646 -147.720031) (xy 83.872051 -147.677626) (xy 83.919627 -147.64112) (xy 83.971561 -147.611136)
			(xy 84.026965 -147.588187) (xy 84.08489 -147.572666) (xy 84.144346 -147.564838) (xy 84.204314 -147.564838)
			(xy 84.26377 -147.572666) (xy 84.321695 -147.588187) (xy 84.377099 -147.611136) (xy 84.429033 -147.64112)
			(xy 84.476609 -147.677626) (xy 84.519014 -147.720031) (xy 84.55552 -147.767607) (xy 84.585504 -147.819541)
			(xy 84.608453 -147.874945) (xy 84.623974 -147.93287) (xy 84.631802 -147.992326) (xy 84.632292 -148.02231)
			(xy 84.632292 -148.88591) (xy 84.631802 -148.915894) (xy 84.623974 -148.97535) (xy 84.608453 -149.033275)
			(xy 84.585504 -149.088679) (xy 84.55552 -149.140613) (xy 84.519014 -149.188189) (xy 84.476609 -149.230594)
			(xy 84.429033 -149.2671) (xy 84.377099 -149.297084) (xy 84.321695 -149.320033) (xy 84.26377 -149.335554)
			(xy 84.204314 -149.343382) (xy 84.144346 -149.343382) (xy 84.08489 -149.335554) (xy 84.026965 -149.320033)
			(xy 83.971561 -149.297084) (xy 83.919627 -149.2671) (xy 83.872051 -149.230594) (xy 83.829646 -149.188189)
			(xy 83.79314 -149.140613) (xy 83.763156 -149.088679) (xy 83.740207 -149.033275) (xy 83.724686 -148.97535)
			(xy 83.716858 -148.915894) (xy 83.716368 -148.88591) (xy 80.035732 -148.88591) (xy 79.804712 -150.67915)
			(xy 81.07426 -150.67915) (xy 81.07426 -149.81555) (xy 81.07475 -149.785566) (xy 81.082578 -149.72611)
			(xy 81.098099 -149.668185) (xy 81.121048 -149.612781) (xy 81.151032 -149.560847) (xy 81.187538 -149.513271)
			(xy 81.229943 -149.470866) (xy 81.277519 -149.43436) (xy 81.329453 -149.404376) (xy 81.384857 -149.381427)
			(xy 81.442782 -149.365906) (xy 81.502238 -149.358078) (xy 81.562206 -149.358078) (xy 81.621662 -149.365906)
			(xy 81.679587 -149.381427) (xy 81.734991 -149.404376) (xy 81.786925 -149.43436) (xy 81.834501 -149.470866)
			(xy 81.876906 -149.513271) (xy 81.913412 -149.560847) (xy 81.943396 -149.612781) (xy 81.966345 -149.668185)
			(xy 81.981866 -149.72611) (xy 81.989694 -149.785566) (xy 81.990184 -149.81555) (xy 81.990184 -150.67915)
			(xy 81.989694 -150.709134) (xy 81.981866 -150.76859) (xy 81.966345 -150.826515) (xy 81.943396 -150.881919)
			(xy 81.913412 -150.933853) (xy 81.876906 -150.981429) (xy 81.834501 -151.023834) (xy 81.786925 -151.06034)
			(xy 81.734991 -151.090324) (xy 81.679587 -151.113273) (xy 81.621662 -151.128794) (xy 81.562206 -151.136622)
			(xy 81.502238 -151.136622) (xy 81.442782 -151.128794) (xy 81.384857 -151.113273) (xy 81.329453 -151.090324)
			(xy 81.277519 -151.06034) (xy 81.229943 -151.023834) (xy 81.187538 -150.981429) (xy 81.151032 -150.933853)
			(xy 81.121048 -150.881919) (xy 81.098099 -150.826515) (xy 81.082578 -150.76859) (xy 81.07475 -150.709134)
			(xy 81.07426 -150.67915) (xy 79.804712 -150.67915) (xy 79.571958 -152.485852) (xy 83.716368 -152.485852)
			(xy 83.716368 -151.622252) (xy 83.716858 -151.592268) (xy 83.724686 -151.532812) (xy 83.740207 -151.474887)
			(xy 83.763156 -151.419483) (xy 83.79314 -151.367549) (xy 83.829646 -151.319973) (xy 83.872051 -151.277568)
			(xy 83.919627 -151.241062) (xy 83.971561 -151.211078) (xy 84.026965 -151.188129) (xy 84.08489 -151.172608)
			(xy 84.144346 -151.16478) (xy 84.204314 -151.16478) (xy 84.26377 -151.172608) (xy 84.321695 -151.188129)
			(xy 84.377099 -151.211078) (xy 84.429033 -151.241062) (xy 84.476609 -151.277568) (xy 84.519014 -151.319973)
			(xy 84.55552 -151.367549) (xy 84.585504 -151.419483) (xy 84.608453 -151.474887) (xy 84.623974 -151.532812)
			(xy 84.631802 -151.592268) (xy 84.632292 -151.622252) (xy 84.632292 -152.485852) (xy 84.631802 -152.515836)
			(xy 84.623974 -152.575292) (xy 84.608453 -152.633217) (xy 84.585504 -152.688621) (xy 84.55552 -152.740555)
			(xy 84.519014 -152.788131) (xy 84.476609 -152.830536) (xy 84.429033 -152.867042) (xy 84.377099 -152.897026)
			(xy 84.321695 -152.919975) (xy 84.26377 -152.935496) (xy 84.204314 -152.943324) (xy 84.144346 -152.943324)
			(xy 84.08489 -152.935496) (xy 84.026965 -152.919975) (xy 83.971561 -152.897026) (xy 83.919627 -152.867042)
			(xy 83.872051 -152.830536) (xy 83.829646 -152.788131) (xy 83.79314 -152.740555) (xy 83.763156 -152.688621)
			(xy 83.740207 -152.633217) (xy 83.724686 -152.575292) (xy 83.716858 -152.515836) (xy 83.716368 -152.485852)
			(xy 79.571958 -152.485852) (xy 79.340905 -154.279346) (xy 81.07426 -154.279346) (xy 81.07426 -153.415746)
			(xy 81.07475 -153.385762) (xy 81.082578 -153.326306) (xy 81.098099 -153.268381) (xy 81.121048 -153.212977)
			(xy 81.151032 -153.161043) (xy 81.187538 -153.113467) (xy 81.229943 -153.071062) (xy 81.277519 -153.034556)
			(xy 81.329453 -153.004572) (xy 81.384857 -152.981623) (xy 81.442782 -152.966102) (xy 81.502238 -152.958274)
			(xy 81.562206 -152.958274) (xy 81.621662 -152.966102) (xy 81.679587 -152.981623) (xy 81.734991 -153.004572)
			(xy 81.786925 -153.034556) (xy 81.834501 -153.071062) (xy 81.876906 -153.113467) (xy 81.913412 -153.161043)
			(xy 81.943396 -153.212977) (xy 81.966345 -153.268381) (xy 81.981866 -153.326306) (xy 81.989694 -153.385762)
			(xy 81.990184 -153.415746) (xy 81.990184 -154.279346) (xy 81.989694 -154.30933) (xy 81.981866 -154.368786)
			(xy 81.966345 -154.426711) (xy 81.943396 -154.482115) (xy 81.913412 -154.534049) (xy 81.876906 -154.581625)
			(xy 81.834501 -154.62403) (xy 81.786925 -154.660536) (xy 81.734991 -154.69052) (xy 81.679587 -154.713469)
			(xy 81.621662 -154.72899) (xy 81.562206 -154.736818) (xy 81.502238 -154.736818) (xy 81.442782 -154.72899)
			(xy 81.384857 -154.713469) (xy 81.329453 -154.69052) (xy 81.277519 -154.660536) (xy 81.229943 -154.62403)
			(xy 81.187538 -154.581625) (xy 81.151032 -154.534049) (xy 81.121048 -154.482115) (xy 81.098099 -154.426711)
			(xy 81.082578 -154.368786) (xy 81.07475 -154.30933) (xy 81.07426 -154.279346) (xy 79.340905 -154.279346)
			(xy 79.252064 -154.968956) (xy 79.24546 -155.012644) (xy 79.058566 -156.085794) (xy 83.716368 -156.085794)
			(xy 83.716368 -155.222194) (xy 83.716858 -155.19221) (xy 83.724686 -155.132754) (xy 83.740207 -155.074829)
			(xy 83.763156 -155.019425) (xy 83.79314 -154.967491) (xy 83.829646 -154.919915) (xy 83.872051 -154.87751)
			(xy 83.919627 -154.841004) (xy 83.971561 -154.81102) (xy 84.026965 -154.788071) (xy 84.08489 -154.77255)
			(xy 84.144346 -154.764722) (xy 84.204314 -154.764722) (xy 84.26377 -154.77255) (xy 84.321695 -154.788071)
			(xy 84.377099 -154.81102) (xy 84.429033 -154.841004) (xy 84.476609 -154.87751) (xy 84.519014 -154.919915)
			(xy 84.55552 -154.967491) (xy 84.585504 -155.019425) (xy 84.608453 -155.074829) (xy 84.623974 -155.132754)
			(xy 84.631802 -155.19221) (xy 84.632292 -155.222194) (xy 84.632292 -156.085794) (xy 84.631802 -156.115778)
			(xy 84.623974 -156.175234) (xy 84.608453 -156.233159) (xy 84.585504 -156.288563) (xy 84.55552 -156.340497)
			(xy 84.519014 -156.388073) (xy 84.476609 -156.430478) (xy 84.429033 -156.466984) (xy 84.377099 -156.496968)
			(xy 84.321695 -156.519917) (xy 84.26377 -156.535438) (xy 84.204314 -156.543266) (xy 84.144346 -156.543266)
			(xy 84.08489 -156.535438) (xy 84.026965 -156.519917) (xy 83.971561 -156.496968) (xy 83.919627 -156.466984)
			(xy 83.872051 -156.430478) (xy 83.829646 -156.388073) (xy 83.79314 -156.340497) (xy 83.763156 -156.288563)
			(xy 83.740207 -156.233159) (xy 83.724686 -156.175234) (xy 83.716858 -156.115778) (xy 83.716368 -156.085794)
			(xy 79.058566 -156.085794) (xy 78.686946 -158.219648) (xy 81.182208 -158.219648) (xy 81.186279 -158.164026)
			(xy 81.198405 -158.109589) (xy 81.218328 -158.057498) (xy 81.245624 -158.008863) (xy 81.27971 -157.96472)
			(xy 81.319859 -157.926011) (xy 81.365217 -157.89356) (xy 81.414817 -157.868059) (xy 81.467601 -157.850052)
			(xy 81.522444 -157.839922) (xy 81.578178 -157.837885) (xy 81.633615 -157.843985) (xy 81.687572 -157.858091)
			(xy 81.738901 -157.879903) (xy 81.786507 -157.908957) (xy 81.829375 -157.944632) (xy 81.866592 -157.986169)
			(xy 81.897365 -158.032682) (xy 81.921037 -158.083179) (xy 81.937105 -158.136586) (xy 81.945225 -158.191762)
			(xy 81.945734 -158.219648) (xy 81.945225 -158.247534) (xy 81.937105 -158.30271) (xy 81.921037 -158.356117)
			(xy 81.897365 -158.406614) (xy 81.866592 -158.453127) (xy 81.829375 -158.494664) (xy 81.786507 -158.530339)
			(xy 81.738901 -158.559393) (xy 81.687572 -158.581205) (xy 81.633615 -158.595311) (xy 81.578178 -158.601411)
			(xy 81.522444 -158.599374) (xy 81.467601 -158.589244) (xy 81.414817 -158.571237) (xy 81.365217 -158.545736)
			(xy 81.319859 -158.513285) (xy 81.27971 -158.474576) (xy 81.245624 -158.430433) (xy 81.218328 -158.381798)
			(xy 81.198405 -158.329707) (xy 81.186279 -158.27527) (xy 81.182208 -158.219648) (xy 78.686946 -158.219648)
			(xy 78.560168 -158.947612) (xy 107.304584 -158.947612) (xy 107.308655 -158.89199) (xy 107.320781 -158.837553)
			(xy 107.340704 -158.785462) (xy 107.368 -158.736827) (xy 107.402086 -158.692684) (xy 107.442235 -158.653975)
			(xy 107.487593 -158.621524) (xy 107.537193 -158.596023) (xy 107.589977 -158.578016) (xy 107.64482 -158.567886)
			(xy 107.700554 -158.565849) (xy 107.755991 -158.571949) (xy 107.809948 -158.586055) (xy 107.861277 -158.607867)
			(xy 107.908883 -158.636921) (xy 107.951751 -158.672596) (xy 107.988968 -158.714133) (xy 108.019741 -158.760646)
			(xy 108.043413 -158.811143) (xy 108.059481 -158.86455) (xy 108.067601 -158.919726) (xy 108.06811 -158.947612)
			(xy 108.067601 -158.975498) (xy 108.059481 -159.030674) (xy 108.043413 -159.084081) (xy 108.019741 -159.134578)
			(xy 107.988968 -159.181091) (xy 107.951751 -159.222628) (xy 107.908883 -159.258303) (xy 107.861277 -159.287357)
			(xy 107.809948 -159.309169) (xy 107.755991 -159.323275) (xy 107.700554 -159.329375) (xy 107.64482 -159.327338)
			(xy 107.589977 -159.317208) (xy 107.537193 -159.299201) (xy 107.487593 -159.2737) (xy 107.442235 -159.241249)
			(xy 107.402086 -159.20254) (xy 107.368 -159.158397) (xy 107.340704 -159.109762) (xy 107.320781 -159.057671)
			(xy 107.308655 -159.003234) (xy 107.304584 -158.947612) (xy 78.560168 -158.947612) (xy 78.432372 -159.681418)
			(xy 112.176558 -159.681418) (xy 112.180629 -159.625796) (xy 112.192755 -159.571359) (xy 112.212678 -159.519268)
			(xy 112.239974 -159.470633) (xy 112.27406 -159.42649) (xy 112.314209 -159.387781) (xy 112.359567 -159.35533)
			(xy 112.409167 -159.329829) (xy 112.461951 -159.311822) (xy 112.516794 -159.301692) (xy 112.572528 -159.299655)
			(xy 112.627965 -159.305755) (xy 112.681922 -159.319861) (xy 112.733251 -159.341673) (xy 112.780857 -159.370727)
			(xy 112.823725 -159.406402) (xy 112.860942 -159.447939) (xy 112.891715 -159.494452) (xy 112.915387 -159.544949)
			(xy 112.931455 -159.598356) (xy 112.939575 -159.653532) (xy 112.940084 -159.681418) (xy 112.939575 -159.709304)
			(xy 112.931455 -159.76448) (xy 112.915387 -159.817887) (xy 112.891715 -159.868384) (xy 112.860942 -159.914897)
			(xy 112.823725 -159.956434) (xy 112.780857 -159.992109) (xy 112.733251 -160.021163) (xy 112.681922 -160.042975)
			(xy 112.627965 -160.057081) (xy 112.572528 -160.063181) (xy 112.516794 -160.061144) (xy 112.461951 -160.051014)
			(xy 112.409167 -160.033007) (xy 112.359567 -160.007506) (xy 112.314209 -159.975055) (xy 112.27406 -159.936346)
			(xy 112.239974 -159.892203) (xy 112.212678 -159.843568) (xy 112.192755 -159.791477) (xy 112.180629 -159.73704)
			(xy 112.176558 -159.681418) (xy 78.432372 -159.681418) (xy 78.338505 -160.220406) (xy 113.389916 -160.220406)
			(xy 113.393987 -160.164784) (xy 113.406113 -160.110347) (xy 113.426036 -160.058256) (xy 113.453332 -160.009621)
			(xy 113.487418 -159.965478) (xy 113.527567 -159.926769) (xy 113.572925 -159.894318) (xy 113.622525 -159.868817)
			(xy 113.675309 -159.85081) (xy 113.730152 -159.84068) (xy 113.785886 -159.838643) (xy 113.841323 -159.844743)
			(xy 113.89528 -159.858849) (xy 113.946609 -159.880661) (xy 113.994215 -159.909715) (xy 114.037083 -159.94539)
			(xy 114.0743 -159.986927) (xy 114.105073 -160.03344) (xy 114.128745 -160.083937) (xy 114.144813 -160.137344)
			(xy 114.152933 -160.19252) (xy 114.153442 -160.220406) (xy 114.152933 -160.248292) (xy 114.144813 -160.303468)
			(xy 114.128745 -160.356875) (xy 114.105073 -160.407372) (xy 114.0743 -160.453885) (xy 114.058189 -160.471866)
			(xy 114.82019 -160.471866) (xy 114.824261 -160.416244) (xy 114.836387 -160.361807) (xy 114.85631 -160.309716)
			(xy 114.883606 -160.261081) (xy 114.917692 -160.216938) (xy 114.957841 -160.178229) (xy 115.003199 -160.145778)
			(xy 115.052799 -160.120277) (xy 115.105583 -160.10227) (xy 115.160426 -160.09214) (xy 115.21616 -160.090103)
			(xy 115.271597 -160.096203) (xy 115.325554 -160.110309) (xy 115.376883 -160.132121) (xy 115.424489 -160.161175)
			(xy 115.467357 -160.19685) (xy 115.504574 -160.238387) (xy 115.535347 -160.2849) (xy 115.559019 -160.335397)
			(xy 115.575087 -160.388804) (xy 115.583207 -160.44398) (xy 115.583716 -160.471866) (xy 115.583207 -160.499752)
			(xy 115.575087 -160.554928) (xy 115.559019 -160.608335) (xy 115.535347 -160.658832) (xy 115.504574 -160.705345)
			(xy 115.467357 -160.746882) (xy 115.424489 -160.782557) (xy 115.376883 -160.811611) (xy 115.325554 -160.833423)
			(xy 115.271597 -160.847529) (xy 115.21616 -160.853629) (xy 115.160426 -160.851592) (xy 115.105583 -160.841462)
			(xy 115.052799 -160.823455) (xy 115.003199 -160.797954) (xy 114.957841 -160.765503) (xy 114.917692 -160.726794)
			(xy 114.883606 -160.682651) (xy 114.85631 -160.634016) (xy 114.836387 -160.581925) (xy 114.824261 -160.527488)
			(xy 114.82019 -160.471866) (xy 114.058189 -160.471866) (xy 114.037083 -160.495422) (xy 113.994215 -160.531097)
			(xy 113.946609 -160.560151) (xy 113.89528 -160.581963) (xy 113.841323 -160.596069) (xy 113.785886 -160.602169)
			(xy 113.730152 -160.600132) (xy 113.675309 -160.590002) (xy 113.622525 -160.571995) (xy 113.572925 -160.546494)
			(xy 113.527567 -160.514043) (xy 113.487418 -160.475334) (xy 113.453332 -160.431191) (xy 113.426036 -160.382556)
			(xy 113.406113 -160.330465) (xy 113.393987 -160.276028) (xy 113.389916 -160.220406) (xy 78.338505 -160.220406)
			(xy 78.005679 -162.131502) (xy 111.67313 -162.131502) (xy 111.677201 -162.07588) (xy 111.689327 -162.021443)
			(xy 111.70925 -161.969352) (xy 111.736546 -161.920717) (xy 111.770632 -161.876574) (xy 111.810781 -161.837865)
			(xy 111.856139 -161.805414) (xy 111.905739 -161.779913) (xy 111.958523 -161.761906) (xy 112.013366 -161.751776)
			(xy 112.0691 -161.749739) (xy 112.124537 -161.755839) (xy 112.178494 -161.769945) (xy 112.229823 -161.791757)
			(xy 112.252954 -161.805874) (xy 113.226848 -161.805874) (xy 113.230919 -161.750252) (xy 113.243045 -161.695815)
			(xy 113.262968 -161.643724) (xy 113.290264 -161.595089) (xy 113.32435 -161.550946) (xy 113.364499 -161.512237)
			(xy 113.409857 -161.479786) (xy 113.459457 -161.454285) (xy 113.512241 -161.436278) (xy 113.567084 -161.426148)
			(xy 113.622818 -161.424111) (xy 113.678255 -161.430211) (xy 113.732212 -161.444317) (xy 113.783541 -161.466129)
			(xy 113.831147 -161.495183) (xy 113.874015 -161.530858) (xy 113.911232 -161.572395) (xy 113.942005 -161.618908)
			(xy 113.965677 -161.669405) (xy 113.981745 -161.722812) (xy 113.989865 -161.777988) (xy 113.990374 -161.805874)
			(xy 113.989865 -161.83376) (xy 113.981745 -161.888936) (xy 113.965677 -161.942343) (xy 113.942005 -161.99284)
			(xy 113.911232 -162.039353) (xy 113.874015 -162.08089) (xy 113.831147 -162.116565) (xy 113.783541 -162.145619)
			(xy 113.732212 -162.167431) (xy 113.678255 -162.181537) (xy 113.622818 -162.187637) (xy 113.567084 -162.1856)
			(xy 113.512241 -162.17547) (xy 113.459457 -162.157463) (xy 113.409857 -162.131962) (xy 113.364499 -162.099511)
			(xy 113.32435 -162.060802) (xy 113.290264 -162.016659) (xy 113.262968 -161.968024) (xy 113.243045 -161.915933)
			(xy 113.230919 -161.861496) (xy 113.226848 -161.805874) (xy 112.252954 -161.805874) (xy 112.277429 -161.820811)
			(xy 112.320297 -161.856486) (xy 112.357514 -161.898023) (xy 112.388287 -161.944536) (xy 112.411959 -161.995033)
			(xy 112.428027 -162.04844) (xy 112.436147 -162.103616) (xy 112.436656 -162.131502) (xy 112.436147 -162.159388)
			(xy 112.428027 -162.214564) (xy 112.411959 -162.267971) (xy 112.388287 -162.318468) (xy 112.357514 -162.364981)
			(xy 112.320297 -162.406518) (xy 112.277429 -162.442193) (xy 112.229823 -162.471247) (xy 112.178494 -162.493059)
			(xy 112.124537 -162.507165) (xy 112.0691 -162.513265) (xy 112.013366 -162.511228) (xy 111.958523 -162.501098)
			(xy 111.905739 -162.483091) (xy 111.856139 -162.45759) (xy 111.810781 -162.425139) (xy 111.770632 -162.38643)
			(xy 111.736546 -162.342287) (xy 111.70925 -162.293652) (xy 111.689327 -162.241561) (xy 111.677201 -162.187124)
			(xy 111.67313 -162.131502) (xy 78.005679 -162.131502) (xy 77.782424 -163.41344) (xy 113.15268 -163.41344)
			(xy 113.156751 -163.357818) (xy 113.168877 -163.303381) (xy 113.1888 -163.25129) (xy 113.216096 -163.202655)
			(xy 113.250182 -163.158512) (xy 113.290331 -163.119803) (xy 113.335689 -163.087352) (xy 113.385289 -163.061851)
			(xy 113.438073 -163.043844) (xy 113.492916 -163.033714) (xy 113.54865 -163.031677) (xy 113.604087 -163.037777)
			(xy 113.658044 -163.051883) (xy 113.709373 -163.073695) (xy 113.756979 -163.102749) (xy 113.799847 -163.138424)
			(xy 113.837064 -163.179961) (xy 113.867837 -163.226474) (xy 113.891509 -163.276971) (xy 113.907577 -163.330378)
			(xy 113.915697 -163.385554) (xy 113.916206 -163.41344) (xy 113.915697 -163.441326) (xy 113.907577 -163.496502)
			(xy 113.891509 -163.549909) (xy 113.867837 -163.600406) (xy 113.837064 -163.646919) (xy 113.799847 -163.688456)
			(xy 113.756979 -163.724131) (xy 113.709373 -163.753185) (xy 113.658044 -163.774997) (xy 113.604087 -163.789103)
			(xy 113.54865 -163.795203) (xy 113.492916 -163.793166) (xy 113.438073 -163.783036) (xy 113.385289 -163.765029)
			(xy 113.335689 -163.739528) (xy 113.290331 -163.707077) (xy 113.250182 -163.668368) (xy 113.216096 -163.624225)
			(xy 113.1888 -163.57559) (xy 113.168877 -163.523499) (xy 113.156751 -163.469062) (xy 113.15268 -163.41344)
			(xy 77.782424 -163.41344) (xy 74.813696 -180.459953) (xy 91.824765 -180.459953) (xy 91.824765 -180.405447)
			(xy 91.832522 -180.351497) (xy 91.847879 -180.2992) (xy 91.870521 -180.24962) (xy 91.899989 -180.203768)
			(xy 91.935683 -180.162576) (xy 91.976876 -180.126883) (xy 92.022729 -180.097416) (xy 92.072309 -180.074775)
			(xy 92.124607 -180.05942) (xy 92.178557 -180.051665) (xy 92.20581 -180.051202) (xy 92.232634 -180.051673)
			(xy 92.285755 -180.059185) (xy 92.3373 -180.074059) (xy 92.386256 -180.096004) (xy 92.431657 -180.124586)
			(xy 92.47261 -180.159242) (xy 92.490798 -180.178964) (xy 92.49791 -180.187092) (xy 92.51823 -180.195982)
			(xy 92.61729 -180.194966) (xy 92.637102 -180.185568) (xy 92.644214 -180.177186) (xy 92.662401 -180.156397)
			(xy 92.703771 -180.119799) (xy 92.74999 -180.089556) (xy 92.800091 -180.066302) (xy 92.853024 -180.050522)
			(xy 92.907681 -180.042549) (xy 92.935298 -180.042058) (xy 92.962549 -180.042589) (xy 93.016495 -180.050345)
			(xy 93.068788 -180.0657) (xy 93.118364 -180.08834) (xy 93.164214 -180.117805) (xy 93.205403 -180.153496)
			(xy 93.241093 -180.194685) (xy 93.270559 -180.240534) (xy 93.2932 -180.29011) (xy 93.308554 -180.342403)
			(xy 93.316311 -180.396349) (xy 93.316311 -180.450851) (xy 93.308554 -180.504797) (xy 93.2932 -180.55709)
			(xy 93.270559 -180.606666) (xy 93.241093 -180.652515) (xy 93.205403 -180.693704) (xy 93.164214 -180.729395)
			(xy 93.118364 -180.75886) (xy 93.068788 -180.7815) (xy 93.016495 -180.796855) (xy 92.962549 -180.804611)
			(xy 92.935298 -180.805074) (xy 92.908473 -180.804606) (xy 92.855353 -180.797094) (xy 92.803807 -180.78222)
			(xy 92.754851 -180.760275) (xy 92.70945 -180.731692) (xy 92.668498 -180.697034) (xy 92.65031 -180.677312)
			(xy 92.643198 -180.669184) (xy 92.622878 -180.660294) (xy 92.523818 -180.66131) (xy 92.504006 -180.670708)
			(xy 92.496894 -180.67909) (xy 92.478698 -180.69987) (xy 92.43733 -180.73647) (xy 92.391113 -180.766715)
			(xy 92.341014 -180.789971) (xy 92.288082 -180.805752) (xy 92.233427 -180.813726) (xy 92.20581 -180.814218)
			(xy 92.178557 -180.813735) (xy 92.124607 -180.80598) (xy 92.072309 -180.790625) (xy 92.022729 -180.767984)
			(xy 91.976876 -180.738517) (xy 91.935683 -180.702824) (xy 91.899989 -180.661632) (xy 91.870521 -180.61578)
			(xy 91.847879 -180.5662) (xy 91.832522 -180.513903) (xy 91.824765 -180.459953) (xy 74.813696 -180.459953)
			(xy 74.730191 -180.93944) (xy 107.97667 -180.93944) (xy 107.977165 -180.9107) (xy 107.985796 -180.853872)
			(xy 108.002853 -180.798981) (xy 108.027951 -180.74727) (xy 108.060521 -180.699908) (xy 108.079794 -180.678582)
			(xy 108.086398 -180.671724) (xy 108.09351 -180.65369) (xy 108.09351 -180.56479) (xy 108.086398 -180.546756)
			(xy 108.079794 -180.539898) (xy 108.060552 -180.518546) (xy 108.02798 -180.471192) (xy 108.002881 -180.419487)
			(xy 107.985824 -180.364601) (xy 107.977195 -180.307777) (xy 107.97667 -180.27904) (xy 107.977192 -180.251789)
			(xy 107.984943 -180.197841) (xy 108.000293 -180.145546) (xy 108.022929 -180.095968) (xy 108.052391 -180.050115)
			(xy 108.088079 -180.008923) (xy 108.129266 -179.973228) (xy 108.175113 -179.943759) (xy 108.224688 -179.921115)
			(xy 108.276981 -179.905757) (xy 108.330927 -179.897997) (xy 108.358178 -179.897532) (xy 108.383547 -179.897949)
			(xy 108.433837 -179.904672) (xy 108.482791 -179.918002) (xy 108.529547 -179.937705) (xy 108.573278 -179.963431)
			(xy 108.613213 -179.994728) (xy 108.631228 -180.012594) (xy 108.638551 -180.019352) (xy 108.656844 -180.027202)
			(xy 108.666788 -180.027834) (xy 108.74883 -180.02885) (xy 108.767118 -180.021738) (xy 108.774484 -180.014626)
			(xy 108.795961 -179.994638) (xy 108.843891 -179.960808) (xy 108.896434 -179.934711) (xy 108.952352 -179.916962)
			(xy 109.010327 -179.907978) (xy 109.03966 -179.907438) (xy 109.06703 -179.907918) (xy 109.121209 -179.915731)
			(xy 109.173712 -179.931216) (xy 109.223459 -179.954055) (xy 109.269426 -179.983778) (xy 109.290358 -180.001418)
			(xy 109.290612 -180.001672) (xy 109.297685 -180.007278) (xy 109.314612 -180.013511) (xy 109.323632 -180.013864)
			(xy 109.390688 -180.013864) (xy 109.399705 -180.013509) (xy 109.416622 -180.007261) (xy 109.423708 -180.001672)
			(xy 109.423708 -180.001418) (xy 109.423962 -180.001418) (xy 109.444895 -179.983777) (xy 109.490863 -179.954053)
			(xy 109.540609 -179.931207) (xy 109.593111 -179.915711) (xy 109.647289 -179.907882) (xy 109.702031 -179.907882)
			(xy 109.756209 -179.915711) (xy 109.808711 -179.931207) (xy 109.858457 -179.954053) (xy 109.904425 -179.983777)
			(xy 109.925358 -180.001418) (xy 109.925612 -180.001672) (xy 109.932685 -180.007278) (xy 109.949612 -180.013511)
			(xy 109.958632 -180.013864) (xy 110.025688 -180.013864) (xy 110.034705 -180.013509) (xy 110.051622 -180.007261)
			(xy 110.058708 -180.001672) (xy 110.058708 -180.001418) (xy 110.058962 -180.001418) (xy 110.079895 -179.983777)
			(xy 110.125863 -179.954053) (xy 110.175609 -179.931207) (xy 110.228111 -179.915711) (xy 110.282289 -179.907882)
			(xy 110.337031 -179.907882) (xy 110.391209 -179.915711) (xy 110.443711 -179.931207) (xy 110.493457 -179.954053)
			(xy 110.539425 -179.983777) (xy 110.560358 -180.001418) (xy 110.560612 -180.001672) (xy 110.567685 -180.007278)
			(xy 110.584612 -180.013511) (xy 110.593632 -180.013864) (xy 110.660688 -180.013864) (xy 110.669705 -180.013509)
			(xy 110.686622 -180.007261) (xy 110.693708 -180.001672) (xy 110.693708 -180.001418) (xy 110.693962 -180.001418)
			(xy 110.714895 -179.983777) (xy 110.760863 -179.954053) (xy 110.810609 -179.931207) (xy 110.863111 -179.915711)
			(xy 110.917289 -179.907882) (xy 110.972031 -179.907882) (xy 111.026209 -179.915711) (xy 111.078711 -179.931207)
			(xy 111.128457 -179.954053) (xy 111.174425 -179.983777) (xy 111.195358 -180.001418) (xy 111.195612 -180.001672)
			(xy 111.202685 -180.007278) (xy 111.219612 -180.013511) (xy 111.228632 -180.013864) (xy 111.295688 -180.013864)
			(xy 111.304705 -180.013509) (xy 111.321622 -180.007261) (xy 111.328708 -180.001672) (xy 111.328708 -180.001418)
			(xy 111.328962 -180.001418) (xy 111.3499 -179.983786) (xy 111.395871 -179.954073) (xy 111.445617 -179.931235)
			(xy 111.498116 -179.915742) (xy 111.552291 -179.907913) (xy 111.57966 -179.907438) (xy 111.606914 -179.907893)
			(xy 111.660868 -179.915645) (xy 111.713168 -179.930999) (xy 111.762751 -179.95364) (xy 111.808607 -179.983108)
			(xy 111.849801 -180.018803) (xy 111.885496 -180.059998) (xy 111.914963 -180.105854) (xy 111.937603 -180.155437)
			(xy 111.952956 -180.207738) (xy 111.960708 -180.261692) (xy 111.961168 -180.288946) (xy 111.960654 -180.317685)
			(xy 111.952026 -180.374512) (xy 111.934973 -180.429402) (xy 111.90988 -180.481114) (xy 111.877314 -180.528477)
			(xy 111.858044 -180.549804) (xy 111.85144 -180.556662) (xy 111.844328 -180.574696) (xy 111.844328 -180.663596)
			(xy 111.85144 -180.68163) (xy 111.858044 -180.688488) (xy 111.877334 -180.709799) (xy 111.909898 -180.757165)
			(xy 111.934987 -180.808881) (xy 111.952033 -180.863775) (xy 111.96065 -180.920606) (xy 111.961168 -180.949346)
			(xy 111.960765 -180.9766) (xy 111.953001 -181.030553) (xy 111.937638 -181.082852) (xy 111.914989 -181.132432)
			(xy 111.885514 -181.178284) (xy 111.849814 -181.219475) (xy 111.808615 -181.255165) (xy 111.762756 -181.28463)
			(xy 111.713171 -181.307268) (xy 111.660869 -181.322619) (xy 111.606914 -181.330371) (xy 111.57966 -181.330854)
			(xy 111.552291 -181.330364) (xy 111.498112 -181.322554) (xy 111.445609 -181.307071) (xy 111.395861 -181.284234)
			(xy 111.349894 -181.254514) (xy 111.328962 -181.236874) (xy 111.328708 -181.23662) (xy 111.32163 -181.231021)
			(xy 111.304706 -181.224784) (xy 111.295688 -181.224428) (xy 111.228632 -181.224428) (xy 111.219616 -181.224794)
			(xy 111.202699 -181.231035) (xy 111.195612 -181.23662) (xy 111.195358 -181.236874) (xy 111.174425 -181.254515)
			(xy 111.128457 -181.284239) (xy 111.078711 -181.307085) (xy 111.026209 -181.322581) (xy 110.972031 -181.33041)
			(xy 110.917289 -181.33041) (xy 110.863111 -181.322581) (xy 110.810609 -181.307085) (xy 110.760863 -181.284239)
			(xy 110.714895 -181.254515) (xy 110.693962 -181.236874) (xy 110.693708 -181.23662) (xy 110.68663 -181.231021)
			(xy 110.669706 -181.224784) (xy 110.660688 -181.224428) (xy 110.593632 -181.224428) (xy 110.584616 -181.224794)
			(xy 110.567699 -181.231035) (xy 110.560612 -181.23662) (xy 110.560612 -181.236874) (xy 110.560358 -181.236874)
			(xy 110.539425 -181.254515) (xy 110.493457 -181.284239) (xy 110.443711 -181.307085) (xy 110.391209 -181.322581)
			(xy 110.337031 -181.33041) (xy 110.282289 -181.33041) (xy 110.228111 -181.322581) (xy 110.175609 -181.307085)
			(xy 110.125863 -181.284239) (xy 110.079895 -181.254515) (xy 110.058962 -181.236874) (xy 110.058708 -181.23662)
			(xy 110.05163 -181.231021) (xy 110.034706 -181.224784) (xy 110.025688 -181.224428) (xy 109.958632 -181.224428)
			(xy 109.949616 -181.224794) (xy 109.932699 -181.231035) (xy 109.925612 -181.23662) (xy 109.925612 -181.236874)
			(xy 109.925358 -181.236874) (xy 109.904425 -181.254515) (xy 109.858457 -181.284239) (xy 109.808711 -181.307085)
			(xy 109.756209 -181.322581) (xy 109.702031 -181.33041) (xy 109.647289 -181.33041) (xy 109.593111 -181.322581)
			(xy 109.540609 -181.307085) (xy 109.490863 -181.284239) (xy 109.444895 -181.254515) (xy 109.423962 -181.236874)
			(xy 109.423708 -181.23662) (xy 109.41663 -181.231021) (xy 109.399706 -181.224784) (xy 109.390688 -181.224428)
			(xy 109.323632 -181.224428) (xy 109.314616 -181.224794) (xy 109.297699 -181.231035) (xy 109.290612 -181.23662)
			(xy 109.290612 -181.236874) (xy 109.290358 -181.236874) (xy 109.269412 -181.254495) (xy 109.223443 -181.284211)
			(xy 109.173699 -181.30705) (xy 109.121202 -181.322546) (xy 109.067028 -181.330378) (xy 109.03966 -181.330854)
			(xy 109.01429 -181.330482) (xy 108.963998 -181.32375) (xy 108.915042 -181.310411) (xy 108.868286 -181.290701)
			(xy 108.824556 -181.264966) (xy 108.784624 -181.233662) (xy 108.76661 -181.215792) (xy 108.75931 -181.209005)
			(xy 108.741 -181.201172) (xy 108.73105 -181.200552) (xy 108.649008 -181.199536) (xy 108.63072 -181.206648)
			(xy 108.623354 -181.21376) (xy 108.601875 -181.233744) (xy 108.553943 -181.267571) (xy 108.501401 -181.293668)
			(xy 108.445485 -181.311418) (xy 108.387511 -181.320405) (xy 108.358178 -181.320948) (xy 108.330928 -181.320443)
			(xy 108.276983 -181.312684) (xy 108.224691 -181.297328) (xy 108.175117 -181.274688) (xy 108.129268 -181.245223)
			(xy 108.088079 -181.209534) (xy 108.052388 -181.168346) (xy 108.022921 -181.122499) (xy 108.000278 -181.072926)
			(xy 107.98492 -181.020635) (xy 107.977158 -180.96669) (xy 107.97667 -180.93944) (xy 74.730191 -180.93944)
			(xy 73.905646 -185.674) (xy 96.382584 -185.674) (xy 96.386655 -185.618378) (xy 96.398781 -185.563941)
			(xy 96.418704 -185.51185) (xy 96.446 -185.463215) (xy 96.480086 -185.419072) (xy 96.520235 -185.380363)
			(xy 96.565593 -185.347912) (xy 96.615193 -185.322411) (xy 96.667977 -185.304404) (xy 96.72282 -185.294274)
			(xy 96.778554 -185.292237) (xy 96.833991 -185.298337) (xy 96.887948 -185.312443) (xy 96.939277 -185.334255)
			(xy 96.986883 -185.363309) (xy 97.029751 -185.398984) (xy 97.066968 -185.440521) (xy 97.097741 -185.487034)
			(xy 97.121413 -185.537531) (xy 97.137481 -185.590938) (xy 97.145601 -185.646114) (xy 97.14611 -185.674)
			(xy 97.145601 -185.701886) (xy 97.137481 -185.757062) (xy 97.121413 -185.810469) (xy 97.097741 -185.860966)
			(xy 97.066968 -185.907479) (xy 97.029751 -185.949016) (xy 96.986883 -185.984691) (xy 96.939277 -186.013745)
			(xy 96.887948 -186.035557) (xy 96.833991 -186.049663) (xy 96.778554 -186.055763) (xy 96.72282 -186.053726)
			(xy 96.667977 -186.043596) (xy 96.615193 -186.025589) (xy 96.565593 -186.000088) (xy 96.520235 -185.967637)
			(xy 96.480086 -185.928928) (xy 96.446 -185.884785) (xy 96.418704 -185.83615) (xy 96.398781 -185.784059)
			(xy 96.386655 -185.729622) (xy 96.382584 -185.674) (xy 73.905646 -185.674) (xy 73.823147 -186.14771)
			(xy 99.051362 -186.14771) (xy 99.055433 -186.092088) (xy 99.067559 -186.037651) (xy 99.087482 -185.98556)
			(xy 99.114778 -185.936925) (xy 99.148864 -185.892782) (xy 99.189013 -185.854073) (xy 99.234371 -185.821622)
			(xy 99.283971 -185.796121) (xy 99.336755 -185.778114) (xy 99.391598 -185.767984) (xy 99.447332 -185.765947)
			(xy 99.502769 -185.772047) (xy 99.556726 -185.786153) (xy 99.608055 -185.807965) (xy 99.655661 -185.837019)
			(xy 99.698529 -185.872694) (xy 99.735746 -185.914231) (xy 99.766519 -185.960744) (xy 99.790191 -186.011241)
			(xy 99.806259 -186.064648) (xy 99.814379 -186.119824) (xy 99.814888 -186.14771) (xy 99.814379 -186.175596)
			(xy 99.806259 -186.230772) (xy 99.790191 -186.284179) (xy 99.766519 -186.334676) (xy 99.735746 -186.381189)
			(xy 99.698529 -186.422726) (xy 99.655661 -186.458401) (xy 99.608055 -186.487455) (xy 99.556726 -186.509267)
			(xy 99.502769 -186.523373) (xy 99.447332 -186.529473) (xy 99.391598 -186.527436) (xy 99.336755 -186.517306)
			(xy 99.283971 -186.499299) (xy 99.234371 -186.473798) (xy 99.189013 -186.441347) (xy 99.148864 -186.402638)
			(xy 99.114778 -186.358495) (xy 99.087482 -186.30986) (xy 99.067559 -186.257769) (xy 99.055433 -186.203332)
			(xy 99.051362 -186.14771) (xy 73.823147 -186.14771) (xy 73.492445 -188.046614) (xy 96.614232 -188.046614)
			(xy 96.618303 -187.990992) (xy 96.630429 -187.936555) (xy 96.650352 -187.884464) (xy 96.677648 -187.835829)
			(xy 96.711734 -187.791686) (xy 96.751883 -187.752977) (xy 96.797241 -187.720526) (xy 96.846841 -187.695025)
			(xy 96.899625 -187.677018) (xy 96.954468 -187.666888) (xy 97.010202 -187.664851) (xy 97.065639 -187.670951)
			(xy 97.119596 -187.685057) (xy 97.170925 -187.706869) (xy 97.218531 -187.735923) (xy 97.261399 -187.771598)
			(xy 97.298616 -187.813135) (xy 97.329389 -187.859648) (xy 97.353061 -187.910145) (xy 97.369129 -187.963552)
			(xy 97.377249 -188.018728) (xy 97.377758 -188.046614) (xy 97.377249 -188.0745) (xy 97.369129 -188.129676)
			(xy 97.353061 -188.183083) (xy 97.329389 -188.23358) (xy 97.298616 -188.280093) (xy 97.28956 -188.2902)
			(xy 102.792782 -188.2902) (xy 102.796853 -188.234578) (xy 102.808979 -188.180141) (xy 102.828902 -188.12805)
			(xy 102.856198 -188.079415) (xy 102.890284 -188.035272) (xy 102.930433 -187.996563) (xy 102.975791 -187.964112)
			(xy 103.025391 -187.938611) (xy 103.078175 -187.920604) (xy 103.133018 -187.910474) (xy 103.188752 -187.908437)
			(xy 103.244189 -187.914537) (xy 103.298146 -187.928643) (xy 103.349475 -187.950455) (xy 103.397081 -187.979509)
			(xy 103.439949 -188.015184) (xy 103.477166 -188.056721) (xy 103.507939 -188.103234) (xy 103.531611 -188.153731)
			(xy 103.547679 -188.207138) (xy 103.555799 -188.262314) (xy 103.556308 -188.2902) (xy 103.555799 -188.318086)
			(xy 103.547679 -188.373262) (xy 103.531611 -188.426669) (xy 103.507939 -188.477166) (xy 103.477166 -188.523679)
			(xy 103.439949 -188.565216) (xy 103.397081 -188.600891) (xy 103.349475 -188.629945) (xy 103.298146 -188.651757)
			(xy 103.244189 -188.665863) (xy 103.188752 -188.671963) (xy 103.133018 -188.669926) (xy 103.078175 -188.659796)
			(xy 103.025391 -188.641789) (xy 102.975791 -188.616288) (xy 102.930433 -188.583837) (xy 102.890284 -188.545128)
			(xy 102.856198 -188.500985) (xy 102.828902 -188.45235) (xy 102.808979 -188.400259) (xy 102.796853 -188.345822)
			(xy 102.792782 -188.2902) (xy 97.28956 -188.2902) (xy 97.261399 -188.32163) (xy 97.218531 -188.357305)
			(xy 97.170925 -188.386359) (xy 97.119596 -188.408171) (xy 97.065639 -188.422277) (xy 97.010202 -188.428377)
			(xy 96.954468 -188.42634) (xy 96.899625 -188.41621) (xy 96.846841 -188.398203) (xy 96.797241 -188.372702)
			(xy 96.751883 -188.340251) (xy 96.711734 -188.301542) (xy 96.677648 -188.257399) (xy 96.650352 -188.208764)
			(xy 96.630429 -188.156673) (xy 96.618303 -188.102236) (xy 96.614232 -188.046614) (xy 73.492445 -188.046614)
			(xy 73.228847 -189.5602) (xy 94.207582 -189.5602) (xy 94.211653 -189.504578) (xy 94.223779 -189.450141)
			(xy 94.243702 -189.39805) (xy 94.270998 -189.349415) (xy 94.305084 -189.305272) (xy 94.345233 -189.266563)
			(xy 94.390591 -189.234112) (xy 94.440191 -189.208611) (xy 94.492975 -189.190604) (xy 94.547818 -189.180474)
			(xy 94.603552 -189.178437) (xy 94.658989 -189.184537) (xy 94.712946 -189.198643) (xy 94.764275 -189.220455)
			(xy 94.811881 -189.249509) (xy 94.854749 -189.285184) (xy 94.891966 -189.326721) (xy 94.922739 -189.373234)
			(xy 94.946411 -189.423731) (xy 94.962479 -189.477138) (xy 94.970599 -189.532314) (xy 94.971108 -189.5602)
			(xy 94.970599 -189.588086) (xy 94.962479 -189.643262) (xy 94.946411 -189.696669) (xy 94.922739 -189.747166)
			(xy 94.891966 -189.793679) (xy 94.854749 -189.835216) (xy 94.811881 -189.870891) (xy 94.764275 -189.899945)
			(xy 94.712946 -189.921757) (xy 94.658989 -189.935863) (xy 94.603552 -189.941963) (xy 94.547818 -189.939926)
			(xy 94.492975 -189.929796) (xy 94.440191 -189.911789) (xy 94.390591 -189.886288) (xy 94.345233 -189.853837)
			(xy 94.305084 -189.815128) (xy 94.270998 -189.770985) (xy 94.243702 -189.72235) (xy 94.223779 -189.670259)
			(xy 94.211653 -189.615822) (xy 94.207582 -189.5602) (xy 73.228847 -189.5602) (xy 72.629592 -193.001138)
			(xy 108.648244 -193.001138) (xy 108.652315 -192.945516) (xy 108.664441 -192.891079) (xy 108.684364 -192.838988)
			(xy 108.71166 -192.790353) (xy 108.745746 -192.74621) (xy 108.785895 -192.707501) (xy 108.831253 -192.67505)
			(xy 108.880853 -192.649549) (xy 108.933637 -192.631542) (xy 108.98848 -192.621412) (xy 109.044214 -192.619375)
			(xy 109.099651 -192.625475) (xy 109.153608 -192.639581) (xy 109.204937 -192.661393) (xy 109.252543 -192.690447)
			(xy 109.295411 -192.726122) (xy 109.332628 -192.767659) (xy 109.363401 -192.814172) (xy 109.387073 -192.864669)
			(xy 109.403141 -192.918076) (xy 109.411261 -192.973252) (xy 109.41177 -193.001138) (xy 109.411261 -193.029024)
			(xy 109.403141 -193.0842) (xy 109.387073 -193.137607) (xy 109.363401 -193.188104) (xy 109.332628 -193.234617)
			(xy 109.295411 -193.276154) (xy 109.252543 -193.311829) (xy 109.204937 -193.340883) (xy 109.153608 -193.362695)
			(xy 109.099651 -193.376801) (xy 109.044214 -193.382901) (xy 108.98848 -193.380864) (xy 108.933637 -193.370734)
			(xy 108.880853 -193.352727) (xy 108.831253 -193.327226) (xy 108.785895 -193.294775) (xy 108.745746 -193.256066)
			(xy 108.71166 -193.211923) (xy 108.684364 -193.163288) (xy 108.664441 -193.111197) (xy 108.652315 -193.05676)
			(xy 108.648244 -193.001138) (xy 72.629592 -193.001138) (xy 72.347895 -194.618651) (xy 93.704387 -194.618651)
			(xy 93.704387 -194.564149) (xy 93.712144 -194.510202) (xy 93.727499 -194.457907) (xy 93.75014 -194.408331)
			(xy 93.779607 -194.362481) (xy 93.815299 -194.321292) (xy 93.856489 -194.285601) (xy 93.90234 -194.256136)
			(xy 93.951917 -194.233496) (xy 94.004211 -194.218142) (xy 94.058159 -194.210387) (xy 94.08541 -194.209924)
			(xy 94.112557 -194.210397) (xy 94.166299 -194.218116) (xy 94.218406 -194.233369) (xy 94.267828 -194.255848)
			(xy 94.313568 -194.2851) (xy 94.354704 -194.320535) (xy 94.390406 -194.36144) (xy 94.419956 -194.406988)
			(xy 94.442756 -194.456263) (xy 94.458348 -194.508269) (xy 94.462854 -194.535044) (xy 94.462854 -194.535298)
			(xy 94.464558 -194.544101) (xy 94.473145 -194.559826) (xy 94.486624 -194.57163) (xy 94.494858 -194.575176)
			(xy 94.589854 -194.612006) (xy 94.616778 -194.607688) (xy 94.627446 -194.598798) (xy 94.647958 -194.582592)
			(xy 94.692585 -194.555367) (xy 94.740506 -194.534479) (xy 94.790827 -194.520316) (xy 94.842608 -194.513143)
			(xy 94.868746 -194.512692) (xy 94.869 -194.512692) (xy 94.895314 -194.513162) (xy 94.947442 -194.520397)
			(xy 94.998085 -194.534715) (xy 95.046284 -194.555847) (xy 95.091127 -194.583393) (xy 95.131767 -194.616831)
			(xy 95.149924 -194.635882) (xy 95.157437 -194.643294) (xy 95.176724 -194.651813) (xy 95.187262 -194.652392)
			(xy 95.261938 -194.652392) (xy 95.272486 -194.651845) (xy 95.291781 -194.643323) (xy 95.299276 -194.635882)
			(xy 95.317447 -194.616842) (xy 95.358074 -194.583384) (xy 95.402911 -194.555823) (xy 95.451109 -194.534682)
			(xy 95.501753 -194.520362) (xy 95.553885 -194.513133) (xy 95.5802 -194.512692) (xy 95.607451 -194.513178)
			(xy 95.661399 -194.520934) (xy 95.713694 -194.536289) (xy 95.763271 -194.558931) (xy 95.809121 -194.588397)
			(xy 95.850312 -194.624088) (xy 95.886003 -194.665279) (xy 95.915469 -194.711129) (xy 95.938111 -194.760706)
			(xy 95.953466 -194.813001) (xy 95.961222 -194.866949) (xy 95.961222 -194.921451) (xy 95.953466 -194.975399)
			(xy 95.938111 -195.027694) (xy 95.915469 -195.077271) (xy 95.886003 -195.123121) (xy 95.850312 -195.164312)
			(xy 95.809121 -195.200003) (xy 95.763271 -195.229469) (xy 95.713694 -195.252111) (xy 95.661399 -195.267466)
			(xy 95.607451 -195.275222) (xy 95.5802 -195.275708) (xy 95.553886 -195.275238) (xy 95.501758 -195.268003)
			(xy 95.451115 -195.253685) (xy 95.402916 -195.232553) (xy 95.358073 -195.205007) (xy 95.317433 -195.171569)
			(xy 95.299276 -195.152518) (xy 95.291763 -195.145106) (xy 95.272476 -195.136587) (xy 95.261938 -195.136008)
			(xy 95.187262 -195.136008) (xy 95.176714 -195.136555) (xy 95.157419 -195.145077) (xy 95.149924 -195.152518)
			(xy 95.131753 -195.171558) (xy 95.091126 -195.205016) (xy 95.046289 -195.232577) (xy 94.998091 -195.253718)
			(xy 94.947447 -195.268038) (xy 94.895315 -195.275267) (xy 94.869 -195.275708) (xy 94.841855 -195.275198)
			(xy 94.788115 -195.267481) (xy 94.73601 -195.252231) (xy 94.686591 -195.229756) (xy 94.640852 -195.200508)
			(xy 94.599716 -195.165077) (xy 94.564013 -195.124177) (xy 94.534463 -195.078633) (xy 94.51166 -195.029363)
			(xy 94.496065 -194.977361) (xy 94.491556 -194.950588) (xy 94.491556 -194.950334) (xy 94.489888 -194.941522)
			(xy 94.481283 -194.925799) (xy 94.467791 -194.913999) (xy 94.459552 -194.910456) (xy 94.364556 -194.873626)
			(xy 94.337632 -194.877944) (xy 94.326964 -194.886834) (xy 94.306452 -194.90304) (xy 94.261825 -194.930264)
			(xy 94.213903 -194.951152) (xy 94.163583 -194.965315) (xy 94.111801 -194.972488) (xy 94.085664 -194.97294)
			(xy 94.08541 -194.97294) (xy 94.058159 -194.972413) (xy 94.004211 -194.964658) (xy 93.951917 -194.949304)
			(xy 93.90234 -194.926664) (xy 93.856489 -194.897199) (xy 93.815299 -194.861508) (xy 93.779607 -194.820319)
			(xy 93.75014 -194.774469) (xy 93.727499 -194.724893) (xy 93.712144 -194.672598) (xy 93.704387 -194.618651)
			(xy 72.347895 -194.618651) (xy 72.21586 -195.3768) (xy 96.087182 -195.3768) (xy 96.091253 -195.321178)
			(xy 96.103379 -195.266741) (xy 96.123302 -195.21465) (xy 96.150598 -195.166015) (xy 96.184684 -195.121872)
			(xy 96.224833 -195.083163) (xy 96.270191 -195.050712) (xy 96.319791 -195.025211) (xy 96.372575 -195.007204)
			(xy 96.427418 -194.997074) (xy 96.483152 -194.995037) (xy 96.538589 -195.001137) (xy 96.592546 -195.015243)
			(xy 96.643875 -195.037055) (xy 96.691481 -195.066109) (xy 96.734349 -195.101784) (xy 96.771566 -195.143321)
			(xy 96.802339 -195.189834) (xy 96.826011 -195.240331) (xy 96.842079 -195.293738) (xy 96.850199 -195.348914)
			(xy 96.850708 -195.3768) (xy 96.850199 -195.404686) (xy 96.842079 -195.459862) (xy 96.826011 -195.513269)
			(xy 96.802339 -195.563766) (xy 96.771566 -195.610279) (xy 96.734349 -195.651816) (xy 96.691481 -195.687491)
			(xy 96.643875 -195.716545) (xy 96.592546 -195.738357) (xy 96.538589 -195.752463) (xy 96.483152 -195.758563)
			(xy 96.427418 -195.756526) (xy 96.372575 -195.746396) (xy 96.319791 -195.728389) (xy 96.270191 -195.702888)
			(xy 96.224833 -195.670437) (xy 96.184684 -195.631728) (xy 96.150598 -195.587585) (xy 96.123302 -195.53895)
			(xy 96.103379 -195.486859) (xy 96.091253 -195.432422) (xy 96.087182 -195.3768) (xy 72.21586 -195.3768)
			(xy 72.000984 -196.610624) (xy 92.543863 -196.610624) (xy 92.543863 -196.555976) (xy 92.551641 -196.501885)
			(xy 92.567037 -196.449451) (xy 92.589738 -196.399742) (xy 92.619283 -196.353769) (xy 92.655069 -196.312469)
			(xy 92.696369 -196.276683) (xy 92.742342 -196.247138) (xy 92.792051 -196.224437) (xy 92.844485 -196.209041)
			(xy 92.898576 -196.201263) (xy 92.9259 -196.200776) (xy 103.0351 -196.200776) (xy 103.065165 -196.201305)
			(xy 103.124555 -196.210701) (xy 103.181742 -196.229277) (xy 103.235317 -196.256576) (xy 103.283959 -196.291923)
			(xy 103.30561 -196.31279) (xy 106.524044 -199.53097) (xy 106.532201 -199.538409) (xy 106.552887 -199.546048)
			(xy 106.563922 -199.545702) (xy 106.64063 -199.53986) (xy 106.651448 -199.53847) (xy 106.670533 -199.527962)
			(xy 106.67746 -199.51954) (xy 106.677714 -199.519286) (xy 106.695856 -199.495686) (xy 106.738168 -199.453821)
			(xy 106.786471 -199.41904) (xy 106.839591 -199.392186) (xy 106.896239 -199.373913) (xy 106.955039 -199.364664)
			(xy 106.9848 -199.364092) (xy 107.012051 -199.364578) (xy 107.065999 -199.372334) (xy 107.118294 -199.387689)
			(xy 107.160617 -199.407018) (xy 109.422944 -199.407018) (xy 109.427015 -199.351396) (xy 109.439141 -199.296959)
			(xy 109.459064 -199.244868) (xy 109.48636 -199.196233) (xy 109.520446 -199.15209) (xy 109.560595 -199.113381)
			(xy 109.605953 -199.08093) (xy 109.655553 -199.055429) (xy 109.708337 -199.037422) (xy 109.76318 -199.027292)
			(xy 109.818914 -199.025255) (xy 109.874351 -199.031355) (xy 109.928308 -199.045461) (xy 109.979637 -199.067273)
			(xy 110.027243 -199.096327) (xy 110.070111 -199.132002) (xy 110.107328 -199.173539) (xy 110.138101 -199.220052)
			(xy 110.161773 -199.270549) (xy 110.177841 -199.323956) (xy 110.185961 -199.379132) (xy 110.18647 -199.407018)
			(xy 110.185961 -199.434904) (xy 110.177841 -199.49008) (xy 110.161773 -199.543487) (xy 110.138101 -199.593984)
			(xy 110.107328 -199.640497) (xy 110.070111 -199.682034) (xy 110.027243 -199.717709) (xy 109.979637 -199.746763)
			(xy 109.928308 -199.768575) (xy 109.874351 -199.782681) (xy 109.818914 -199.788781) (xy 109.76318 -199.786744)
			(xy 109.708337 -199.776614) (xy 109.655553 -199.758607) (xy 109.605953 -199.733106) (xy 109.560595 -199.700655)
			(xy 109.520446 -199.661946) (xy 109.48636 -199.617803) (xy 109.459064 -199.569168) (xy 109.439141 -199.517077)
			(xy 109.427015 -199.46264) (xy 109.422944 -199.407018) (xy 107.160617 -199.407018) (xy 107.167871 -199.410331)
			(xy 107.213721 -199.439797) (xy 107.254912 -199.475488) (xy 107.290603 -199.516679) (xy 107.320069 -199.562529)
			(xy 107.342711 -199.612106) (xy 107.358066 -199.664401) (xy 107.365822 -199.718349) (xy 107.366308 -199.7456)
			(xy 107.365732 -199.775361) (xy 107.356475 -199.83416) (xy 107.338201 -199.890808) (xy 107.311353 -199.943931)
			(xy 107.276582 -199.992242) (xy 107.234733 -200.034569) (xy 107.211114 -200.052686) (xy 107.21086 -200.05294)
			(xy 107.202396 -200.059833) (xy 107.19187 -200.078934) (xy 107.19054 -200.08977) (xy 107.184698 -200.166478)
			(xy 107.184406 -200.177505) (xy 107.192031 -200.198176) (xy 107.19943 -200.206356) (xy 108.55071 -201.55789)
			(xy 108.571558 -201.579553) (xy 108.606882 -201.628203) (xy 108.634164 -201.681777) (xy 108.652734 -201.738958)
			(xy 108.662135 -201.79834) (xy 108.662724 -201.8284) (xy 108.662724 -202.5396) (xy 108.990382 -202.5396)
			(xy 108.994453 -202.483978) (xy 109.006579 -202.429541) (xy 109.026502 -202.37745) (xy 109.053798 -202.328815)
			(xy 109.087884 -202.284672) (xy 109.128033 -202.245963) (xy 109.173391 -202.213512) (xy 109.222991 -202.188011)
			(xy 109.275775 -202.170004) (xy 109.330618 -202.159874) (xy 109.386352 -202.157837) (xy 109.441789 -202.163937)
			(xy 109.495746 -202.178043) (xy 109.547075 -202.199855) (xy 109.594681 -202.228909) (xy 109.637549 -202.264584)
			(xy 109.674766 -202.306121) (xy 109.705539 -202.352634) (xy 109.729211 -202.403131) (xy 109.745279 -202.456538)
			(xy 109.753399 -202.511714) (xy 109.753908 -202.5396) (xy 109.879382 -202.5396) (xy 109.883453 -202.483978)
			(xy 109.895579 -202.429541) (xy 109.915502 -202.37745) (xy 109.942798 -202.328815) (xy 109.976884 -202.284672)
			(xy 110.017033 -202.245963) (xy 110.062391 -202.213512) (xy 110.111991 -202.188011) (xy 110.164775 -202.170004)
			(xy 110.219618 -202.159874) (xy 110.275352 -202.157837) (xy 110.330789 -202.163937) (xy 110.384746 -202.178043)
			(xy 110.436075 -202.199855) (xy 110.483681 -202.228909) (xy 110.526549 -202.264584) (xy 110.563766 -202.306121)
			(xy 110.594539 -202.352634) (xy 110.618211 -202.403131) (xy 110.634279 -202.456538) (xy 110.642399 -202.511714)
			(xy 110.642908 -202.5396) (xy 110.642399 -202.567486) (xy 110.634279 -202.622662) (xy 110.618211 -202.676069)
			(xy 110.594539 -202.726566) (xy 110.563766 -202.773079) (xy 110.526549 -202.814616) (xy 110.483681 -202.850291)
			(xy 110.436075 -202.879345) (xy 110.384746 -202.901157) (xy 110.330789 -202.915263) (xy 110.275352 -202.921363)
			(xy 110.219618 -202.919326) (xy 110.164775 -202.909196) (xy 110.111991 -202.891189) (xy 110.062391 -202.865688)
			(xy 110.017033 -202.833237) (xy 109.976884 -202.794528) (xy 109.942798 -202.750385) (xy 109.915502 -202.70175)
			(xy 109.895579 -202.649659) (xy 109.883453 -202.595222) (xy 109.879382 -202.5396) (xy 109.753908 -202.5396)
			(xy 109.753399 -202.567486) (xy 109.745279 -202.622662) (xy 109.729211 -202.676069) (xy 109.705539 -202.726566)
			(xy 109.674766 -202.773079) (xy 109.637549 -202.814616) (xy 109.594681 -202.850291) (xy 109.547075 -202.879345)
			(xy 109.495746 -202.901157) (xy 109.441789 -202.915263) (xy 109.386352 -202.921363) (xy 109.330618 -202.919326)
			(xy 109.275775 -202.909196) (xy 109.222991 -202.891189) (xy 109.173391 -202.865688) (xy 109.128033 -202.833237)
			(xy 109.087884 -202.794528) (xy 109.053798 -202.750385) (xy 109.026502 -202.70175) (xy 109.006579 -202.649659)
			(xy 108.994453 -202.595222) (xy 108.990382 -202.5396) (xy 108.662724 -202.5396) (xy 108.662237 -202.566924)
			(xy 108.654459 -202.621015) (xy 108.639063 -202.673449) (xy 108.616362 -202.723158) (xy 108.586817 -202.769131)
			(xy 108.551031 -202.810431) (xy 108.509731 -202.846217) (xy 108.463758 -202.875762) (xy 108.414049 -202.898463)
			(xy 108.361615 -202.913859) (xy 108.307524 -202.921637) (xy 108.252876 -202.921637) (xy 108.198785 -202.913859)
			(xy 108.146351 -202.898463) (xy 108.096642 -202.875762) (xy 108.050669 -202.846217) (xy 108.009369 -202.810431)
			(xy 107.973583 -202.769131) (xy 107.944038 -202.723158) (xy 107.921337 -202.673449) (xy 107.905941 -202.621015)
			(xy 107.898163 -202.566924) (xy 107.897676 -202.5396) (xy 107.897676 -202.506834) (xy 107.897122 -202.494348)
			(xy 107.885524 -202.47224) (xy 107.875578 -202.46467) (xy 107.795568 -202.410568) (xy 107.770676 -202.407774)
			(xy 107.758992 -202.412346) (xy 107.736861 -202.420617) (xy 107.691064 -202.432234) (xy 107.644185 -202.438122)
			(xy 107.620562 -202.438508) (xy 107.6198 -202.438508) (xy 107.592549 -202.438022) (xy 107.538601 -202.430266)
			(xy 107.486306 -202.414911) (xy 107.436729 -202.392269) (xy 107.390879 -202.362803) (xy 107.349688 -202.327112)
			(xy 107.313997 -202.285921) (xy 107.284531 -202.240071) (xy 107.261889 -202.190494) (xy 107.246534 -202.138199)
			(xy 107.238778 -202.084251) (xy 107.238292 -202.057) (xy 107.238733 -202.031024) (xy 107.245783 -201.979552)
			(xy 107.259753 -201.929513) (xy 107.280384 -201.881833) (xy 107.307294 -201.837394) (xy 107.339986 -201.797017)
			(xy 107.377855 -201.761451) (xy 107.4202 -201.731352) (xy 107.443016 -201.718926) (xy 107.453343 -201.712828)
			(xy 107.467258 -201.693334) (xy 107.469686 -201.681588) (xy 107.482132 -201.600562) (xy 107.483243 -201.588592)
			(xy 107.475703 -201.565801) (xy 107.467654 -201.556874) (xy 102.89159 -196.98081) (xy 102.884186 -196.973974)
			(xy 102.86559 -196.966252) (xy 102.855522 -196.965824) (xy 92.9259 -196.965824) (xy 92.898576 -196.965337)
			(xy 92.844485 -196.957559) (xy 92.792051 -196.942163) (xy 92.742342 -196.919462) (xy 92.696369 -196.889917)
			(xy 92.655069 -196.854131) (xy 92.619283 -196.812831) (xy 92.589738 -196.766858) (xy 92.567037 -196.717149)
			(xy 92.551641 -196.664715) (xy 92.543863 -196.610624) (xy 72.000984 -196.610624) (xy 71.625098 -198.76897)
			(xy 94.538544 -198.76897) (xy 94.542615 -198.713348) (xy 94.554741 -198.658911) (xy 94.574664 -198.60682)
			(xy 94.60196 -198.558185) (xy 94.636046 -198.514042) (xy 94.676195 -198.475333) (xy 94.721553 -198.442882)
			(xy 94.771153 -198.417381) (xy 94.823937 -198.399374) (xy 94.87878 -198.389244) (xy 94.934514 -198.387207)
			(xy 94.989951 -198.393307) (xy 95.043908 -198.407413) (xy 95.095237 -198.429225) (xy 95.142843 -198.458279)
			(xy 95.185711 -198.493954) (xy 95.222928 -198.535491) (xy 95.253701 -198.582004) (xy 95.277373 -198.632501)
			(xy 95.293441 -198.685908) (xy 95.301561 -198.741084) (xy 95.30207 -198.76897) (xy 95.301736 -198.787258)
			(xy 96.222056 -198.787258) (xy 96.226127 -198.731636) (xy 96.238253 -198.677199) (xy 96.258176 -198.625108)
			(xy 96.285472 -198.576473) (xy 96.319558 -198.53233) (xy 96.359707 -198.493621) (xy 96.405065 -198.46117)
			(xy 96.454665 -198.435669) (xy 96.507449 -198.417662) (xy 96.562292 -198.407532) (xy 96.618026 -198.405495)
			(xy 96.673463 -198.411595) (xy 96.72742 -198.425701) (xy 96.778749 -198.447513) (xy 96.826355 -198.476567)
			(xy 96.869223 -198.512242) (xy 96.90644 -198.553779) (xy 96.937213 -198.600292) (xy 96.960885 -198.650789)
			(xy 96.976953 -198.704196) (xy 96.985073 -198.759372) (xy 96.985582 -198.787258) (xy 96.985073 -198.815144)
			(xy 96.976953 -198.87032) (xy 96.960885 -198.923727) (xy 96.937213 -198.974224) (xy 96.90644 -199.020737)
			(xy 96.869223 -199.062274) (xy 96.826355 -199.097949) (xy 96.778749 -199.127003) (xy 96.72742 -199.148815)
			(xy 96.673463 -199.162921) (xy 96.618026 -199.169021) (xy 96.562292 -199.166984) (xy 96.507449 -199.156854)
			(xy 96.454665 -199.138847) (xy 96.405065 -199.113346) (xy 96.359707 -199.080895) (xy 96.319558 -199.042186)
			(xy 96.285472 -198.998043) (xy 96.258176 -198.949408) (xy 96.238253 -198.897317) (xy 96.226127 -198.84288)
			(xy 96.222056 -198.787258) (xy 95.301736 -198.787258) (xy 95.301561 -198.796856) (xy 95.293441 -198.852032)
			(xy 95.277373 -198.905439) (xy 95.253701 -198.955936) (xy 95.222928 -199.002449) (xy 95.185711 -199.043986)
			(xy 95.142843 -199.079661) (xy 95.095237 -199.108715) (xy 95.043908 -199.130527) (xy 94.989951 -199.144633)
			(xy 94.934514 -199.150733) (xy 94.87878 -199.148696) (xy 94.823937 -199.138566) (xy 94.771153 -199.120559)
			(xy 94.721553 -199.095058) (xy 94.676195 -199.062607) (xy 94.636046 -199.023898) (xy 94.60196 -198.979755)
			(xy 94.574664 -198.93112) (xy 94.554741 -198.879029) (xy 94.542615 -198.824592) (xy 94.538544 -198.76897)
			(xy 71.625098 -198.76897) (xy 71.530213 -199.3138) (xy 102.995982 -199.3138) (xy 103.000053 -199.258178)
			(xy 103.012179 -199.203741) (xy 103.032102 -199.15165) (xy 103.059398 -199.103015) (xy 103.093484 -199.058872)
			(xy 103.133633 -199.020163) (xy 103.178991 -198.987712) (xy 103.228591 -198.962211) (xy 103.281375 -198.944204)
			(xy 103.336218 -198.934074) (xy 103.391952 -198.932037) (xy 103.447389 -198.938137) (xy 103.501346 -198.952243)
			(xy 103.552675 -198.974055) (xy 103.600281 -199.003109) (xy 103.643149 -199.038784) (xy 103.680366 -199.080321)
			(xy 103.711139 -199.126834) (xy 103.734811 -199.177331) (xy 103.750879 -199.230738) (xy 103.758999 -199.285914)
			(xy 103.759508 -199.3138) (xy 103.758999 -199.341686) (xy 103.750879 -199.396862) (xy 103.734811 -199.450269)
			(xy 103.711139 -199.500766) (xy 103.680366 -199.547279) (xy 103.643149 -199.588816) (xy 103.600281 -199.624491)
			(xy 103.552675 -199.653545) (xy 103.501346 -199.675357) (xy 103.447389 -199.689463) (xy 103.391952 -199.695563)
			(xy 103.336218 -199.693526) (xy 103.281375 -199.683396) (xy 103.228591 -199.665389) (xy 103.178991 -199.639888)
			(xy 103.133633 -199.607437) (xy 103.093484 -199.568728) (xy 103.059398 -199.524585) (xy 103.032102 -199.47595)
			(xy 103.012179 -199.423859) (xy 103.000053 -199.369422) (xy 102.995982 -199.3138) (xy 71.530213 -199.3138)
			(xy 71.43148 -199.880728) (xy 96.29216 -199.880728) (xy 96.296231 -199.825106) (xy 96.308357 -199.770669)
			(xy 96.32828 -199.718578) (xy 96.355576 -199.669943) (xy 96.389662 -199.6258) (xy 96.429811 -199.587091)
			(xy 96.475169 -199.55464) (xy 96.524769 -199.529139) (xy 96.577553 -199.511132) (xy 96.632396 -199.501002)
			(xy 96.68813 -199.498965) (xy 96.743567 -199.505065) (xy 96.797524 -199.519171) (xy 96.848853 -199.540983)
			(xy 96.896459 -199.570037) (xy 96.939327 -199.605712) (xy 96.976544 -199.647249) (xy 97.007317 -199.693762)
			(xy 97.030989 -199.744259) (xy 97.047057 -199.797666) (xy 97.055177 -199.852842) (xy 97.055686 -199.880728)
			(xy 97.055177 -199.908614) (xy 97.047057 -199.96379) (xy 97.030989 -200.017197) (xy 97.007317 -200.067694)
			(xy 96.976544 -200.114207) (xy 96.939327 -200.155744) (xy 96.896459 -200.191419) (xy 96.848853 -200.220473)
			(xy 96.797524 -200.242285) (xy 96.743567 -200.256391) (xy 96.68813 -200.262491) (xy 96.632396 -200.260454)
			(xy 96.577553 -200.250324) (xy 96.524769 -200.232317) (xy 96.475169 -200.206816) (xy 96.429811 -200.174365)
			(xy 96.389662 -200.135656) (xy 96.355576 -200.091513) (xy 96.32828 -200.042878) (xy 96.308357 -199.990787)
			(xy 96.296231 -199.93635) (xy 96.29216 -199.880728) (xy 71.43148 -199.880728) (xy 71.340002 -200.406)
			(xy 100.684582 -200.406) (xy 100.688653 -200.350378) (xy 100.700779 -200.295941) (xy 100.720702 -200.24385)
			(xy 100.747998 -200.195215) (xy 100.782084 -200.151072) (xy 100.822233 -200.112363) (xy 100.867591 -200.079912)
			(xy 100.917191 -200.054411) (xy 100.969975 -200.036404) (xy 101.024818 -200.026274) (xy 101.080552 -200.024237)
			(xy 101.135989 -200.030337) (xy 101.189946 -200.044443) (xy 101.241275 -200.066255) (xy 101.288881 -200.095309)
			(xy 101.331749 -200.130984) (xy 101.368966 -200.172521) (xy 101.399739 -200.219034) (xy 101.423411 -200.269531)
			(xy 101.439479 -200.322938) (xy 101.447599 -200.378114) (xy 101.448108 -200.406) (xy 101.447599 -200.433886)
			(xy 101.439479 -200.489062) (xy 101.423411 -200.542469) (xy 101.399739 -200.592966) (xy 101.368966 -200.639479)
			(xy 101.331749 -200.681016) (xy 101.288881 -200.716691) (xy 101.241275 -200.745745) (xy 101.189946 -200.767557)
			(xy 101.135989 -200.781663) (xy 101.080552 -200.787763) (xy 101.024818 -200.785726) (xy 100.969975 -200.775596)
			(xy 100.917191 -200.757589) (xy 100.867591 -200.732088) (xy 100.822233 -200.699637) (xy 100.782084 -200.660928)
			(xy 100.747998 -200.616785) (xy 100.720702 -200.56815) (xy 100.700779 -200.516059) (xy 100.688653 -200.461622)
			(xy 100.684582 -200.406) (xy 71.340002 -200.406) (xy 71.243215 -200.961752) (xy 93.962726 -200.961752)
			(xy 93.966797 -200.90613) (xy 93.978923 -200.851693) (xy 93.998846 -200.799602) (xy 94.026142 -200.750967)
			(xy 94.060228 -200.706824) (xy 94.100377 -200.668115) (xy 94.145735 -200.635664) (xy 94.195335 -200.610163)
			(xy 94.248119 -200.592156) (xy 94.302962 -200.582026) (xy 94.358696 -200.579989) (xy 94.414133 -200.586089)
			(xy 94.46809 -200.600195) (xy 94.519419 -200.622007) (xy 94.567025 -200.651061) (xy 94.609893 -200.686736)
			(xy 94.64711 -200.728273) (xy 94.677883 -200.774786) (xy 94.701555 -200.825283) (xy 94.717623 -200.87869)
			(xy 94.725743 -200.933866) (xy 94.726252 -200.961752) (xy 94.725743 -200.989638) (xy 94.717623 -201.044814)
			(xy 94.701555 -201.098221) (xy 94.677883 -201.148718) (xy 94.64711 -201.195231) (xy 94.609893 -201.236768)
			(xy 94.567025 -201.272443) (xy 94.519419 -201.301497) (xy 94.46809 -201.323309) (xy 94.414133 -201.337415)
			(xy 94.358696 -201.343515) (xy 94.302962 -201.341478) (xy 94.248119 -201.331348) (xy 94.195335 -201.313341)
			(xy 94.145735 -201.28784) (xy 94.100377 -201.255389) (xy 94.060228 -201.21668) (xy 94.026142 -201.172537)
			(xy 93.998846 -201.123902) (xy 93.978923 -201.071811) (xy 93.966797 -201.017374) (xy 93.962726 -200.961752)
			(xy 71.243215 -200.961752) (xy 71.170485 -201.379368) (xy 98.428551 -201.379368) (xy 98.428551 -201.324832)
			(xy 98.436313 -201.270851) (xy 98.451678 -201.218525) (xy 98.474333 -201.168917) (xy 98.503818 -201.123039)
			(xy 98.539531 -201.081824) (xy 98.580747 -201.046112) (xy 98.626626 -201.016628) (xy 98.676234 -200.993974)
			(xy 98.728561 -200.978611) (xy 98.782542 -200.970851) (xy 98.80981 -200.970388) (xy 99.67341 -200.970388)
			(xy 99.700682 -200.970775) (xy 99.754672 -200.978539) (xy 99.807007 -200.993907) (xy 99.856623 -201.016567)
			(xy 99.902508 -201.046057) (xy 99.94373 -201.081777) (xy 99.979449 -201.123) (xy 100.008938 -201.168886)
			(xy 100.031596 -201.218502) (xy 100.046963 -201.270838) (xy 100.054725 -201.324828) (xy 100.054725 -201.379372)
			(xy 100.046963 -201.433362) (xy 100.031596 -201.485698) (xy 100.008938 -201.535314) (xy 99.979449 -201.5812)
			(xy 99.94373 -201.622423) (xy 99.902508 -201.658143) (xy 99.856623 -201.687633) (xy 99.807007 -201.710293)
			(xy 99.754672 -201.725661) (xy 99.700682 -201.733425) (xy 99.67341 -201.733912) (xy 98.80981 -201.733912)
			(xy 98.782542 -201.733349) (xy 98.728561 -201.725589) (xy 98.676234 -201.710226) (xy 98.626626 -201.687572)
			(xy 98.580747 -201.658088) (xy 98.539531 -201.622376) (xy 98.503818 -201.581161) (xy 98.474333 -201.535283)
			(xy 98.451678 -201.485675) (xy 98.436313 -201.433349) (xy 98.428551 -201.379368) (xy 71.170485 -201.379368)
			(xy 70.990568 -202.412457) (xy 100.513523 -202.412457) (xy 100.513523 -202.357943) (xy 100.521282 -202.303984)
			(xy 100.536641 -202.251678) (xy 100.559289 -202.202091) (xy 100.588763 -202.156232) (xy 100.624464 -202.115035)
			(xy 100.665666 -202.079338) (xy 100.711528 -202.049869) (xy 100.761117 -202.027227) (xy 100.813425 -202.011873)
			(xy 100.867385 -202.00412) (xy 100.894642 -202.00366) (xy 100.920958 -202.00408) (xy 100.973089 -202.011322)
			(xy 101.023734 -202.025649) (xy 101.071933 -202.04679) (xy 101.116775 -202.074346) (xy 101.157412 -202.107794)
			(xy 101.175566 -202.12685) (xy 101.183105 -202.134231) (xy 101.202372 -202.142769) (xy 101.212904 -202.14336)
			(xy 101.28758 -202.14336) (xy 101.298132 -202.142846) (xy 101.317428 -202.134301) (xy 101.324918 -202.12685)
			(xy 101.343062 -202.107783) (xy 101.383695 -202.074329) (xy 101.428538 -202.046773) (xy 101.476741 -202.025637)
			(xy 101.52739 -202.011321) (xy 101.579525 -202.004098) (xy 101.605842 -202.00366) (xy 101.633089 -202.004213)
			(xy 101.687028 -202.011974) (xy 101.739313 -202.027331) (xy 101.788881 -202.049973) (xy 101.834722 -202.079438)
			(xy 101.875903 -202.115126) (xy 101.911587 -202.156312) (xy 101.941047 -202.202156) (xy 101.963683 -202.251727)
			(xy 101.979035 -202.304014) (xy 101.98679 -202.357953) (xy 101.98679 -202.412447) (xy 101.979035 -202.466386)
			(xy 101.963683 -202.518673) (xy 101.941047 -202.568244) (xy 101.911587 -202.614088) (xy 101.875903 -202.655274)
			(xy 101.834722 -202.690962) (xy 101.788881 -202.720427) (xy 101.739313 -202.743069) (xy 101.687028 -202.758426)
			(xy 101.633089 -202.766187) (xy 101.605842 -202.766676) (xy 101.579526 -202.766255) (xy 101.527396 -202.759012)
			(xy 101.476752 -202.744684) (xy 101.428553 -202.723543) (xy 101.38371 -202.695988) (xy 101.343073 -202.662541)
			(xy 101.324918 -202.643486) (xy 101.317394 -202.636088) (xy 101.298116 -202.627562) (xy 101.28758 -202.626976)
			(xy 101.212904 -202.626976) (xy 101.202354 -202.627501) (xy 101.183059 -202.63604) (xy 101.175566 -202.643486)
			(xy 101.157417 -202.662548) (xy 101.116786 -202.696005) (xy 101.071945 -202.723564) (xy 101.023743 -202.744701)
			(xy 100.973094 -202.759017) (xy 100.920959 -202.766239) (xy 100.894642 -202.766676) (xy 100.867385 -202.76628)
			(xy 100.813425 -202.758527) (xy 100.761117 -202.743173) (xy 100.711528 -202.720531) (xy 100.665666 -202.691062)
			(xy 100.624464 -202.655365) (xy 100.588763 -202.614168) (xy 100.559289 -202.568309) (xy 100.536641 -202.518722)
			(xy 100.521282 -202.466416) (xy 100.513523 -202.412457) (xy 70.990568 -202.412457) (xy 70.676473 -204.216)
			(xy 96.999296 -204.216) (xy 97.003367 -204.160378) (xy 97.015493 -204.105941) (xy 97.035416 -204.05385)
			(xy 97.062712 -204.005215) (xy 97.096798 -203.961072) (xy 97.136947 -203.922363) (xy 97.182305 -203.889912)
			(xy 97.231905 -203.864411) (xy 97.284689 -203.846404) (xy 97.339532 -203.836274) (xy 97.395266 -203.834237)
			(xy 97.450703 -203.840337) (xy 97.50466 -203.854443) (xy 97.555989 -203.876255) (xy 97.603595 -203.905309)
			(xy 97.646463 -203.940984) (xy 97.68368 -203.982521) (xy 97.714453 -204.029034) (xy 97.738125 -204.079531)
			(xy 97.754193 -204.132938) (xy 97.762313 -204.188114) (xy 97.762822 -204.216) (xy 97.762313 -204.243886)
			(xy 97.754193 -204.299062) (xy 97.738125 -204.352469) (xy 97.714453 -204.402966) (xy 97.68368 -204.449479)
			(xy 97.646463 -204.491016) (xy 97.603595 -204.526691) (xy 97.555989 -204.555745) (xy 97.50466 -204.577557)
			(xy 97.450703 -204.591663) (xy 97.395266 -204.597763) (xy 97.339532 -204.595726) (xy 97.284689 -204.585596)
			(xy 97.231905 -204.567589) (xy 97.182305 -204.542088) (xy 97.136947 -204.509637) (xy 97.096798 -204.470928)
			(xy 97.062712 -204.426785) (xy 97.035416 -204.37815) (xy 97.015493 -204.326059) (xy 97.003367 -204.271622)
			(xy 96.999296 -204.216) (xy 70.676473 -204.216) (xy 70.199971 -206.952088) (xy 91.57665 -206.952088)
			(xy 91.580721 -206.896466) (xy 91.592847 -206.842029) (xy 91.61277 -206.789938) (xy 91.640066 -206.741303)
			(xy 91.674152 -206.69716) (xy 91.714301 -206.658451) (xy 91.759659 -206.626) (xy 91.809259 -206.600499)
			(xy 91.862043 -206.582492) (xy 91.916886 -206.572362) (xy 91.97262 -206.570325) (xy 92.028057 -206.576425)
			(xy 92.082014 -206.590531) (xy 92.133343 -206.612343) (xy 92.180949 -206.641397) (xy 92.223817 -206.677072)
			(xy 92.261034 -206.718609) (xy 92.291807 -206.765122) (xy 92.315479 -206.815619) (xy 92.331547 -206.869026)
			(xy 92.339667 -206.924202) (xy 92.340176 -206.952088) (xy 92.339667 -206.979974) (xy 92.331547 -207.03515)
			(xy 92.329408 -207.042258) (xy 92.503496 -207.042258) (xy 92.507567 -206.986636) (xy 92.519693 -206.932199)
			(xy 92.539616 -206.880108) (xy 92.566912 -206.831473) (xy 92.600998 -206.78733) (xy 92.641147 -206.748621)
			(xy 92.686505 -206.71617) (xy 92.736105 -206.690669) (xy 92.788889 -206.672662) (xy 92.843732 -206.662532)
			(xy 92.899466 -206.660495) (xy 92.954903 -206.666595) (xy 93.00886 -206.680701) (xy 93.060189 -206.702513)
			(xy 93.107795 -206.731567) (xy 93.150663 -206.767242) (xy 93.18788 -206.808779) (xy 93.218653 -206.855292)
			(xy 93.242325 -206.905789) (xy 93.258393 -206.959196) (xy 93.266513 -207.014372) (xy 93.267022 -207.042258)
			(xy 93.266513 -207.070144) (xy 93.264038 -207.086962) (xy 93.98076 -207.086962) (xy 93.984831 -207.03134)
			(xy 93.996957 -206.976903) (xy 94.01688 -206.924812) (xy 94.044176 -206.876177) (xy 94.078262 -206.832034)
			(xy 94.118411 -206.793325) (xy 94.163769 -206.760874) (xy 94.213369 -206.735373) (xy 94.266153 -206.717366)
			(xy 94.320996 -206.707236) (xy 94.37673 -206.705199) (xy 94.432167 -206.711299) (xy 94.486124 -206.725405)
			(xy 94.537453 -206.747217) (xy 94.585059 -206.776271) (xy 94.627927 -206.811946) (xy 94.635633 -206.820547)
			(xy 96.553316 -206.820547) (xy 96.553316 -206.766053) (xy 96.561071 -206.712113) (xy 96.576423 -206.659825)
			(xy 96.59906 -206.610255) (xy 96.628521 -206.56441) (xy 96.664206 -206.523225) (xy 96.705389 -206.487537)
			(xy 96.751232 -206.458073) (xy 96.800801 -206.435433) (xy 96.853087 -206.420077) (xy 96.907027 -206.412318)
			(xy 96.934274 -206.41183) (xy 96.963191 -206.412356) (xy 97.020362 -206.421082) (xy 97.075561 -206.438337)
			(xy 97.127523 -206.463727) (xy 97.175057 -206.49667) (xy 97.217074 -206.536411) (xy 97.235264 -206.558896)
			(xy 97.24263 -206.568548) (xy 97.263966 -206.578708) (xy 97.369376 -206.577184) (xy 97.390458 -206.566262)
			(xy 97.397316 -206.55661) (xy 97.415454 -206.53289) (xy 97.457838 -206.490833) (xy 97.506252 -206.455885)
			(xy 97.559515 -206.428899) (xy 97.616329 -206.410533) (xy 97.675309 -206.401233) (xy 97.705164 -206.400654)
			(xy 97.734969 -206.40125) (xy 97.793851 -206.410536) (xy 97.85057 -206.42887) (xy 97.903747 -206.455807)
			(xy 97.952084 -206.49069) (xy 97.994404 -206.53267) (xy 98.012504 -206.556356) (xy 98.012758 -206.55661)
			(xy 98.018331 -206.563579) (xy 98.033234 -206.573372) (xy 98.050602 -206.577423) (xy 98.059494 -206.576676)
			(xy 98.147886 -206.565754) (xy 98.156673 -206.564234) (xy 98.172522 -206.556093) (xy 98.184674 -206.543062)
			(xy 98.188526 -206.53502) (xy 98.188526 -206.534766) (xy 98.199728 -206.508917) (xy 98.228558 -206.46052)
			(xy 98.264194 -206.416892) (xy 98.305861 -206.378981) (xy 98.352652 -206.347613) (xy 98.40355 -206.32347)
			(xy 98.457445 -206.307079) (xy 98.513166 -206.298795) (xy 98.541332 -206.298292) (xy 98.568582 -206.29878)
			(xy 98.622526 -206.30654) (xy 98.674817 -206.321898) (xy 98.72439 -206.344541) (xy 98.770237 -206.374008)
			(xy 98.811423 -206.4097) (xy 98.847111 -206.450889) (xy 98.876574 -206.496738) (xy 98.899213 -206.546313)
			(xy 98.914567 -206.598605) (xy 98.922322 -206.65255) (xy 98.922322 -206.70705) (xy 98.914567 -206.760995)
			(xy 98.899213 -206.813287) (xy 98.876574 -206.862862) (xy 98.847111 -206.908711) (xy 98.811423 -206.9499)
			(xy 98.770237 -206.985592) (xy 98.72439 -207.015059) (xy 98.674817 -207.037702) (xy 98.622526 -207.05306)
			(xy 98.568582 -207.06082) (xy 98.541332 -207.061308) (xy 98.511529 -207.060689) (xy 98.452649 -207.051405)
			(xy 98.395931 -207.033073) (xy 98.342755 -207.006141) (xy 98.294417 -206.971263) (xy 98.252094 -206.929289)
			(xy 98.233992 -206.905606) (xy 98.233738 -206.905352) (xy 98.228176 -206.898374) (xy 98.213266 -206.888586)
			(xy 98.195895 -206.884538) (xy 98.187002 -206.885286) (xy 98.09861 -206.896208) (xy 98.089815 -206.897692)
			(xy 98.073962 -206.905844) (xy 98.061816 -206.918892) (xy 98.05797 -206.926942) (xy 98.05797 -206.927196)
			(xy 98.046802 -206.95306) (xy 98.017965 -207.001455) (xy 97.982323 -207.045081) (xy 97.94065 -207.08299)
			(xy 97.893854 -207.114355) (xy 97.842953 -207.138495) (xy 97.789055 -207.154885) (xy 97.733332 -207.163167)
			(xy 97.705164 -207.16367) (xy 97.676248 -207.163117) (xy 97.619078 -207.154397) (xy 97.563879 -207.137147)
			(xy 97.511917 -207.111762) (xy 97.464383 -207.078824) (xy 97.422365 -207.039087) (xy 97.404174 -207.016604)
			(xy 97.396808 -207.006952) (xy 97.375472 -206.996792) (xy 97.270062 -206.998316) (xy 97.24898 -207.009238)
			(xy 97.242122 -207.01889) (xy 97.22402 -207.04264) (xy 97.181629 -207.084695) (xy 97.133208 -207.119639)
			(xy 97.079938 -207.14662) (xy 97.023117 -207.16498) (xy 96.964131 -207.174271) (xy 96.934274 -207.174846)
			(xy 96.907027 -207.174282) (xy 96.853087 -207.166523) (xy 96.800801 -207.151167) (xy 96.751232 -207.128527)
			(xy 96.705389 -207.099063) (xy 96.664206 -207.063375) (xy 96.628521 -207.02219) (xy 96.59906 -206.976345)
			(xy 96.576423 -206.926775) (xy 96.561071 -206.874487) (xy 96.553316 -206.820547) (xy 94.635633 -206.820547)
			(xy 94.665144 -206.853483) (xy 94.695917 -206.899996) (xy 94.719589 -206.950493) (xy 94.735657 -207.0039)
			(xy 94.743777 -207.059076) (xy 94.744286 -207.086962) (xy 94.743777 -207.114848) (xy 94.735657 -207.170024)
			(xy 94.719589 -207.223431) (xy 94.695917 -207.273928) (xy 94.665144 -207.320441) (xy 94.627927 -207.361978)
			(xy 94.585059 -207.397653) (xy 94.537453 -207.426707) (xy 94.486124 -207.448519) (xy 94.432167 -207.462625)
			(xy 94.37673 -207.468725) (xy 94.320996 -207.466688) (xy 94.266153 -207.456558) (xy 94.213369 -207.438551)
			(xy 94.163769 -207.41305) (xy 94.118411 -207.380599) (xy 94.078262 -207.34189) (xy 94.044176 -207.297747)
			(xy 94.01688 -207.249112) (xy 93.996957 -207.197021) (xy 93.984831 -207.142584) (xy 93.98076 -207.086962)
			(xy 93.264038 -207.086962) (xy 93.258393 -207.12532) (xy 93.242325 -207.178727) (xy 93.218653 -207.229224)
			(xy 93.18788 -207.275737) (xy 93.150663 -207.317274) (xy 93.107795 -207.352949) (xy 93.060189 -207.382003)
			(xy 93.00886 -207.403815) (xy 92.954903 -207.417921) (xy 92.899466 -207.424021) (xy 92.843732 -207.421984)
			(xy 92.788889 -207.411854) (xy 92.736105 -207.393847) (xy 92.686505 -207.368346) (xy 92.641147 -207.335895)
			(xy 92.600998 -207.297186) (xy 92.566912 -207.253043) (xy 92.539616 -207.204408) (xy 92.519693 -207.152317)
			(xy 92.507567 -207.09788) (xy 92.503496 -207.042258) (xy 92.329408 -207.042258) (xy 92.315479 -207.088557)
			(xy 92.291807 -207.139054) (xy 92.261034 -207.185567) (xy 92.223817 -207.227104) (xy 92.180949 -207.262779)
			(xy 92.133343 -207.291833) (xy 92.082014 -207.313645) (xy 92.028057 -207.327751) (xy 91.97262 -207.333851)
			(xy 91.916886 -207.331814) (xy 91.862043 -207.321684) (xy 91.809259 -207.303677) (xy 91.759659 -207.278176)
			(xy 91.714301 -207.245725) (xy 91.674152 -207.207016) (xy 91.640066 -207.162873) (xy 91.61277 -207.114238)
			(xy 91.592847 -207.062147) (xy 91.580721 -207.00771) (xy 91.57665 -206.952088) (xy 70.199971 -206.952088)
			(xy 69.966586 -208.292192) (xy 69.968364 -208.30667) (xy 69.971412 -208.313782) (xy 69.980812 -208.336772)
			(xy 69.994262 -208.384584) (xy 70.001407 -208.433736) (xy 70.002146 -208.458562) (xy 70.002146 -208.46415)
			(xy 70.000622 -208.497678) (xy 69.999352 -208.509108) (xy 69.995241 -208.538933) (xy 69.978856 -208.596865)
			(xy 69.953595 -208.651512) (xy 69.92008 -208.701525) (xy 69.900038 -208.723992) (xy 69.89445 -208.729834)
			(xy 69.891148 -208.736692) (xy 69.887084 -208.749646) (xy 69.751956 -209.526124) (xy 69.62775 -210.238594)
			(xy 69.591682 -210.445604) (xy 69.564758 -210.599782) (xy 69.563628 -210.608246) (xy 69.566439 -210.625078)
			(xy 69.574659 -210.640033) (xy 69.58076 -210.64601) (xy 69.615304 -210.677506) (xy 69.62013 -210.681316)
			(xy 69.628004 -210.686904) (xy 69.628258 -210.686904) (xy 69.635077 -210.69109) (xy 69.650484 -210.695373)
			(xy 69.658484 -210.695286) (xy 69.670422 -210.693762) (xy 69.673724 -210.693) (xy 69.674486 -210.692746)
			(xy 69.698433 -210.686814) (xy 69.747355 -210.680439) (xy 69.772022 -210.680046) (xy 69.773038 -210.680046)
			(xy 69.800289 -210.680534) (xy 69.854235 -210.688295) (xy 69.906528 -210.703653) (xy 69.956103 -210.726296)
			(xy 70.001952 -210.755762) (xy 70.043141 -210.791453) (xy 70.078833 -210.832642) (xy 70.108301 -210.87849)
			(xy 70.130944 -210.928065) (xy 70.146303 -210.980357) (xy 70.154065 -211.034303) (xy 70.154546 -211.061554)
			(xy 70.154072 -211.088585) (xy 70.146434 -211.142104) (xy 70.131317 -211.194009) (xy 70.109025 -211.24326)
			(xy 70.104723 -211.250022) (xy 104.08031 -211.250022) (xy 104.080787 -211.222652) (xy 104.088601 -211.168473)
			(xy 104.104088 -211.11597) (xy 104.126927 -211.066223) (xy 104.15665 -211.020256) (xy 104.17429 -210.999324)
			(xy 104.174544 -210.99907) (xy 104.180113 -210.991971) (xy 104.186369 -210.975064) (xy 104.186736 -210.96605)
			(xy 104.186736 -210.898994) (xy 104.186374 -210.889978) (xy 104.180129 -210.873061) (xy 104.174544 -210.865974)
			(xy 104.17429 -210.865974) (xy 104.17429 -210.86572) (xy 104.156645 -210.844793) (xy 104.126935 -210.798818)
			(xy 104.1041 -210.74907) (xy 104.08861 -210.696568) (xy 104.080783 -210.642391) (xy 104.08031 -210.615022)
			(xy 104.080776 -210.587769) (xy 104.08853 -210.533817) (xy 104.103884 -210.481518) (xy 104.126526 -210.431937)
			(xy 104.155993 -210.386083) (xy 104.191687 -210.344889) (xy 104.23288 -210.309195) (xy 104.278733 -210.279728)
			(xy 104.328314 -210.257086) (xy 104.380613 -210.241731) (xy 104.434565 -210.233976) (xy 104.461818 -210.233514)
			(xy 104.489189 -210.233966) (xy 104.543369 -210.241787) (xy 104.595872 -210.257279) (xy 104.645619 -210.280124)
			(xy 104.691585 -210.309851) (xy 104.712516 -210.327494) (xy 104.71277 -210.327748) (xy 104.719857 -210.333334)
			(xy 104.736774 -210.33958) (xy 104.74579 -210.33994) (xy 104.812846 -210.33994) (xy 104.821862 -210.33957)
			(xy 104.83878 -210.333333) (xy 104.845866 -210.327748) (xy 104.845866 -210.327494) (xy 104.84612 -210.327494)
			(xy 104.867053 -210.309853) (xy 104.913021 -210.280129) (xy 104.962767 -210.257283) (xy 105.015269 -210.241787)
			(xy 105.069447 -210.233958) (xy 105.124189 -210.233958) (xy 105.178367 -210.241787) (xy 105.230869 -210.257283)
			(xy 105.280615 -210.280129) (xy 105.326583 -210.309853) (xy 105.347516 -210.327494) (xy 105.34777 -210.327748)
			(xy 105.354857 -210.333334) (xy 105.371774 -210.33958) (xy 105.38079 -210.33994) (xy 105.447846 -210.33994)
			(xy 105.456862 -210.33957) (xy 105.47378 -210.333333) (xy 105.480866 -210.327748) (xy 105.480866 -210.327494)
			(xy 105.48112 -210.327494) (xy 105.502071 -210.309878) (xy 105.548038 -210.280163) (xy 105.597781 -210.257323)
			(xy 105.650278 -210.241826) (xy 105.70445 -210.233992) (xy 105.731818 -210.233514) (xy 105.759072 -210.233938)
			(xy 105.813026 -210.241698) (xy 105.865326 -210.257058) (xy 105.914908 -210.279704) (xy 105.960762 -210.309176)
			(xy 106.001955 -210.344874) (xy 106.037648 -210.38607) (xy 106.067115 -210.431928) (xy 106.089756 -210.481512)
			(xy 106.10511 -210.533813) (xy 106.112865 -210.587768) (xy 106.113326 -210.615022) (xy 106.112891 -210.642394)
			(xy 106.105068 -210.696575) (xy 106.089573 -210.749079) (xy 106.066724 -210.798825) (xy 106.036991 -210.84479)
			(xy 106.019346 -210.86572) (xy 106.019092 -210.865974) (xy 106.013509 -210.873063) (xy 106.007261 -210.889978)
			(xy 106.0069 -210.898994) (xy 106.0069 -210.96605) (xy 106.007281 -210.975064) (xy 106.013512 -210.991981)
			(xy 106.019092 -210.99907) (xy 106.019346 -210.99907) (xy 106.019346 -210.999324) (xy 106.036955 -211.020281)
			(xy 106.066673 -211.066246) (xy 106.089516 -211.115987) (xy 106.105014 -211.168483) (xy 106.112849 -211.222654)
			(xy 106.113326 -211.250022) (xy 106.112843 -211.277273) (xy 106.105084 -211.33122) (xy 106.089727 -211.383514)
			(xy 106.067084 -211.43309) (xy 106.037617 -211.478939) (xy 106.001926 -211.520129) (xy 105.960736 -211.55582)
			(xy 105.914886 -211.585286) (xy 105.86531 -211.607928) (xy 105.813016 -211.623285) (xy 105.759069 -211.631043)
			(xy 105.731818 -211.63153) (xy 105.704447 -211.63107) (xy 105.650267 -211.623254) (xy 105.597763 -211.607764)
			(xy 105.548017 -211.58492) (xy 105.502051 -211.555193) (xy 105.48112 -211.53755) (xy 105.480866 -211.537296)
			(xy 105.473765 -211.53173) (xy 105.456859 -211.525471) (xy 105.447846 -211.525104) (xy 105.38079 -211.525104)
			(xy 105.371773 -211.525455) (xy 105.354856 -211.531707) (xy 105.34777 -211.537296) (xy 105.347516 -211.53755)
			(xy 105.326583 -211.555191) (xy 105.280615 -211.584915) (xy 105.230869 -211.607761) (xy 105.178367 -211.623257)
			(xy 105.124189 -211.631086) (xy 105.069447 -211.631086) (xy 105.015269 -211.623257) (xy 104.962767 -211.607761)
			(xy 104.913021 -211.584915) (xy 104.867053 -211.555191) (xy 104.84612 -211.53755) (xy 104.845866 -211.537296)
			(xy 104.838765 -211.53173) (xy 104.821859 -211.525471) (xy 104.812846 -211.525104) (xy 104.74579 -211.525104)
			(xy 104.736773 -211.525455) (xy 104.719856 -211.531707) (xy 104.71277 -211.537296) (xy 104.71277 -211.53755)
			(xy 104.712516 -211.53755) (xy 104.691582 -211.555187) (xy 104.645611 -211.584901) (xy 104.595864 -211.607738)
			(xy 104.543363 -211.623229) (xy 104.489187 -211.631057) (xy 104.461818 -211.63153) (xy 104.434568 -211.631005)
			(xy 104.380623 -211.623252) (xy 104.32833 -211.6079) (xy 104.278755 -211.585262) (xy 104.232905 -211.5558)
			(xy 104.191716 -211.520113) (xy 104.156024 -211.478927) (xy 104.126557 -211.43308) (xy 104.103914 -211.383507)
			(xy 104.088557 -211.331216) (xy 104.080798 -211.277272) (xy 104.08031 -211.250022) (xy 70.104723 -211.250022)
			(xy 70.080004 -211.288872) (xy 70.044836 -211.329931) (xy 70.004224 -211.365614) (xy 69.958981 -211.395207)
			(xy 69.910015 -211.418118) (xy 69.858304 -211.433888) (xy 69.804886 -211.442201) (xy 69.777864 -211.443062)
			(xy 69.77253 -211.443062) (xy 69.743899 -211.442529) (xy 69.687285 -211.433929) (xy 69.632593 -211.416965)
			(xy 69.581051 -211.392015) (xy 69.557138 -211.37626) (xy 69.554852 -211.374482) (xy 69.5452 -211.369148)
			(xy 69.541135 -211.367064) (xy 69.532443 -211.364257) (xy 69.527928 -211.36356) (xy 69.525642 -211.363306)
			(xy 69.520743 -211.363132) (xy 69.511024 -211.364406) (xy 69.506338 -211.365846) (xy 69.472556 -211.379816)
			(xy 69.454014 -211.387436) (xy 69.453506 -211.38769) (xy 69.450458 -211.38896) (xy 69.439416 -211.39456)
			(xy 69.424131 -211.414001) (xy 69.421248 -211.426044) (xy 69.240881 -212.461348) (xy 90.60256 -212.461348)
			(xy 90.606631 -212.405726) (xy 90.618757 -212.351289) (xy 90.63868 -212.299198) (xy 90.665976 -212.250563)
			(xy 90.700062 -212.20642) (xy 90.740211 -212.167711) (xy 90.785569 -212.13526) (xy 90.835169 -212.109759)
			(xy 90.887953 -212.091752) (xy 90.942796 -212.081622) (xy 90.99853 -212.079585) (xy 91.053967 -212.085685)
			(xy 91.107924 -212.099791) (xy 91.159253 -212.121603) (xy 91.206859 -212.150657) (xy 91.249727 -212.186332)
			(xy 91.286944 -212.227869) (xy 91.317717 -212.274382) (xy 91.341389 -212.324879) (xy 91.357457 -212.378286)
			(xy 91.365577 -212.433462) (xy 91.366086 -212.461348) (xy 91.365577 -212.489234) (xy 91.357457 -212.54441)
			(xy 91.341389 -212.597817) (xy 91.317717 -212.648314) (xy 91.286944 -212.694827) (xy 91.249727 -212.736364)
			(xy 91.206859 -212.772039) (xy 91.159253 -212.801093) (xy 91.107924 -212.822905) (xy 91.053967 -212.837011)
			(xy 90.99853 -212.843111) (xy 90.942796 -212.841074) (xy 90.887953 -212.830944) (xy 90.835169 -212.812937)
			(xy 90.785569 -212.787436) (xy 90.740211 -212.754985) (xy 90.700062 -212.716276) (xy 90.665976 -212.672133)
			(xy 90.63868 -212.623498) (xy 90.618757 -212.571407) (xy 90.606631 -212.51697) (xy 90.60256 -212.461348)
			(xy 69.240881 -212.461348) (xy 68.735888 -215.359996) (xy 69.499224 -215.359996) (xy 69.503295 -215.304374)
			(xy 69.515421 -215.249937) (xy 69.535344 -215.197846) (xy 69.56264 -215.149211) (xy 69.596726 -215.105068)
			(xy 69.636875 -215.066359) (xy 69.682233 -215.033908) (xy 69.731833 -215.008407) (xy 69.784617 -214.9904)
			(xy 69.83946 -214.98027) (xy 69.895194 -214.978233) (xy 69.950631 -214.984333) (xy 70.004588 -214.998439)
			(xy 70.055917 -215.020251) (xy 70.103523 -215.049305) (xy 70.146391 -215.08498) (xy 70.164311 -215.10498)
			(xy 117.322598 -215.10498) (xy 117.326669 -215.049358) (xy 117.338795 -214.994921) (xy 117.358718 -214.94283)
			(xy 117.386014 -214.894195) (xy 117.4201 -214.850052) (xy 117.460249 -214.811343) (xy 117.505607 -214.778892)
			(xy 117.555207 -214.753391) (xy 117.607991 -214.735384) (xy 117.662834 -214.725254) (xy 117.718568 -214.723217)
			(xy 117.774005 -214.729317) (xy 117.827962 -214.743423) (xy 117.879291 -214.765235) (xy 117.926897 -214.794289)
			(xy 117.969765 -214.829964) (xy 118.006982 -214.871501) (xy 118.037755 -214.918014) (xy 118.061427 -214.968511)
			(xy 118.077495 -215.021918) (xy 118.085615 -215.077094) (xy 118.086124 -215.10498) (xy 118.085615 -215.132866)
			(xy 118.077495 -215.188042) (xy 118.061427 -215.241449) (xy 118.037755 -215.291946) (xy 118.006982 -215.338459)
			(xy 117.969765 -215.379996) (xy 117.926897 -215.415671) (xy 117.879291 -215.444725) (xy 117.827962 -215.466537)
			(xy 117.774005 -215.480643) (xy 117.718568 -215.486743) (xy 117.662834 -215.484706) (xy 117.607991 -215.474576)
			(xy 117.555207 -215.456569) (xy 117.505607 -215.431068) (xy 117.460249 -215.398617) (xy 117.4201 -215.359908)
			(xy 117.386014 -215.315765) (xy 117.358718 -215.26713) (xy 117.338795 -215.215039) (xy 117.326669 -215.160602)
			(xy 117.322598 -215.10498) (xy 70.164311 -215.10498) (xy 70.183608 -215.126517) (xy 70.214381 -215.17303)
			(xy 70.238053 -215.223527) (xy 70.254121 -215.276934) (xy 70.262241 -215.33211) (xy 70.26275 -215.359996)
			(xy 70.262241 -215.387882) (xy 70.254121 -215.443058) (xy 70.238053 -215.496465) (xy 70.214381 -215.546962)
			(xy 70.183608 -215.593475) (xy 70.146391 -215.635012) (xy 70.103523 -215.670687) (xy 70.055917 -215.699741)
			(xy 70.004588 -215.721553) (xy 69.950631 -215.735659) (xy 69.895194 -215.741759) (xy 69.83946 -215.739722)
			(xy 69.784617 -215.729592) (xy 69.731833 -215.711585) (xy 69.682233 -215.686084) (xy 69.636875 -215.653633)
			(xy 69.596726 -215.614924) (xy 69.56264 -215.570781) (xy 69.535344 -215.522146) (xy 69.515421 -215.470055)
			(xy 69.503295 -215.415618) (xy 69.499224 -215.359996) (xy 68.735888 -215.359996) (xy 68.668848 -215.744806)
			(xy 125.525782 -215.744806) (xy 125.529853 -215.689184) (xy 125.541979 -215.634747) (xy 125.561902 -215.582656)
			(xy 125.589198 -215.534021) (xy 125.623284 -215.489878) (xy 125.663433 -215.451169) (xy 125.708791 -215.418718)
			(xy 125.758391 -215.393217) (xy 125.811175 -215.37521) (xy 125.866018 -215.36508) (xy 125.921752 -215.363043)
			(xy 125.977189 -215.369143) (xy 126.031146 -215.383249) (xy 126.082475 -215.405061) (xy 126.130081 -215.434115)
			(xy 126.172949 -215.46979) (xy 126.210166 -215.511327) (xy 126.240939 -215.55784) (xy 126.264611 -215.608337)
			(xy 126.280679 -215.661744) (xy 126.288799 -215.71692) (xy 126.289308 -215.744806) (xy 126.288799 -215.772692)
			(xy 126.280679 -215.827868) (xy 126.264611 -215.881275) (xy 126.240939 -215.931772) (xy 126.210166 -215.978285)
			(xy 126.172949 -216.019822) (xy 126.130081 -216.055497) (xy 126.082475 -216.084551) (xy 126.031146 -216.106363)
			(xy 125.977189 -216.120469) (xy 125.921752 -216.126569) (xy 125.866018 -216.124532) (xy 125.811175 -216.114402)
			(xy 125.758391 -216.096395) (xy 125.708791 -216.070894) (xy 125.663433 -216.038443) (xy 125.623284 -215.999734)
			(xy 125.589198 -215.955591) (xy 125.561902 -215.906956) (xy 125.541979 -215.854865) (xy 125.529853 -215.800428)
			(xy 125.525782 -215.744806) (xy 68.668848 -215.744806) (xy 68.578222 -216.264998) (xy 68.577092 -216.274235)
			(xy 68.58073 -216.292471) (xy 68.585334 -216.300558) (xy 68.59016 -216.308432) (xy 68.604384 -216.319354)
			(xy 68.613782 -216.322148) (xy 68.639594 -216.330421) (xy 68.688757 -216.353245) (xy 68.734195 -216.382796)
			(xy 68.774994 -216.41848) (xy 68.810333 -216.459578) (xy 68.839501 -216.505263) (xy 68.86191 -216.554616)
			(xy 68.87711 -216.606644) (xy 68.884794 -216.660299) (xy 68.885308 -216.6874) (xy 68.884822 -216.714651)
			(xy 68.877066 -216.768599) (xy 68.861711 -216.820894) (xy 68.839069 -216.870471) (xy 68.809603 -216.916321)
			(xy 68.773912 -216.957512) (xy 68.732721 -216.993203) (xy 68.686871 -217.022669) (xy 68.637294 -217.045311)
			(xy 68.584999 -217.060666) (xy 68.531051 -217.068422) (xy 68.5038 -217.068908) (xy 68.503292 -217.068908)
			(xy 68.483734 -217.0684) (xy 68.48094 -217.0684) (xy 68.469722 -217.069039) (xy 68.449456 -217.078677)
			(xy 68.435204 -217.096012) (xy 68.431918 -217.106754) (xy 68.176035 -218.57589) (xy 97.01733 -218.57589)
			(xy 97.021401 -218.520268) (xy 97.033527 -218.465831) (xy 97.05345 -218.41374) (xy 97.080746 -218.365105)
			(xy 97.114832 -218.320962) (xy 97.154981 -218.282253) (xy 97.200339 -218.249802) (xy 97.249939 -218.224301)
			(xy 97.302723 -218.206294) (xy 97.357566 -218.196164) (xy 97.4133 -218.194127) (xy 97.468737 -218.200227)
			(xy 97.522694 -218.214333) (xy 97.574023 -218.236145) (xy 97.621629 -218.265199) (xy 97.664497 -218.300874)
			(xy 97.701714 -218.342411) (xy 97.732487 -218.388924) (xy 97.756159 -218.439421) (xy 97.772227 -218.492828)
			(xy 97.780347 -218.548004) (xy 97.780856 -218.57589) (xy 97.780347 -218.603776) (xy 97.772227 -218.658952)
			(xy 97.756159 -218.712359) (xy 97.732487 -218.762856) (xy 97.701714 -218.809369) (xy 97.664497 -218.850906)
			(xy 97.621629 -218.886581) (xy 97.574023 -218.915635) (xy 97.522694 -218.937447) (xy 97.511475 -218.94038)
			(xy 117.85295 -218.94038) (xy 117.857021 -218.884758) (xy 117.869147 -218.830321) (xy 117.88907 -218.77823)
			(xy 117.916366 -218.729595) (xy 117.950452 -218.685452) (xy 117.990601 -218.646743) (xy 118.035959 -218.614292)
			(xy 118.085559 -218.588791) (xy 118.138343 -218.570784) (xy 118.193186 -218.560654) (xy 118.24892 -218.558617)
			(xy 118.304357 -218.564717) (xy 118.358314 -218.578823) (xy 118.409643 -218.600635) (xy 118.457249 -218.629689)
			(xy 118.478062 -218.64701) (xy 120.921778 -218.64701) (xy 120.925849 -218.591388) (xy 120.937975 -218.536951)
			(xy 120.957898 -218.48486) (xy 120.985194 -218.436225) (xy 121.01928 -218.392082) (xy 121.059429 -218.353373)
			(xy 121.104787 -218.320922) (xy 121.154387 -218.295421) (xy 121.207171 -218.277414) (xy 121.262014 -218.267284)
			(xy 121.317748 -218.265247) (xy 121.373185 -218.271347) (xy 121.376088 -218.272106) (xy 124.257306 -218.272106)
			(xy 124.261377 -218.216484) (xy 124.273503 -218.162047) (xy 124.293426 -218.109956) (xy 124.320722 -218.061321)
			(xy 124.354808 -218.017178) (xy 124.394957 -217.978469) (xy 124.440315 -217.946018) (xy 124.489915 -217.920517)
			(xy 124.542699 -217.90251) (xy 124.597542 -217.89238) (xy 124.653276 -217.890343) (xy 124.708713 -217.896443)
			(xy 124.76267 -217.910549) (xy 124.813999 -217.932361) (xy 124.861605 -217.961415) (xy 124.904473 -217.99709)
			(xy 124.94169 -218.038627) (xy 124.972463 -218.08514) (xy 124.996135 -218.135637) (xy 125.012203 -218.189044)
			(xy 125.020323 -218.24422) (xy 125.020832 -218.272106) (xy 125.020323 -218.299992) (xy 125.012203 -218.355168)
			(xy 124.996135 -218.408575) (xy 124.972463 -218.459072) (xy 124.94169 -218.505585) (xy 124.904473 -218.547122)
			(xy 124.861605 -218.582797) (xy 124.813999 -218.611851) (xy 124.76267 -218.633663) (xy 124.708713 -218.647769)
			(xy 124.653276 -218.653869) (xy 124.597542 -218.651832) (xy 124.542699 -218.641702) (xy 124.489915 -218.623695)
			(xy 124.440315 -218.598194) (xy 124.394957 -218.565743) (xy 124.354808 -218.527034) (xy 124.320722 -218.482891)
			(xy 124.293426 -218.434256) (xy 124.273503 -218.382165) (xy 124.261377 -218.327728) (xy 124.257306 -218.272106)
			(xy 121.376088 -218.272106) (xy 121.427142 -218.285453) (xy 121.478471 -218.307265) (xy 121.526077 -218.336319)
			(xy 121.568945 -218.371994) (xy 121.606162 -218.413531) (xy 121.636935 -218.460044) (xy 121.660607 -218.510541)
			(xy 121.676675 -218.563948) (xy 121.684795 -218.619124) (xy 121.685304 -218.64701) (xy 121.684795 -218.674896)
			(xy 121.676675 -218.730072) (xy 121.660607 -218.783479) (xy 121.636935 -218.833976) (xy 121.606162 -218.880489)
			(xy 121.568945 -218.922026) (xy 121.526077 -218.957701) (xy 121.478471 -218.986755) (xy 121.427142 -219.008567)
			(xy 121.373185 -219.022673) (xy 121.317748 -219.028773) (xy 121.262014 -219.026736) (xy 121.207171 -219.016606)
			(xy 121.154387 -218.998599) (xy 121.104787 -218.973098) (xy 121.059429 -218.940647) (xy 121.01928 -218.901938)
			(xy 120.985194 -218.857795) (xy 120.957898 -218.80916) (xy 120.937975 -218.757069) (xy 120.925849 -218.702632)
			(xy 120.921778 -218.64701) (xy 118.478062 -218.64701) (xy 118.500117 -218.665364) (xy 118.537334 -218.706901)
			(xy 118.568107 -218.753414) (xy 118.591779 -218.803911) (xy 118.607847 -218.857318) (xy 118.615967 -218.912494)
			(xy 118.616476 -218.94038) (xy 118.615967 -218.968266) (xy 118.607847 -219.023442) (xy 118.591779 -219.076849)
			(xy 118.568107 -219.127346) (xy 118.537334 -219.173859) (xy 118.500117 -219.215396) (xy 118.457249 -219.251071)
			(xy 118.409643 -219.280125) (xy 118.358314 -219.301937) (xy 118.304357 -219.316043) (xy 118.24892 -219.322143)
			(xy 118.193186 -219.320106) (xy 118.138343 -219.309976) (xy 118.085559 -219.291969) (xy 118.035959 -219.266468)
			(xy 117.990601 -219.234017) (xy 117.950452 -219.195308) (xy 117.916366 -219.151165) (xy 117.88907 -219.10253)
			(xy 117.869147 -219.050439) (xy 117.857021 -218.996002) (xy 117.85295 -218.94038) (xy 97.511475 -218.94038)
			(xy 97.468737 -218.951553) (xy 97.4133 -218.957653) (xy 97.357566 -218.955616) (xy 97.302723 -218.945486)
			(xy 97.249939 -218.927479) (xy 97.200339 -218.901978) (xy 97.154981 -218.869527) (xy 97.114832 -218.830818)
			(xy 97.080746 -218.786675) (xy 97.05345 -218.73804) (xy 97.033527 -218.685949) (xy 97.021401 -218.631512)
			(xy 97.01733 -218.57589) (xy 68.176035 -218.57589) (xy 68.005048 -219.5576) (xy 69.569582 -219.5576)
			(xy 69.573653 -219.501978) (xy 69.585779 -219.447541) (xy 69.605702 -219.39545) (xy 69.632998 -219.346815)
			(xy 69.667084 -219.302672) (xy 69.707233 -219.263963) (xy 69.752591 -219.231512) (xy 69.802191 -219.206011)
			(xy 69.854975 -219.188004) (xy 69.909818 -219.177874) (xy 69.965552 -219.175837) (xy 70.020989 -219.181937)
			(xy 70.074946 -219.196043) (xy 70.126275 -219.217855) (xy 70.173881 -219.246909) (xy 70.216749 -219.282584)
			(xy 70.253966 -219.324121) (xy 70.284739 -219.370634) (xy 70.308411 -219.421131) (xy 70.324479 -219.474538)
			(xy 70.332599 -219.529714) (xy 70.333108 -219.5576) (xy 70.333071 -219.559632) (xy 97.811588 -219.559632)
			(xy 97.815659 -219.50401) (xy 97.827785 -219.449573) (xy 97.847708 -219.397482) (xy 97.875004 -219.348847)
			(xy 97.90909 -219.304704) (xy 97.949239 -219.265995) (xy 97.994597 -219.233544) (xy 98.044197 -219.208043)
			(xy 98.096981 -219.190036) (xy 98.151824 -219.179906) (xy 98.207558 -219.177869) (xy 98.262995 -219.183969)
			(xy 98.316952 -219.198075) (xy 98.368281 -219.219887) (xy 98.415887 -219.248941) (xy 98.458755 -219.284616)
			(xy 98.495972 -219.326153) (xy 98.526745 -219.372666) (xy 98.550417 -219.423163) (xy 98.566485 -219.47657)
			(xy 98.574605 -219.531746) (xy 98.575114 -219.559632) (xy 98.575109 -219.559886) (xy 100.279706 -219.559886)
			(xy 100.283777 -219.504264) (xy 100.295903 -219.449827) (xy 100.315826 -219.397736) (xy 100.343122 -219.349101)
			(xy 100.377208 -219.304958) (xy 100.417357 -219.266249) (xy 100.462715 -219.233798) (xy 100.512315 -219.208297)
			(xy 100.565099 -219.19029) (xy 100.619942 -219.18016) (xy 100.675676 -219.178123) (xy 100.731113 -219.184223)
			(xy 100.78507 -219.198329) (xy 100.836399 -219.220141) (xy 100.884005 -219.249195) (xy 100.926873 -219.28487)
			(xy 100.96409 -219.326407) (xy 100.994863 -219.37292) (xy 101.018535 -219.423417) (xy 101.034603 -219.476824)
			(xy 101.042723 -219.532) (xy 101.043223 -219.559378) (xy 102.352854 -219.559378) (xy 102.356925 -219.503756)
			(xy 102.369051 -219.449319) (xy 102.388974 -219.397228) (xy 102.41627 -219.348593) (xy 102.450356 -219.30445)
			(xy 102.490505 -219.265741) (xy 102.535863 -219.23329) (xy 102.585463 -219.207789) (xy 102.638247 -219.189782)
			(xy 102.69309 -219.179652) (xy 102.748824 -219.177615) (xy 102.804261 -219.183715) (xy 102.858218 -219.197821)
			(xy 102.909547 -219.219633) (xy 102.957153 -219.248687) (xy 103.000021 -219.284362) (xy 103.037238 -219.325899)
			(xy 103.068011 -219.372412) (xy 103.091683 -219.422909) (xy 103.107751 -219.476316) (xy 103.115871 -219.531492)
			(xy 103.11638 -219.559378) (xy 103.115871 -219.587264) (xy 103.107751 -219.64244) (xy 103.091683 -219.695847)
			(xy 103.068011 -219.746344) (xy 103.037238 -219.792857) (xy 103.000021 -219.834394) (xy 102.957153 -219.870069)
			(xy 102.909547 -219.899123) (xy 102.858218 -219.920935) (xy 102.804261 -219.935041) (xy 102.748824 -219.941141)
			(xy 102.69309 -219.939104) (xy 102.638247 -219.928974) (xy 102.585463 -219.910967) (xy 102.535863 -219.885466)
			(xy 102.490505 -219.853015) (xy 102.450356 -219.814306) (xy 102.41627 -219.770163) (xy 102.388974 -219.721528)
			(xy 102.369051 -219.669437) (xy 102.356925 -219.615) (xy 102.352854 -219.559378) (xy 101.043223 -219.559378)
			(xy 101.043232 -219.559886) (xy 101.042723 -219.587772) (xy 101.034603 -219.642948) (xy 101.018535 -219.696355)
			(xy 100.994863 -219.746852) (xy 100.96409 -219.793365) (xy 100.926873 -219.834902) (xy 100.884005 -219.870577)
			(xy 100.836399 -219.899631) (xy 100.78507 -219.921443) (xy 100.731113 -219.935549) (xy 100.675676 -219.941649)
			(xy 100.619942 -219.939612) (xy 100.565099 -219.929482) (xy 100.512315 -219.911475) (xy 100.462715 -219.885974)
			(xy 100.417357 -219.853523) (xy 100.377208 -219.814814) (xy 100.343122 -219.770671) (xy 100.315826 -219.722036)
			(xy 100.295903 -219.669945) (xy 100.283777 -219.615508) (xy 100.279706 -219.559886) (xy 98.575109 -219.559886)
			(xy 98.574605 -219.587518) (xy 98.566485 -219.642694) (xy 98.550417 -219.696101) (xy 98.526745 -219.746598)
			(xy 98.495972 -219.793111) (xy 98.458755 -219.834648) (xy 98.415887 -219.870323) (xy 98.368281 -219.899377)
			(xy 98.316952 -219.921189) (xy 98.262995 -219.935295) (xy 98.207558 -219.941395) (xy 98.151824 -219.939358)
			(xy 98.096981 -219.929228) (xy 98.044197 -219.911221) (xy 97.994597 -219.88572) (xy 97.949239 -219.853269)
			(xy 97.90909 -219.81456) (xy 97.875004 -219.770417) (xy 97.847708 -219.721782) (xy 97.827785 -219.669691)
			(xy 97.815659 -219.615254) (xy 97.811588 -219.559632) (xy 70.333071 -219.559632) (xy 70.332599 -219.585486)
			(xy 70.324479 -219.640662) (xy 70.308411 -219.694069) (xy 70.284739 -219.744566) (xy 70.253966 -219.791079)
			(xy 70.216749 -219.832616) (xy 70.173881 -219.868291) (xy 70.126275 -219.897345) (xy 70.074946 -219.919157)
			(xy 70.020989 -219.933263) (xy 69.965552 -219.939363) (xy 69.909818 -219.937326) (xy 69.854975 -219.927196)
			(xy 69.802191 -219.909189) (xy 69.752591 -219.883688) (xy 69.707233 -219.851237) (xy 69.667084 -219.812528)
			(xy 69.632998 -219.768385) (xy 69.605702 -219.71975) (xy 69.585779 -219.667659) (xy 69.573653 -219.613222)
			(xy 69.569582 -219.5576) (xy 68.005048 -219.5576) (xy 67.750624 -221.018354) (xy 96.817432 -221.018354)
			(xy 96.821503 -220.962732) (xy 96.833629 -220.908295) (xy 96.853552 -220.856204) (xy 96.880848 -220.807569)
			(xy 96.914934 -220.763426) (xy 96.955083 -220.724717) (xy 97.000441 -220.692266) (xy 97.050041 -220.666765)
			(xy 97.102825 -220.648758) (xy 97.157668 -220.638628) (xy 97.213402 -220.636591) (xy 97.268839 -220.642691)
			(xy 97.322796 -220.656797) (xy 97.374125 -220.678609) (xy 97.421731 -220.707663) (xy 97.464599 -220.743338)
			(xy 97.501816 -220.784875) (xy 97.532589 -220.831388) (xy 97.556261 -220.881885) (xy 97.572329 -220.935292)
			(xy 97.580449 -220.990468) (xy 97.580958 -221.018354) (xy 97.580449 -221.04624) (xy 97.572329 -221.101416)
			(xy 97.558881 -221.146116) (xy 100.565456 -221.146116) (xy 100.569527 -221.090494) (xy 100.581653 -221.036057)
			(xy 100.601576 -220.983966) (xy 100.628872 -220.935331) (xy 100.662958 -220.891188) (xy 100.703107 -220.852479)
			(xy 100.748465 -220.820028) (xy 100.798065 -220.794527) (xy 100.850849 -220.77652) (xy 100.905692 -220.76639)
			(xy 100.961426 -220.764353) (xy 101.016863 -220.770453) (xy 101.07082 -220.784559) (xy 101.122149 -220.806371)
			(xy 101.169755 -220.835425) (xy 101.212623 -220.8711) (xy 101.24984 -220.912637) (xy 101.255253 -220.920818)
			(xy 102.937562 -220.920818) (xy 102.941633 -220.865196) (xy 102.953759 -220.810759) (xy 102.973682 -220.758668)
			(xy 103.000978 -220.710033) (xy 103.035064 -220.66589) (xy 103.075213 -220.627181) (xy 103.120571 -220.59473)
			(xy 103.170171 -220.569229) (xy 103.222955 -220.551222) (xy 103.277798 -220.541092) (xy 103.333532 -220.539055)
			(xy 103.388969 -220.545155) (xy 103.442926 -220.559261) (xy 103.494255 -220.581073) (xy 103.541861 -220.610127)
			(xy 103.584729 -220.645802) (xy 103.621946 -220.687339) (xy 103.652719 -220.733852) (xy 103.676391 -220.784349)
			(xy 103.692459 -220.837756) (xy 103.700579 -220.892932) (xy 103.701088 -220.920818) (xy 103.700579 -220.948704)
			(xy 103.692459 -221.00388) (xy 103.676391 -221.057287) (xy 103.672852 -221.064836) (xy 116.584474 -221.064836)
			(xy 116.588545 -221.009214) (xy 116.600671 -220.954777) (xy 116.620594 -220.902686) (xy 116.64789 -220.854051)
			(xy 116.681976 -220.809908) (xy 116.722125 -220.771199) (xy 116.767483 -220.738748) (xy 116.817083 -220.713247)
			(xy 116.869867 -220.69524) (xy 116.92471 -220.68511) (xy 116.980444 -220.683073) (xy 117.035881 -220.689173)
			(xy 117.089838 -220.703279) (xy 117.141167 -220.725091) (xy 117.188773 -220.754145) (xy 117.231641 -220.78982)
			(xy 117.268858 -220.831357) (xy 117.299631 -220.87787) (xy 117.323303 -220.928367) (xy 117.339371 -220.981774)
			(xy 117.347491 -221.03695) (xy 117.348 -221.064836) (xy 117.347491 -221.092722) (xy 117.339371 -221.147898)
			(xy 117.323303 -221.201305) (xy 117.299631 -221.251802) (xy 117.268858 -221.298315) (xy 117.231641 -221.339852)
			(xy 117.188773 -221.375527) (xy 117.141167 -221.404581) (xy 117.089838 -221.426393) (xy 117.035881 -221.440499)
			(xy 116.980444 -221.446599) (xy 116.92471 -221.444562) (xy 116.869867 -221.434432) (xy 116.817083 -221.416425)
			(xy 116.767483 -221.390924) (xy 116.722125 -221.358473) (xy 116.681976 -221.319764) (xy 116.64789 -221.275621)
			(xy 116.620594 -221.226986) (xy 116.600671 -221.174895) (xy 116.588545 -221.120458) (xy 116.584474 -221.064836)
			(xy 103.672852 -221.064836) (xy 103.652719 -221.107784) (xy 103.621946 -221.154297) (xy 103.584729 -221.195834)
			(xy 103.541861 -221.231509) (xy 103.494255 -221.260563) (xy 103.442926 -221.282375) (xy 103.388969 -221.296481)
			(xy 103.333532 -221.302581) (xy 103.277798 -221.300544) (xy 103.222955 -221.290414) (xy 103.170171 -221.272407)
			(xy 103.120571 -221.246906) (xy 103.075213 -221.214455) (xy 103.035064 -221.175746) (xy 103.000978 -221.131603)
			(xy 102.973682 -221.082968) (xy 102.953759 -221.030877) (xy 102.941633 -220.97644) (xy 102.937562 -220.920818)
			(xy 101.255253 -220.920818) (xy 101.280613 -220.95915) (xy 101.304285 -221.009647) (xy 101.320353 -221.063054)
			(xy 101.328473 -221.11823) (xy 101.328982 -221.146116) (xy 101.328473 -221.174002) (xy 101.320353 -221.229178)
			(xy 101.304285 -221.282585) (xy 101.280613 -221.333082) (xy 101.24984 -221.379595) (xy 101.212623 -221.421132)
			(xy 101.169755 -221.456807) (xy 101.122149 -221.485861) (xy 101.07082 -221.507673) (xy 101.016863 -221.521779)
			(xy 100.961426 -221.527879) (xy 100.905692 -221.525842) (xy 100.850849 -221.515712) (xy 100.798065 -221.497705)
			(xy 100.748465 -221.472204) (xy 100.703107 -221.439753) (xy 100.662958 -221.401044) (xy 100.628872 -221.356901)
			(xy 100.601576 -221.308266) (xy 100.581653 -221.256175) (xy 100.569527 -221.201738) (xy 100.565456 -221.146116)
			(xy 97.558881 -221.146116) (xy 97.556261 -221.154823) (xy 97.532589 -221.20532) (xy 97.501816 -221.251833)
			(xy 97.464599 -221.29337) (xy 97.421731 -221.329045) (xy 97.374125 -221.358099) (xy 97.322796 -221.379911)
			(xy 97.268839 -221.394017) (xy 97.213402 -221.400117) (xy 97.157668 -221.39808) (xy 97.102825 -221.38795)
			(xy 97.050041 -221.369943) (xy 97.000441 -221.344442) (xy 96.955083 -221.311991) (xy 96.914934 -221.273282)
			(xy 96.880848 -221.229139) (xy 96.853552 -221.180504) (xy 96.833629 -221.128413) (xy 96.821503 -221.073976)
			(xy 96.817432 -221.018354) (xy 67.750624 -221.018354) (xy 67.498722 -222.46463) (xy 99.334318 -222.46463)
			(xy 99.338389 -222.409008) (xy 99.350515 -222.354571) (xy 99.370438 -222.30248) (xy 99.397734 -222.253845)
			(xy 99.43182 -222.209702) (xy 99.471969 -222.170993) (xy 99.517327 -222.138542) (xy 99.566927 -222.113041)
			(xy 99.619711 -222.095034) (xy 99.674554 -222.084904) (xy 99.730288 -222.082867) (xy 99.785725 -222.088967)
			(xy 99.839682 -222.103073) (xy 99.891011 -222.124885) (xy 99.938617 -222.153939) (xy 99.981485 -222.189614)
			(xy 100.018702 -222.231151) (xy 100.049475 -222.277664) (xy 100.073147 -222.328161) (xy 100.089215 -222.381568)
			(xy 100.097335 -222.436744) (xy 100.097844 -222.46463) (xy 100.097335 -222.492516) (xy 100.089215 -222.547692)
			(xy 100.073147 -222.601099) (xy 100.049475 -222.651596) (xy 100.018702 -222.698109) (xy 99.981485 -222.739646)
			(xy 99.938617 -222.775321) (xy 99.891011 -222.804375) (xy 99.839682 -222.826187) (xy 99.785725 -222.840293)
			(xy 99.730288 -222.846393) (xy 99.674554 -222.844356) (xy 99.619711 -222.834226) (xy 99.566927 -222.816219)
			(xy 99.517327 -222.790718) (xy 99.471969 -222.758267) (xy 99.43182 -222.719558) (xy 99.397734 -222.675415)
			(xy 99.370438 -222.62678) (xy 99.350515 -222.574689) (xy 99.338389 -222.520252) (xy 99.334318 -222.46463)
			(xy 67.498722 -222.46463) (xy 67.38184 -223.135698) (xy 101.499414 -223.135698) (xy 101.503485 -223.080076)
			(xy 101.515611 -223.025639) (xy 101.535534 -222.973548) (xy 101.56283 -222.924913) (xy 101.596916 -222.88077)
			(xy 101.637065 -222.842061) (xy 101.682423 -222.80961) (xy 101.732023 -222.784109) (xy 101.784807 -222.766102)
			(xy 101.83965 -222.755972) (xy 101.895384 -222.753935) (xy 101.950821 -222.760035) (xy 102.004778 -222.774141)
			(xy 102.056107 -222.795953) (xy 102.103713 -222.825007) (xy 102.146581 -222.860682) (xy 102.183798 -222.902219)
			(xy 102.214571 -222.948732) (xy 102.238243 -222.999229) (xy 102.254311 -223.052636) (xy 102.262431 -223.107812)
			(xy 102.26294 -223.135698) (xy 102.262431 -223.163584) (xy 102.254311 -223.21876) (xy 102.238243 -223.272167)
			(xy 102.214571 -223.322664) (xy 102.183798 -223.369177) (xy 102.146581 -223.410714) (xy 102.103713 -223.446389)
			(xy 102.056107 -223.475443) (xy 102.004778 -223.497255) (xy 101.950821 -223.511361) (xy 101.895384 -223.517461)
			(xy 101.83965 -223.515424) (xy 101.784807 -223.505294) (xy 101.732023 -223.487287) (xy 101.682423 -223.461786)
			(xy 101.637065 -223.429335) (xy 101.596916 -223.390626) (xy 101.56283 -223.346483) (xy 101.535534 -223.297848)
			(xy 101.515611 -223.245757) (xy 101.503485 -223.19132) (xy 101.499414 -223.135698) (xy 67.38184 -223.135698)
			(xy 67.257438 -223.849946) (xy 102.606346 -223.849946) (xy 102.610417 -223.794324) (xy 102.622543 -223.739887)
			(xy 102.642466 -223.687796) (xy 102.669762 -223.639161) (xy 102.703848 -223.595018) (xy 102.743997 -223.556309)
			(xy 102.789355 -223.523858) (xy 102.838955 -223.498357) (xy 102.891739 -223.48035) (xy 102.946582 -223.47022)
			(xy 103.002316 -223.468183) (xy 103.057753 -223.474283) (xy 103.11171 -223.488389) (xy 103.163039 -223.510201)
			(xy 103.210645 -223.539255) (xy 103.253513 -223.57493) (xy 103.29073 -223.616467) (xy 103.321503 -223.66298)
			(xy 103.345175 -223.713477) (xy 103.361243 -223.766884) (xy 103.369363 -223.82206) (xy 103.369872 -223.849946)
			(xy 103.369363 -223.877832) (xy 103.361243 -223.933008) (xy 103.345175 -223.986415) (xy 103.321503 -224.036912)
			(xy 103.29073 -224.083425) (xy 103.253513 -224.124962) (xy 103.210645 -224.160637) (xy 103.163039 -224.189691)
			(xy 103.11171 -224.211503) (xy 103.057753 -224.225609) (xy 103.002316 -224.231709) (xy 102.946582 -224.229672)
			(xy 102.891739 -224.219542) (xy 102.838955 -224.201535) (xy 102.789355 -224.176034) (xy 102.743997 -224.143583)
			(xy 102.703848 -224.104874) (xy 102.669762 -224.060731) (xy 102.642466 -224.012096) (xy 102.622543 -223.960005)
			(xy 102.610417 -223.905568) (xy 102.606346 -223.849946) (xy 67.257438 -223.849946) (xy 67.138787 -224.531174)
			(xy 107.58373 -224.531174) (xy 107.587801 -224.475552) (xy 107.599927 -224.421115) (xy 107.61985 -224.369024)
			(xy 107.647146 -224.320389) (xy 107.681232 -224.276246) (xy 107.721381 -224.237537) (xy 107.766739 -224.205086)
			(xy 107.816339 -224.179585) (xy 107.869123 -224.161578) (xy 107.923966 -224.151448) (xy 107.9797 -224.149411)
			(xy 108.035137 -224.155511) (xy 108.089094 -224.169617) (xy 108.140423 -224.191429) (xy 108.188029 -224.220483)
			(xy 108.230897 -224.256158) (xy 108.268114 -224.297695) (xy 108.298887 -224.344208) (xy 108.322559 -224.394705)
			(xy 108.338627 -224.448112) (xy 108.340534 -224.46107) (xy 119.436386 -224.46107) (xy 119.440457 -224.405448)
			(xy 119.452583 -224.351011) (xy 119.472506 -224.29892) (xy 119.499802 -224.250285) (xy 119.533888 -224.206142)
			(xy 119.574037 -224.167433) (xy 119.619395 -224.134982) (xy 119.668995 -224.109481) (xy 119.721779 -224.091474)
			(xy 119.776622 -224.081344) (xy 119.832356 -224.079307) (xy 119.887793 -224.085407) (xy 119.94175 -224.099513)
			(xy 119.993079 -224.121325) (xy 120.040685 -224.150379) (xy 120.083553 -224.186054) (xy 120.12077 -224.227591)
			(xy 120.151543 -224.274104) (xy 120.175215 -224.324601) (xy 120.191283 -224.378008) (xy 120.199403 -224.433184)
			(xy 120.199912 -224.46107) (xy 120.199403 -224.488956) (xy 120.191283 -224.544132) (xy 120.175215 -224.597539)
			(xy 120.151543 -224.648036) (xy 120.12077 -224.694549) (xy 120.083553 -224.736086) (xy 120.040685 -224.771761)
			(xy 119.993079 -224.800815) (xy 119.94175 -224.822627) (xy 119.887793 -224.836733) (xy 119.832356 -224.842833)
			(xy 119.776622 -224.840796) (xy 119.721779 -224.830666) (xy 119.668995 -224.812659) (xy 119.619395 -224.787158)
			(xy 119.574037 -224.754707) (xy 119.533888 -224.715998) (xy 119.499802 -224.671855) (xy 119.472506 -224.62322)
			(xy 119.452583 -224.571129) (xy 119.440457 -224.516692) (xy 119.436386 -224.46107) (xy 108.340534 -224.46107)
			(xy 108.346747 -224.503288) (xy 108.347256 -224.531174) (xy 108.346747 -224.55906) (xy 108.338627 -224.614236)
			(xy 108.322559 -224.667643) (xy 108.298887 -224.71814) (xy 108.268114 -224.764653) (xy 108.230897 -224.80619)
			(xy 108.188029 -224.841865) (xy 108.140423 -224.870919) (xy 108.089094 -224.892731) (xy 108.035137 -224.906837)
			(xy 107.9797 -224.912937) (xy 107.923966 -224.9109) (xy 107.869123 -224.90077) (xy 107.816339 -224.882763)
			(xy 107.766739 -224.857262) (xy 107.721381 -224.824811) (xy 107.681232 -224.786102) (xy 107.647146 -224.741959)
			(xy 107.61985 -224.693324) (xy 107.599927 -224.641233) (xy 107.587801 -224.586796) (xy 107.58373 -224.531174)
			(xy 67.138787 -224.531174) (xy 66.83539 -226.273106) (xy 70.331582 -226.273106) (xy 70.335653 -226.217484)
			(xy 70.347779 -226.163047) (xy 70.367702 -226.110956) (xy 70.394998 -226.062321) (xy 70.429084 -226.018178)
			(xy 70.469233 -225.979469) (xy 70.514591 -225.947018) (xy 70.564191 -225.921517) (xy 70.616975 -225.90351)
			(xy 70.671818 -225.89338) (xy 70.727552 -225.891343) (xy 70.782989 -225.897443) (xy 70.836946 -225.911549)
			(xy 70.888275 -225.933361) (xy 70.935881 -225.962415) (xy 70.978749 -225.99809) (xy 71.015966 -226.039627)
			(xy 71.046739 -226.08614) (xy 71.070411 -226.136637) (xy 71.086479 -226.190044) (xy 71.094599 -226.24522)
			(xy 71.095108 -226.273106) (xy 71.094599 -226.300992) (xy 71.086479 -226.356168) (xy 71.070411 -226.409575)
			(xy 71.046739 -226.460072) (xy 71.015966 -226.506585) (xy 70.978749 -226.548122) (xy 70.935881 -226.583797)
			(xy 70.888275 -226.612851) (xy 70.836946 -226.634663) (xy 70.782989 -226.648769) (xy 70.727552 -226.654869)
			(xy 70.671818 -226.652832) (xy 70.616975 -226.642702) (xy 70.564191 -226.624695) (xy 70.514591 -226.599194)
			(xy 70.469233 -226.566743) (xy 70.429084 -226.528034) (xy 70.394998 -226.483891) (xy 70.367702 -226.435256)
			(xy 70.347779 -226.383165) (xy 70.335653 -226.328728) (xy 70.331582 -226.273106) (xy 66.83539 -226.273106)
			(xy 66.456653 -228.4476) (xy 69.569582 -228.4476) (xy 69.573653 -228.391978) (xy 69.585779 -228.337541)
			(xy 69.605702 -228.28545) (xy 69.632998 -228.236815) (xy 69.667084 -228.192672) (xy 69.707233 -228.153963)
			(xy 69.752591 -228.121512) (xy 69.802191 -228.096011) (xy 69.854975 -228.078004) (xy 69.909818 -228.067874)
			(xy 69.965552 -228.065837) (xy 70.020989 -228.071937) (xy 70.074946 -228.086043) (xy 70.126275 -228.107855)
			(xy 70.173881 -228.136909) (xy 70.216749 -228.172584) (xy 70.253966 -228.214121) (xy 70.284739 -228.260634)
			(xy 70.308411 -228.311131) (xy 70.324479 -228.364538) (xy 70.332599 -228.419714) (xy 70.333108 -228.4476)
			(xy 70.332599 -228.475486) (xy 70.324479 -228.530662) (xy 70.308411 -228.584069) (xy 70.284739 -228.634566)
			(xy 70.253966 -228.681079) (xy 70.216749 -228.722616) (xy 70.173881 -228.758291) (xy 70.126275 -228.787345)
			(xy 70.074946 -228.809157) (xy 70.020989 -228.823263) (xy 69.965552 -228.829363) (xy 69.909818 -228.827326)
			(xy 69.854975 -228.817196) (xy 69.802191 -228.799189) (xy 69.752591 -228.773688) (xy 69.707233 -228.741237)
			(xy 69.667084 -228.702528) (xy 69.632998 -228.658385) (xy 69.605702 -228.60975) (xy 69.585779 -228.557659)
			(xy 69.573653 -228.503222) (xy 69.569582 -228.4476) (xy 66.456653 -228.4476) (xy 65.60185 -233.355388)
			(xy 65.476403 -234.080558) (xy 119.279922 -234.080558) (xy 119.283993 -234.024936) (xy 119.296119 -233.970499)
			(xy 119.316042 -233.918408) (xy 119.343338 -233.869773) (xy 119.377424 -233.82563) (xy 119.417573 -233.786921)
			(xy 119.462931 -233.75447) (xy 119.512531 -233.728969) (xy 119.565315 -233.710962) (xy 119.620158 -233.700832)
			(xy 119.675892 -233.698795) (xy 119.731329 -233.704895) (xy 119.785286 -233.719001) (xy 119.836615 -233.740813)
			(xy 119.884221 -233.769867) (xy 119.927089 -233.805542) (xy 119.964306 -233.847079) (xy 119.995079 -233.893592)
			(xy 120.018751 -233.944089) (xy 120.034819 -233.997496) (xy 120.042939 -234.052672) (xy 120.043448 -234.080558)
			(xy 120.042939 -234.108444) (xy 120.034819 -234.16362) (xy 120.018751 -234.217027) (xy 119.995079 -234.267524)
			(xy 119.964306 -234.314037) (xy 119.927089 -234.355574) (xy 119.884221 -234.391249) (xy 119.836615 -234.420303)
			(xy 119.785286 -234.442115) (xy 119.731329 -234.456221) (xy 119.675892 -234.462321) (xy 119.620158 -234.460284)
			(xy 119.565315 -234.450154) (xy 119.512531 -234.432147) (xy 119.462931 -234.406646) (xy 119.417573 -234.374195)
			(xy 119.377424 -234.335486) (xy 119.343338 -234.291343) (xy 119.316042 -234.242708) (xy 119.296119 -234.190617)
			(xy 119.283993 -234.13618) (xy 119.279922 -234.080558) (xy 65.476403 -234.080558) (xy 65.267164 -235.290106)
			(xy 70.550276 -235.290106) (xy 70.554347 -235.234484) (xy 70.566473 -235.180047) (xy 70.586396 -235.127956)
			(xy 70.613692 -235.079321) (xy 70.647778 -235.035178) (xy 70.687927 -234.996469) (xy 70.733285 -234.964018)
			(xy 70.782885 -234.938517) (xy 70.835669 -234.92051) (xy 70.890512 -234.91038) (xy 70.946246 -234.908343)
			(xy 71.001683 -234.914443) (xy 71.05564 -234.928549) (xy 71.106969 -234.950361) (xy 71.154575 -234.979415)
			(xy 71.160738 -234.984544) (xy 93.107 -234.984544) (xy 93.111071 -234.928922) (xy 93.123197 -234.874485)
			(xy 93.14312 -234.822394) (xy 93.170416 -234.773759) (xy 93.204502 -234.729616) (xy 93.244651 -234.690907)
			(xy 93.290009 -234.658456) (xy 93.339609 -234.632955) (xy 93.392393 -234.614948) (xy 93.447236 -234.604818)
			(xy 93.50297 -234.602781) (xy 93.558407 -234.608881) (xy 93.612364 -234.622987) (xy 93.663693 -234.644799)
			(xy 93.711299 -234.673853) (xy 93.754167 -234.709528) (xy 93.791384 -234.751065) (xy 93.822157 -234.797578)
			(xy 93.845829 -234.848075) (xy 93.861897 -234.901482) (xy 93.870017 -234.956658) (xy 93.870526 -234.984544)
			(xy 93.870017 -235.01243) (xy 93.861897 -235.067606) (xy 93.845829 -235.121013) (xy 93.822157 -235.17151)
			(xy 93.791384 -235.218023) (xy 93.754167 -235.25956) (xy 93.711299 -235.295235) (xy 93.663693 -235.324289)
			(xy 93.612364 -235.346101) (xy 93.558407 -235.360207) (xy 93.50297 -235.366307) (xy 93.447236 -235.36427)
			(xy 93.392393 -235.35414) (xy 93.339609 -235.336133) (xy 93.290009 -235.310632) (xy 93.244651 -235.278181)
			(xy 93.204502 -235.239472) (xy 93.170416 -235.195329) (xy 93.14312 -235.146694) (xy 93.123197 -235.094603)
			(xy 93.111071 -235.040166) (xy 93.107 -234.984544) (xy 71.160738 -234.984544) (xy 71.197443 -235.01509)
			(xy 71.23466 -235.056627) (xy 71.265433 -235.10314) (xy 71.289105 -235.153637) (xy 71.305173 -235.207044)
			(xy 71.313293 -235.26222) (xy 71.313802 -235.290106) (xy 71.313293 -235.317992) (xy 71.305173 -235.373168)
			(xy 71.289105 -235.426575) (xy 71.265433 -235.477072) (xy 71.23466 -235.523585) (xy 71.215818 -235.544614)
			(xy 120.151142 -235.544614) (xy 120.155213 -235.488992) (xy 120.167339 -235.434555) (xy 120.187262 -235.382464)
			(xy 120.214558 -235.333829) (xy 120.248644 -235.289686) (xy 120.288793 -235.250977) (xy 120.334151 -235.218526)
			(xy 120.383751 -235.193025) (xy 120.436535 -235.175018) (xy 120.491378 -235.164888) (xy 120.547112 -235.162851)
			(xy 120.602549 -235.168951) (xy 120.656506 -235.183057) (xy 120.707835 -235.204869) (xy 120.755441 -235.233923)
			(xy 120.798309 -235.269598) (xy 120.835526 -235.311135) (xy 120.866299 -235.357648) (xy 120.889971 -235.408145)
			(xy 120.906039 -235.461552) (xy 120.914159 -235.516728) (xy 120.914668 -235.544614) (xy 120.914159 -235.5725)
			(xy 120.906039 -235.627676) (xy 120.889971 -235.681083) (xy 120.866299 -235.73158) (xy 120.835526 -235.778093)
			(xy 120.798309 -235.81963) (xy 120.755441 -235.855305) (xy 120.707835 -235.884359) (xy 120.656506 -235.906171)
			(xy 120.602549 -235.920277) (xy 120.547112 -235.926377) (xy 120.491378 -235.92434) (xy 120.436535 -235.91421)
			(xy 120.383751 -235.896203) (xy 120.334151 -235.870702) (xy 120.288793 -235.838251) (xy 120.248644 -235.799542)
			(xy 120.214558 -235.755399) (xy 120.187262 -235.706764) (xy 120.167339 -235.654673) (xy 120.155213 -235.600236)
			(xy 120.151142 -235.544614) (xy 71.215818 -235.544614) (xy 71.197443 -235.565122) (xy 71.154575 -235.600797)
			(xy 71.106969 -235.629851) (xy 71.05564 -235.651663) (xy 71.001683 -235.665769) (xy 70.946246 -235.671869)
			(xy 70.890512 -235.669832) (xy 70.835669 -235.659702) (xy 70.782885 -235.641695) (xy 70.733285 -235.616194)
			(xy 70.687927 -235.583743) (xy 70.647778 -235.545034) (xy 70.613692 -235.500891) (xy 70.586396 -235.452256)
			(xy 70.566473 -235.400165) (xy 70.554347 -235.345728) (xy 70.550276 -235.290106) (xy 65.267164 -235.290106)
			(xy 65.04716 -236.561884) (xy 93.248986 -236.561884) (xy 93.253057 -236.506262) (xy 93.265183 -236.451825)
			(xy 93.285106 -236.399734) (xy 93.312402 -236.351099) (xy 93.346488 -236.306956) (xy 93.386637 -236.268247)
			(xy 93.431995 -236.235796) (xy 93.481595 -236.210295) (xy 93.534379 -236.192288) (xy 93.589222 -236.182158)
			(xy 93.644956 -236.180121) (xy 93.700393 -236.186221) (xy 93.75435 -236.200327) (xy 93.805679 -236.222139)
			(xy 93.853285 -236.251193) (xy 93.896153 -236.286868) (xy 93.93337 -236.328405) (xy 93.964143 -236.374918)
			(xy 93.972012 -236.391704) (xy 99.087938 -236.391704) (xy 99.092009 -236.336082) (xy 99.104135 -236.281645)
			(xy 99.124058 -236.229554) (xy 99.151354 -236.180919) (xy 99.18544 -236.136776) (xy 99.225589 -236.098067)
			(xy 99.270947 -236.065616) (xy 99.320547 -236.040115) (xy 99.373331 -236.022108) (xy 99.428174 -236.011978)
			(xy 99.483908 -236.009941) (xy 99.539345 -236.016041) (xy 99.593302 -236.030147) (xy 99.644631 -236.051959)
			(xy 99.692237 -236.081013) (xy 99.735105 -236.116688) (xy 99.772322 -236.158225) (xy 99.803095 -236.204738)
			(xy 99.826767 -236.255235) (xy 99.842835 -236.308642) (xy 99.850955 -236.363818) (xy 99.851464 -236.391704)
			(xy 99.850955 -236.41959) (xy 99.842835 -236.474766) (xy 99.826767 -236.528173) (xy 99.803095 -236.57867)
			(xy 99.772322 -236.625183) (xy 99.735105 -236.66672) (xy 99.692237 -236.702395) (xy 99.644631 -236.731449)
			(xy 99.593302 -236.753261) (xy 99.539345 -236.767367) (xy 99.483908 -236.773467) (xy 99.428174 -236.77143)
			(xy 99.373331 -236.7613) (xy 99.320547 -236.743293) (xy 99.270947 -236.717792) (xy 99.225589 -236.685341)
			(xy 99.18544 -236.646632) (xy 99.151354 -236.602489) (xy 99.124058 -236.553854) (xy 99.104135 -236.501763)
			(xy 99.092009 -236.447326) (xy 99.087938 -236.391704) (xy 93.972012 -236.391704) (xy 93.987815 -236.425415)
			(xy 94.003883 -236.478822) (xy 94.012003 -236.533998) (xy 94.012512 -236.561884) (xy 94.012003 -236.58977)
			(xy 94.003883 -236.644946) (xy 93.987815 -236.698353) (xy 93.964143 -236.74885) (xy 93.946681 -236.775244)
			(xy 101.503226 -236.775244) (xy 101.503712 -236.747874) (xy 101.511524 -236.693696) (xy 101.527008 -236.641193)
			(xy 101.549845 -236.591446) (xy 101.579566 -236.545478) (xy 101.597206 -236.524546) (xy 101.59746 -236.524292)
			(xy 101.603063 -236.517217) (xy 101.609298 -236.500291) (xy 101.609652 -236.491272) (xy 101.609652 -236.424216)
			(xy 101.609298 -236.415199) (xy 101.603049 -236.398281) (xy 101.59746 -236.391196) (xy 101.597206 -236.391196)
			(xy 101.597206 -236.390942) (xy 101.579574 -236.370004) (xy 101.549861 -236.324033) (xy 101.527024 -236.274287)
			(xy 101.511531 -236.221788) (xy 101.503701 -236.167613) (xy 101.503226 -236.140244) (xy 101.503712 -236.112993)
			(xy 101.511468 -236.059045) (xy 101.526823 -236.00675) (xy 101.549465 -235.957173) (xy 101.578931 -235.911323)
			(xy 101.614622 -235.870132) (xy 101.655813 -235.834441) (xy 101.701663 -235.804975) (xy 101.75124 -235.782333)
			(xy 101.803535 -235.766978) (xy 101.857483 -235.759222) (xy 101.911985 -235.759222) (xy 101.965933 -235.766978)
			(xy 102.018228 -235.782333) (xy 102.067805 -235.804975) (xy 102.113655 -235.834441) (xy 102.154846 -235.870132)
			(xy 102.190537 -235.911323) (xy 102.220003 -235.957173) (xy 102.242645 -236.00675) (xy 102.258 -236.059045)
			(xy 102.265756 -236.112993) (xy 102.266242 -236.140244) (xy 102.265757 -236.167614) (xy 102.257946 -236.221793)
			(xy 102.242462 -236.274296) (xy 102.219624 -236.324043) (xy 102.189902 -236.37001) (xy 102.172262 -236.390942)
			(xy 102.172008 -236.391196) (xy 102.166418 -236.39828) (xy 102.160173 -236.415199) (xy 102.159816 -236.424216)
			(xy 102.159816 -236.491272) (xy 102.160183 -236.500288) (xy 102.166423 -236.517205) (xy 102.172008 -236.524292)
			(xy 102.172262 -236.524292) (xy 102.172262 -236.524546) (xy 102.189883 -236.545492) (xy 102.219599 -236.591461)
			(xy 102.242439 -236.641205) (xy 102.257934 -236.693702) (xy 102.265766 -236.747876) (xy 102.266242 -236.775244)
			(xy 103.535226 -236.775244) (xy 103.535712 -236.747874) (xy 103.543524 -236.693696) (xy 103.559008 -236.641193)
			(xy 103.581845 -236.591446) (xy 103.611566 -236.545478) (xy 103.629206 -236.524546) (xy 103.62946 -236.524292)
			(xy 103.635063 -236.517217) (xy 103.641298 -236.500291) (xy 103.641652 -236.491272) (xy 103.641652 -236.424216)
			(xy 103.641298 -236.415199) (xy 103.635049 -236.398281) (xy 103.62946 -236.391196) (xy 103.629206 -236.391196)
			(xy 103.629206 -236.390942) (xy 103.611574 -236.370004) (xy 103.581861 -236.324033) (xy 103.559024 -236.274287)
			(xy 103.543531 -236.221788) (xy 103.535701 -236.167613) (xy 103.535226 -236.140244) (xy 103.535712 -236.112993)
			(xy 103.543468 -236.059045) (xy 103.558823 -236.00675) (xy 103.581465 -235.957173) (xy 103.610931 -235.911323)
			(xy 103.646622 -235.870132) (xy 103.687813 -235.834441) (xy 103.733663 -235.804975) (xy 103.78324 -235.782333)
			(xy 103.835535 -235.766978) (xy 103.889483 -235.759222) (xy 103.943985 -235.759222) (xy 103.997933 -235.766978)
			(xy 104.050228 -235.782333) (xy 104.099805 -235.804975) (xy 104.145655 -235.834441) (xy 104.186846 -235.870132)
			(xy 104.222537 -235.911323) (xy 104.252003 -235.957173) (xy 104.274645 -236.00675) (xy 104.29 -236.059045)
			(xy 104.297756 -236.112993) (xy 104.298242 -236.140244) (xy 104.297757 -236.167614) (xy 104.289946 -236.221793)
			(xy 104.274462 -236.274296) (xy 104.251624 -236.324043) (xy 104.221902 -236.37001) (xy 104.204262 -236.390942)
			(xy 104.204008 -236.391196) (xy 104.198418 -236.39828) (xy 104.192173 -236.415199) (xy 104.191816 -236.424216)
			(xy 104.191816 -236.491272) (xy 104.192183 -236.500288) (xy 104.198423 -236.517205) (xy 104.204008 -236.524292)
			(xy 104.204262 -236.524292) (xy 104.204262 -236.524546) (xy 104.221883 -236.545492) (xy 104.251599 -236.591461)
			(xy 104.274439 -236.641205) (xy 104.289934 -236.693702) (xy 104.297766 -236.747876) (xy 104.298242 -236.775244)
			(xy 105.567226 -236.775244) (xy 105.567712 -236.747874) (xy 105.575524 -236.693696) (xy 105.591008 -236.641193)
			(xy 105.613845 -236.591446) (xy 105.643566 -236.545478) (xy 105.661206 -236.524546) (xy 105.66146 -236.524292)
			(xy 105.667063 -236.517217) (xy 105.673298 -236.500291) (xy 105.673652 -236.491272) (xy 105.673652 -236.424216)
			(xy 105.673298 -236.415199) (xy 105.667049 -236.398281) (xy 105.66146 -236.391196) (xy 105.661206 -236.391196)
			(xy 105.661206 -236.390942) (xy 105.643574 -236.370004) (xy 105.613861 -236.324033) (xy 105.591024 -236.274287)
			(xy 105.575531 -236.221788) (xy 105.567701 -236.167613) (xy 105.567226 -236.140244) (xy 105.567712 -236.112993)
			(xy 105.575468 -236.059045) (xy 105.590823 -236.00675) (xy 105.613465 -235.957173) (xy 105.642931 -235.911323)
			(xy 105.678622 -235.870132) (xy 105.719813 -235.834441) (xy 105.765663 -235.804975) (xy 105.81524 -235.782333)
			(xy 105.867535 -235.766978) (xy 105.921483 -235.759222) (xy 105.975985 -235.759222) (xy 106.029933 -235.766978)
			(xy 106.082228 -235.782333) (xy 106.131805 -235.804975) (xy 106.177655 -235.834441) (xy 106.218846 -235.870132)
			(xy 106.254537 -235.911323) (xy 106.284003 -235.957173) (xy 106.306645 -236.00675) (xy 106.322 -236.059045)
			(xy 106.329756 -236.112993) (xy 106.330242 -236.140244) (xy 106.329757 -236.167614) (xy 106.321946 -236.221793)
			(xy 106.306462 -236.274296) (xy 106.283624 -236.324043) (xy 106.253902 -236.37001) (xy 106.236262 -236.390942)
			(xy 106.236008 -236.391196) (xy 106.230418 -236.39828) (xy 106.224173 -236.415199) (xy 106.223816 -236.424216)
			(xy 106.223816 -236.491272) (xy 106.224183 -236.500288) (xy 106.230423 -236.517205) (xy 106.236008 -236.524292)
			(xy 106.236262 -236.524292) (xy 106.236262 -236.524546) (xy 106.253883 -236.545492) (xy 106.283599 -236.591461)
			(xy 106.306439 -236.641205) (xy 106.321934 -236.693702) (xy 106.329766 -236.747876) (xy 106.330242 -236.775244)
			(xy 107.599226 -236.775244) (xy 107.599712 -236.747874) (xy 107.607524 -236.693696) (xy 107.623008 -236.641193)
			(xy 107.645845 -236.591446) (xy 107.675566 -236.545478) (xy 107.693206 -236.524546) (xy 107.69346 -236.524292)
			(xy 107.699063 -236.517217) (xy 107.705298 -236.500291) (xy 107.705652 -236.491272) (xy 107.705652 -236.424216)
			(xy 107.705298 -236.415199) (xy 107.699049 -236.398281) (xy 107.69346 -236.391196) (xy 107.693206 -236.391196)
			(xy 107.693206 -236.390942) (xy 107.675574 -236.370004) (xy 107.645861 -236.324033) (xy 107.623024 -236.274287)
			(xy 107.607531 -236.221788) (xy 107.599701 -236.167613) (xy 107.599226 -236.140244) (xy 107.599712 -236.112993)
			(xy 107.607468 -236.059045) (xy 107.622823 -236.00675) (xy 107.645465 -235.957173) (xy 107.674931 -235.911323)
			(xy 107.710622 -235.870132) (xy 107.751813 -235.834441) (xy 107.797663 -235.804975) (xy 107.84724 -235.782333)
			(xy 107.899535 -235.766978) (xy 107.953483 -235.759222) (xy 108.007985 -235.759222) (xy 108.061933 -235.766978)
			(xy 108.114228 -235.782333) (xy 108.163805 -235.804975) (xy 108.209655 -235.834441) (xy 108.250846 -235.870132)
			(xy 108.286537 -235.911323) (xy 108.316003 -235.957173) (xy 108.338645 -236.00675) (xy 108.354 -236.059045)
			(xy 108.361756 -236.112993) (xy 108.362242 -236.140244) (xy 108.361757 -236.167614) (xy 108.353946 -236.221793)
			(xy 108.338462 -236.274296) (xy 108.335986 -236.27969) (xy 119.269254 -236.27969) (xy 119.273325 -236.224068)
			(xy 119.285451 -236.169631) (xy 119.305374 -236.11754) (xy 119.33267 -236.068905) (xy 119.366756 -236.024762)
			(xy 119.406905 -235.986053) (xy 119.452263 -235.953602) (xy 119.501863 -235.928101) (xy 119.554647 -235.910094)
			(xy 119.60949 -235.899964) (xy 119.665224 -235.897927) (xy 119.720661 -235.904027) (xy 119.774618 -235.918133)
			(xy 119.825947 -235.939945) (xy 119.873553 -235.968999) (xy 119.916421 -236.004674) (xy 119.953638 -236.046211)
			(xy 119.984411 -236.092724) (xy 120.008083 -236.143221) (xy 120.024151 -236.196628) (xy 120.032271 -236.251804)
			(xy 120.03278 -236.27969) (xy 120.032271 -236.307576) (xy 120.024151 -236.362752) (xy 120.008083 -236.416159)
			(xy 119.984411 -236.466656) (xy 119.953638 -236.513169) (xy 119.916421 -236.554706) (xy 119.873553 -236.590381)
			(xy 119.825947 -236.619435) (xy 119.774618 -236.641247) (xy 119.720661 -236.655353) (xy 119.665224 -236.661453)
			(xy 119.60949 -236.659416) (xy 119.554647 -236.649286) (xy 119.501863 -236.631279) (xy 119.452263 -236.605778)
			(xy 119.406905 -236.573327) (xy 119.366756 -236.534618) (xy 119.33267 -236.490475) (xy 119.305374 -236.44184)
			(xy 119.285451 -236.389749) (xy 119.273325 -236.335312) (xy 119.269254 -236.27969) (xy 108.335986 -236.27969)
			(xy 108.315624 -236.324043) (xy 108.285902 -236.37001) (xy 108.268262 -236.390942) (xy 108.268008 -236.391196)
			(xy 108.262418 -236.39828) (xy 108.256173 -236.415199) (xy 108.255816 -236.424216) (xy 108.255816 -236.491272)
			(xy 108.256183 -236.500288) (xy 108.262423 -236.517205) (xy 108.268008 -236.524292) (xy 108.268262 -236.524292)
			(xy 108.268262 -236.524546) (xy 108.285883 -236.545492) (xy 108.315599 -236.591461) (xy 108.338439 -236.641205)
			(xy 108.353934 -236.693702) (xy 108.361766 -236.747876) (xy 108.362242 -236.775244) (xy 108.361756 -236.802495)
			(xy 108.354 -236.856443) (xy 108.338645 -236.908738) (xy 108.316003 -236.958315) (xy 108.286537 -237.004165)
			(xy 108.250846 -237.045356) (xy 108.209655 -237.081047) (xy 108.163805 -237.110513) (xy 108.114228 -237.133155)
			(xy 108.061933 -237.14851) (xy 108.007985 -237.156266) (xy 107.953483 -237.156266) (xy 107.899535 -237.14851)
			(xy 107.84724 -237.133155) (xy 107.797663 -237.110513) (xy 107.751813 -237.081047) (xy 107.710622 -237.045356)
			(xy 107.674931 -237.004165) (xy 107.645465 -236.958315) (xy 107.622823 -236.908738) (xy 107.607468 -236.856443)
			(xy 107.599712 -236.802495) (xy 107.599226 -236.775244) (xy 106.330242 -236.775244) (xy 106.329756 -236.802495)
			(xy 106.322 -236.856443) (xy 106.306645 -236.908738) (xy 106.284003 -236.958315) (xy 106.254537 -237.004165)
			(xy 106.218846 -237.045356) (xy 106.177655 -237.081047) (xy 106.131805 -237.110513) (xy 106.082228 -237.133155)
			(xy 106.029933 -237.14851) (xy 105.975985 -237.156266) (xy 105.921483 -237.156266) (xy 105.867535 -237.14851)
			(xy 105.81524 -237.133155) (xy 105.765663 -237.110513) (xy 105.719813 -237.081047) (xy 105.678622 -237.045356)
			(xy 105.642931 -237.004165) (xy 105.613465 -236.958315) (xy 105.590823 -236.908738) (xy 105.575468 -236.856443)
			(xy 105.567712 -236.802495) (xy 105.567226 -236.775244) (xy 104.298242 -236.775244) (xy 104.297756 -236.802495)
			(xy 104.29 -236.856443) (xy 104.274645 -236.908738) (xy 104.252003 -236.958315) (xy 104.222537 -237.004165)
			(xy 104.186846 -237.045356) (xy 104.145655 -237.081047) (xy 104.099805 -237.110513) (xy 104.050228 -237.133155)
			(xy 103.997933 -237.14851) (xy 103.943985 -237.156266) (xy 103.889483 -237.156266) (xy 103.835535 -237.14851)
			(xy 103.78324 -237.133155) (xy 103.733663 -237.110513) (xy 103.687813 -237.081047) (xy 103.646622 -237.045356)
			(xy 103.610931 -237.004165) (xy 103.581465 -236.958315) (xy 103.558823 -236.908738) (xy 103.543468 -236.856443)
			(xy 103.535712 -236.802495) (xy 103.535226 -236.775244) (xy 102.266242 -236.775244) (xy 102.265756 -236.802495)
			(xy 102.258 -236.856443) (xy 102.242645 -236.908738) (xy 102.220003 -236.958315) (xy 102.190537 -237.004165)
			(xy 102.154846 -237.045356) (xy 102.113655 -237.081047) (xy 102.067805 -237.110513) (xy 102.018228 -237.133155)
			(xy 101.965933 -237.14851) (xy 101.911985 -237.156266) (xy 101.857483 -237.156266) (xy 101.803535 -237.14851)
			(xy 101.75124 -237.133155) (xy 101.701663 -237.110513) (xy 101.655813 -237.081047) (xy 101.614622 -237.045356)
			(xy 101.578931 -237.004165) (xy 101.549465 -236.958315) (xy 101.526823 -236.908738) (xy 101.511468 -236.856443)
			(xy 101.503712 -236.802495) (xy 101.503226 -236.775244) (xy 93.946681 -236.775244) (xy 93.93337 -236.795363)
			(xy 93.896153 -236.8369) (xy 93.853285 -236.872575) (xy 93.805679 -236.901629) (xy 93.75435 -236.923441)
			(xy 93.700393 -236.937547) (xy 93.644956 -236.943647) (xy 93.589222 -236.94161) (xy 93.534379 -236.93148)
			(xy 93.481595 -236.913473) (xy 93.431995 -236.887972) (xy 93.386637 -236.855521) (xy 93.346488 -236.816812)
			(xy 93.312402 -236.772669) (xy 93.285106 -236.724034) (xy 93.265183 -236.671943) (xy 93.253057 -236.617506)
			(xy 93.248986 -236.561884) (xy 65.04716 -236.561884) (xy 64.906378 -237.3757) (xy 92.775276 -237.3757)
			(xy 92.779347 -237.320078) (xy 92.791473 -237.265641) (xy 92.811396 -237.21355) (xy 92.838692 -237.164915)
			(xy 92.872778 -237.120772) (xy 92.912927 -237.082063) (xy 92.958285 -237.049612) (xy 93.007885 -237.024111)
			(xy 93.060669 -237.006104) (xy 93.115512 -236.995974) (xy 93.171246 -236.993937) (xy 93.226683 -237.000037)
			(xy 93.28064 -237.014143) (xy 93.331969 -237.035955) (xy 93.379575 -237.065009) (xy 93.422443 -237.100684)
			(xy 93.45966 -237.142221) (xy 93.490433 -237.188734) (xy 93.514105 -237.239231) (xy 93.530173 -237.292638)
			(xy 93.538293 -237.347814) (xy 93.538802 -237.3757) (xy 93.538293 -237.403586) (xy 93.530173 -237.458762)
			(xy 93.514105 -237.512169) (xy 93.508304 -237.524544) (xy 94.323914 -237.524544) (xy 94.327985 -237.468922)
			(xy 94.340111 -237.414485) (xy 94.360034 -237.362394) (xy 94.38733 -237.313759) (xy 94.421416 -237.269616)
			(xy 94.461565 -237.230907) (xy 94.506923 -237.198456) (xy 94.556523 -237.172955) (xy 94.609307 -237.154948)
			(xy 94.66415 -237.144818) (xy 94.719884 -237.142781) (xy 94.775321 -237.148881) (xy 94.829278 -237.162987)
			(xy 94.880607 -237.184799) (xy 94.928213 -237.213853) (xy 94.971081 -237.249528) (xy 95.008298 -237.291065)
			(xy 95.039071 -237.337578) (xy 95.062743 -237.388075) (xy 95.078811 -237.441482) (xy 95.086931 -237.496658)
			(xy 95.08744 -237.524544) (xy 95.086931 -237.55243) (xy 95.078811 -237.607606) (xy 95.062743 -237.661013)
			(xy 95.039071 -237.71151) (xy 95.008298 -237.758023) (xy 94.971081 -237.79956) (xy 94.928213 -237.835235)
			(xy 94.880607 -237.864289) (xy 94.829278 -237.886101) (xy 94.775321 -237.900207) (xy 94.719884 -237.906307)
			(xy 94.66415 -237.90427) (xy 94.609307 -237.89414) (xy 94.556523 -237.876133) (xy 94.506923 -237.850632)
			(xy 94.461565 -237.818181) (xy 94.421416 -237.779472) (xy 94.38733 -237.735329) (xy 94.360034 -237.686694)
			(xy 94.340111 -237.634603) (xy 94.327985 -237.580166) (xy 94.323914 -237.524544) (xy 93.508304 -237.524544)
			(xy 93.490433 -237.562666) (xy 93.45966 -237.609179) (xy 93.422443 -237.650716) (xy 93.379575 -237.686391)
			(xy 93.331969 -237.715445) (xy 93.28064 -237.737257) (xy 93.226683 -237.751363) (xy 93.171246 -237.757463)
			(xy 93.115512 -237.755426) (xy 93.060669 -237.745296) (xy 93.007885 -237.727289) (xy 92.958285 -237.701788)
			(xy 92.912927 -237.669337) (xy 92.872778 -237.630628) (xy 92.838692 -237.586485) (xy 92.811396 -237.53785)
			(xy 92.791473 -237.485759) (xy 92.779347 -237.431322) (xy 92.775276 -237.3757) (xy 64.906378 -237.3757)
			(xy 64.823377 -237.855506) (xy 70.417688 -237.855506) (xy 70.421759 -237.799884) (xy 70.433885 -237.745447)
			(xy 70.453808 -237.693356) (xy 70.481104 -237.644721) (xy 70.51519 -237.600578) (xy 70.555339 -237.561869)
			(xy 70.600697 -237.529418) (xy 70.650297 -237.503917) (xy 70.703081 -237.48591) (xy 70.757924 -237.47578)
			(xy 70.813658 -237.473743) (xy 70.869095 -237.479843) (xy 70.923052 -237.493949) (xy 70.974381 -237.515761)
			(xy 71.021987 -237.544815) (xy 71.064855 -237.58049) (xy 71.102072 -237.622027) (xy 71.132845 -237.66854)
			(xy 71.156517 -237.719037) (xy 71.172585 -237.772444) (xy 71.180705 -237.82762) (xy 71.181214 -237.855506)
			(xy 71.180705 -237.883392) (xy 71.172585 -237.938568) (xy 71.156517 -237.991975) (xy 71.132845 -238.042472)
			(xy 71.102072 -238.088985) (xy 71.064855 -238.130522) (xy 71.021987 -238.166197) (xy 70.990437 -238.185452)
			(xy 93.334838 -238.185452) (xy 93.338909 -238.12983) (xy 93.351035 -238.075393) (xy 93.370958 -238.023302)
			(xy 93.398254 -237.974667) (xy 93.43234 -237.930524) (xy 93.472489 -237.891815) (xy 93.517847 -237.859364)
			(xy 93.567447 -237.833863) (xy 93.620231 -237.815856) (xy 93.675074 -237.805726) (xy 93.730808 -237.803689)
			(xy 93.786245 -237.809789) (xy 93.840202 -237.823895) (xy 93.891531 -237.845707) (xy 93.939137 -237.874761)
			(xy 93.982005 -237.910436) (xy 94.019222 -237.951973) (xy 94.049995 -237.998486) (xy 94.073667 -238.048983)
			(xy 94.076363 -238.057944) (xy 119.474486 -238.057944) (xy 119.478557 -238.002322) (xy 119.490683 -237.947885)
			(xy 119.510606 -237.895794) (xy 119.537902 -237.847159) (xy 119.571988 -237.803016) (xy 119.612137 -237.764307)
			(xy 119.657495 -237.731856) (xy 119.707095 -237.706355) (xy 119.759879 -237.688348) (xy 119.814722 -237.678218)
			(xy 119.870456 -237.676181) (xy 119.925893 -237.682281) (xy 119.97985 -237.696387) (xy 120.031179 -237.718199)
			(xy 120.078785 -237.747253) (xy 120.121653 -237.782928) (xy 120.15887 -237.824465) (xy 120.189643 -237.870978)
			(xy 120.213315 -237.921475) (xy 120.229383 -237.974882) (xy 120.237503 -238.030058) (xy 120.238012 -238.057944)
			(xy 120.237503 -238.08583) (xy 120.229383 -238.141006) (xy 120.213315 -238.194413) (xy 120.189643 -238.24491)
			(xy 120.15887 -238.291423) (xy 120.121653 -238.33296) (xy 120.078785 -238.368635) (xy 120.031179 -238.397689)
			(xy 119.97985 -238.419501) (xy 119.925893 -238.433607) (xy 119.870456 -238.439707) (xy 119.814722 -238.43767)
			(xy 119.759879 -238.42754) (xy 119.707095 -238.409533) (xy 119.657495 -238.384032) (xy 119.612137 -238.351581)
			(xy 119.571988 -238.312872) (xy 119.537902 -238.268729) (xy 119.510606 -238.220094) (xy 119.490683 -238.168003)
			(xy 119.478557 -238.113566) (xy 119.474486 -238.057944) (xy 94.076363 -238.057944) (xy 94.089735 -238.10239)
			(xy 94.097855 -238.157566) (xy 94.098364 -238.185452) (xy 94.097855 -238.213338) (xy 94.089735 -238.268514)
			(xy 94.073667 -238.321921) (xy 94.049995 -238.372418) (xy 94.019222 -238.418931) (xy 93.982005 -238.460468)
			(xy 93.939137 -238.496143) (xy 93.891531 -238.525197) (xy 93.840202 -238.547009) (xy 93.786245 -238.561115)
			(xy 93.730808 -238.567215) (xy 93.675074 -238.565178) (xy 93.620231 -238.555048) (xy 93.567447 -238.537041)
			(xy 93.517847 -238.51154) (xy 93.472489 -238.479089) (xy 93.43234 -238.44038) (xy 93.398254 -238.396237)
			(xy 93.370958 -238.347602) (xy 93.351035 -238.295511) (xy 93.338909 -238.241074) (xy 93.334838 -238.185452)
			(xy 70.990437 -238.185452) (xy 70.974381 -238.195251) (xy 70.923052 -238.217063) (xy 70.869095 -238.231169)
			(xy 70.813658 -238.237269) (xy 70.757924 -238.235232) (xy 70.703081 -238.225102) (xy 70.650297 -238.207095)
			(xy 70.600697 -238.181594) (xy 70.555339 -238.149143) (xy 70.51519 -238.110434) (xy 70.481104 -238.066291)
			(xy 70.453808 -238.017656) (xy 70.433885 -237.965565) (xy 70.421759 -237.911128) (xy 70.417688 -237.855506)
			(xy 64.823377 -237.855506) (xy 64.499412 -239.728248) (xy 93.652338 -239.728248) (xy 93.656409 -239.672626)
			(xy 93.668535 -239.618189) (xy 93.688458 -239.566098) (xy 93.715754 -239.517463) (xy 93.74984 -239.47332)
			(xy 93.789989 -239.434611) (xy 93.835347 -239.40216) (xy 93.884947 -239.376659) (xy 93.937731 -239.358652)
			(xy 93.992574 -239.348522) (xy 94.048308 -239.346485) (xy 94.103745 -239.352585) (xy 94.157702 -239.366691)
			(xy 94.209031 -239.388503) (xy 94.256637 -239.417557) (xy 94.299505 -239.453232) (xy 94.336722 -239.494769)
			(xy 94.367495 -239.541282) (xy 94.391167 -239.591779) (xy 94.407235 -239.645186) (xy 94.415355 -239.700362)
			(xy 94.415864 -239.728248) (xy 94.415355 -239.756134) (xy 94.407235 -239.81131) (xy 94.391167 -239.864717)
			(xy 94.367495 -239.915214) (xy 94.336722 -239.961727) (xy 94.299505 -240.003264) (xy 94.256637 -240.038939)
			(xy 94.209031 -240.067993) (xy 94.157702 -240.089805) (xy 94.103745 -240.103911) (xy 94.048308 -240.110011)
			(xy 93.992574 -240.107974) (xy 93.937731 -240.097844) (xy 93.884947 -240.079837) (xy 93.835347 -240.054336)
			(xy 93.789989 -240.021885) (xy 93.74984 -239.983176) (xy 93.715754 -239.939033) (xy 93.688458 -239.890398)
			(xy 93.668535 -239.838307) (xy 93.656409 -239.78387) (xy 93.652338 -239.728248) (xy 64.499412 -239.728248)
			(xy 64.365353 -240.503202) (xy 92.046804 -240.503202) (xy 92.050875 -240.44758) (xy 92.063001 -240.393143)
			(xy 92.082924 -240.341052) (xy 92.11022 -240.292417) (xy 92.144306 -240.248274) (xy 92.184455 -240.209565)
			(xy 92.229813 -240.177114) (xy 92.279413 -240.151613) (xy 92.332197 -240.133606) (xy 92.38704 -240.123476)
			(xy 92.442774 -240.121439) (xy 92.498211 -240.127539) (xy 92.552168 -240.141645) (xy 92.603497 -240.163457)
			(xy 92.651103 -240.192511) (xy 92.693971 -240.228186) (xy 92.731188 -240.269723) (xy 92.761961 -240.316236)
			(xy 92.785633 -240.366733) (xy 92.801701 -240.42014) (xy 92.809821 -240.475316) (xy 92.81033 -240.503202)
			(xy 92.809821 -240.531088) (xy 92.801701 -240.586264) (xy 92.785633 -240.639671) (xy 92.761961 -240.690168)
			(xy 92.731188 -240.736681) (xy 92.724408 -240.744248) (xy 93.652338 -240.744248) (xy 93.656409 -240.688626)
			(xy 93.668535 -240.634189) (xy 93.688458 -240.582098) (xy 93.715754 -240.533463) (xy 93.74984 -240.48932)
			(xy 93.789989 -240.450611) (xy 93.835347 -240.41816) (xy 93.884947 -240.392659) (xy 93.937731 -240.374652)
			(xy 93.992574 -240.364522) (xy 94.048308 -240.362485) (xy 94.103745 -240.368585) (xy 94.157702 -240.382691)
			(xy 94.209031 -240.404503) (xy 94.256637 -240.433557) (xy 94.299505 -240.469232) (xy 94.336722 -240.510769)
			(xy 94.367495 -240.557282) (xy 94.391167 -240.607779) (xy 94.407235 -240.661186) (xy 94.415355 -240.716362)
			(xy 94.415864 -240.744248) (xy 94.415355 -240.772134) (xy 94.412917 -240.788698) (xy 97.371406 -240.788698)
			(xy 97.375477 -240.733076) (xy 97.387603 -240.678639) (xy 97.407526 -240.626548) (xy 97.434822 -240.577913)
			(xy 97.468908 -240.53377) (xy 97.509057 -240.495061) (xy 97.554415 -240.46261) (xy 97.604015 -240.437109)
			(xy 97.656799 -240.419102) (xy 97.711642 -240.408972) (xy 97.767376 -240.406935) (xy 97.822813 -240.413035)
			(xy 97.87677 -240.427141) (xy 97.928099 -240.448953) (xy 97.975705 -240.478007) (xy 98.018573 -240.513682)
			(xy 98.05579 -240.555219) (xy 98.086563 -240.601732) (xy 98.110235 -240.652229) (xy 98.126303 -240.705636)
			(xy 98.134423 -240.760812) (xy 98.134932 -240.788698) (xy 98.134423 -240.816584) (xy 98.126303 -240.87176)
			(xy 98.110235 -240.925167) (xy 98.108839 -240.928144) (xy 99.417122 -240.928144) (xy 99.421193 -240.872522)
			(xy 99.433319 -240.818085) (xy 99.453242 -240.765994) (xy 99.480538 -240.717359) (xy 99.514624 -240.673216)
			(xy 99.554773 -240.634507) (xy 99.600131 -240.602056) (xy 99.649731 -240.576555) (xy 99.702515 -240.558548)
			(xy 99.757358 -240.548418) (xy 99.813092 -240.546381) (xy 99.868529 -240.552481) (xy 99.922486 -240.566587)
			(xy 99.973815 -240.588399) (xy 100.021421 -240.617453) (xy 100.064289 -240.653128) (xy 100.101506 -240.694665)
			(xy 100.132279 -240.741178) (xy 100.155951 -240.791675) (xy 100.172019 -240.845082) (xy 100.180139 -240.900258)
			(xy 100.180648 -240.928144) (xy 100.180139 -240.95603) (xy 100.172019 -241.011206) (xy 100.155951 -241.064613)
			(xy 100.132279 -241.11511) (xy 100.101506 -241.161623) (xy 100.064289 -241.20316) (xy 100.021421 -241.238835)
			(xy 99.973815 -241.267889) (xy 99.922486 -241.289701) (xy 99.868529 -241.303807) (xy 99.813092 -241.309907)
			(xy 99.757358 -241.30787) (xy 99.702515 -241.29774) (xy 99.649731 -241.279733) (xy 99.600131 -241.254232)
			(xy 99.554773 -241.221781) (xy 99.514624 -241.183072) (xy 99.480538 -241.138929) (xy 99.453242 -241.090294)
			(xy 99.433319 -241.038203) (xy 99.421193 -240.983766) (xy 99.417122 -240.928144) (xy 98.108839 -240.928144)
			(xy 98.086563 -240.975664) (xy 98.05579 -241.022177) (xy 98.018573 -241.063714) (xy 97.975705 -241.099389)
			(xy 97.928099 -241.128443) (xy 97.87677 -241.150255) (xy 97.822813 -241.164361) (xy 97.767376 -241.170461)
			(xy 97.711642 -241.168424) (xy 97.656799 -241.158294) (xy 97.604015 -241.140287) (xy 97.554415 -241.114786)
			(xy 97.509057 -241.082335) (xy 97.468908 -241.043626) (xy 97.434822 -240.999483) (xy 97.407526 -240.950848)
			(xy 97.387603 -240.898757) (xy 97.375477 -240.84432) (xy 97.371406 -240.788698) (xy 94.412917 -240.788698)
			(xy 94.407235 -240.82731) (xy 94.391167 -240.880717) (xy 94.367495 -240.931214) (xy 94.336722 -240.977727)
			(xy 94.299505 -241.019264) (xy 94.256637 -241.054939) (xy 94.209031 -241.083993) (xy 94.157702 -241.105805)
			(xy 94.103745 -241.119911) (xy 94.048308 -241.126011) (xy 93.992574 -241.123974) (xy 93.937731 -241.113844)
			(xy 93.884947 -241.095837) (xy 93.835347 -241.070336) (xy 93.789989 -241.037885) (xy 93.74984 -240.999176)
			(xy 93.715754 -240.955033) (xy 93.688458 -240.906398) (xy 93.668535 -240.854307) (xy 93.656409 -240.79987)
			(xy 93.652338 -240.744248) (xy 92.724408 -240.744248) (xy 92.693971 -240.778218) (xy 92.651103 -240.813893)
			(xy 92.603497 -240.842947) (xy 92.552168 -240.864759) (xy 92.498211 -240.878865) (xy 92.442774 -240.884965)
			(xy 92.38704 -240.882928) (xy 92.332197 -240.872798) (xy 92.279413 -240.854791) (xy 92.229813 -240.82929)
			(xy 92.184455 -240.796839) (xy 92.144306 -240.75813) (xy 92.11022 -240.713987) (xy 92.082924 -240.665352)
			(xy 92.063001 -240.613261) (xy 92.050875 -240.558824) (xy 92.046804 -240.503202) (xy 64.365353 -240.503202)
			(xy 64.237446 -241.242596) (xy 96.119694 -241.242596) (xy 96.123765 -241.186974) (xy 96.135891 -241.132537)
			(xy 96.155814 -241.080446) (xy 96.18311 -241.031811) (xy 96.217196 -240.987668) (xy 96.257345 -240.948959)
			(xy 96.302703 -240.916508) (xy 96.352303 -240.891007) (xy 96.405087 -240.873) (xy 96.45993 -240.86287)
			(xy 96.515664 -240.860833) (xy 96.571101 -240.866933) (xy 96.625058 -240.881039) (xy 96.676387 -240.902851)
			(xy 96.723993 -240.931905) (xy 96.766861 -240.96758) (xy 96.804078 -241.009117) (xy 96.834851 -241.05563)
			(xy 96.858523 -241.106127) (xy 96.874591 -241.159534) (xy 96.882711 -241.21471) (xy 96.88322 -241.242596)
			(xy 96.882711 -241.270482) (xy 96.874591 -241.325658) (xy 96.858523 -241.379065) (xy 96.834851 -241.429562)
			(xy 96.804078 -241.476075) (xy 96.766861 -241.517612) (xy 96.723993 -241.553287) (xy 96.676387 -241.582341)
			(xy 96.625058 -241.604153) (xy 96.571101 -241.618259) (xy 96.515664 -241.624359) (xy 96.45993 -241.622322)
			(xy 96.405087 -241.612192) (xy 96.352303 -241.594185) (xy 96.302703 -241.568684) (xy 96.257345 -241.536233)
			(xy 96.217196 -241.497524) (xy 96.18311 -241.453381) (xy 96.155814 -241.404746) (xy 96.135891 -241.352655)
			(xy 96.123765 -241.298218) (xy 96.119694 -241.242596) (xy 64.237446 -241.242596) (xy 64.05501 -242.297204)
			(xy 71.240902 -242.297204) (xy 71.244973 -242.241582) (xy 71.257099 -242.187145) (xy 71.277022 -242.135054)
			(xy 71.304318 -242.086419) (xy 71.338404 -242.042276) (xy 71.378553 -242.003567) (xy 71.423911 -241.971116)
			(xy 71.473511 -241.945615) (xy 71.526295 -241.927608) (xy 71.581138 -241.917478) (xy 71.636872 -241.915441)
			(xy 71.692309 -241.921541) (xy 71.746266 -241.935647) (xy 71.797595 -241.957459) (xy 71.845201 -241.986513)
			(xy 71.888069 -242.022188) (xy 71.925286 -242.063725) (xy 71.956059 -242.110238) (xy 71.979731 -242.160735)
			(xy 71.995799 -242.214142) (xy 71.999538 -242.239546) (xy 93.623636 -242.239546) (xy 93.627707 -242.183924)
			(xy 93.639833 -242.129487) (xy 93.659756 -242.077396) (xy 93.687052 -242.028761) (xy 93.721138 -241.984618)
			(xy 93.761287 -241.945909) (xy 93.806645 -241.913458) (xy 93.856245 -241.887957) (xy 93.909029 -241.86995)
			(xy 93.963872 -241.85982) (xy 94.019606 -241.857783) (xy 94.075043 -241.863883) (xy 94.129 -241.877989)
			(xy 94.180329 -241.899801) (xy 94.227935 -241.928855) (xy 94.270803 -241.96453) (xy 94.30802 -242.006067)
			(xy 94.338793 -242.05258) (xy 94.362465 -242.103077) (xy 94.378533 -242.156484) (xy 94.386653 -242.21166)
			(xy 94.387148 -242.238784) (xy 95.660718 -242.238784) (xy 95.661204 -242.211533) (xy 95.66896 -242.157585)
			(xy 95.684315 -242.10529) (xy 95.706957 -242.055713) (xy 95.736423 -242.009863) (xy 95.772114 -241.968672)
			(xy 95.813305 -241.932981) (xy 95.859155 -241.903515) (xy 95.908732 -241.880873) (xy 95.961027 -241.865518)
			(xy 96.014975 -241.857762) (xy 96.069477 -241.857762) (xy 96.123425 -241.865518) (xy 96.17572 -241.880873)
			(xy 96.225297 -241.903515) (xy 96.271147 -241.932981) (xy 96.312338 -241.968672) (xy 96.348029 -242.009863)
			(xy 96.377495 -242.055713) (xy 96.400137 -242.10529) (xy 96.415492 -242.157585) (xy 96.423248 -242.211533)
			(xy 96.423734 -242.238784) (xy 96.423734 -242.239038) (xy 96.423195 -242.268248) (xy 96.414295 -242.325986)
			(xy 96.39668 -242.381687) (xy 96.370762 -242.434043) (xy 96.354392 -242.45824) (xy 96.346586 -242.470125)
			(xy 96.33728 -242.496984) (xy 96.335729 -242.525366) (xy 96.342052 -242.553079) (xy 96.355761 -242.57798)
			(xy 96.375796 -242.598144) (xy 96.400608 -242.612012) (xy 96.414336 -242.61572) (xy 96.441951 -242.622701)
			(xy 96.494916 -242.643645) (xy 96.544177 -242.672233) (xy 96.588637 -242.707831) (xy 96.627309 -242.749645)
			(xy 96.659331 -242.796745) (xy 96.683992 -242.848085) (xy 96.700743 -242.902522) (xy 96.709211 -242.958844)
			(xy 96.709738 -242.987322) (xy 96.709252 -243.014573) (xy 96.701496 -243.068521) (xy 96.686141 -243.120816)
			(xy 96.663499 -243.170393) (xy 96.634033 -243.216243) (xy 96.598342 -243.257434) (xy 96.557151 -243.293125)
			(xy 96.511301 -243.322591) (xy 96.461724 -243.345233) (xy 96.409429 -243.360588) (xy 96.355481 -243.368344)
			(xy 96.300979 -243.368344) (xy 96.247031 -243.360588) (xy 96.194736 -243.345233) (xy 96.145159 -243.322591)
			(xy 96.099309 -243.293125) (xy 96.058118 -243.257434) (xy 96.022427 -243.216243) (xy 95.992961 -243.170393)
			(xy 95.970319 -243.120816) (xy 95.954964 -243.068521) (xy 95.947208 -243.014573) (xy 95.946722 -242.987322)
			(xy 95.946722 -242.987068) (xy 95.947272 -242.957858) (xy 95.95617 -242.900121) (xy 95.973782 -242.844421)
			(xy 95.999696 -242.792064) (xy 96.016064 -242.767866) (xy 96.02383 -242.755959) (xy 96.033129 -242.729108)
			(xy 96.034678 -242.700736) (xy 96.02836 -242.673032) (xy 96.014661 -242.648137) (xy 95.994639 -242.627974)
			(xy 95.969842 -242.614099) (xy 95.95612 -242.610386) (xy 95.928499 -242.60343) (xy 95.875535 -242.58248)
			(xy 95.826275 -242.553887) (xy 95.781816 -242.518286) (xy 95.743146 -242.476469) (xy 95.711124 -242.429366)
			(xy 95.686464 -242.378024) (xy 95.669714 -242.323586) (xy 95.661246 -242.267262) (xy 95.660718 -242.238784)
			(xy 94.387148 -242.238784) (xy 94.387162 -242.239546) (xy 94.386653 -242.267432) (xy 94.378533 -242.322608)
			(xy 94.362465 -242.376015) (xy 94.338793 -242.426512) (xy 94.30802 -242.473025) (xy 94.270803 -242.514562)
			(xy 94.227935 -242.550237) (xy 94.180329 -242.579291) (xy 94.129 -242.601103) (xy 94.075043 -242.615209)
			(xy 94.019606 -242.621309) (xy 93.963872 -242.619272) (xy 93.909029 -242.609142) (xy 93.856245 -242.591135)
			(xy 93.806645 -242.565634) (xy 93.761287 -242.533183) (xy 93.721138 -242.494474) (xy 93.687052 -242.450331)
			(xy 93.659756 -242.401696) (xy 93.639833 -242.349605) (xy 93.627707 -242.295168) (xy 93.623636 -242.239546)
			(xy 71.999538 -242.239546) (xy 72.003919 -242.269318) (xy 72.004428 -242.297204) (xy 72.003919 -242.32509)
			(xy 71.995799 -242.380266) (xy 71.979731 -242.433673) (xy 71.956059 -242.48417) (xy 71.925286 -242.530683)
			(xy 71.888069 -242.57222) (xy 71.845201 -242.607895) (xy 71.797595 -242.636949) (xy 71.746266 -242.658761)
			(xy 71.692309 -242.672867) (xy 71.636872 -242.678967) (xy 71.581138 -242.67693) (xy 71.526295 -242.6668)
			(xy 71.473511 -242.648793) (xy 71.423911 -242.623292) (xy 71.378553 -242.590841) (xy 71.338404 -242.552132)
			(xy 71.304318 -242.507989) (xy 71.277022 -242.459354) (xy 71.257099 -242.407263) (xy 71.244973 -242.352826)
			(xy 71.240902 -242.297204) (xy 64.05501 -242.297204) (xy 63.706308 -244.312948) (xy 95.852232 -244.312948)
			(xy 95.856303 -244.257326) (xy 95.868429 -244.202889) (xy 95.888352 -244.150798) (xy 95.915648 -244.102163)
			(xy 95.949734 -244.05802) (xy 95.989883 -244.019311) (xy 96.035241 -243.98686) (xy 96.084841 -243.961359)
			(xy 96.137625 -243.943352) (xy 96.192468 -243.933222) (xy 96.248202 -243.931185) (xy 96.303639 -243.937285)
			(xy 96.357596 -243.951391) (xy 96.408925 -243.973203) (xy 96.456531 -244.002257) (xy 96.499399 -244.037932)
			(xy 96.536616 -244.079469) (xy 96.567389 -244.125982) (xy 96.591061 -244.176479) (xy 96.607129 -244.229886)
			(xy 96.615249 -244.285062) (xy 96.615758 -244.312948) (xy 96.615249 -244.340834) (xy 96.607129 -244.39601)
			(xy 96.591061 -244.449417) (xy 96.567389 -244.499914) (xy 96.536616 -244.546427) (xy 96.518457 -244.566694)
			(xy 100.51999 -244.566694) (xy 100.524061 -244.511072) (xy 100.536187 -244.456635) (xy 100.55611 -244.404544)
			(xy 100.583406 -244.355909) (xy 100.617492 -244.311766) (xy 100.657641 -244.273057) (xy 100.702999 -244.240606)
			(xy 100.752599 -244.215105) (xy 100.805383 -244.197098) (xy 100.860226 -244.186968) (xy 100.91596 -244.184931)
			(xy 100.971397 -244.191031) (xy 101.025354 -244.205137) (xy 101.076683 -244.226949) (xy 101.124289 -244.256003)
			(xy 101.167157 -244.291678) (xy 101.204374 -244.333215) (xy 101.235147 -244.379728) (xy 101.258819 -244.430225)
			(xy 101.274887 -244.483632) (xy 101.283007 -244.538808) (xy 101.283516 -244.566694) (xy 101.283007 -244.59458)
			(xy 101.274887 -244.649756) (xy 101.258819 -244.703163) (xy 101.235147 -244.75366) (xy 101.204374 -244.800173)
			(xy 101.167157 -244.84171) (xy 101.124289 -244.877385) (xy 101.076683 -244.906439) (xy 101.025354 -244.928251)
			(xy 100.971397 -244.942357) (xy 100.91596 -244.948457) (xy 100.860226 -244.94642) (xy 100.805383 -244.93629)
			(xy 100.752599 -244.918283) (xy 100.702999 -244.892782) (xy 100.657641 -244.860331) (xy 100.617492 -244.821622)
			(xy 100.583406 -244.777479) (xy 100.55611 -244.728844) (xy 100.536187 -244.676753) (xy 100.524061 -244.622316)
			(xy 100.51999 -244.566694) (xy 96.518457 -244.566694) (xy 96.499399 -244.587964) (xy 96.456531 -244.623639)
			(xy 96.408925 -244.652693) (xy 96.357596 -244.674505) (xy 96.303639 -244.688611) (xy 96.248202 -244.694711)
			(xy 96.192468 -244.692674) (xy 96.137625 -244.682544) (xy 96.084841 -244.664537) (xy 96.035241 -244.639036)
			(xy 95.989883 -244.606585) (xy 95.949734 -244.567876) (xy 95.915648 -244.523733) (xy 95.888352 -244.475098)
			(xy 95.868429 -244.423007) (xy 95.856303 -244.36857) (xy 95.852232 -244.312948) (xy 63.706308 -244.312948)
			(xy 63.620626 -244.808248) (xy 93.652338 -244.808248) (xy 93.656409 -244.752626) (xy 93.668535 -244.698189)
			(xy 93.688458 -244.646098) (xy 93.715754 -244.597463) (xy 93.74984 -244.55332) (xy 93.789989 -244.514611)
			(xy 93.835347 -244.48216) (xy 93.884947 -244.456659) (xy 93.937731 -244.438652) (xy 93.992574 -244.428522)
			(xy 94.048308 -244.426485) (xy 94.103745 -244.432585) (xy 94.157702 -244.446691) (xy 94.209031 -244.468503)
			(xy 94.256637 -244.497557) (xy 94.299505 -244.533232) (xy 94.336722 -244.574769) (xy 94.367495 -244.621282)
			(xy 94.391167 -244.671779) (xy 94.407235 -244.725186) (xy 94.415355 -244.780362) (xy 94.415864 -244.808248)
			(xy 94.415355 -244.836134) (xy 94.407235 -244.89131) (xy 94.391167 -244.944717) (xy 94.367495 -244.995214)
			(xy 94.336722 -245.041727) (xy 94.299505 -245.083264) (xy 94.256637 -245.118939) (xy 94.209031 -245.147993)
			(xy 94.157702 -245.169805) (xy 94.103745 -245.183911) (xy 94.048308 -245.190011) (xy 93.992574 -245.187974)
			(xy 93.937731 -245.177844) (xy 93.884947 -245.159837) (xy 93.835347 -245.134336) (xy 93.789989 -245.101885)
			(xy 93.74984 -245.063176) (xy 93.715754 -245.019033) (xy 93.688458 -244.970398) (xy 93.668535 -244.918307)
			(xy 93.656409 -244.86387) (xy 93.652338 -244.808248) (xy 63.620626 -244.808248) (xy 63.444869 -245.824248)
			(xy 95.865694 -245.824248) (xy 95.869765 -245.768626) (xy 95.881891 -245.714189) (xy 95.901814 -245.662098)
			(xy 95.92911 -245.613463) (xy 95.963196 -245.56932) (xy 96.003345 -245.530611) (xy 96.048703 -245.49816)
			(xy 96.098303 -245.472659) (xy 96.151087 -245.454652) (xy 96.20593 -245.444522) (xy 96.261664 -245.442485)
			(xy 96.317101 -245.448585) (xy 96.371058 -245.462691) (xy 96.422387 -245.484503) (xy 96.469993 -245.513557)
			(xy 96.512861 -245.549232) (xy 96.550078 -245.590769) (xy 96.580851 -245.637282) (xy 96.604523 -245.687779)
			(xy 96.620591 -245.741186) (xy 96.628711 -245.796362) (xy 96.62922 -245.824248) (xy 96.628711 -245.852134)
			(xy 96.620591 -245.90731) (xy 96.609282 -245.944898) (xy 100.372416 -245.944898) (xy 100.376487 -245.889276)
			(xy 100.388613 -245.834839) (xy 100.408536 -245.782748) (xy 100.435832 -245.734113) (xy 100.469918 -245.68997)
			(xy 100.510067 -245.651261) (xy 100.555425 -245.61881) (xy 100.605025 -245.593309) (xy 100.657809 -245.575302)
			(xy 100.712652 -245.565172) (xy 100.768386 -245.563135) (xy 100.823823 -245.569235) (xy 100.87778 -245.583341)
			(xy 100.929109 -245.605153) (xy 100.976715 -245.634207) (xy 101.019583 -245.669882) (xy 101.0568 -245.711419)
			(xy 101.087573 -245.757932) (xy 101.111245 -245.808429) (xy 101.127313 -245.861836) (xy 101.135433 -245.917012)
			(xy 101.135942 -245.944898) (xy 101.135433 -245.972784) (xy 101.127313 -246.02796) (xy 101.111245 -246.081367)
			(xy 101.087573 -246.131864) (xy 101.0568 -246.178377) (xy 101.019583 -246.219914) (xy 100.976715 -246.255589)
			(xy 100.929109 -246.284643) (xy 100.87778 -246.306455) (xy 100.823823 -246.320561) (xy 100.768386 -246.326661)
			(xy 100.712652 -246.324624) (xy 100.657809 -246.314494) (xy 100.605025 -246.296487) (xy 100.555425 -246.270986)
			(xy 100.510067 -246.238535) (xy 100.469918 -246.199826) (xy 100.435832 -246.155683) (xy 100.408536 -246.107048)
			(xy 100.388613 -246.054957) (xy 100.376487 -246.00052) (xy 100.372416 -245.944898) (xy 96.609282 -245.944898)
			(xy 96.604523 -245.960717) (xy 96.580851 -246.011214) (xy 96.550078 -246.057727) (xy 96.512861 -246.099264)
			(xy 96.469993 -246.134939) (xy 96.422387 -246.163993) (xy 96.371058 -246.185805) (xy 96.317101 -246.199911)
			(xy 96.261664 -246.206011) (xy 96.20593 -246.203974) (xy 96.151087 -246.193844) (xy 96.098303 -246.175837)
			(xy 96.048703 -246.150336) (xy 96.003345 -246.117885) (xy 95.963196 -246.079176) (xy 95.92911 -246.035033)
			(xy 95.901814 -245.986398) (xy 95.881891 -245.934307) (xy 95.869765 -245.87987) (xy 95.865694 -245.824248)
			(xy 63.444869 -245.824248) (xy 63.269112 -246.840248) (xy 93.652338 -246.840248) (xy 93.656409 -246.784626)
			(xy 93.668535 -246.730189) (xy 93.688458 -246.678098) (xy 93.715754 -246.629463) (xy 93.74984 -246.58532)
			(xy 93.789989 -246.546611) (xy 93.835347 -246.51416) (xy 93.884947 -246.488659) (xy 93.937731 -246.470652)
			(xy 93.992574 -246.460522) (xy 94.048308 -246.458485) (xy 94.103745 -246.464585) (xy 94.157702 -246.478691)
			(xy 94.209031 -246.500503) (xy 94.256637 -246.529557) (xy 94.299505 -246.565232) (xy 94.336722 -246.606769)
			(xy 94.367495 -246.653282) (xy 94.391167 -246.703779) (xy 94.407235 -246.757186) (xy 94.415355 -246.812362)
			(xy 94.415716 -246.83212) (xy 99.693474 -246.83212) (xy 99.697545 -246.776498) (xy 99.709671 -246.722061)
			(xy 99.729594 -246.66997) (xy 99.75689 -246.621335) (xy 99.790976 -246.577192) (xy 99.831125 -246.538483)
			(xy 99.876483 -246.506032) (xy 99.926083 -246.480531) (xy 99.978867 -246.462524) (xy 100.03371 -246.452394)
			(xy 100.089444 -246.450357) (xy 100.144881 -246.456457) (xy 100.198838 -246.470563) (xy 100.250167 -246.492375)
			(xy 100.297773 -246.521429) (xy 100.340641 -246.557104) (xy 100.377858 -246.598641) (xy 100.408631 -246.645154)
			(xy 100.432303 -246.695651) (xy 100.448371 -246.749058) (xy 100.456491 -246.804234) (xy 100.457 -246.83212)
			(xy 100.456491 -246.860006) (xy 100.448371 -246.915182) (xy 100.432303 -246.968589) (xy 100.408631 -247.019086)
			(xy 100.377858 -247.065599) (xy 100.340641 -247.107136) (xy 100.297773 -247.142811) (xy 100.250167 -247.171865)
			(xy 100.198838 -247.193677) (xy 100.144881 -247.207783) (xy 100.089444 -247.213883) (xy 100.03371 -247.211846)
			(xy 99.978867 -247.201716) (xy 99.926083 -247.183709) (xy 99.876483 -247.158208) (xy 99.831125 -247.125757)
			(xy 99.790976 -247.087048) (xy 99.75689 -247.042905) (xy 99.729594 -246.99427) (xy 99.709671 -246.942179)
			(xy 99.697545 -246.887742) (xy 99.693474 -246.83212) (xy 94.415716 -246.83212) (xy 94.415864 -246.840248)
			(xy 94.415355 -246.868134) (xy 94.407235 -246.92331) (xy 94.391167 -246.976717) (xy 94.367495 -247.027214)
			(xy 94.336722 -247.073727) (xy 94.299505 -247.115264) (xy 94.256637 -247.150939) (xy 94.209031 -247.179993)
			(xy 94.157702 -247.201805) (xy 94.103745 -247.215911) (xy 94.048308 -247.222011) (xy 93.992574 -247.219974)
			(xy 93.937731 -247.209844) (xy 93.884947 -247.191837) (xy 93.835347 -247.166336) (xy 93.789989 -247.133885)
			(xy 93.74984 -247.095176) (xy 93.715754 -247.051033) (xy 93.688458 -247.002398) (xy 93.668535 -246.950307)
			(xy 93.656409 -246.89587) (xy 93.652338 -246.840248) (xy 63.269112 -246.840248) (xy 62.489717 -251.3457)
			(xy 123.339096 -251.3457) (xy 123.343167 -251.290078) (xy 123.355293 -251.235641) (xy 123.375216 -251.18355)
			(xy 123.402512 -251.134915) (xy 123.436598 -251.090772) (xy 123.476747 -251.052063) (xy 123.522105 -251.019612)
			(xy 123.571705 -250.994111) (xy 123.624489 -250.976104) (xy 123.679332 -250.965974) (xy 123.735066 -250.963937)
			(xy 123.790503 -250.970037) (xy 123.84446 -250.984143) (xy 123.895789 -251.005955) (xy 123.943395 -251.035009)
			(xy 123.986263 -251.070684) (xy 124.02348 -251.112221) (xy 124.054253 -251.158734) (xy 124.077925 -251.209231)
			(xy 124.093993 -251.262638) (xy 124.102113 -251.317814) (xy 124.102622 -251.3457) (xy 124.863096 -251.3457)
			(xy 124.867167 -251.290078) (xy 124.879293 -251.235641) (xy 124.899216 -251.18355) (xy 124.926512 -251.134915)
			(xy 124.960598 -251.090772) (xy 125.000747 -251.052063) (xy 125.046105 -251.019612) (xy 125.095705 -250.994111)
			(xy 125.148489 -250.976104) (xy 125.203332 -250.965974) (xy 125.259066 -250.963937) (xy 125.314503 -250.970037)
			(xy 125.36846 -250.984143) (xy 125.419789 -251.005955) (xy 125.467395 -251.035009) (xy 125.510263 -251.070684)
			(xy 125.54748 -251.112221) (xy 125.578253 -251.158734) (xy 125.601925 -251.209231) (xy 125.617993 -251.262638)
			(xy 125.626113 -251.317814) (xy 125.626622 -251.3457) (xy 125.626113 -251.373586) (xy 125.617993 -251.428762)
			(xy 125.601925 -251.482169) (xy 125.578253 -251.532666) (xy 125.54748 -251.579179) (xy 125.510263 -251.620716)
			(xy 125.467395 -251.656391) (xy 125.419789 -251.685445) (xy 125.36846 -251.707257) (xy 125.314503 -251.721363)
			(xy 125.259066 -251.727463) (xy 125.203332 -251.725426) (xy 125.148489 -251.715296) (xy 125.095705 -251.697289)
			(xy 125.046105 -251.671788) (xy 125.000747 -251.639337) (xy 124.960598 -251.600628) (xy 124.926512 -251.556485)
			(xy 124.899216 -251.50785) (xy 124.879293 -251.455759) (xy 124.867167 -251.401322) (xy 124.863096 -251.3457)
			(xy 124.102622 -251.3457) (xy 124.102113 -251.373586) (xy 124.093993 -251.428762) (xy 124.077925 -251.482169)
			(xy 124.054253 -251.532666) (xy 124.02348 -251.579179) (xy 123.986263 -251.620716) (xy 123.943395 -251.656391)
			(xy 123.895789 -251.685445) (xy 123.84446 -251.707257) (xy 123.790503 -251.721363) (xy 123.735066 -251.727463)
			(xy 123.679332 -251.725426) (xy 123.624489 -251.715296) (xy 123.571705 -251.697289) (xy 123.522105 -251.671788)
			(xy 123.476747 -251.639337) (xy 123.436598 -251.600628) (xy 123.402512 -251.556485) (xy 123.375216 -251.50785)
			(xy 123.355293 -251.455759) (xy 123.343167 -251.401322) (xy 123.339096 -251.3457) (xy 62.489717 -251.3457)
			(xy 62.357108 -252.112272) (xy 120.272554 -252.112272) (xy 120.276625 -252.05665) (xy 120.288751 -252.002213)
			(xy 120.308674 -251.950122) (xy 120.33597 -251.901487) (xy 120.370056 -251.857344) (xy 120.410205 -251.818635)
			(xy 120.455563 -251.786184) (xy 120.505163 -251.760683) (xy 120.557947 -251.742676) (xy 120.61279 -251.732546)
			(xy 120.668524 -251.730509) (xy 120.723961 -251.736609) (xy 120.777918 -251.750715) (xy 120.829247 -251.772527)
			(xy 120.876853 -251.801581) (xy 120.919721 -251.837256) (xy 120.956938 -251.878793) (xy 120.987711 -251.925306)
			(xy 121.011383 -251.975803) (xy 121.027451 -252.02921) (xy 121.035571 -252.084386) (xy 121.03608 -252.112272)
			(xy 121.035571 -252.140158) (xy 121.027451 -252.195334) (xy 121.011383 -252.248741) (xy 120.987711 -252.299238)
			(xy 120.956938 -252.345751) (xy 120.919721 -252.387288) (xy 120.876853 -252.422963) (xy 120.829247 -252.452017)
			(xy 120.777918 -252.473829) (xy 120.723961 -252.487935) (xy 120.668524 -252.494035) (xy 120.61279 -252.491998)
			(xy 120.557947 -252.481868) (xy 120.505163 -252.463861) (xy 120.455563 -252.43836) (xy 120.410205 -252.405909)
			(xy 120.370056 -252.3672) (xy 120.33597 -252.323057) (xy 120.308674 -252.274422) (xy 120.288751 -252.222331)
			(xy 120.276625 -252.167894) (xy 120.272554 -252.112272) (xy 62.357108 -252.112272) (xy 62.185218 -253.10592)
			(xy 118.323612 -253.10592) (xy 118.327683 -253.050298) (xy 118.339809 -252.995861) (xy 118.359732 -252.94377)
			(xy 118.387028 -252.895135) (xy 118.421114 -252.850992) (xy 118.461263 -252.812283) (xy 118.506621 -252.779832)
			(xy 118.556221 -252.754331) (xy 118.609005 -252.736324) (xy 118.663848 -252.726194) (xy 118.719582 -252.724157)
			(xy 118.775019 -252.730257) (xy 118.828976 -252.744363) (xy 118.880305 -252.766175) (xy 118.927911 -252.795229)
			(xy 118.970779 -252.830904) (xy 119.007996 -252.872441) (xy 119.038769 -252.918954) (xy 119.062441 -252.969451)
			(xy 119.078509 -253.022858) (xy 119.086629 -253.078034) (xy 119.087138 -253.10592) (xy 119.086629 -253.133806)
			(xy 119.078509 -253.188982) (xy 119.062441 -253.242389) (xy 119.038769 -253.292886) (xy 119.007996 -253.339399)
			(xy 118.970779 -253.380936) (xy 118.962459 -253.38786) (xy 126.243078 -253.38786) (xy 126.247149 -253.332238)
			(xy 126.259275 -253.277801) (xy 126.279198 -253.22571) (xy 126.306494 -253.177075) (xy 126.34058 -253.132932)
			(xy 126.380729 -253.094223) (xy 126.426087 -253.061772) (xy 126.475687 -253.036271) (xy 126.528471 -253.018264)
			(xy 126.583314 -253.008134) (xy 126.639048 -253.006097) (xy 126.694485 -253.012197) (xy 126.748442 -253.026303)
			(xy 126.799771 -253.048115) (xy 126.847377 -253.077169) (xy 126.890245 -253.112844) (xy 126.927462 -253.154381)
			(xy 126.943461 -253.178564) (xy 128.285746 -253.178564) (xy 128.289817 -253.122942) (xy 128.301943 -253.068505)
			(xy 128.321866 -253.016414) (xy 128.349162 -252.967779) (xy 128.383248 -252.923636) (xy 128.423397 -252.884927)
			(xy 128.468755 -252.852476) (xy 128.518355 -252.826975) (xy 128.571139 -252.808968) (xy 128.625982 -252.798838)
			(xy 128.681716 -252.796801) (xy 128.737153 -252.802901) (xy 128.79111 -252.817007) (xy 128.842439 -252.838819)
			(xy 128.890045 -252.867873) (xy 128.932913 -252.903548) (xy 128.97013 -252.945085) (xy 129.000903 -252.991598)
			(xy 129.024575 -253.042095) (xy 129.040643 -253.095502) (xy 129.048763 -253.150678) (xy 129.049272 -253.178564)
			(xy 130.349242 -253.178564) (xy 130.353313 -253.122942) (xy 130.365439 -253.068505) (xy 130.385362 -253.016414)
			(xy 130.412658 -252.967779) (xy 130.446744 -252.923636) (xy 130.486893 -252.884927) (xy 130.532251 -252.852476)
			(xy 130.581851 -252.826975) (xy 130.634635 -252.808968) (xy 130.689478 -252.798838) (xy 130.745212 -252.796801)
			(xy 130.800649 -252.802901) (xy 130.854606 -252.817007) (xy 130.905935 -252.838819) (xy 130.953541 -252.867873)
			(xy 130.996409 -252.903548) (xy 131.033626 -252.945085) (xy 131.064399 -252.991598) (xy 131.088071 -253.042095)
			(xy 131.104139 -253.095502) (xy 131.112259 -253.150678) (xy 131.112768 -253.178564) (xy 131.112259 -253.20645)
			(xy 131.104139 -253.261626) (xy 131.088071 -253.315033) (xy 131.064399 -253.36553) (xy 131.033626 -253.412043)
			(xy 130.996409 -253.45358) (xy 130.953541 -253.489255) (xy 130.905935 -253.518309) (xy 130.854606 -253.540121)
			(xy 130.800649 -253.554227) (xy 130.745212 -253.560327) (xy 130.689478 -253.55829) (xy 130.634635 -253.54816)
			(xy 130.581851 -253.530153) (xy 130.532251 -253.504652) (xy 130.486893 -253.472201) (xy 130.446744 -253.433492)
			(xy 130.412658 -253.389349) (xy 130.385362 -253.340714) (xy 130.365439 -253.288623) (xy 130.353313 -253.234186)
			(xy 130.349242 -253.178564) (xy 129.049272 -253.178564) (xy 129.048763 -253.20645) (xy 129.040643 -253.261626)
			(xy 129.024575 -253.315033) (xy 129.000903 -253.36553) (xy 128.97013 -253.412043) (xy 128.932913 -253.45358)
			(xy 128.890045 -253.489255) (xy 128.842439 -253.518309) (xy 128.79111 -253.540121) (xy 128.737153 -253.554227)
			(xy 128.681716 -253.560327) (xy 128.625982 -253.55829) (xy 128.571139 -253.54816) (xy 128.518355 -253.530153)
			(xy 128.468755 -253.504652) (xy 128.423397 -253.472201) (xy 128.383248 -253.433492) (xy 128.349162 -253.389349)
			(xy 128.321866 -253.340714) (xy 128.301943 -253.288623) (xy 128.289817 -253.234186) (xy 128.285746 -253.178564)
			(xy 126.943461 -253.178564) (xy 126.958235 -253.200894) (xy 126.981907 -253.251391) (xy 126.997975 -253.304798)
			(xy 127.006095 -253.359974) (xy 127.006604 -253.38786) (xy 127.006095 -253.415746) (xy 126.997975 -253.470922)
			(xy 126.981907 -253.524329) (xy 126.958235 -253.574826) (xy 126.927462 -253.621339) (xy 126.890245 -253.662876)
			(xy 126.847377 -253.698551) (xy 126.799771 -253.727605) (xy 126.748442 -253.749417) (xy 126.694485 -253.763523)
			(xy 126.639048 -253.769623) (xy 126.583314 -253.767586) (xy 126.528471 -253.757456) (xy 126.475687 -253.739449)
			(xy 126.426087 -253.713948) (xy 126.380729 -253.681497) (xy 126.34058 -253.642788) (xy 126.306494 -253.598645)
			(xy 126.279198 -253.55001) (xy 126.259275 -253.497919) (xy 126.247149 -253.443482) (xy 126.243078 -253.38786)
			(xy 118.962459 -253.38786) (xy 118.927911 -253.416611) (xy 118.880305 -253.445665) (xy 118.828976 -253.467477)
			(xy 118.775019 -253.481583) (xy 118.719582 -253.487683) (xy 118.663848 -253.485646) (xy 118.609005 -253.475516)
			(xy 118.556221 -253.457509) (xy 118.506621 -253.432008) (xy 118.461263 -253.399557) (xy 118.421114 -253.360848)
			(xy 118.387028 -253.316705) (xy 118.359732 -253.26807) (xy 118.339809 -253.215979) (xy 118.327683 -253.161542)
			(xy 118.323612 -253.10592) (xy 62.185218 -253.10592) (xy 61.982965 -254.275082) (xy 95.830642 -254.275082)
			(xy 95.834713 -254.21946) (xy 95.846839 -254.165023) (xy 95.866762 -254.112932) (xy 95.894058 -254.064297)
			(xy 95.928144 -254.020154) (xy 95.968293 -253.981445) (xy 96.013651 -253.948994) (xy 96.063251 -253.923493)
			(xy 96.116035 -253.905486) (xy 96.170878 -253.895356) (xy 96.226612 -253.893319) (xy 96.282049 -253.899419)
			(xy 96.336006 -253.913525) (xy 96.387335 -253.935337) (xy 96.434941 -253.964391) (xy 96.477809 -254.000066)
			(xy 96.515026 -254.041603) (xy 96.545799 -254.088116) (xy 96.569471 -254.138613) (xy 96.577211 -254.164338)
			(xy 117.675912 -254.164338) (xy 117.679983 -254.108716) (xy 117.692109 -254.054279) (xy 117.712032 -254.002188)
			(xy 117.739328 -253.953553) (xy 117.773414 -253.90941) (xy 117.813563 -253.870701) (xy 117.858921 -253.83825)
			(xy 117.908521 -253.812749) (xy 117.961305 -253.794742) (xy 118.016148 -253.784612) (xy 118.071882 -253.782575)
			(xy 118.127319 -253.788675) (xy 118.181276 -253.802781) (xy 118.232605 -253.824593) (xy 118.280211 -253.853647)
			(xy 118.323079 -253.889322) (xy 118.360296 -253.930859) (xy 118.391069 -253.977372) (xy 118.394651 -253.985014)
			(xy 121.718576 -253.985014) (xy 121.722647 -253.929392) (xy 121.734773 -253.874955) (xy 121.754696 -253.822864)
			(xy 121.781992 -253.774229) (xy 121.816078 -253.730086) (xy 121.856227 -253.691377) (xy 121.901585 -253.658926)
			(xy 121.951185 -253.633425) (xy 122.003969 -253.615418) (xy 122.058812 -253.605288) (xy 122.114546 -253.603251)
			(xy 122.169983 -253.609351) (xy 122.22394 -253.623457) (xy 122.275269 -253.645269) (xy 122.322875 -253.674323)
			(xy 122.365743 -253.709998) (xy 122.40296 -253.751535) (xy 122.433733 -253.798048) (xy 122.457405 -253.848545)
			(xy 122.473473 -253.901952) (xy 122.481593 -253.957128) (xy 122.482102 -253.985014) (xy 122.481593 -254.0129)
			(xy 122.473473 -254.068076) (xy 122.457405 -254.121483) (xy 122.433733 -254.17198) (xy 122.418791 -254.194564)
			(xy 130.317746 -254.194564) (xy 130.321817 -254.138942) (xy 130.333943 -254.084505) (xy 130.353866 -254.032414)
			(xy 130.381162 -253.983779) (xy 130.415248 -253.939636) (xy 130.455397 -253.900927) (xy 130.500755 -253.868476)
			(xy 130.550355 -253.842975) (xy 130.603139 -253.824968) (xy 130.657982 -253.814838) (xy 130.713716 -253.812801)
			(xy 130.769153 -253.818901) (xy 130.82311 -253.833007) (xy 130.874439 -253.854819) (xy 130.922045 -253.883873)
			(xy 130.964913 -253.919548) (xy 131.00213 -253.961085) (xy 131.032903 -254.007598) (xy 131.056575 -254.058095)
			(xy 131.072643 -254.111502) (xy 131.080763 -254.166678) (xy 131.081272 -254.194564) (xy 131.080763 -254.22245)
			(xy 131.072643 -254.277626) (xy 131.056575 -254.331033) (xy 131.032903 -254.38153) (xy 131.00213 -254.428043)
			(xy 130.964913 -254.46958) (xy 130.922045 -254.505255) (xy 130.874439 -254.534309) (xy 130.82311 -254.556121)
			(xy 130.769153 -254.570227) (xy 130.713716 -254.576327) (xy 130.657982 -254.57429) (xy 130.603139 -254.56416)
			(xy 130.550355 -254.546153) (xy 130.500755 -254.520652) (xy 130.455397 -254.488201) (xy 130.415248 -254.449492)
			(xy 130.381162 -254.405349) (xy 130.353866 -254.356714) (xy 130.333943 -254.304623) (xy 130.321817 -254.250186)
			(xy 130.317746 -254.194564) (xy 122.418791 -254.194564) (xy 122.40296 -254.218493) (xy 122.365743 -254.26003)
			(xy 122.322875 -254.295705) (xy 122.275269 -254.324759) (xy 122.22394 -254.346571) (xy 122.169983 -254.360677)
			(xy 122.114546 -254.366777) (xy 122.058812 -254.36474) (xy 122.003969 -254.35461) (xy 121.951185 -254.336603)
			(xy 121.901585 -254.311102) (xy 121.856227 -254.278651) (xy 121.816078 -254.239942) (xy 121.781992 -254.195799)
			(xy 121.754696 -254.147164) (xy 121.734773 -254.095073) (xy 121.722647 -254.040636) (xy 121.718576 -253.985014)
			(xy 118.394651 -253.985014) (xy 118.414741 -254.027869) (xy 118.430809 -254.081276) (xy 118.438929 -254.136452)
			(xy 118.439438 -254.164338) (xy 118.438929 -254.192224) (xy 118.430809 -254.2474) (xy 118.414741 -254.300807)
			(xy 118.391069 -254.351304) (xy 118.360296 -254.397817) (xy 118.323079 -254.439354) (xy 118.280211 -254.475029)
			(xy 118.232605 -254.504083) (xy 118.181276 -254.525895) (xy 118.127319 -254.540001) (xy 118.071882 -254.546101)
			(xy 118.016148 -254.544064) (xy 117.961305 -254.533934) (xy 117.908521 -254.515927) (xy 117.858921 -254.490426)
			(xy 117.813563 -254.457975) (xy 117.773414 -254.419266) (xy 117.739328 -254.375123) (xy 117.712032 -254.326488)
			(xy 117.692109 -254.274397) (xy 117.679983 -254.21996) (xy 117.675912 -254.164338) (xy 96.577211 -254.164338)
			(xy 96.585539 -254.19202) (xy 96.593659 -254.247196) (xy 96.594168 -254.275082) (xy 96.593659 -254.302968)
			(xy 96.585539 -254.358144) (xy 96.569471 -254.411551) (xy 96.545799 -254.462048) (xy 96.515026 -254.508561)
			(xy 96.477809 -254.550098) (xy 96.434941 -254.585773) (xy 96.387335 -254.614827) (xy 96.336006 -254.636639)
			(xy 96.282049 -254.650745) (xy 96.226612 -254.656845) (xy 96.170878 -254.654808) (xy 96.116035 -254.644678)
			(xy 96.063251 -254.626671) (xy 96.013651 -254.60117) (xy 95.968293 -254.568719) (xy 95.928144 -254.53001)
			(xy 95.894058 -254.485867) (xy 95.866762 -254.437232) (xy 95.846839 -254.385141) (xy 95.834713 -254.330704)
			(xy 95.830642 -254.275082) (xy 61.982965 -254.275082) (xy 61.763796 -255.542034) (xy 96.209102 -255.542034)
			(xy 96.213173 -255.486412) (xy 96.225299 -255.431975) (xy 96.245222 -255.379884) (xy 96.272518 -255.331249)
			(xy 96.306604 -255.287106) (xy 96.346753 -255.248397) (xy 96.392111 -255.215946) (xy 96.441711 -255.190445)
			(xy 96.494495 -255.172438) (xy 96.549338 -255.162308) (xy 96.605072 -255.160271) (xy 96.660509 -255.166371)
			(xy 96.714466 -255.180477) (xy 96.765795 -255.202289) (xy 96.813401 -255.231343) (xy 96.821227 -255.237856)
			(xy 114.069019 -255.237856) (xy 114.069019 -255.183344) (xy 114.076777 -255.129387) (xy 114.092135 -255.077083)
			(xy 114.114781 -255.027497) (xy 114.144253 -254.981639) (xy 114.179952 -254.940442) (xy 114.22115 -254.904745)
			(xy 114.267009 -254.875274) (xy 114.316596 -254.85263) (xy 114.3689 -254.837274) (xy 114.422858 -254.829518)
			(xy 114.450114 -254.829056) (xy 114.481487 -254.829688) (xy 114.543386 -254.839967) (xy 114.602771 -254.860231)
			(xy 114.630708 -254.874522) (xy 114.640549 -254.879178) (xy 114.66225 -254.880636) (xy 114.672618 -254.877316)
			(xy 114.743992 -254.850646) (xy 114.754001 -254.84633) (xy 114.769404 -254.83094) (xy 114.77371 -254.820928)
			(xy 114.784422 -254.794132) (xy 114.812718 -254.743841) (xy 114.848266 -254.698384) (xy 114.890253 -254.6588)
			(xy 114.937724 -254.62599) (xy 114.989594 -254.600704) (xy 115.044681 -254.583519) (xy 115.101727 -254.574825)
			(xy 115.13058 -254.574294) (xy 115.157834 -254.574752) (xy 115.211787 -254.582507) (xy 115.264088 -254.597861)
			(xy 115.313671 -254.620503) (xy 115.359527 -254.64997) (xy 115.400722 -254.685664) (xy 115.436418 -254.726857)
			(xy 115.465888 -254.772712) (xy 115.488532 -254.822293) (xy 115.503889 -254.874593) (xy 115.511647 -254.928546)
			(xy 115.511647 -254.983054) (xy 115.503889 -255.037007) (xy 115.488532 -255.089307) (xy 115.465888 -255.138888)
			(xy 115.436418 -255.184743) (xy 115.432972 -255.18872) (xy 116.295422 -255.18872) (xy 116.299493 -255.133098)
			(xy 116.311619 -255.078661) (xy 116.331542 -255.02657) (xy 116.358838 -254.977935) (xy 116.392924 -254.933792)
			(xy 116.433073 -254.895083) (xy 116.478431 -254.862632) (xy 116.528031 -254.837131) (xy 116.580815 -254.819124)
			(xy 116.635658 -254.808994) (xy 116.691392 -254.806957) (xy 116.746829 -254.813057) (xy 116.800786 -254.827163)
			(xy 116.852115 -254.848975) (xy 116.899721 -254.878029) (xy 116.942589 -254.913704) (xy 116.979806 -254.955241)
			(xy 117.010579 -255.001754) (xy 117.034251 -255.052251) (xy 117.050319 -255.105658) (xy 117.051142 -255.11125)
			(xy 120.99366 -255.11125) (xy 120.997731 -255.055628) (xy 121.009857 -255.001191) (xy 121.02978 -254.9491)
			(xy 121.057076 -254.900465) (xy 121.091162 -254.856322) (xy 121.131311 -254.817613) (xy 121.176669 -254.785162)
			(xy 121.226269 -254.759661) (xy 121.279053 -254.741654) (xy 121.333896 -254.731524) (xy 121.38963 -254.729487)
			(xy 121.445067 -254.735587) (xy 121.499024 -254.749693) (xy 121.550353 -254.771505) (xy 121.597959 -254.800559)
			(xy 121.640827 -254.836234) (xy 121.678044 -254.877771) (xy 121.708817 -254.924284) (xy 121.732489 -254.974781)
			(xy 121.748557 -255.028188) (xy 121.756677 -255.083364) (xy 121.757186 -255.11125) (xy 121.756677 -255.139136)
			(xy 121.748557 -255.194312) (xy 121.743667 -255.210564) (xy 130.349242 -255.210564) (xy 130.353313 -255.154942)
			(xy 130.365439 -255.100505) (xy 130.385362 -255.048414) (xy 130.412658 -254.999779) (xy 130.446744 -254.955636)
			(xy 130.486893 -254.916927) (xy 130.532251 -254.884476) (xy 130.581851 -254.858975) (xy 130.634635 -254.840968)
			(xy 130.689478 -254.830838) (xy 130.745212 -254.828801) (xy 130.800649 -254.834901) (xy 130.854606 -254.849007)
			(xy 130.905935 -254.870819) (xy 130.953541 -254.899873) (xy 130.996409 -254.935548) (xy 131.033626 -254.977085)
			(xy 131.064399 -255.023598) (xy 131.088071 -255.074095) (xy 131.104139 -255.127502) (xy 131.112259 -255.182678)
			(xy 131.112768 -255.210564) (xy 131.112259 -255.23845) (xy 131.104139 -255.293626) (xy 131.088071 -255.347033)
			(xy 131.064399 -255.39753) (xy 131.033626 -255.444043) (xy 130.996409 -255.48558) (xy 130.953541 -255.521255)
			(xy 130.905935 -255.550309) (xy 130.854606 -255.572121) (xy 130.800649 -255.586227) (xy 130.745212 -255.592327)
			(xy 130.689478 -255.59029) (xy 130.634635 -255.58016) (xy 130.581851 -255.562153) (xy 130.532251 -255.536652)
			(xy 130.486893 -255.504201) (xy 130.446744 -255.465492) (xy 130.412658 -255.421349) (xy 130.385362 -255.372714)
			(xy 130.365439 -255.320623) (xy 130.353313 -255.266186) (xy 130.349242 -255.210564) (xy 121.743667 -255.210564)
			(xy 121.732489 -255.247719) (xy 121.708817 -255.298216) (xy 121.678044 -255.344729) (xy 121.640827 -255.386266)
			(xy 121.597959 -255.421941) (xy 121.550353 -255.450995) (xy 121.499024 -255.472807) (xy 121.445067 -255.486913)
			(xy 121.38963 -255.493013) (xy 121.333896 -255.490976) (xy 121.279053 -255.480846) (xy 121.226269 -255.462839)
			(xy 121.176669 -255.437338) (xy 121.131311 -255.404887) (xy 121.091162 -255.366178) (xy 121.057076 -255.322035)
			(xy 121.02978 -255.2734) (xy 121.009857 -255.221309) (xy 120.997731 -255.166872) (xy 120.99366 -255.11125)
			(xy 117.051142 -255.11125) (xy 117.058439 -255.160834) (xy 117.058948 -255.18872) (xy 117.058439 -255.216606)
			(xy 117.050319 -255.271782) (xy 117.034251 -255.325189) (xy 117.010579 -255.375686) (xy 116.979806 -255.422199)
			(xy 116.942589 -255.463736) (xy 116.899721 -255.499411) (xy 116.852115 -255.528465) (xy 116.800786 -255.550277)
			(xy 116.746829 -255.564383) (xy 116.691392 -255.570483) (xy 116.635658 -255.568446) (xy 116.580815 -255.558316)
			(xy 116.528031 -255.540309) (xy 116.478431 -255.514808) (xy 116.433073 -255.482357) (xy 116.392924 -255.443648)
			(xy 116.358838 -255.399505) (xy 116.331542 -255.35087) (xy 116.311619 -255.298779) (xy 116.299493 -255.244342)
			(xy 116.295422 -255.18872) (xy 115.432972 -255.18872) (xy 115.400722 -255.225936) (xy 115.359527 -255.26163)
			(xy 115.313671 -255.291097) (xy 115.264088 -255.313739) (xy 115.211787 -255.329093) (xy 115.157834 -255.336848)
			(xy 115.13058 -255.33731) (xy 115.099206 -255.336685) (xy 115.037307 -255.326403) (xy 114.977922 -255.306137)
			(xy 114.949986 -255.291844) (xy 114.940146 -255.287183) (xy 114.918443 -255.285726) (xy 114.908076 -255.28905)
			(xy 114.836702 -255.31572) (xy 114.826677 -255.320006) (xy 114.81128 -255.335416) (xy 114.806984 -255.345438)
			(xy 114.796259 -255.372229) (xy 114.767966 -255.422521) (xy 114.732422 -255.467979) (xy 114.690436 -255.507565)
			(xy 114.642967 -255.540375) (xy 114.591098 -255.565662) (xy 114.536012 -255.582848) (xy 114.478966 -255.591541)
			(xy 114.450114 -255.592072) (xy 114.422858 -255.591682) (xy 114.3689 -255.583926) (xy 114.316596 -255.56857)
			(xy 114.267009 -255.545926) (xy 114.22115 -255.516455) (xy 114.179952 -255.480758) (xy 114.144253 -255.439561)
			(xy 114.114781 -255.393703) (xy 114.092135 -255.344117) (xy 114.076777 -255.291813) (xy 114.069019 -255.237856)
			(xy 96.821227 -255.237856) (xy 96.856269 -255.267018) (xy 96.893486 -255.308555) (xy 96.924259 -255.355068)
			(xy 96.947931 -255.405565) (xy 96.963999 -255.458972) (xy 96.972119 -255.514148) (xy 96.972628 -255.542034)
			(xy 96.972119 -255.56992) (xy 96.963999 -255.625096) (xy 96.947931 -255.678503) (xy 96.924259 -255.729)
			(xy 96.893486 -255.775513) (xy 96.856269 -255.81705) (xy 96.816817 -255.849882) (xy 97.080322 -255.849882)
			(xy 97.084393 -255.79426) (xy 97.096519 -255.739823) (xy 97.116442 -255.687732) (xy 97.143738 -255.639097)
			(xy 97.177824 -255.594954) (xy 97.217973 -255.556245) (xy 97.263331 -255.523794) (xy 97.312931 -255.498293)
			(xy 97.365715 -255.480286) (xy 97.420558 -255.470156) (xy 97.476292 -255.468119) (xy 97.531729 -255.474219)
			(xy 97.585686 -255.488325) (xy 97.637015 -255.510137) (xy 97.684621 -255.539191) (xy 97.727489 -255.574866)
			(xy 97.764706 -255.616403) (xy 97.795479 -255.662916) (xy 97.819151 -255.713413) (xy 97.835219 -255.76682)
			(xy 97.843339 -255.821996) (xy 97.843848 -255.849882) (xy 97.843339 -255.877768) (xy 97.835219 -255.932944)
			(xy 97.819151 -255.986351) (xy 97.795479 -256.036848) (xy 97.764706 -256.083361) (xy 97.727489 -256.124898)
			(xy 97.684621 -256.160573) (xy 97.637015 -256.189627) (xy 97.585686 -256.211439) (xy 97.531729 -256.225545)
			(xy 97.522468 -256.226564) (xy 126.220472 -256.226564) (xy 126.224543 -256.170942) (xy 126.236669 -256.116505)
			(xy 126.256592 -256.064414) (xy 126.283888 -256.015779) (xy 126.317974 -255.971636) (xy 126.358123 -255.932927)
			(xy 126.403481 -255.900476) (xy 126.453081 -255.874975) (xy 126.505865 -255.856968) (xy 126.560708 -255.846838)
			(xy 126.616442 -255.844801) (xy 126.671879 -255.850901) (xy 126.725836 -255.865007) (xy 126.777165 -255.886819)
			(xy 126.824771 -255.915873) (xy 126.867639 -255.951548) (xy 126.904856 -255.993085) (xy 126.935629 -256.039598)
			(xy 126.959301 -256.090095) (xy 126.975369 -256.143502) (xy 126.983489 -256.198678) (xy 126.983998 -256.226564)
			(xy 128.285746 -256.226564) (xy 128.289817 -256.170942) (xy 128.301943 -256.116505) (xy 128.321866 -256.064414)
			(xy 128.349162 -256.015779) (xy 128.383248 -255.971636) (xy 128.423397 -255.932927) (xy 128.468755 -255.900476)
			(xy 128.518355 -255.874975) (xy 128.571139 -255.856968) (xy 128.625982 -255.846838) (xy 128.681716 -255.844801)
			(xy 128.737153 -255.850901) (xy 128.79111 -255.865007) (xy 128.842439 -255.886819) (xy 128.890045 -255.915873)
			(xy 128.932913 -255.951548) (xy 128.97013 -255.993085) (xy 129.000903 -256.039598) (xy 129.024575 -256.090095)
			(xy 129.040643 -256.143502) (xy 129.048763 -256.198678) (xy 129.049272 -256.226564) (xy 129.048763 -256.25445)
			(xy 129.040643 -256.309626) (xy 129.024575 -256.363033) (xy 129.000903 -256.41353) (xy 128.97013 -256.460043)
			(xy 128.932913 -256.50158) (xy 128.890045 -256.537255) (xy 128.842439 -256.566309) (xy 128.79111 -256.588121)
			(xy 128.737153 -256.602227) (xy 128.681716 -256.608327) (xy 128.625982 -256.60629) (xy 128.571139 -256.59616)
			(xy 128.518355 -256.578153) (xy 128.468755 -256.552652) (xy 128.423397 -256.520201) (xy 128.383248 -256.481492)
			(xy 128.349162 -256.437349) (xy 128.321866 -256.388714) (xy 128.301943 -256.336623) (xy 128.289817 -256.282186)
			(xy 128.285746 -256.226564) (xy 126.983998 -256.226564) (xy 126.983489 -256.25445) (xy 126.975369 -256.309626)
			(xy 126.959301 -256.363033) (xy 126.935629 -256.41353) (xy 126.904856 -256.460043) (xy 126.867639 -256.50158)
			(xy 126.824771 -256.537255) (xy 126.777165 -256.566309) (xy 126.725836 -256.588121) (xy 126.671879 -256.602227)
			(xy 126.616442 -256.608327) (xy 126.560708 -256.60629) (xy 126.505865 -256.59616) (xy 126.453081 -256.578153)
			(xy 126.403481 -256.552652) (xy 126.358123 -256.520201) (xy 126.317974 -256.481492) (xy 126.283888 -256.437349)
			(xy 126.256592 -256.388714) (xy 126.236669 -256.336623) (xy 126.224543 -256.282186) (xy 126.220472 -256.226564)
			(xy 97.522468 -256.226564) (xy 97.476292 -256.231645) (xy 97.420558 -256.229608) (xy 97.365715 -256.219478)
			(xy 97.312931 -256.201471) (xy 97.263331 -256.17597) (xy 97.217973 -256.143519) (xy 97.177824 -256.10481)
			(xy 97.143738 -256.060667) (xy 97.116442 -256.012032) (xy 97.096519 -255.959941) (xy 97.084393 -255.905504)
			(xy 97.080322 -255.849882) (xy 96.816817 -255.849882) (xy 96.813401 -255.852725) (xy 96.765795 -255.881779)
			(xy 96.714466 -255.903591) (xy 96.660509 -255.917697) (xy 96.605072 -255.923797) (xy 96.549338 -255.92176)
			(xy 96.494495 -255.91163) (xy 96.441711 -255.893623) (xy 96.392111 -255.868122) (xy 96.346753 -255.835671)
			(xy 96.306604 -255.796962) (xy 96.272518 -255.752819) (xy 96.245222 -255.704184) (xy 96.225299 -255.652093)
			(xy 96.213173 -255.597656) (xy 96.209102 -255.542034) (xy 61.763796 -255.542034) (xy 61.484386 -257.15722)
			(xy 96.764092 -257.15722) (xy 96.768163 -257.101598) (xy 96.780289 -257.047161) (xy 96.800212 -256.99507)
			(xy 96.827508 -256.946435) (xy 96.861594 -256.902292) (xy 96.901743 -256.863583) (xy 96.947101 -256.831132)
			(xy 96.996701 -256.805631) (xy 97.049485 -256.787624) (xy 97.104328 -256.777494) (xy 97.160062 -256.775457)
			(xy 97.215499 -256.781557) (xy 97.269456 -256.795663) (xy 97.320785 -256.817475) (xy 97.368391 -256.846529)
			(xy 97.411259 -256.882204) (xy 97.448476 -256.923741) (xy 97.479249 -256.970254) (xy 97.502921 -257.020751)
			(xy 97.518989 -257.074158) (xy 97.527109 -257.129334) (xy 97.527131 -257.13055) (xy 116.295422 -257.13055)
			(xy 116.299493 -257.074928) (xy 116.311619 -257.020491) (xy 116.331542 -256.9684) (xy 116.358838 -256.919765)
			(xy 116.392924 -256.875622) (xy 116.433073 -256.836913) (xy 116.478431 -256.804462) (xy 116.528031 -256.778961)
			(xy 116.580815 -256.760954) (xy 116.635658 -256.750824) (xy 116.691392 -256.748787) (xy 116.746829 -256.754887)
			(xy 116.800786 -256.768993) (xy 116.852115 -256.790805) (xy 116.899721 -256.819859) (xy 116.942589 -256.855534)
			(xy 116.979806 -256.897071) (xy 117.010579 -256.943584) (xy 117.034251 -256.994081) (xy 117.050319 -257.047488)
			(xy 117.058439 -257.102664) (xy 117.058674 -257.115564) (xy 128.285746 -257.115564) (xy 128.289817 -257.059942)
			(xy 128.301943 -257.005505) (xy 128.321866 -256.953414) (xy 128.349162 -256.904779) (xy 128.383248 -256.860636)
			(xy 128.423397 -256.821927) (xy 128.468755 -256.789476) (xy 128.518355 -256.763975) (xy 128.571139 -256.745968)
			(xy 128.625982 -256.735838) (xy 128.681716 -256.733801) (xy 128.737153 -256.739901) (xy 128.79111 -256.754007)
			(xy 128.842439 -256.775819) (xy 128.890045 -256.804873) (xy 128.932913 -256.840548) (xy 128.97013 -256.882085)
			(xy 129.000903 -256.928598) (xy 129.024575 -256.979095) (xy 129.040643 -257.032502) (xy 129.048763 -257.087678)
			(xy 129.049272 -257.115564) (xy 129.048763 -257.14345) (xy 129.040643 -257.198626) (xy 129.024575 -257.252033)
			(xy 129.000903 -257.30253) (xy 128.97013 -257.349043) (xy 128.932913 -257.39058) (xy 128.890045 -257.426255)
			(xy 128.842439 -257.455309) (xy 128.79111 -257.477121) (xy 128.737153 -257.491227) (xy 128.681716 -257.497327)
			(xy 128.625982 -257.49529) (xy 128.571139 -257.48516) (xy 128.518355 -257.467153) (xy 128.468755 -257.441652)
			(xy 128.423397 -257.409201) (xy 128.383248 -257.370492) (xy 128.349162 -257.326349) (xy 128.321866 -257.277714)
			(xy 128.301943 -257.225623) (xy 128.289817 -257.171186) (xy 128.285746 -257.115564) (xy 117.058674 -257.115564)
			(xy 117.058948 -257.13055) (xy 117.058439 -257.158436) (xy 117.050319 -257.213612) (xy 117.034251 -257.267019)
			(xy 117.010579 -257.317516) (xy 116.979806 -257.364029) (xy 116.942589 -257.405566) (xy 116.899721 -257.441241)
			(xy 116.852115 -257.470295) (xy 116.800786 -257.492107) (xy 116.746829 -257.506213) (xy 116.691392 -257.512313)
			(xy 116.635658 -257.510276) (xy 116.580815 -257.500146) (xy 116.528031 -257.482139) (xy 116.478431 -257.456638)
			(xy 116.433073 -257.424187) (xy 116.392924 -257.385478) (xy 116.358838 -257.341335) (xy 116.331542 -257.2927)
			(xy 116.311619 -257.240609) (xy 116.299493 -257.186172) (xy 116.295422 -257.13055) (xy 97.527131 -257.13055)
			(xy 97.527618 -257.15722) (xy 97.527109 -257.185106) (xy 97.518989 -257.240282) (xy 97.502921 -257.293689)
			(xy 97.479249 -257.344186) (xy 97.448476 -257.390699) (xy 97.411259 -257.432236) (xy 97.368391 -257.467911)
			(xy 97.320785 -257.496965) (xy 97.269456 -257.518777) (xy 97.215499 -257.532883) (xy 97.160062 -257.538983)
			(xy 97.104328 -257.536946) (xy 97.049485 -257.526816) (xy 96.996701 -257.508809) (xy 96.947101 -257.483308)
			(xy 96.901743 -257.450857) (xy 96.861594 -257.412148) (xy 96.827508 -257.368005) (xy 96.800212 -257.31937)
			(xy 96.780289 -257.267279) (xy 96.768163 -257.212842) (xy 96.764092 -257.15722) (xy 61.484386 -257.15722)
			(xy 61.24206 -258.55803) (xy 84.450172 -258.55803) (xy 84.454243 -258.502408) (xy 84.466369 -258.447971)
			(xy 84.486292 -258.39588) (xy 84.513588 -258.347245) (xy 84.547674 -258.303102) (xy 84.587823 -258.264393)
			(xy 84.633181 -258.231942) (xy 84.682781 -258.206441) (xy 84.735565 -258.188434) (xy 84.790408 -258.178304)
			(xy 84.846142 -258.176267) (xy 84.901579 -258.182367) (xy 84.955536 -258.196473) (xy 85.006865 -258.218285)
			(xy 85.054471 -258.247339) (xy 85.097339 -258.283014) (xy 85.134556 -258.324551) (xy 85.165329 -258.371064)
			(xy 85.189001 -258.421561) (xy 85.205069 -258.474968) (xy 85.213189 -258.530144) (xy 85.213698 -258.55803)
			(xy 85.213189 -258.585916) (xy 85.213144 -258.586224) (xy 86.25154 -258.586224) (xy 86.255611 -258.530602)
			(xy 86.267737 -258.476165) (xy 86.28766 -258.424074) (xy 86.314956 -258.375439) (xy 86.349042 -258.331296)
			(xy 86.389191 -258.292587) (xy 86.434549 -258.260136) (xy 86.484149 -258.234635) (xy 86.536933 -258.216628)
			(xy 86.591776 -258.206498) (xy 86.64751 -258.204461) (xy 86.702947 -258.210561) (xy 86.756904 -258.224667)
			(xy 86.808233 -258.246479) (xy 86.855839 -258.275533) (xy 86.898707 -258.311208) (xy 86.935924 -258.352745)
			(xy 86.966697 -258.399258) (xy 86.990369 -258.449755) (xy 87.006437 -258.503162) (xy 87.014557 -258.558338)
			(xy 87.015066 -258.586224) (xy 87.014557 -258.61411) (xy 87.006437 -258.669286) (xy 86.990369 -258.722693)
			(xy 86.966697 -258.77319) (xy 86.935924 -258.819703) (xy 86.898707 -258.86124) (xy 86.855839 -258.896915)
			(xy 86.808233 -258.925969) (xy 86.756904 -258.947781) (xy 86.702947 -258.961887) (xy 86.64751 -258.967987)
			(xy 86.591776 -258.96595) (xy 86.536933 -258.95582) (xy 86.484149 -258.937813) (xy 86.434549 -258.912312)
			(xy 86.389191 -258.879861) (xy 86.349042 -258.841152) (xy 86.314956 -258.797009) (xy 86.28766 -258.748374)
			(xy 86.267737 -258.696283) (xy 86.255611 -258.641846) (xy 86.25154 -258.586224) (xy 85.213144 -258.586224)
			(xy 85.205069 -258.641092) (xy 85.189001 -258.694499) (xy 85.165329 -258.744996) (xy 85.134556 -258.791509)
			(xy 85.097339 -258.833046) (xy 85.054471 -258.868721) (xy 85.006865 -258.897775) (xy 84.955536 -258.919587)
			(xy 84.901579 -258.933693) (xy 84.846142 -258.939793) (xy 84.790408 -258.937756) (xy 84.735565 -258.927626)
			(xy 84.682781 -258.909619) (xy 84.633181 -258.884118) (xy 84.587823 -258.851667) (xy 84.547674 -258.812958)
			(xy 84.513588 -258.768815) (xy 84.486292 -258.72018) (xy 84.466369 -258.668089) (xy 84.454243 -258.613652)
			(xy 84.450172 -258.55803) (xy 61.24206 -258.55803) (xy 60.813696 -261.034276) (xy 60.533788 -262.65251)
			(xy 60.50915 -262.794496) (xy 60.508388 -262.803132) (xy 60.508388 -263.999472) (xy 60.50915 -264.0076)
			(xy 60.50915 -264.008108) (xy 60.510746 -264.015629) (xy 60.517713 -264.029327) (xy 60.522866 -264.035032)
			(xy 62.011306 -265.523472) (xy 62.016987 -265.528661) (xy 62.030694 -265.535633) (xy 62.03823 -265.537188)
			(xy 62.038738 -265.537188) (xy 62.046866 -265.53795) (xy 92.77604 -265.53795) (xy 92.78112 -265.529822)
			(xy 92.787978 -265.529314) (xy 97.268284 -265.529314) (xy 97.278308 -265.528897) (xy 97.296833 -265.521231)
			(xy 97.311014 -265.507058) (xy 97.318691 -265.488538) (xy 97.319084 -265.478514) (xy 97.319084 -263.54786)
			(xy 97.319603 -263.516229) (xy 97.327862 -263.453508) (xy 97.344234 -263.392401) (xy 97.368439 -263.333953)
			(xy 97.400062 -263.279162) (xy 97.438564 -263.228965) (xy 97.460562 -263.20623) (xy 102.084886 -258.581906)
			(xy 102.107604 -258.559888) (xy 102.157797 -258.521374) (xy 102.212589 -258.489744) (xy 102.271043 -258.465539)
			(xy 102.332156 -258.449174) (xy 102.394883 -258.440928) (xy 102.426516 -258.440428) (xy 107.885484 -258.440428)
			(xy 107.895496 -258.439943) (xy 107.913998 -258.432288) (xy 107.928163 -258.418135) (xy 107.935835 -258.399639)
			(xy 107.936284 -258.389628) (xy 107.936284 -257.920744) (xy 107.937046 -257.912362) (xy 107.971844 -257.877564)
			(xy 107.975908 -257.872992) (xy 107.980734 -257.86715) (xy 107.983274 -257.86334) (xy 107.984036 -257.86207)
			(xy 107.984798 -257.8608) (xy 107.985052 -257.860546) (xy 107.985814 -257.859276) (xy 107.986068 -257.859022)
			(xy 107.992672 -257.84937) (xy 107.992926 -257.849116) (xy 107.993434 -257.848354) (xy 107.994196 -257.847338)
			(xy 107.995466 -257.84556) (xy 107.99699 -257.843528) (xy 107.997244 -257.843274) (xy 108.003884 -257.834508)
			(xy 108.018252 -257.817857) (xy 108.025946 -257.81) (xy 108.182664 -257.653282) (xy 108.19046 -257.645595)
			(xy 108.206986 -257.631229) (xy 108.215684 -257.62458) (xy 108.220256 -257.621278) (xy 108.223812 -257.618738)
			(xy 108.228892 -257.615182) (xy 108.229654 -257.614674) (xy 108.233972 -257.61188) (xy 108.23448 -257.611372)
			(xy 108.238036 -257.60934) (xy 108.246926 -257.602482) (xy 108.24845 -257.600958) (xy 108.251863 -257.597968)
			(xy 108.259532 -257.593123) (xy 108.26369 -257.591306) (xy 108.272834 -257.587496) (xy 108.2802 -257.587496)
			(xy 108.28909 -257.58394) (xy 108.309664 -257.576828) (xy 108.310172 -257.576828) (xy 108.314998 -257.575304)
			(xy 108.31703 -257.574796) (xy 108.317792 -257.574542) (xy 108.320078 -257.57378) (xy 108.32084 -257.57378)
			(xy 108.324396 -257.572764) (xy 108.326428 -257.572256) (xy 108.327444 -257.572002) (xy 108.328968 -257.571494)
			(xy 108.330746 -257.57124) (xy 108.333032 -257.570732) (xy 108.333286 -257.570732) (xy 108.334048 -257.570478)
			(xy 108.334302 -257.570478) (xy 108.350175 -257.56728) (xy 108.382374 -257.563845) (xy 108.398564 -257.56362)
			(xy 110.111032 -257.56362) (xy 110.133999 -257.564555) (xy 110.179278 -257.572463) (xy 110.201202 -257.579368)
			(xy 110.20171 -257.579368) (xy 110.2106 -257.58267) (xy 110.21187 -257.583178) (xy 110.212378 -257.583178)
			(xy 110.212886 -257.583432) (xy 110.214664 -257.58394) (xy 110.223643 -257.58752) (xy 110.241182 -257.595656)
			(xy 110.249716 -257.600196) (xy 110.259565 -257.605669) (xy 110.278508 -257.617873) (xy 110.287562 -257.62458)
			(xy 110.29633 -257.631218) (xy 110.312986 -257.645581) (xy 110.320836 -257.653282) (xy 110.384082 -257.716528)
			(xy 110.391774 -257.724387) (xy 110.406141 -257.741038) (xy 110.412784 -257.749802) (xy 110.422834 -257.763592)
			(xy 110.440146 -257.792998) (xy 110.447328 -257.808476) (xy 110.457996 -257.835654) (xy 110.45825 -257.836416)
			(xy 110.459012 -257.838702) (xy 110.46333 -257.85191) (xy 110.465362 -257.8608) (xy 110.468156 -257.874262)
			(xy 110.470768 -257.888597) (xy 110.473572 -257.917604) (xy 110.473744 -257.932174) (xy 110.473744 -258.01955)
			(xy 116.422932 -258.01955) (xy 116.423402 -257.992297) (xy 116.431153 -257.938344) (xy 116.446505 -257.886044)
			(xy 116.469144 -257.836461) (xy 116.498611 -257.790606) (xy 116.534304 -257.749411) (xy 116.575498 -257.713717)
			(xy 116.621352 -257.684249) (xy 116.670934 -257.661608) (xy 116.723234 -257.646255) (xy 116.777187 -257.638503)
			(xy 116.80444 -257.638042) (xy 116.831497 -257.638464) (xy 116.885066 -257.646128) (xy 116.937014 -257.661283)
			(xy 116.986301 -257.683624) (xy 117.031938 -257.712704) (xy 117.073009 -257.747939) (xy 117.108691 -257.788623)
			(xy 117.138267 -257.833939) (xy 117.150134 -257.85826) (xy 117.154198 -257.866896) (xy 117.167406 -257.879596)
			(xy 117.246908 -257.913886) (xy 117.26545 -257.914648) (xy 117.27434 -257.9116) (xy 117.303608 -257.902509)
			(xy 117.364096 -257.892677) (xy 117.394736 -257.892042) (xy 117.39499 -257.892042) (xy 117.422247 -257.892404)
			(xy 117.476206 -257.900161) (xy 117.528512 -257.915518) (xy 117.5781 -257.938163) (xy 117.62396 -257.967635)
			(xy 117.66516 -258.003333) (xy 117.700859 -258.044532) (xy 117.730332 -258.090391) (xy 117.749135 -258.131564)
			(xy 126.258572 -258.131564) (xy 126.262643 -258.075942) (xy 126.274769 -258.021505) (xy 126.294692 -257.969414)
			(xy 126.321988 -257.920779) (xy 126.356074 -257.876636) (xy 126.396223 -257.837927) (xy 126.441581 -257.805476)
			(xy 126.491181 -257.779975) (xy 126.543965 -257.761968) (xy 126.598808 -257.751838) (xy 126.654542 -257.749801)
			(xy 126.709979 -257.755901) (xy 126.763936 -257.770007) (xy 126.815265 -257.791819) (xy 126.862871 -257.820873)
			(xy 126.905739 -257.856548) (xy 126.942956 -257.898085) (xy 126.973729 -257.944598) (xy 126.997401 -257.995095)
			(xy 127.013469 -258.048502) (xy 127.021589 -258.103678) (xy 127.022098 -258.131564) (xy 130.317746 -258.131564)
			(xy 130.321817 -258.075942) (xy 130.333943 -258.021505) (xy 130.353866 -257.969414) (xy 130.381162 -257.920779)
			(xy 130.415248 -257.876636) (xy 130.455397 -257.837927) (xy 130.500755 -257.805476) (xy 130.550355 -257.779975)
			(xy 130.603139 -257.761968) (xy 130.657982 -257.751838) (xy 130.713716 -257.749801) (xy 130.769153 -257.755901)
			(xy 130.82311 -257.770007) (xy 130.874439 -257.791819) (xy 130.922045 -257.820873) (xy 130.964913 -257.856548)
			(xy 131.00213 -257.898085) (xy 131.032903 -257.944598) (xy 131.056575 -257.995095) (xy 131.072643 -258.048502)
			(xy 131.080763 -258.103678) (xy 131.081272 -258.131564) (xy 131.080763 -258.15945) (xy 131.072643 -258.214626)
			(xy 131.056575 -258.268033) (xy 131.032903 -258.31853) (xy 131.00213 -258.365043) (xy 130.964913 -258.40658)
			(xy 130.922045 -258.442255) (xy 130.874439 -258.471309) (xy 130.82311 -258.493121) (xy 130.769153 -258.507227)
			(xy 130.713716 -258.513327) (xy 130.657982 -258.51129) (xy 130.603139 -258.50116) (xy 130.550355 -258.483153)
			(xy 130.500755 -258.457652) (xy 130.455397 -258.425201) (xy 130.415248 -258.386492) (xy 130.381162 -258.342349)
			(xy 130.353866 -258.293714) (xy 130.333943 -258.241623) (xy 130.321817 -258.187186) (xy 130.317746 -258.131564)
			(xy 127.022098 -258.131564) (xy 127.021589 -258.15945) (xy 127.013469 -258.214626) (xy 126.997401 -258.268033)
			(xy 126.973729 -258.31853) (xy 126.942956 -258.365043) (xy 126.905739 -258.40658) (xy 126.862871 -258.442255)
			(xy 126.815265 -258.471309) (xy 126.763936 -258.493121) (xy 126.709979 -258.507227) (xy 126.654542 -258.513327)
			(xy 126.598808 -258.51129) (xy 126.543965 -258.50116) (xy 126.491181 -258.483153) (xy 126.441581 -258.457652)
			(xy 126.396223 -258.425201) (xy 126.356074 -258.386492) (xy 126.321988 -258.342349) (xy 126.294692 -258.293714)
			(xy 126.274769 -258.241623) (xy 126.262643 -258.187186) (xy 126.258572 -258.131564) (xy 117.749135 -258.131564)
			(xy 117.752978 -258.139979) (xy 117.768337 -258.192284) (xy 117.776095 -258.246243) (xy 117.776095 -258.300757)
			(xy 117.768337 -258.354716) (xy 117.752978 -258.407021) (xy 117.730332 -258.456609) (xy 117.700859 -258.502468)
			(xy 117.66516 -258.543667) (xy 117.62396 -258.579365) (xy 117.5781 -258.608837) (xy 117.528512 -258.631482)
			(xy 117.476206 -258.646839) (xy 117.422247 -258.654596) (xy 117.39499 -258.655058) (xy 117.374442 -258.654758)
			(xy 117.333586 -258.650305) (xy 117.313456 -258.646168) (xy 117.313202 -258.646168) (xy 117.301468 -258.644428)
			(xy 117.278569 -258.650502) (xy 117.26926 -258.657852) (xy 117.198394 -258.720336) (xy 117.189504 -258.742688)
			(xy 117.19052 -258.754626) (xy 117.19052 -258.755134) (xy 117.192298 -258.79044) (xy 117.191812 -258.817691)
			(xy 117.184056 -258.871639) (xy 117.168701 -258.923934) (xy 117.146059 -258.973511) (xy 117.116593 -259.019361)
			(xy 117.080902 -259.060552) (xy 117.039711 -259.096243) (xy 116.993861 -259.125709) (xy 116.944284 -259.148351)
			(xy 116.891989 -259.163706) (xy 116.838041 -259.171462) (xy 116.783539 -259.171462) (xy 116.729591 -259.163706)
			(xy 116.677296 -259.148351) (xy 116.627719 -259.125709) (xy 116.581869 -259.096243) (xy 116.540678 -259.060552)
			(xy 116.504987 -259.019361) (xy 116.475521 -258.973511) (xy 116.452879 -258.923934) (xy 116.437524 -258.871639)
			(xy 116.429768 -258.817691) (xy 116.429282 -258.79044) (xy 116.429857 -258.761315) (xy 116.438719 -258.703744)
			(xy 116.456227 -258.648188) (xy 116.481976 -258.595939) (xy 116.515366 -258.548209) (xy 116.555622 -258.506109)
			(xy 116.57838 -258.487926) (xy 116.58737 -258.480273) (xy 116.597709 -258.459082) (xy 116.598192 -258.447286)
			(xy 116.59743 -258.354068) (xy 116.586508 -258.332986) (xy 116.576856 -258.325874) (xy 116.553429 -258.307703)
			(xy 116.511899 -258.265397) (xy 116.477407 -258.21718) (xy 116.450783 -258.16421) (xy 116.432668 -258.107762)
			(xy 116.423496 -258.049192) (xy 116.422932 -258.01955) (xy 110.473744 -258.01955) (xy 110.473744 -259.020564)
			(xy 112.290096 -259.020564) (xy 112.294167 -258.964942) (xy 112.306293 -258.910505) (xy 112.326216 -258.858414)
			(xy 112.353512 -258.809779) (xy 112.387598 -258.765636) (xy 112.427747 -258.726927) (xy 112.473105 -258.694476)
			(xy 112.522705 -258.668975) (xy 112.575489 -258.650968) (xy 112.630332 -258.640838) (xy 112.686066 -258.638801)
			(xy 112.741503 -258.644901) (xy 112.79546 -258.659007) (xy 112.846789 -258.680819) (xy 112.894395 -258.709873)
			(xy 112.937263 -258.745548) (xy 112.97448 -258.787085) (xy 113.005253 -258.833598) (xy 113.028925 -258.884095)
			(xy 113.044993 -258.937502) (xy 113.053113 -258.992678) (xy 113.053622 -259.020564) (xy 113.179096 -259.020564)
			(xy 113.183167 -258.964942) (xy 113.195293 -258.910505) (xy 113.215216 -258.858414) (xy 113.242512 -258.809779)
			(xy 113.276598 -258.765636) (xy 113.316747 -258.726927) (xy 113.362105 -258.694476) (xy 113.411705 -258.668975)
			(xy 113.464489 -258.650968) (xy 113.519332 -258.640838) (xy 113.575066 -258.638801) (xy 113.630503 -258.644901)
			(xy 113.68446 -258.659007) (xy 113.735789 -258.680819) (xy 113.783395 -258.709873) (xy 113.826263 -258.745548)
			(xy 113.86348 -258.787085) (xy 113.894253 -258.833598) (xy 113.917925 -258.884095) (xy 113.933993 -258.937502)
			(xy 113.942113 -258.992678) (xy 113.942622 -259.020564) (xy 113.942113 -259.04845) (xy 113.933993 -259.103626)
			(xy 113.917925 -259.157033) (xy 113.894253 -259.20753) (xy 113.86348 -259.254043) (xy 113.826263 -259.29558)
			(xy 113.783395 -259.331255) (xy 113.735789 -259.360309) (xy 113.68446 -259.382121) (xy 113.630503 -259.396227)
			(xy 113.575066 -259.402327) (xy 113.519332 -259.40029) (xy 113.464489 -259.39016) (xy 113.411705 -259.372153)
			(xy 113.362105 -259.346652) (xy 113.316747 -259.314201) (xy 113.276598 -259.275492) (xy 113.242512 -259.231349)
			(xy 113.215216 -259.182714) (xy 113.195293 -259.130623) (xy 113.183167 -259.076186) (xy 113.179096 -259.020564)
			(xy 113.053622 -259.020564) (xy 113.053113 -259.04845) (xy 113.044993 -259.103626) (xy 113.028925 -259.157033)
			(xy 113.005253 -259.20753) (xy 112.97448 -259.254043) (xy 112.937263 -259.29558) (xy 112.894395 -259.331255)
			(xy 112.846789 -259.360309) (xy 112.79546 -259.382121) (xy 112.741503 -259.396227) (xy 112.686066 -259.402327)
			(xy 112.630332 -259.40029) (xy 112.575489 -259.39016) (xy 112.522705 -259.372153) (xy 112.473105 -259.346652)
			(xy 112.427747 -259.314201) (xy 112.387598 -259.275492) (xy 112.353512 -259.231349) (xy 112.326216 -259.182714)
			(xy 112.306293 -259.130623) (xy 112.294167 -259.076186) (xy 112.290096 -259.020564) (xy 110.473744 -259.020564)
			(xy 110.473744 -259.030978) (xy 110.472813 -259.053946) (xy 110.464911 -259.099227) (xy 110.457996 -259.121148)
			(xy 110.457996 -259.121656) (xy 110.454694 -259.130546) (xy 110.454186 -259.131816) (xy 110.454186 -259.132324)
			(xy 110.453932 -259.132832) (xy 110.453424 -259.13461) (xy 110.449846 -259.14359) (xy 110.441714 -259.161131)
			(xy 110.437168 -259.169662) (xy 110.431693 -259.17951) (xy 110.419486 -259.19845) (xy 110.412784 -259.207508)
			(xy 110.406144 -259.216274) (xy 110.391779 -259.232927) (xy 110.384082 -259.240782) (xy 110.258606 -259.366258)
			(xy 110.250747 -259.37395) (xy 110.234093 -259.388314) (xy 110.225332 -259.39496) (xy 110.224824 -259.395468)
			(xy 110.2233 -259.396738) (xy 110.222284 -259.3975) (xy 110.22076 -259.398516) (xy 110.219236 -259.399532)
			(xy 110.21822 -259.400294) (xy 110.215934 -259.402072) (xy 110.215426 -259.40258) (xy 110.213902 -259.403596)
			(xy 110.21314 -259.404104) (xy 110.211362 -259.40512) (xy 110.208568 -259.407152) (xy 110.201964 -259.411216)
			(xy 110.198916 -259.412994) (xy 110.198662 -259.413248) (xy 110.197392 -259.41401) (xy 110.195614 -259.414772)
			(xy 110.19536 -259.415026) (xy 110.19409 -259.415788) (xy 110.18901 -259.418582) (xy 110.167928 -259.428996)
			(xy 110.159292 -259.432806) (xy 110.151164 -259.440934) (xy 110.143767 -259.447782) (xy 110.125168 -259.455514)
			(xy 110.115096 -259.45592) (xy 108.231178 -259.45592) (xy 108.226082 -259.455804) (xy 108.216098 -259.453751)
			(xy 108.211366 -259.451856) (xy 108.202222 -259.448046) (xy 108.199174 -259.444998) (xy 108.197904 -259.443982)
			(xy 108.19638 -259.442458) (xy 108.175298 -259.421376) (xy 108.171568 -259.417854) (xy 108.162994 -259.412224)
			(xy 108.15828 -259.4102) (xy 108.149644 -259.406644) (xy 102.64775 -259.406644) (xy 102.639471 -259.406968)
			(xy 102.623791 -259.412287) (xy 102.617016 -259.417058) (xy 102.61473 -259.41909) (xy 102.612952 -259.420868)
			(xy 102.609142 -259.42417) (xy 102.49789 -259.535422) (xy 114.207542 -259.535422) (xy 114.211613 -259.4798)
			(xy 114.223739 -259.425363) (xy 114.243662 -259.373272) (xy 114.270958 -259.324637) (xy 114.305044 -259.280494)
			(xy 114.345193 -259.241785) (xy 114.390551 -259.209334) (xy 114.440151 -259.183833) (xy 114.492935 -259.165826)
			(xy 114.547778 -259.155696) (xy 114.603512 -259.153659) (xy 114.658949 -259.159759) (xy 114.712906 -259.173865)
			(xy 114.755017 -259.19176) (xy 123.580396 -259.19176) (xy 123.584467 -259.136138) (xy 123.596593 -259.081701)
			(xy 123.616516 -259.02961) (xy 123.643812 -258.980975) (xy 123.677898 -258.936832) (xy 123.718047 -258.898123)
			(xy 123.763405 -258.865672) (xy 123.813005 -258.840171) (xy 123.865789 -258.822164) (xy 123.920632 -258.812034)
			(xy 123.976366 -258.809997) (xy 124.031803 -258.816097) (xy 124.08576 -258.830203) (xy 124.137089 -258.852015)
			(xy 124.184695 -258.881069) (xy 124.227563 -258.916744) (xy 124.26478 -258.958281) (xy 124.295553 -259.004794)
			(xy 124.319225 -259.055291) (xy 124.335293 -259.108698) (xy 124.341013 -259.147564) (xy 130.338828 -259.147564)
			(xy 130.342899 -259.091942) (xy 130.355025 -259.037505) (xy 130.374948 -258.985414) (xy 130.402244 -258.936779)
			(xy 130.43633 -258.892636) (xy 130.476479 -258.853927) (xy 130.521837 -258.821476) (xy 130.571437 -258.795975)
			(xy 130.624221 -258.777968) (xy 130.679064 -258.767838) (xy 130.734798 -258.765801) (xy 130.790235 -258.771901)
			(xy 130.844192 -258.786007) (xy 130.895521 -258.807819) (xy 130.943127 -258.836873) (xy 130.985995 -258.872548)
			(xy 131.023212 -258.914085) (xy 131.053985 -258.960598) (xy 131.077657 -259.011095) (xy 131.093725 -259.064502)
			(xy 131.101845 -259.119678) (xy 131.102354 -259.147564) (xy 131.101845 -259.17545) (xy 131.093725 -259.230626)
			(xy 131.077657 -259.284033) (xy 131.053985 -259.33453) (xy 131.023212 -259.381043) (xy 130.985995 -259.42258)
			(xy 130.943127 -259.458255) (xy 130.895521 -259.487309) (xy 130.844192 -259.509121) (xy 130.790235 -259.523227)
			(xy 130.734798 -259.529327) (xy 130.679064 -259.52729) (xy 130.624221 -259.51716) (xy 130.571437 -259.499153)
			(xy 130.521837 -259.473652) (xy 130.476479 -259.441201) (xy 130.43633 -259.402492) (xy 130.402244 -259.358349)
			(xy 130.374948 -259.309714) (xy 130.355025 -259.257623) (xy 130.342899 -259.203186) (xy 130.338828 -259.147564)
			(xy 124.341013 -259.147564) (xy 124.343413 -259.163874) (xy 124.343922 -259.19176) (xy 124.343413 -259.219646)
			(xy 124.335293 -259.274822) (xy 124.319225 -259.328229) (xy 124.295553 -259.378726) (xy 124.26478 -259.425239)
			(xy 124.227563 -259.466776) (xy 124.184695 -259.502451) (xy 124.137089 -259.531505) (xy 124.08576 -259.553317)
			(xy 124.031803 -259.567423) (xy 123.976366 -259.573523) (xy 123.920632 -259.571486) (xy 123.865789 -259.561356)
			(xy 123.813005 -259.543349) (xy 123.763405 -259.517848) (xy 123.718047 -259.485397) (xy 123.677898 -259.446688)
			(xy 123.643812 -259.402545) (xy 123.616516 -259.35391) (xy 123.596593 -259.301819) (xy 123.584467 -259.247382)
			(xy 123.580396 -259.19176) (xy 114.755017 -259.19176) (xy 114.764235 -259.195677) (xy 114.811841 -259.224731)
			(xy 114.854709 -259.260406) (xy 114.891926 -259.301943) (xy 114.922699 -259.348456) (xy 114.946371 -259.398953)
			(xy 114.962439 -259.45236) (xy 114.970559 -259.507536) (xy 114.971068 -259.535422) (xy 114.970559 -259.563308)
			(xy 114.962439 -259.618484) (xy 114.946371 -259.671891) (xy 114.922699 -259.722388) (xy 114.891926 -259.768901)
			(xy 114.854709 -259.810438) (xy 114.811841 -259.846113) (xy 114.764235 -259.875167) (xy 114.712906 -259.896979)
			(xy 114.658949 -259.911085) (xy 114.603512 -259.917185) (xy 114.547778 -259.915148) (xy 114.492935 -259.905018)
			(xy 114.440151 -259.887011) (xy 114.390551 -259.86151) (xy 114.345193 -259.829059) (xy 114.305044 -259.79035)
			(xy 114.270958 -259.746207) (xy 114.243662 -259.697572) (xy 114.223739 -259.645481) (xy 114.211613 -259.591044)
			(xy 114.207542 -259.535422) (xy 102.49789 -259.535422) (xy 101.361748 -260.671564) (xy 112.163096 -260.671564)
			(xy 112.167167 -260.615942) (xy 112.179293 -260.561505) (xy 112.199216 -260.509414) (xy 112.226512 -260.460779)
			(xy 112.260598 -260.416636) (xy 112.300747 -260.377927) (xy 112.346105 -260.345476) (xy 112.395705 -260.319975)
			(xy 112.448489 -260.301968) (xy 112.503332 -260.291838) (xy 112.559066 -260.289801) (xy 112.614503 -260.295901)
			(xy 112.66846 -260.310007) (xy 112.719789 -260.331819) (xy 112.767395 -260.360873) (xy 112.810263 -260.396548)
			(xy 112.84748 -260.438085) (xy 112.878253 -260.484598) (xy 112.901925 -260.535095) (xy 112.917993 -260.588502)
			(xy 112.926113 -260.643678) (xy 112.926622 -260.671564) (xy 112.926113 -260.69945) (xy 112.917993 -260.754626)
			(xy 112.901925 -260.808033) (xy 112.878253 -260.85853) (xy 112.84748 -260.905043) (xy 112.810263 -260.94658)
			(xy 112.767395 -260.982255) (xy 112.719789 -261.011309) (xy 112.66846 -261.033121) (xy 112.614503 -261.047227)
			(xy 112.559066 -261.053327) (xy 112.503332 -261.05129) (xy 112.448489 -261.04116) (xy 112.395705 -261.023153)
			(xy 112.346105 -260.997652) (xy 112.300747 -260.965201) (xy 112.260598 -260.926492) (xy 112.226512 -260.882349)
			(xy 112.199216 -260.833714) (xy 112.179293 -260.781623) (xy 112.167167 -260.727186) (xy 112.163096 -260.671564)
			(xy 101.361748 -260.671564) (xy 100.815648 -261.217664) (xy 114.140232 -261.217664) (xy 114.144303 -261.162042)
			(xy 114.156429 -261.107605) (xy 114.176352 -261.055514) (xy 114.203648 -261.006879) (xy 114.237734 -260.962736)
			(xy 114.277883 -260.924027) (xy 114.323241 -260.891576) (xy 114.372841 -260.866075) (xy 114.425625 -260.848068)
			(xy 114.480468 -260.837938) (xy 114.536202 -260.835901) (xy 114.591639 -260.842001) (xy 114.645596 -260.856107)
			(xy 114.696925 -260.877919) (xy 114.744531 -260.906973) (xy 114.787399 -260.942648) (xy 114.824616 -260.984185)
			(xy 114.855389 -261.030698) (xy 114.879061 -261.081195) (xy 114.895129 -261.134602) (xy 114.903249 -261.189778)
			(xy 114.903758 -261.217664) (xy 114.903249 -261.24555) (xy 114.895129 -261.300726) (xy 114.879061 -261.354133)
			(xy 114.855389 -261.40463) (xy 114.824616 -261.451143) (xy 114.787399 -261.49268) (xy 114.759795 -261.515652)
			(xy 119.394683 -261.515652) (xy 119.394683 -261.461148) (xy 119.402441 -261.407198) (xy 119.417797 -261.354901)
			(xy 119.44044 -261.305323) (xy 119.469909 -261.259471) (xy 119.505604 -261.218281) (xy 119.546797 -261.18259)
			(xy 119.592651 -261.153125) (xy 119.642231 -261.130486) (xy 119.694529 -261.115134) (xy 119.74848 -261.107381)
			(xy 119.775732 -261.10692) (xy 119.804331 -261.107398) (xy 119.860888 -261.115942) (xy 119.915535 -261.132832)
			(xy 119.967049 -261.157692) (xy 120.014274 -261.189963) (xy 120.033402 -261.207758) (xy 131.570982 -261.207758)
			(xy 131.575053 -261.152136) (xy 131.587179 -261.097699) (xy 131.607102 -261.045608) (xy 131.634398 -260.996973)
			(xy 131.668484 -260.95283) (xy 131.708633 -260.914121) (xy 131.753991 -260.88167) (xy 131.803591 -260.856169)
			(xy 131.856375 -260.838162) (xy 131.911218 -260.828032) (xy 131.966952 -260.825995) (xy 132.022389 -260.832095)
			(xy 132.076346 -260.846201) (xy 132.127675 -260.868013) (xy 132.175281 -260.897067) (xy 132.218149 -260.932742)
			(xy 132.255366 -260.974279) (xy 132.286139 -261.020792) (xy 132.309811 -261.071289) (xy 132.325879 -261.124696)
			(xy 132.333999 -261.179872) (xy 132.334508 -261.207758) (xy 132.333999 -261.235644) (xy 132.325879 -261.29082)
			(xy 132.309811 -261.344227) (xy 132.286139 -261.394724) (xy 132.255366 -261.441237) (xy 132.218149 -261.482774)
			(xy 132.175281 -261.518449) (xy 132.127675 -261.547503) (xy 132.076346 -261.569315) (xy 132.022389 -261.583421)
			(xy 131.966952 -261.589521) (xy 131.911218 -261.587484) (xy 131.856375 -261.577354) (xy 131.803591 -261.559347)
			(xy 131.753991 -261.533846) (xy 131.708633 -261.501395) (xy 131.668484 -261.462686) (xy 131.634398 -261.418543)
			(xy 131.607102 -261.369908) (xy 131.587179 -261.317817) (xy 131.575053 -261.26338) (xy 131.570982 -261.207758)
			(xy 120.033402 -261.207758) (xy 120.056152 -261.228922) (xy 120.091745 -261.273697) (xy 120.120256 -261.323283)
			(xy 120.141044 -261.37657) (xy 120.147842 -261.404354) (xy 120.150257 -261.413351) (xy 120.160559 -261.428854)
			(xy 120.167908 -261.43458) (xy 120.223534 -261.474204) (xy 120.2314 -261.479256) (xy 120.249518 -261.483807)
			(xy 120.25884 -261.483094) (xy 120.259094 -261.483094) (xy 120.270352 -261.481798) (xy 120.292974 -261.480402)
			(xy 120.304306 -261.4803) (xy 120.331558 -261.48077) (xy 120.385506 -261.488528) (xy 120.437801 -261.503884)
			(xy 120.487378 -261.526526) (xy 120.533229 -261.555993) (xy 120.574419 -261.591685) (xy 120.610111 -261.632876)
			(xy 120.639577 -261.678727) (xy 120.662219 -261.728305) (xy 120.677574 -261.7806) (xy 120.682457 -261.814564)
			(xy 130.388104 -261.814564) (xy 130.392175 -261.758942) (xy 130.404301 -261.704505) (xy 130.424224 -261.652414)
			(xy 130.45152 -261.603779) (xy 130.485606 -261.559636) (xy 130.525755 -261.520927) (xy 130.571113 -261.488476)
			(xy 130.620713 -261.462975) (xy 130.673497 -261.444968) (xy 130.72834 -261.434838) (xy 130.784074 -261.432801)
			(xy 130.839511 -261.438901) (xy 130.893468 -261.453007) (xy 130.944797 -261.474819) (xy 130.992403 -261.503873)
			(xy 131.035271 -261.539548) (xy 131.072488 -261.581085) (xy 131.103261 -261.627598) (xy 131.126933 -261.678095)
			(xy 131.143001 -261.731502) (xy 131.151121 -261.786678) (xy 131.15163 -261.814564) (xy 131.151121 -261.84245)
			(xy 131.143001 -261.897626) (xy 131.126933 -261.951033) (xy 131.103261 -262.00153) (xy 131.072488 -262.048043)
			(xy 131.035271 -262.08958) (xy 130.992403 -262.125255) (xy 130.944797 -262.154309) (xy 130.893468 -262.176121)
			(xy 130.839511 -262.190227) (xy 130.784074 -262.196327) (xy 130.72834 -262.19429) (xy 130.673497 -262.18416)
			(xy 130.620713 -262.166153) (xy 130.571113 -262.140652) (xy 130.525755 -262.108201) (xy 130.485606 -262.069492)
			(xy 130.45152 -262.025349) (xy 130.424224 -261.976714) (xy 130.404301 -261.924623) (xy 130.392175 -261.870186)
			(xy 130.388104 -261.814564) (xy 120.682457 -261.814564) (xy 120.68533 -261.834548) (xy 120.68533 -261.889052)
			(xy 120.677574 -261.943) (xy 120.662219 -261.995295) (xy 120.639577 -262.044873) (xy 120.610111 -262.090724)
			(xy 120.574419 -262.131915) (xy 120.533229 -262.167607) (xy 120.487378 -262.197074) (xy 120.437801 -262.219716)
			(xy 120.385506 -262.235072) (xy 120.331558 -262.24283) (xy 120.304306 -262.243316) (xy 120.275709 -262.242776)
			(xy 120.219157 -262.234239) (xy 120.164512 -262.217355) (xy 120.113001 -262.192503) (xy 120.065776 -262.16024)
			(xy 120.023897 -262.121288) (xy 119.988302 -262.076522) (xy 119.959789 -262.026943) (xy 119.938997 -261.973663)
			(xy 119.932196 -261.945882) (xy 119.929754 -261.936894) (xy 119.919471 -261.921387) (xy 119.91213 -261.915656)
			(xy 119.856504 -261.876032) (xy 119.848626 -261.871001) (xy 119.830518 -261.866436) (xy 119.821198 -261.867142)
			(xy 119.820944 -261.867142) (xy 119.809685 -261.868435) (xy 119.787064 -261.869833) (xy 119.775732 -261.869936)
			(xy 119.74848 -261.869419) (xy 119.694529 -261.861666) (xy 119.642231 -261.846314) (xy 119.592651 -261.823675)
			(xy 119.546797 -261.79421) (xy 119.505604 -261.758519) (xy 119.469909 -261.717329) (xy 119.44044 -261.671477)
			(xy 119.417797 -261.621899) (xy 119.402441 -261.569602) (xy 119.394683 -261.515652) (xy 114.759795 -261.515652)
			(xy 114.744531 -261.528355) (xy 114.696925 -261.557409) (xy 114.645596 -261.579221) (xy 114.591639 -261.593327)
			(xy 114.536202 -261.599427) (xy 114.480468 -261.59739) (xy 114.425625 -261.58726) (xy 114.372841 -261.569253)
			(xy 114.323241 -261.543752) (xy 114.277883 -261.511301) (xy 114.237734 -261.472592) (xy 114.203648 -261.428449)
			(xy 114.176352 -261.379814) (xy 114.156429 -261.327723) (xy 114.144303 -261.273286) (xy 114.140232 -261.217664)
			(xy 100.815648 -261.217664) (xy 99.837748 -262.195564) (xy 116.381782 -262.195564) (xy 116.385853 -262.139942)
			(xy 116.397979 -262.085505) (xy 116.417902 -262.033414) (xy 116.445198 -261.984779) (xy 116.479284 -261.940636)
			(xy 116.519433 -261.901927) (xy 116.564791 -261.869476) (xy 116.614391 -261.843975) (xy 116.667175 -261.825968)
			(xy 116.722018 -261.815838) (xy 116.777752 -261.813801) (xy 116.833189 -261.819901) (xy 116.887146 -261.834007)
			(xy 116.938475 -261.855819) (xy 116.986081 -261.884873) (xy 117.028949 -261.920548) (xy 117.066166 -261.962085)
			(xy 117.096939 -262.008598) (xy 117.120611 -262.059095) (xy 117.136679 -262.112502) (xy 117.144799 -262.167678)
			(xy 117.145308 -262.195564) (xy 117.144799 -262.22345) (xy 117.136679 -262.278626) (xy 117.120611 -262.332033)
			(xy 117.096939 -262.38253) (xy 117.066166 -262.429043) (xy 117.028949 -262.47058) (xy 116.986081 -262.506255)
			(xy 116.938475 -262.535309) (xy 116.887146 -262.557121) (xy 116.833189 -262.571227) (xy 116.777752 -262.577327)
			(xy 116.722018 -262.57529) (xy 116.667175 -262.56516) (xy 116.614391 -262.547153) (xy 116.564791 -262.521652)
			(xy 116.519433 -262.489201) (xy 116.479284 -262.450492) (xy 116.445198 -262.406349) (xy 116.417902 -262.357714)
			(xy 116.397979 -262.305623) (xy 116.385853 -262.251186) (xy 116.381782 -262.195564) (xy 99.837748 -262.195564)
			(xy 99.329748 -262.703564) (xy 112.163096 -262.703564) (xy 112.167167 -262.647942) (xy 112.179293 -262.593505)
			(xy 112.199216 -262.541414) (xy 112.226512 -262.492779) (xy 112.260598 -262.448636) (xy 112.300747 -262.409927)
			(xy 112.346105 -262.377476) (xy 112.395705 -262.351975) (xy 112.448489 -262.333968) (xy 112.503332 -262.323838)
			(xy 112.559066 -262.321801) (xy 112.614503 -262.327901) (xy 112.66846 -262.342007) (xy 112.719789 -262.363819)
			(xy 112.767395 -262.392873) (xy 112.810263 -262.428548) (xy 112.84748 -262.470085) (xy 112.878253 -262.516598)
			(xy 112.901925 -262.567095) (xy 112.906073 -262.580882) (xy 119.152922 -262.580882) (xy 119.156993 -262.52526)
			(xy 119.169119 -262.470823) (xy 119.189042 -262.418732) (xy 119.216338 -262.370097) (xy 119.250424 -262.325954)
			(xy 119.290573 -262.287245) (xy 119.335931 -262.254794) (xy 119.385531 -262.229293) (xy 119.438315 -262.211286)
			(xy 119.493158 -262.201156) (xy 119.548892 -262.199119) (xy 119.604329 -262.205219) (xy 119.658286 -262.219325)
			(xy 119.709615 -262.241137) (xy 119.757221 -262.270191) (xy 119.800089 -262.305866) (xy 119.837306 -262.347403)
			(xy 119.868079 -262.393916) (xy 119.891751 -262.444413) (xy 119.907819 -262.49782) (xy 119.915939 -262.552996)
			(xy 119.916448 -262.580882) (xy 119.915939 -262.608768) (xy 119.907819 -262.663944) (xy 119.891751 -262.717351)
			(xy 119.868079 -262.767848) (xy 119.837306 -262.814361) (xy 119.800089 -262.855898) (xy 119.757221 -262.891573)
			(xy 119.709615 -262.920627) (xy 119.658286 -262.942439) (xy 119.604329 -262.956545) (xy 119.548892 -262.962645)
			(xy 119.493158 -262.960608) (xy 119.438315 -262.950478) (xy 119.385531 -262.932471) (xy 119.335931 -262.90697)
			(xy 119.290573 -262.874519) (xy 119.250424 -262.83581) (xy 119.216338 -262.791667) (xy 119.189042 -262.743032)
			(xy 119.169119 -262.690941) (xy 119.156993 -262.636504) (xy 119.152922 -262.580882) (xy 112.906073 -262.580882)
			(xy 112.917993 -262.620502) (xy 112.926113 -262.675678) (xy 112.926622 -262.703564) (xy 112.926113 -262.73145)
			(xy 112.917993 -262.786626) (xy 112.901925 -262.840033) (xy 112.878253 -262.89053) (xy 112.84748 -262.937043)
			(xy 112.810263 -262.97858) (xy 112.767395 -263.014255) (xy 112.719789 -263.043309) (xy 112.66846 -263.065121)
			(xy 112.642667 -263.071864) (xy 116.381782 -263.071864) (xy 116.385853 -263.016242) (xy 116.397979 -262.961805)
			(xy 116.417902 -262.909714) (xy 116.445198 -262.861079) (xy 116.479284 -262.816936) (xy 116.519433 -262.778227)
			(xy 116.564791 -262.745776) (xy 116.614391 -262.720275) (xy 116.667175 -262.702268) (xy 116.722018 -262.692138)
			(xy 116.777752 -262.690101) (xy 116.833189 -262.696201) (xy 116.887146 -262.710307) (xy 116.938475 -262.732119)
			(xy 116.986081 -262.761173) (xy 117.028949 -262.796848) (xy 117.066166 -262.838385) (xy 117.096939 -262.884898)
			(xy 117.120611 -262.935395) (xy 117.136679 -262.988802) (xy 117.144799 -263.043978) (xy 117.145308 -263.071864)
			(xy 117.144799 -263.09975) (xy 117.136679 -263.154926) (xy 117.128121 -263.18337) (xy 122.968764 -263.18337)
			(xy 122.972835 -263.127748) (xy 122.984961 -263.073311) (xy 123.004884 -263.02122) (xy 123.03218 -262.972585)
			(xy 123.066266 -262.928442) (xy 123.106415 -262.889733) (xy 123.151773 -262.857282) (xy 123.201373 -262.831781)
			(xy 123.254157 -262.813774) (xy 123.309 -262.803644) (xy 123.364734 -262.801607) (xy 123.420171 -262.807707)
			(xy 123.474128 -262.821813) (xy 123.525457 -262.843625) (xy 123.573063 -262.872679) (xy 123.615931 -262.908354)
			(xy 123.653148 -262.949891) (xy 123.683921 -262.996404) (xy 123.707593 -263.046901) (xy 123.723661 -263.100308)
			(xy 123.731781 -263.155484) (xy 123.73229 -263.18337) (xy 123.731781 -263.211256) (xy 123.723661 -263.266432)
			(xy 123.707593 -263.319839) (xy 123.683921 -263.370336) (xy 123.653148 -263.416849) (xy 123.615931 -263.458386)
			(xy 123.573063 -263.494061) (xy 123.525457 -263.523115) (xy 123.474128 -263.544927) (xy 123.420171 -263.559033)
			(xy 123.364734 -263.565133) (xy 123.309 -263.563096) (xy 123.254157 -263.552966) (xy 123.201373 -263.534959)
			(xy 123.151773 -263.509458) (xy 123.106415 -263.477007) (xy 123.066266 -263.438298) (xy 123.03218 -263.394155)
			(xy 123.004884 -263.34552) (xy 122.984961 -263.293429) (xy 122.972835 -263.238992) (xy 122.968764 -263.18337)
			(xy 117.128121 -263.18337) (xy 117.120611 -263.208333) (xy 117.096939 -263.25883) (xy 117.066166 -263.305343)
			(xy 117.028949 -263.34688) (xy 116.986081 -263.382555) (xy 116.938475 -263.411609) (xy 116.887146 -263.433421)
			(xy 116.833189 -263.447527) (xy 116.777752 -263.453627) (xy 116.722018 -263.45159) (xy 116.667175 -263.44146)
			(xy 116.614391 -263.423453) (xy 116.564791 -263.397952) (xy 116.519433 -263.365501) (xy 116.479284 -263.326792)
			(xy 116.445198 -263.282649) (xy 116.417902 -263.234014) (xy 116.397979 -263.181923) (xy 116.385853 -263.127486)
			(xy 116.381782 -263.071864) (xy 112.642667 -263.071864) (xy 112.614503 -263.079227) (xy 112.559066 -263.085327)
			(xy 112.503332 -263.08329) (xy 112.448489 -263.07316) (xy 112.395705 -263.055153) (xy 112.346105 -263.029652)
			(xy 112.300747 -262.997201) (xy 112.260598 -262.958492) (xy 112.226512 -262.914349) (xy 112.199216 -262.865714)
			(xy 112.179293 -262.813623) (xy 112.167167 -262.759186) (xy 112.163096 -262.703564) (xy 99.329748 -262.703564)
			(xy 98.300032 -263.73328) (xy 98.296506 -263.737007) (xy 98.290866 -263.745578) (xy 98.288856 -263.750298)
			(xy 98.2853 -263.758934) (xy 98.2853 -269.417038) (xy 102.50043 -269.417038) (xy 102.500935 -269.388299)
			(xy 102.509565 -269.331471) (xy 102.52662 -269.276581) (xy 102.551716 -269.22487) (xy 102.584283 -269.177507)
			(xy 102.603554 -269.15618) (xy 102.610158 -269.149322) (xy 102.61727 -269.131288) (xy 102.61727 -269.042388)
			(xy 102.610158 -269.024354) (xy 102.603554 -269.017496) (xy 102.584304 -268.996151) (xy 102.551734 -268.948794)
			(xy 102.526638 -268.897087) (xy 102.509582 -268.8422) (xy 102.500954 -268.785376) (xy 102.50043 -268.756638)
			(xy 102.500891 -268.729384) (xy 102.508644 -268.675431) (xy 102.523997 -268.623131) (xy 102.546638 -268.573549)
			(xy 102.576105 -268.527693) (xy 102.611799 -268.486499) (xy 102.652993 -268.450805) (xy 102.698849 -268.421338)
			(xy 102.748431 -268.398697) (xy 102.800731 -268.383344) (xy 102.854684 -268.375591) (xy 102.881938 -268.37513)
			(xy 102.909307 -268.375625) (xy 102.963485 -268.383435) (xy 103.015988 -268.398917) (xy 103.065736 -268.421752)
			(xy 103.111704 -268.451471) (xy 103.132636 -268.46911) (xy 103.13289 -268.469364) (xy 103.13997 -268.47496)
			(xy 103.156892 -268.481199) (xy 103.16591 -268.481556) (xy 103.232966 -268.481556) (xy 103.241982 -268.481192)
			(xy 103.2589 -268.47495) (xy 103.265986 -268.469364) (xy 103.265986 -268.46911) (xy 103.26624 -268.46911)
			(xy 103.287173 -268.451469) (xy 103.333141 -268.421745) (xy 103.382887 -268.398899) (xy 103.435389 -268.383403)
			(xy 103.489567 -268.375574) (xy 103.544309 -268.375574) (xy 103.598487 -268.383403) (xy 103.650989 -268.398899)
			(xy 103.700735 -268.421745) (xy 103.746703 -268.451469) (xy 103.767636 -268.46911) (xy 103.76789 -268.469364)
			(xy 103.77497 -268.47496) (xy 103.791892 -268.481199) (xy 103.80091 -268.481556) (xy 103.867966 -268.481556)
			(xy 103.876982 -268.481192) (xy 103.8939 -268.47495) (xy 103.900986 -268.469364) (xy 103.900986 -268.46911)
			(xy 103.90124 -268.46911) (xy 103.922173 -268.451469) (xy 103.968141 -268.421745) (xy 104.017887 -268.398899)
			(xy 104.070389 -268.383403) (xy 104.124567 -268.375574) (xy 104.179309 -268.375574) (xy 104.233487 -268.383403)
			(xy 104.285989 -268.398899) (xy 104.335735 -268.421745) (xy 104.381703 -268.451469) (xy 104.402636 -268.46911)
			(xy 104.40289 -268.469364) (xy 104.40997 -268.47496) (xy 104.426892 -268.481199) (xy 104.43591 -268.481556)
			(xy 104.502966 -268.481556) (xy 104.511982 -268.481192) (xy 104.5289 -268.47495) (xy 104.535986 -268.469364)
			(xy 104.535986 -268.46911) (xy 104.53624 -268.46911) (xy 104.557173 -268.451469) (xy 104.603141 -268.421745)
			(xy 104.652887 -268.398899) (xy 104.705389 -268.383403) (xy 104.759567 -268.375574) (xy 104.814309 -268.375574)
			(xy 104.868487 -268.383403) (xy 104.920989 -268.398899) (xy 104.970735 -268.421745) (xy 105.016703 -268.451469)
			(xy 105.037636 -268.46911) (xy 105.03789 -268.469364) (xy 105.04497 -268.47496) (xy 105.061892 -268.481199)
			(xy 105.07091 -268.481556) (xy 105.137966 -268.481556) (xy 105.146982 -268.481192) (xy 105.1639 -268.47495)
			(xy 105.170986 -268.469364) (xy 105.170986 -268.46911) (xy 105.17124 -268.46911) (xy 105.192185 -268.451487)
			(xy 105.238154 -268.421773) (xy 105.287898 -268.398933) (xy 105.340396 -268.383438) (xy 105.39457 -268.375606)
			(xy 105.421938 -268.37513) (xy 105.449192 -268.375543) (xy 105.503144 -268.383305) (xy 105.555443 -268.398667)
			(xy 105.605023 -268.421315) (xy 105.650875 -268.450789) (xy 105.692065 -268.486488) (xy 105.727756 -268.527686)
			(xy 105.757221 -268.573544) (xy 105.779859 -268.623129) (xy 105.795211 -268.67543) (xy 105.802963 -268.729384)
			(xy 105.803446 -268.756638) (xy 105.802933 -268.785377) (xy 105.794306 -268.842204) (xy 105.777253 -268.897095)
			(xy 105.752159 -268.948806) (xy 105.719593 -268.996169) (xy 105.700322 -269.017496) (xy 105.693718 -269.024354)
			(xy 105.686606 -269.042388) (xy 105.686606 -269.131288) (xy 105.693718 -269.149322) (xy 105.700322 -269.15618)
			(xy 105.719604 -269.177497) (xy 105.75217 -269.224861) (xy 105.777261 -269.276575) (xy 105.794309 -269.331468)
			(xy 105.802928 -269.388298) (xy 105.803446 -269.417038) (xy 105.802958 -269.444288) (xy 105.795197 -269.498234)
			(xy 105.779839 -269.550526) (xy 105.757196 -269.600101) (xy 105.727729 -269.64595) (xy 105.692038 -269.687138)
			(xy 105.65085 -269.722829) (xy 105.605001 -269.752296) (xy 105.555426 -269.774939) (xy 105.503134 -269.790297)
			(xy 105.449188 -269.798058) (xy 105.421938 -269.798546) (xy 105.394568 -269.798071) (xy 105.340389 -269.790257)
			(xy 105.287885 -269.774771) (xy 105.238138 -269.751931) (xy 105.192171 -269.722207) (xy 105.17124 -269.704566)
			(xy 105.170986 -269.704312) (xy 105.163907 -269.698715) (xy 105.146984 -269.692474) (xy 105.137966 -269.69212)
			(xy 105.07091 -269.69212) (xy 105.061893 -269.692477) (xy 105.044976 -269.698724) (xy 105.03789 -269.704312)
			(xy 105.037636 -269.704566) (xy 105.016703 -269.722207) (xy 104.970735 -269.751931) (xy 104.920989 -269.774777)
			(xy 104.868487 -269.790273) (xy 104.814309 -269.798102) (xy 104.759567 -269.798102) (xy 104.705389 -269.790273)
			(xy 104.652887 -269.774777) (xy 104.603141 -269.751931) (xy 104.557173 -269.722207) (xy 104.53624 -269.704566)
			(xy 104.535986 -269.704312) (xy 104.528907 -269.698715) (xy 104.511984 -269.692474) (xy 104.502966 -269.69212)
			(xy 104.43591 -269.69212) (xy 104.426893 -269.692477) (xy 104.409976 -269.698724) (xy 104.40289 -269.704312)
			(xy 104.40289 -269.704566) (xy 104.402636 -269.704566) (xy 104.381703 -269.722207) (xy 104.335735 -269.751931)
			(xy 104.285989 -269.774777) (xy 104.233487 -269.790273) (xy 104.179309 -269.798102) (xy 104.124567 -269.798102)
			(xy 104.070389 -269.790273) (xy 104.017887 -269.774777) (xy 103.968141 -269.751931) (xy 103.922173 -269.722207)
			(xy 103.90124 -269.704566) (xy 103.900986 -269.704312) (xy 103.893907 -269.698715) (xy 103.876984 -269.692474)
			(xy 103.867966 -269.69212) (xy 103.80091 -269.69212) (xy 103.791893 -269.692477) (xy 103.774976 -269.698724)
			(xy 103.76789 -269.704312) (xy 103.76789 -269.704566) (xy 103.767636 -269.704566) (xy 103.746703 -269.722207)
			(xy 103.700735 -269.751931) (xy 103.650989 -269.774777) (xy 103.598487 -269.790273) (xy 103.544309 -269.798102)
			(xy 103.489567 -269.798102) (xy 103.435389 -269.790273) (xy 103.382887 -269.774777) (xy 103.333141 -269.751931)
			(xy 103.287173 -269.722207) (xy 103.26624 -269.704566) (xy 103.265986 -269.704312) (xy 103.258907 -269.698715)
			(xy 103.241984 -269.692474) (xy 103.232966 -269.69212) (xy 103.16591 -269.69212) (xy 103.156893 -269.692477)
			(xy 103.139976 -269.698724) (xy 103.13289 -269.704312) (xy 103.13289 -269.704566) (xy 103.132636 -269.704566)
			(xy 103.111697 -269.722196) (xy 103.065727 -269.751911) (xy 103.015981 -269.774749) (xy 102.963482 -269.790242)
			(xy 102.909307 -269.798071) (xy 102.881938 -269.798546) (xy 102.854689 -269.797987) (xy 102.800746 -269.790236)
			(xy 102.748455 -269.774888) (xy 102.698881 -269.752254) (xy 102.653032 -269.722795) (xy 102.611843 -269.687111)
			(xy 102.57615 -269.645929) (xy 102.546683 -269.600086) (xy 102.524039 -269.550516) (xy 102.50868 -269.498228)
			(xy 102.500919 -269.444286) (xy 102.50043 -269.417038) (xy 98.2853 -269.417038) (xy 98.2853 -277.864824)
			(xy 103.46563 -277.864824) (xy 103.466154 -277.835907) (xy 103.47488 -277.778736) (xy 103.492136 -277.723537)
			(xy 103.517527 -277.671575) (xy 103.55047 -277.624041) (xy 103.590211 -277.582024) (xy 103.612696 -277.563834)
			(xy 103.621477 -277.556202) (xy 103.631675 -277.53532) (xy 103.632254 -277.523702) (xy 103.632254 -277.443946)
			(xy 103.631748 -277.43231) (xy 103.621537 -277.411399) (xy 103.612696 -277.403814) (xy 103.590218 -277.385616)
			(xy 103.550483 -277.343598) (xy 103.517543 -277.296064) (xy 103.492154 -277.244104) (xy 103.474896 -277.188908)
			(xy 103.466166 -277.13174) (xy 103.46563 -277.102824) (xy 103.466211 -277.073416) (xy 103.475241 -277.015298)
			(xy 103.493076 -276.959253) (xy 103.519295 -276.906604) (xy 103.553276 -276.858599) (xy 103.594217 -276.816372)
			(xy 103.641148 -276.780922) (xy 103.666798 -276.766528) (xy 103.678736 -276.760178) (xy 103.69296 -276.737826)
			(xy 103.698802 -276.624288) (xy 103.686864 -276.600412) (xy 103.675942 -276.593046) (xy 103.654185 -276.577733)
			(xy 103.614705 -276.54207) (xy 103.580561 -276.50127) (xy 103.552414 -276.456123) (xy 103.530809 -276.407504)
			(xy 103.516166 -276.356357) (xy 103.508768 -276.303671) (xy 103.508302 -276.27707) (xy 103.50875 -276.249699)
			(xy 103.516572 -276.195519) (xy 103.532065 -276.143016) (xy 103.554911 -276.093269) (xy 103.584639 -276.047303)
			(xy 103.602282 -276.026372) (xy 103.602536 -276.026118) (xy 103.608125 -276.019033) (xy 103.614369 -276.002115)
			(xy 103.614728 -275.993098) (xy 103.614728 -275.926042) (xy 103.614345 -275.917028) (xy 103.608115 -275.900111)
			(xy 103.602536 -275.893022) (xy 103.602282 -275.893022) (xy 103.602282 -275.892768) (xy 103.584659 -275.871823)
			(xy 103.554945 -275.825854) (xy 103.532106 -275.776109) (xy 103.516611 -275.723612) (xy 103.508779 -275.669438)
			(xy 103.508302 -275.64207) (xy 103.508302 -275.641816) (xy 103.508871 -275.612017) (xy 103.518149 -275.553146)
			(xy 103.536467 -275.496433) (xy 103.563378 -275.443257) (xy 103.598228 -275.394912) (xy 103.618792 -275.373338)
			(xy 103.626158 -275.365972) (xy 103.633778 -275.34743) (xy 103.632762 -275.25472) (xy 103.624888 -275.236178)
			(xy 103.617522 -275.229066) (xy 103.599566 -275.211014) (xy 103.568068 -275.171012) (xy 103.542169 -275.127176)
			(xy 103.522329 -275.080286) (xy 103.508902 -275.031173) (xy 103.502124 -274.980711) (xy 103.501698 -274.955254)
			(xy 103.502135 -274.928001) (xy 103.509898 -274.874052) (xy 103.525259 -274.821756) (xy 103.547906 -274.772178)
			(xy 103.577378 -274.726327) (xy 103.613074 -274.685137) (xy 103.654269 -274.649447) (xy 103.700123 -274.619981)
			(xy 103.749704 -274.597341) (xy 103.802002 -274.581987) (xy 103.855953 -274.574231) (xy 103.883206 -274.573746)
			(xy 103.912124 -274.574243) (xy 103.969297 -274.582974) (xy 104.024497 -274.600235) (xy 104.076459 -274.62563)
			(xy 104.123992 -274.658579) (xy 104.166007 -274.698324) (xy 104.184196 -274.720812) (xy 104.191813 -274.729609)
			(xy 104.212706 -274.739798) (xy 104.224328 -274.74037) (xy 104.304084 -274.74037) (xy 104.315715 -274.739818)
			(xy 104.336625 -274.729639) (xy 104.344216 -274.720812) (xy 104.360969 -274.700029) (xy 104.399323 -274.662899)
			(xy 104.442477 -274.631477) (xy 104.489591 -274.606378) (xy 104.539743 -274.588092) (xy 104.591954 -274.576975)
			(xy 104.645206 -274.573245) (xy 104.698458 -274.576975) (xy 104.750669 -274.588092) (xy 104.800821 -274.606378)
			(xy 104.847935 -274.631477) (xy 104.891089 -274.662899) (xy 104.929443 -274.700029) (xy 104.946196 -274.720812)
			(xy 104.953813 -274.729609) (xy 104.974706 -274.739798) (xy 104.986328 -274.74037) (xy 105.066084 -274.74037)
			(xy 105.077715 -274.739818) (xy 105.098625 -274.729639) (xy 105.106216 -274.720812) (xy 105.124401 -274.698323)
			(xy 105.166422 -274.658588) (xy 105.213958 -274.625649) (xy 105.26592 -274.600262) (xy 105.321119 -274.583007)
			(xy 105.37829 -274.57428) (xy 105.407206 -274.573746) (xy 105.434455 -274.574272) (xy 105.488399 -274.582028)
			(xy 105.54069 -274.597382) (xy 105.590265 -274.62002) (xy 105.636113 -274.649483) (xy 105.677302 -274.68517)
			(xy 105.712993 -274.726355) (xy 105.742461 -274.7722) (xy 105.765104 -274.821772) (xy 105.780463 -274.874062)
			(xy 105.788225 -274.928005) (xy 105.788714 -274.955254) (xy 105.788714 -274.955508) (xy 105.788155 -274.985307)
			(xy 105.778874 -275.044178) (xy 105.760554 -275.100891) (xy 105.733641 -275.154067) (xy 105.698789 -275.202412)
			(xy 105.678224 -275.223986) (xy 105.670858 -275.231352) (xy 105.663238 -275.249894) (xy 105.664254 -275.342604)
			(xy 105.672128 -275.361146) (xy 105.679494 -275.368258) (xy 105.697465 -275.386296) (xy 105.728961 -275.426301)
			(xy 105.754857 -275.47014) (xy 105.774694 -275.517034) (xy 105.788119 -275.566148) (xy 105.794894 -275.616612)
			(xy 105.795318 -275.64207) (xy 105.794809 -275.670988) (xy 105.786083 -275.728161) (xy 105.768825 -275.783361)
			(xy 105.743432 -275.835324) (xy 105.710485 -275.882857) (xy 105.67074 -275.924872) (xy 105.648252 -275.94306)
			(xy 105.639465 -275.950686) (xy 105.629272 -275.971573) (xy 105.628694 -275.983192) (xy 105.628694 -276.062948)
			(xy 105.629222 -276.074581) (xy 105.639419 -276.09549) (xy 105.648252 -276.10308) (xy 105.670737 -276.121269)
			(xy 105.710469 -276.163291) (xy 105.743407 -276.210827) (xy 105.768794 -276.262788) (xy 105.786051 -276.317985)
			(xy 105.794782 -276.375154) (xy 105.795318 -276.40407) (xy 105.794817 -276.431322) (xy 105.787064 -276.485271)
			(xy 105.771712 -276.537567) (xy 105.749074 -276.587147) (xy 105.71961 -276.632999) (xy 105.68392 -276.674192)
			(xy 105.642731 -276.709886) (xy 105.596882 -276.739355) (xy 105.547305 -276.761998) (xy 105.49501 -276.777356)
			(xy 105.441062 -276.785114) (xy 105.41381 -276.785578) (xy 105.384893 -276.785061) (xy 105.327721 -276.776333)
			(xy 105.272522 -276.759075) (xy 105.22056 -276.733683) (xy 105.173026 -276.700739) (xy 105.13101 -276.660998)
			(xy 105.11282 -276.638512) (xy 105.105192 -276.629726) (xy 105.084307 -276.61953) (xy 105.072688 -276.618954)
			(xy 104.992932 -276.618954) (xy 104.981301 -276.619507) (xy 104.96039 -276.629684) (xy 104.9528 -276.638512)
			(xy 104.942769 -276.651117) (xy 104.920893 -276.674769) (xy 104.909112 -276.685756) (xy 104.900222 -276.693884)
			(xy 104.891586 -276.715982) (xy 104.900222 -276.808692) (xy 104.901916 -276.820318) (xy 104.914226 -276.840299)
			(xy 104.923844 -276.847046) (xy 104.924098 -276.8473) (xy 104.947407 -276.862306) (xy 104.989845 -276.897971)
			(xy 105.026673 -276.939405) (xy 105.057113 -276.985734) (xy 105.080524 -277.035983) (xy 105.096413 -277.089091)
			(xy 105.104446 -277.143941) (xy 105.104946 -277.171658) (xy 105.10446 -277.198909) (xy 105.096704 -277.252857)
			(xy 105.081349 -277.305152) (xy 105.058707 -277.354729) (xy 105.029241 -277.400579) (xy 104.99355 -277.44177)
			(xy 104.952359 -277.477461) (xy 104.906509 -277.506927) (xy 104.856932 -277.529569) (xy 104.804637 -277.544924)
			(xy 104.750689 -277.55268) (xy 104.696187 -277.55268) (xy 104.642239 -277.544924) (xy 104.589944 -277.529569)
			(xy 104.540367 -277.506927) (xy 104.494517 -277.477461) (xy 104.453326 -277.44177) (xy 104.417635 -277.400579)
			(xy 104.388169 -277.354729) (xy 104.365527 -277.305152) (xy 104.350172 -277.252857) (xy 104.342416 -277.198909)
			(xy 104.34193 -277.171658) (xy 104.342402 -277.14524) (xy 104.349686 -277.09291) (xy 104.364122 -277.042085)
			(xy 104.385435 -276.99374) (xy 104.413216 -276.948798) (xy 104.446934 -276.908121) (xy 104.466136 -276.889972)
			(xy 104.475026 -276.881844) (xy 104.483662 -276.859746) (xy 104.475026 -276.767036) (xy 104.473338 -276.755409)
			(xy 104.461026 -276.735426) (xy 104.451404 -276.728682) (xy 104.45115 -276.728428) (xy 104.429535 -276.714589)
			(xy 104.389877 -276.68201) (xy 104.354959 -276.644394) (xy 104.325417 -276.602424) (xy 104.313228 -276.579838)
			(xy 104.30764 -276.56917) (xy 104.28859 -276.5552) (xy 104.196388 -276.539706) (xy 104.184684 -276.53846)
			(xy 104.162198 -276.54532) (xy 104.153208 -276.552914) (xy 104.152954 -276.553168) (xy 104.1341 -276.57061)
			(xy 104.09256 -276.600817) (xy 104.07015 -276.613366) (xy 104.058212 -276.619716) (xy 104.043988 -276.642068)
			(xy 104.038146 -276.755606) (xy 104.050084 -276.779482) (xy 104.061006 -276.786848) (xy 104.082749 -276.802181)
			(xy 104.122231 -276.837839) (xy 104.156378 -276.878635) (xy 104.184528 -276.923778) (xy 104.206135 -276.972394)
			(xy 104.22078 -277.02354) (xy 104.22818 -277.076224) (xy 104.228646 -277.102824) (xy 104.228093 -277.13174)
			(xy 104.219374 -277.18891) (xy 104.202124 -277.244109) (xy 104.176739 -277.296072) (xy 104.143801 -277.343606)
			(xy 104.104064 -277.385623) (xy 104.08158 -277.403814) (xy 104.072773 -277.411421) (xy 104.06259 -277.432322)
			(xy 104.062022 -277.443946) (xy 104.062022 -277.523702) (xy 104.062567 -277.535333) (xy 104.072751 -277.556243)
			(xy 104.08158 -277.563834) (xy 104.104076 -277.582011) (xy 104.143811 -277.624033) (xy 104.176749 -277.671571)
			(xy 104.202136 -277.723535) (xy 104.219389 -277.778735) (xy 104.228114 -277.835907) (xy 104.228646 -277.864824)
			(xy 104.22816 -277.892075) (xy 104.220404 -277.946023) (xy 104.205049 -277.998318) (xy 104.182407 -278.047895)
			(xy 104.152941 -278.093745) (xy 104.11725 -278.134936) (xy 104.076059 -278.170627) (xy 104.030209 -278.200093)
			(xy 103.980632 -278.222735) (xy 103.928337 -278.23809) (xy 103.874389 -278.245846) (xy 103.819887 -278.245846)
			(xy 103.765939 -278.23809) (xy 103.713644 -278.222735) (xy 103.664067 -278.200093) (xy 103.618217 -278.170627)
			(xy 103.577026 -278.134936) (xy 103.541335 -278.093745) (xy 103.511869 -278.047895) (xy 103.489227 -277.998318)
			(xy 103.473872 -277.946023) (xy 103.466116 -277.892075) (xy 103.46563 -277.864824) (xy 98.2853 -277.864824)
			(xy 98.2853 -282.904438) (xy 101.903022 -282.904438) (xy 101.903506 -282.876864) (xy 101.911454 -282.822292)
			(xy 101.927175 -282.769432) (xy 101.950341 -282.719386) (xy 101.980471 -282.673196) (xy 102.016936 -282.631824)
			(xy 102.037642 -282.613608) (xy 102.045721 -282.606056) (xy 102.055071 -282.586042) (xy 102.055676 -282.575)
			(xy 102.055676 -282.497276) (xy 102.055073 -282.486231) (xy 102.045733 -282.466209) (xy 102.037642 -282.458668)
			(xy 102.016921 -282.440468) (xy 101.980449 -282.399098) (xy 101.950317 -282.352906) (xy 101.927153 -282.302856)
			(xy 101.911439 -282.249991) (xy 101.903504 -282.195414) (xy 101.903022 -282.167838) (xy 101.903506 -282.140264)
			(xy 101.911454 -282.085692) (xy 101.927175 -282.032832) (xy 101.950341 -281.982786) (xy 101.980471 -281.936596)
			(xy 102.016936 -281.895224) (xy 102.037642 -281.877008) (xy 102.045721 -281.869456) (xy 102.055071 -281.849442)
			(xy 102.055676 -281.8384) (xy 102.055676 -281.760676) (xy 102.055073 -281.749631) (xy 102.045733 -281.729609)
			(xy 102.037642 -281.722068) (xy 102.016921 -281.703868) (xy 101.980449 -281.662498) (xy 101.950317 -281.616306)
			(xy 101.927153 -281.566256) (xy 101.911439 -281.513391) (xy 101.903504 -281.458814) (xy 101.903022 -281.431238)
			(xy 101.903491 -281.403985) (xy 101.911243 -281.350032) (xy 101.926596 -281.297733) (xy 101.949236 -281.248151)
			(xy 101.978703 -281.202296) (xy 102.014397 -281.161102) (xy 102.05559 -281.125408) (xy 102.101444 -281.09594)
			(xy 102.151025 -281.073299) (xy 102.203325 -281.057945) (xy 102.257277 -281.050191) (xy 102.28453 -281.04973)
			(xy 102.312387 -281.050204) (xy 102.367506 -281.058332) (xy 102.420859 -281.074383) (xy 102.471313 -281.098016)
			(xy 102.517798 -281.128729) (xy 102.559327 -281.165871) (xy 102.595019 -281.208652) (xy 102.624116 -281.256165)
			(xy 102.646 -281.307402) (xy 102.653592 -281.33421) (xy 102.655878 -281.3431) (xy 102.666546 -281.35834)
			(xy 102.738428 -281.406092) (xy 102.756462 -281.410156) (xy 102.765606 -281.408886) (xy 102.778623 -281.407218)
			(xy 102.804807 -281.405437) (xy 102.81793 -281.40533) (xy 102.831053 -281.405425) (xy 102.857239 -281.407203)
			(xy 102.870254 -281.408886) (xy 102.879398 -281.410156) (xy 102.897432 -281.406092) (xy 102.969314 -281.35834)
			(xy 102.979982 -281.3431) (xy 102.982268 -281.33421) (xy 102.989866 -281.307402) (xy 103.011728 -281.256153)
			(xy 103.040812 -281.208628) (xy 103.076499 -281.165839) (xy 103.118029 -281.128694) (xy 103.16452 -281.097985)
			(xy 103.214983 -281.074364) (xy 103.268345 -281.058334) (xy 103.323471 -281.050234) (xy 103.35133 -281.04973)
			(xy 103.378585 -281.050127) (xy 103.432541 -281.057889) (xy 103.484842 -281.073251) (xy 103.534425 -281.0959)
			(xy 103.58028 -281.125374) (xy 103.621473 -281.161075) (xy 103.657166 -281.202275) (xy 103.686633 -281.248135)
			(xy 103.709273 -281.297722) (xy 103.724625 -281.350026) (xy 103.732378 -281.403983) (xy 103.732838 -281.431238)
			(xy 103.732367 -281.458537) (xy 103.724591 -281.512579) (xy 103.709189 -281.564959) (xy 103.686476 -281.614609)
			(xy 103.656915 -281.660512) (xy 103.639366 -281.681428) (xy 103.633016 -281.688794) (xy 103.626666 -281.706574)
			(xy 103.629968 -281.795728) (xy 103.637842 -281.813508) (xy 103.6447 -281.820112) (xy 103.665831 -281.841741)
			(xy 103.701631 -281.89047) (xy 103.729295 -281.944237) (xy 103.735566 -281.963368) (xy 108.281722 -281.963368)
			(xy 108.285793 -281.907746) (xy 108.297919 -281.853309) (xy 108.317842 -281.801218) (xy 108.345138 -281.752583)
			(xy 108.379224 -281.70844) (xy 108.419373 -281.669731) (xy 108.464731 -281.63728) (xy 108.514331 -281.611779)
			(xy 108.567115 -281.593772) (xy 108.621958 -281.583642) (xy 108.677692 -281.581605) (xy 108.733129 -281.587705)
			(xy 108.787086 -281.601811) (xy 108.838415 -281.623623) (xy 108.886021 -281.652677) (xy 108.928889 -281.688352)
			(xy 108.966106 -281.729889) (xy 108.996879 -281.776402) (xy 109.020551 -281.826899) (xy 109.036619 -281.880306)
			(xy 109.044739 -281.935482) (xy 109.045248 -281.963368) (xy 109.044739 -281.991254) (xy 109.036619 -282.04643)
			(xy 109.020551 -282.099837) (xy 108.996879 -282.150334) (xy 108.966106 -282.196847) (xy 108.928889 -282.238384)
			(xy 108.886021 -282.274059) (xy 108.838415 -282.303113) (xy 108.787086 -282.324925) (xy 108.733129 -282.339031)
			(xy 108.677692 -282.345131) (xy 108.621958 -282.343094) (xy 108.567115 -282.332964) (xy 108.514331 -282.314957)
			(xy 108.464731 -282.289456) (xy 108.419373 -282.257005) (xy 108.379224 -282.218296) (xy 108.345138 -282.174153)
			(xy 108.317842 -282.125518) (xy 108.297919 -282.073427) (xy 108.285793 -282.01899) (xy 108.281722 -281.963368)
			(xy 103.735566 -281.963368) (xy 103.74813 -282.001695) (xy 103.757663 -282.061405) (xy 103.758238 -282.091638)
			(xy 103.757742 -282.119276) (xy 103.74975 -282.173971) (xy 103.733952 -282.226942) (xy 103.710681 -282.277081)
			(xy 103.680421 -282.323338) (xy 103.66248 -282.344368) (xy 103.654098 -282.353766) (xy 103.648256 -282.37815)
			(xy 103.672386 -282.47213) (xy 103.676088 -282.484075) (xy 103.692864 -282.502584) (xy 103.70439 -282.507436)
			(xy 103.731799 -282.517772) (xy 103.783314 -282.545654) (xy 103.829959 -282.581086) (xy 103.870637 -282.623235)
			(xy 103.904391 -282.671108) (xy 103.930427 -282.72358) (xy 103.948133 -282.779416) (xy 103.957092 -282.837304)
			(xy 103.957628 -282.866592) (xy 103.957115 -282.893842) (xy 103.957113 -282.893854) (xy 104.287247 -282.893854)
			(xy 104.287247 -282.839346) (xy 104.295005 -282.785392) (xy 104.310362 -282.733091) (xy 104.333007 -282.683509)
			(xy 104.362477 -282.637654) (xy 104.398174 -282.59646) (xy 104.43937 -282.560765) (xy 104.485226 -282.531297)
			(xy 104.53481 -282.508655) (xy 104.587111 -282.493301) (xy 104.641066 -282.485546) (xy 104.66832 -282.485084)
			(xy 104.695692 -282.485518) (xy 104.749873 -282.49334) (xy 104.802377 -282.508836) (xy 104.852124 -282.531685)
			(xy 104.898088 -282.561418) (xy 104.919018 -282.579064) (xy 104.919272 -282.579318) (xy 104.926361 -282.584901)
			(xy 104.943276 -282.591149) (xy 104.952292 -282.59151) (xy 105.019348 -282.59151) (xy 105.028362 -282.591126)
			(xy 105.045279 -282.584897) (xy 105.052368 -282.579318) (xy 105.052368 -282.579064) (xy 105.052622 -282.579064)
			(xy 105.073568 -282.561442) (xy 105.119538 -282.531729) (xy 105.169282 -282.50889) (xy 105.221779 -282.493395)
			(xy 105.275952 -282.485561) (xy 105.30332 -282.485084) (xy 105.33057 -282.485587) (xy 105.384514 -282.493346)
			(xy 105.436805 -282.508702) (xy 105.486379 -282.531344) (xy 105.532226 -282.56081) (xy 105.573413 -282.596501)
			(xy 105.609102 -282.63769) (xy 105.638565 -282.683538) (xy 105.661205 -282.733113) (xy 105.676558 -282.785405)
			(xy 105.684314 -282.83935) (xy 105.684314 -282.89385) (xy 105.676558 -282.947795) (xy 105.661205 -283.000087)
			(xy 105.638565 -283.049662) (xy 105.609102 -283.09551) (xy 105.573413 -283.136699) (xy 105.532226 -283.17239)
			(xy 105.486379 -283.201856) (xy 105.436805 -283.224498) (xy 105.384514 -283.239854) (xy 105.33057 -283.247613)
			(xy 105.30332 -283.2481) (xy 105.27595 -283.247622) (xy 105.221772 -283.239807) (xy 105.169269 -283.224321)
			(xy 105.119522 -283.201482) (xy 105.073554 -283.17176) (xy 105.052622 -283.15412) (xy 105.052368 -283.153866)
			(xy 105.045269 -283.148298) (xy 105.028362 -283.142041) (xy 105.019348 -283.141674) (xy 104.952292 -283.141674)
			(xy 104.943275 -283.142033) (xy 104.926359 -283.14828) (xy 104.919272 -283.153866) (xy 104.919272 -283.15412)
			(xy 104.919018 -283.15412) (xy 104.898093 -283.171767) (xy 104.852118 -283.201477) (xy 104.802368 -283.224311)
			(xy 104.749866 -283.2398) (xy 104.69569 -283.247627) (xy 104.66832 -283.2481) (xy 104.641066 -283.247654)
			(xy 104.587111 -283.239899) (xy 104.53481 -283.224545) (xy 104.485226 -283.201903) (xy 104.43937 -283.172435)
			(xy 104.398174 -283.13674) (xy 104.362477 -283.095546) (xy 104.333007 -283.049691) (xy 104.310362 -283.000109)
			(xy 104.295005 -282.947808) (xy 104.287247 -282.893854) (xy 103.957113 -282.893854) (xy 103.94936 -282.947788)
			(xy 103.934007 -283.000081) (xy 103.911368 -283.049657) (xy 103.881904 -283.095506) (xy 103.846216 -283.136696)
			(xy 103.805029 -283.172388) (xy 103.759181 -283.201855) (xy 103.709607 -283.224497) (xy 103.657315 -283.239854)
			(xy 103.60337 -283.247613) (xy 103.57612 -283.2481) (xy 103.549739 -283.247582) (xy 103.497478 -283.240334)
			(xy 103.446716 -283.225947) (xy 103.398425 -283.204695) (xy 103.353526 -283.176985) (xy 103.312879 -283.143347)
			(xy 103.27726 -283.104423) (xy 103.247351 -283.060959) (xy 103.223723 -283.013784) (xy 103.206829 -282.9638)
			(xy 103.20147 -282.937966) (xy 103.19893 -282.92552) (xy 103.18369 -282.906216) (xy 103.082598 -282.862528)
			(xy 103.05796 -282.864306) (xy 103.047292 -282.871164) (xy 103.024324 -282.885206) (xy 102.97525 -282.907336)
			(xy 102.923547 -282.922331) (xy 102.870247 -282.929892) (xy 102.84333 -282.930346) (xy 102.825311 -282.93013)
			(xy 102.789436 -282.926693) (xy 102.771702 -282.923488) (xy 102.76205 -282.92171) (xy 102.743 -282.925266)
			(xy 102.66807 -282.973272) (xy 102.65664 -282.98902) (xy 102.654354 -282.998418) (xy 102.646966 -283.025465)
			(xy 102.625337 -283.077194) (xy 102.596373 -283.125201) (xy 102.560697 -283.168454) (xy 102.519077 -283.206022)
			(xy 102.472407 -283.237096) (xy 102.421694 -283.261007) (xy 102.368028 -283.277242) (xy 102.312564 -283.285449)
			(xy 102.28453 -283.285946) (xy 102.257281 -283.285394) (xy 102.203338 -283.277643) (xy 102.151047 -283.262293)
			(xy 102.101472 -283.239658) (xy 102.055624 -283.210199) (xy 102.014434 -283.174514) (xy 101.978742 -283.133331)
			(xy 101.949274 -283.087487) (xy 101.926631 -283.037917) (xy 101.911272 -282.985629) (xy 101.903511 -282.931687)
			(xy 101.903022 -282.904438) (xy 98.2853 -282.904438) (xy 98.2853 -284.175454) (xy 103.562656 -284.175454)
			(xy 103.566727 -284.119832) (xy 103.578853 -284.065395) (xy 103.598776 -284.013304) (xy 103.626072 -283.964669)
			(xy 103.660158 -283.920526) (xy 103.700307 -283.881817) (xy 103.745665 -283.849366) (xy 103.795265 -283.823865)
			(xy 103.848049 -283.805858) (xy 103.902892 -283.795728) (xy 103.958626 -283.793691) (xy 104.014063 -283.799791)
			(xy 104.06802 -283.813897) (xy 104.119349 -283.835709) (xy 104.166955 -283.864763) (xy 104.209823 -283.900438)
			(xy 104.24704 -283.941975) (xy 104.277813 -283.988488) (xy 104.301485 -284.038985) (xy 104.317553 -284.092392)
			(xy 104.325673 -284.147568) (xy 104.326182 -284.175454) (xy 104.325673 -284.20334) (xy 104.317553 -284.258516)
			(xy 104.301485 -284.311923) (xy 104.277813 -284.36242) (xy 104.24704 -284.408933) (xy 104.209823 -284.45047)
			(xy 104.166955 -284.486145) (xy 104.119349 -284.515199) (xy 104.06802 -284.537011) (xy 104.014063 -284.551117)
			(xy 103.958626 -284.557217) (xy 103.902892 -284.55518) (xy 103.848049 -284.54505) (xy 103.795265 -284.527043)
			(xy 103.745665 -284.501542) (xy 103.700307 -284.469091) (xy 103.660158 -284.430382) (xy 103.626072 -284.386239)
			(xy 103.598776 -284.337604) (xy 103.578853 -284.285513) (xy 103.566727 -284.231076) (xy 103.562656 -284.175454)
			(xy 98.2853 -284.175454) (xy 98.2853 -284.574742) (xy 98.284841 -284.604956) (xy 98.277313 -284.664914)
			(xy 98.262356 -284.723462) (xy 98.240203 -284.779684) (xy 98.211202 -284.832698) (xy 98.19386 -284.857444)
			(xy 98.189288 -284.863794) (xy 98.181668 -284.886146) (xy 98.179382 -284.896814) (xy 98.179128 -284.901894)
			(xy 98.179128 -285.641796) (xy 98.17989 -285.649924) (xy 98.17989 -285.650432) (xy 98.181491 -285.657951)
			(xy 98.188466 -285.67164) (xy 98.193606 -285.677356) (xy 98.927412 -286.411162) (xy 98.933093 -286.416351)
			(xy 98.9468 -286.423323) (xy 98.954336 -286.424878) (xy 98.954844 -286.424878) (xy 98.962972 -286.42564)
			(xy 99.669346 -286.42564) (xy 99.679412 -286.426073) (xy 99.698 -286.433803) (xy 99.705414 -286.440626)
			(xy 99.75088 -286.486092) (xy 99.756468 -286.490918) (xy 99.76057 -286.493841) (xy 99.76965 -286.4982)
			(xy 99.774502 -286.499554) (xy 99.777296 -286.500062) (xy 99.852249 -286.51465) (xy 100.000879 -286.549746)
			(xy 100.147771 -286.591525) (xy 100.292623 -286.639903) (xy 100.364036 -286.66694) (xy 100.43962 -286.696566)
			(xy 100.588155 -286.762129) (xy 100.733371 -286.83475) (xy 100.874931 -286.914263) (xy 101.012508 -287.000482)
			(xy 101.145786 -287.093209) (xy 101.274457 -287.192231) (xy 101.398223 -287.297318) (xy 101.516799 -287.408228)
			(xy 101.629911 -287.524706) (xy 101.737299 -287.646481) (xy 101.838714 -287.773274) (xy 101.933922 -287.904791)
			(xy 102.022704 -288.04073) (xy 102.104854 -288.180775) (xy 102.180183 -288.324605) (xy 102.248517 -288.471886)
			(xy 102.309699 -288.622279) (xy 102.363587 -288.775438) (xy 102.410056 -288.931008) (xy 102.449 -289.08863)
			(xy 102.480329 -289.24794) (xy 102.50397 -289.408572) (xy 102.519869 -289.570153) (xy 102.527989 -289.732312)
			(xy 102.528624 -289.813492) (xy 102.528624 -289.82035) (xy 102.528136 -289.901448) (xy 102.520339 -290.063458)
			(xy 102.504779 -290.224907) (xy 102.481492 -290.385423) (xy 102.450532 -290.544638) (xy 102.411969 -290.702184)
			(xy 102.365894 -290.857699) (xy 102.312412 -291.010825) (xy 102.251646 -291.161208) (xy 102.183735 -291.308504)
			(xy 102.108838 -291.452373) (xy 102.068376 -291.522658) (xy 102.06482 -291.528754) (xy 102.061518 -291.541454)
			(xy 102.059994 -291.553646) (xy 102.059994 -291.564822) (xy 102.063804 -291.577014) (xy 102.077774 -291.600382)
			(xy 102.081838 -291.60724) (xy 102.089352 -291.617434) (xy 102.11161 -291.629446) (xy 102.124256 -291.6301)
			(xy 109.415072 -291.6301) (xy 109.4232 -291.629338) (xy 109.423708 -291.629338) (xy 109.431229 -291.627742)
			(xy 109.444925 -291.620774) (xy 109.450632 -291.615622) (xy 109.577378 -291.488876) (xy 109.582564 -291.483194)
			(xy 109.589531 -291.469486) (xy 109.591094 -291.461952) (xy 109.591094 -291.461444) (xy 109.591856 -291.453316)
			(xy 109.591856 -287.334452) (xy 109.591359 -287.324454) (xy 109.583689 -287.305986) (xy 109.569536 -287.291859)
			(xy 109.551055 -287.284223) (xy 109.541056 -287.283652) (xy 109.02569 -287.283652) (xy 109.015441 -287.283193)
			(xy 108.996561 -287.275212) (xy 108.989114 -287.268158) (xy 108.981748 -287.266888) (xy 108.954415 -287.262354)
			(xy 108.900942 -287.24784) (xy 108.875068 -287.237932) (xy 108.844961 -287.225337) (xy 108.788162 -287.193198)
			(xy 108.736215 -287.153692) (xy 108.712762 -287.130998) (xy 108.364528 -286.782764) (xy 108.340295 -286.757646)
			(xy 108.298582 -286.701689) (xy 108.265361 -286.640309) (xy 108.252768 -286.607758) (xy 108.243394 -286.580992)
			(xy 108.230256 -286.525822) (xy 108.223675 -286.469491) (xy 108.223304 -286.441134) (xy 108.223304 -283.291534)
			(xy 108.223686 -283.263178) (xy 108.230274 -283.20685) (xy 108.243411 -283.151681) (xy 108.252768 -283.12491)
			(xy 108.26537 -283.092364) (xy 108.298597 -283.03099) (xy 108.34031 -282.975036) (xy 108.364528 -282.949904)
			(xy 109.238542 -282.07589) (xy 109.243528 -282.07039) (xy 109.25037 -282.057224) (xy 109.252004 -282.049982)
			(xy 109.25302 -282.04033) (xy 109.25302 -281.649424) (xy 109.25302 -281.648154) (xy 109.252541 -281.640759)
			(xy 109.247892 -281.626696) (xy 109.243876 -281.620468) (xy 109.237526 -281.612848) (xy 109.183932 -281.560778)
			(xy 109.176628 -281.55485) (xy 109.159042 -281.548219) (xy 109.149642 -281.547824) (xy 109.148626 -281.547824)
			(xy 109.139482 -281.548078) (xy 109.137704 -281.548078) (xy 109.110467 -281.547572) (xy 109.056553 -281.539781)
			(xy 109.004296 -281.5244) (xy 108.954758 -281.501741) (xy 108.908947 -281.472266) (xy 108.867794 -281.436575)
			(xy 108.832138 -281.395392) (xy 108.802702 -281.349556) (xy 108.780086 -281.299998) (xy 108.76475 -281.247728)
			(xy 108.757005 -281.193807) (xy 108.75645 -281.16657) (xy 108.756938 -281.139319) (xy 108.764698 -281.085372)
			(xy 108.780055 -281.033079) (xy 108.802697 -280.983503) (xy 108.832164 -280.937653) (xy 108.867854 -280.896463)
			(xy 108.909043 -280.860771) (xy 108.954892 -280.831303) (xy 109.004468 -280.808659) (xy 109.056761 -280.7933)
			(xy 109.110707 -280.785539) (xy 109.137958 -280.785062) (xy 109.165741 -280.785588) (xy 109.220715 -280.793691)
			(xy 109.273933 -280.809676) (xy 109.324274 -280.833204) (xy 109.347762 -280.848054) (xy 109.348016 -280.848054)
			(xy 109.348016 -280.848308) (xy 109.349794 -280.849578) (xy 109.35822 -280.853987) (xy 109.377008 -280.856842)
			(xy 109.38637 -280.855166) (xy 109.457744 -280.839672) (xy 109.462627 -280.838523) (xy 109.471837 -280.83455)
			(xy 109.476032 -280.831798) (xy 109.48416 -280.82621) (xy 109.489748 -280.81732) (xy 109.504406 -280.794644)
			(xy 109.538014 -280.752382) (xy 109.556804 -280.732992) (xy 109.978444 -280.311352) (xy 110.003565 -280.287123)
			(xy 110.059524 -280.245416) (xy 110.120906 -280.212201) (xy 110.15345 -280.199592) (xy 110.180053 -280.190267)
			(xy 110.234886 -280.177169) (xy 110.290871 -280.170549) (xy 110.319058 -280.170128) (xy 112.725708 -280.170128)
			(xy 112.753895 -280.170555) (xy 112.809879 -280.177176) (xy 112.864713 -280.190268) (xy 112.891316 -280.199592)
			(xy 112.923865 -280.21219) (xy 112.985244 -280.245412) (xy 113.041203 -280.287121) (xy 113.066322 -280.311352)
			(xy 113.978944 -281.224228) (xy 113.986341 -281.231075) (xy 114.00494 -281.238805) (xy 114.015012 -281.239214)
			(xy 114.066066 -281.239214) (xy 114.070589 -281.2344) (xy 114.077161 -281.222946) (xy 114.07902 -281.216608)
			(xy 114.075815 -281.198682) (xy 114.072385 -281.162427) (xy 114.072162 -281.144218) (xy 114.072327 -281.12859)
			(xy 114.074867 -281.097436) (xy 114.077242 -281.081988) (xy 114.076155 -281.078441) (xy 114.073089 -281.071686)
			(xy 114.071146 -281.068526) (xy 114.028474 -281.009852) (xy 114.023112 -281.003223) (xy 114.008961 -280.993735)
			(xy 114.000788 -280.99131) (xy 113.998502 -280.990802) (xy 113.970207 -280.98442) (xy 113.915826 -280.964252)
			(xy 113.865123 -280.936086) (xy 113.819268 -280.900571) (xy 113.779316 -280.858524) (xy 113.746188 -280.810915)
			(xy 113.720647 -280.75884) (xy 113.703283 -280.703499) (xy 113.694494 -280.646168) (xy 113.693956 -280.617168)
			(xy 113.694442 -280.589917) (xy 113.702198 -280.535969) (xy 113.717553 -280.483674) (xy 113.740195 -280.434097)
			(xy 113.769661 -280.388247) (xy 113.805352 -280.347056) (xy 113.846543 -280.311365) (xy 113.892393 -280.281899)
			(xy 113.94197 -280.259257) (xy 113.994265 -280.243902) (xy 114.048213 -280.236146) (xy 114.102715 -280.236146)
			(xy 114.156663 -280.243902) (xy 114.208958 -280.259257) (xy 114.258535 -280.281899) (xy 114.304385 -280.311365)
			(xy 114.345576 -280.347056) (xy 114.381267 -280.388247) (xy 114.410733 -280.434097) (xy 114.433375 -280.483674)
			(xy 114.44873 -280.535969) (xy 114.456486 -280.589917) (xy 114.456972 -280.617168) (xy 114.456935 -280.627921)
			(xy 114.455791 -280.649397) (xy 114.454686 -280.660094) (xy 114.454187 -280.668922) (xy 114.458481 -280.686062)
			(xy 114.463068 -280.693622) (xy 114.505994 -280.752804) (xy 114.511074 -280.758392) (xy 114.52098 -280.763218)
			(xy 114.556032 -280.770838) (xy 114.55781 -280.77033) (xy 114.563112 -280.768862) (xy 114.572974 -280.763989)
			(xy 114.577368 -280.760678) (xy 114.59083 -280.75001) (xy 114.591338 -280.749502) (xy 114.638836 -280.71064)
			(xy 114.647231 -280.703023) (xy 114.656978 -280.682588) (xy 114.657632 -280.67127) (xy 114.657632 -280.308558)
			(xy 114.657466 -280.302548) (xy 114.654645 -280.290864) (xy 114.652044 -280.285444) (xy 114.650201 -280.281973)
			(xy 114.6456 -280.275601) (xy 114.6429 -280.272744) (xy 114.029744 -279.659588) (xy 114.00896 -279.637976)
			(xy 113.973711 -279.589473) (xy 113.946481 -279.536055) (xy 113.927939 -279.479036) (xy 113.918542 -279.419819)
			(xy 113.917984 -279.38984) (xy 113.917984 -279.02408) (xy 113.91782 -279.01807) (xy 113.915002 -279.006384)
			(xy 113.912396 -279.000966) (xy 113.910555 -278.997493) (xy 113.90596 -278.991115) (xy 113.903252 -278.988266)
			(xy 113.654586 -278.7396) (xy 113.651734 -278.736896) (xy 113.645353 -278.732308) (xy 113.641886 -278.730456)
			(xy 113.63646 -278.727867) (xy 113.624781 -278.725034) (xy 113.618772 -278.724868) (xy 113.302288 -278.724868)
			(xy 113.296277 -278.725031) (xy 113.28459 -278.727845) (xy 113.279174 -278.730456) (xy 113.275701 -278.732298)
			(xy 113.269327 -278.736896) (xy 113.266474 -278.7396) (xy 112.198912 -279.807162) (xy 112.177336 -279.827898)
			(xy 112.128919 -279.863061) (xy 112.075601 -279.890222) (xy 112.018691 -279.908713) (xy 111.959591 -279.918079)
			(xy 111.929672 -279.918668) (xy 109.678724 -279.918668) (xy 109.648807 -279.918063) (xy 109.589712 -279.908681)
			(xy 109.532805 -279.890189) (xy 109.479483 -279.863041) (xy 109.431052 -279.827903) (xy 109.409484 -279.807162)
			(xy 108.341922 -278.7396) (xy 108.339071 -278.736895) (xy 108.332692 -278.732302) (xy 108.329222 -278.730456)
			(xy 108.323795 -278.727874) (xy 108.312115 -278.725056) (xy 108.306108 -278.724868) (xy 107.86618 -278.724868)
			(xy 107.859068 -278.725376) (xy 107.852045 -278.726608) (xy 107.83902 -278.732401) (xy 107.833414 -278.736806)
			(xy 107.773978 -278.796242) (xy 107.771565 -278.799019) (xy 107.767481 -278.805137) (xy 107.76585 -278.808434)
			(xy 107.763881 -278.812838) (xy 107.761446 -278.822171) (xy 107.761024 -278.826976) (xy 107.761024 -279.414732)
			(xy 107.76154 -279.426179) (xy 107.771446 -279.446818) (xy 107.780074 -279.454356) (xy 107.841542 -279.503886)
			(xy 107.846136 -279.507373) (xy 107.856524 -279.51238) (xy 107.862116 -279.513792) (xy 107.873038 -279.516332)
			(xy 107.884214 -279.514046) (xy 107.904098 -279.510004) (xy 107.944444 -279.505679) (xy 107.964732 -279.50541)
			(xy 107.96905 -279.50541) (xy 107.996126 -279.50615) (xy 108.049667 -279.514337) (xy 108.101512 -279.530015)
			(xy 108.150619 -279.552867) (xy 108.196 -279.582436) (xy 108.236743 -279.618125) (xy 108.272028 -279.659218)
			(xy 108.301147 -279.704889) (xy 108.323513 -279.754219) (xy 108.338678 -279.806217) (xy 108.346336 -279.859836)
			(xy 108.346748 -279.886918) (xy 108.346208 -279.915783) (xy 108.337491 -279.972852) (xy 108.320273 -280.027956)
			(xy 108.294949 -280.079836) (xy 108.262095 -280.127307) (xy 108.222463 -280.169286) (xy 108.176958 -280.204813)
			(xy 108.126619 -280.233077) (xy 108.072596 -280.253432) (xy 108.016122 -280.265414) (xy 107.987338 -280.267664)
			(xy 107.986068 -280.267664) (xy 107.97583 -280.26903) (xy 107.957619 -280.278735) (xy 107.950762 -280.28646)
			(xy 107.90301 -280.353516) (xy 107.899791 -280.358358) (xy 107.89543 -280.369134) (xy 107.894374 -280.374852)
			(xy 107.893104 -280.381964) (xy 107.894628 -280.393902) (xy 107.895136 -280.39568) (xy 107.89539 -280.39695)
			(xy 107.90216 -280.422451) (xy 107.909429 -280.474709) (xy 107.909868 -280.50109) (xy 107.909089 -280.535171)
			(xy 107.896951 -280.602247) (xy 107.885738 -280.63444) (xy 107.883786 -280.640195) (xy 107.882385 -280.652264)
			(xy 107.882944 -280.658316) (xy 107.884214 -280.669492) (xy 107.92841 -280.737818) (xy 107.931795 -280.742705)
			(xy 107.940395 -280.750909) (xy 107.945428 -280.754074) (xy 107.973876 -280.770838) (xy 107.979972 -280.7716)
			(xy 108.008245 -280.77445) (xy 108.06356 -280.787457) (xy 108.116334 -280.808526) (xy 108.165398 -280.837189)
			(xy 108.209669 -280.872813) (xy 108.248165 -280.914609) (xy 108.280035 -280.961654) (xy 108.304575 -281.012906)
			(xy 108.321241 -281.06723) (xy 108.329664 -281.123426) (xy 108.330238 -281.151838) (xy 108.329752 -281.179089)
			(xy 108.321996 -281.233037) (xy 108.306641 -281.285332) (xy 108.283999 -281.334909) (xy 108.254533 -281.380759)
			(xy 108.218842 -281.42195) (xy 108.177651 -281.457641) (xy 108.131801 -281.487107) (xy 108.082224 -281.509749)
			(xy 108.029929 -281.525104) (xy 107.975981 -281.53286) (xy 107.921479 -281.53286) (xy 107.867531 -281.525104)
			(xy 107.815236 -281.509749) (xy 107.765659 -281.487107) (xy 107.719809 -281.457641) (xy 107.678618 -281.42195)
			(xy 107.642927 -281.380759) (xy 107.613461 -281.334909) (xy 107.590819 -281.285332) (xy 107.575464 -281.233037)
			(xy 107.567708 -281.179089) (xy 107.567222 -281.151838) (xy 107.568 -281.117757) (xy 107.580142 -281.050683)
			(xy 107.591352 -281.018488) (xy 107.593638 -281.012646) (xy 107.594908 -281.000962) (xy 107.594146 -280.99512)
			(xy 107.593359 -280.989389) (xy 107.589511 -280.978485) (xy 107.586526 -280.97353) (xy 107.54868 -280.91511)
			(xy 107.545296 -280.910221) (xy 107.536697 -280.902016) (xy 107.531662 -280.898854) (xy 107.503214 -280.88209)
			(xy 107.497372 -280.881328) (xy 107.468546 -280.878499) (xy 107.412168 -280.86523) (xy 107.385104 -280.854912)
			(xy 107.376468 -280.852118) (xy 107.361228 -280.84907) (xy 107.356131 -280.849181) (xy 107.346143 -280.851224)
			(xy 107.341416 -280.853134) (xy 107.270804 -280.886916) (xy 107.266057 -280.889283) (xy 107.257601 -280.895685)
			(xy 107.25404 -280.899616) (xy 107.24769 -280.907236) (xy 107.245404 -280.914348) (xy 107.244388 -280.918158)
			(xy 107.236236 -280.944132) (xy 107.21359 -280.993635) (xy 107.184131 -281.039413) (xy 107.148461 -281.080535)
			(xy 107.107303 -281.116164) (xy 107.061495 -281.145575) (xy 107.011969 -281.168172) (xy 106.959732 -281.183492)
			(xy 106.905847 -281.191226) (xy 106.878628 -281.191716) (xy 106.86589 -281.191639) (xy 106.840469 -281.189987)
			(xy 106.827828 -281.188414) (xy 106.81797 -281.187017) (xy 106.798403 -281.183332) (xy 106.788712 -281.181048)
			(xy 106.785918 -281.180286) (xy 106.773218 -281.178762) (xy 106.767765 -281.178959) (xy 106.757132 -281.181395)
			(xy 106.752136 -281.183588) (xy 106.678476 -281.225752) (xy 106.67365 -281.231848) (xy 106.666591 -281.259761)
			(xy 106.645329 -281.313264) (xy 106.616358 -281.363018) (xy 106.580322 -281.407919) (xy 106.538018 -281.446971)
			(xy 106.490385 -281.47931) (xy 106.438478 -281.504218) (xy 106.383449 -281.521143) (xy 106.326517 -281.529711)
			(xy 106.29773 -281.530298) (xy 106.270149 -281.529832) (xy 106.215547 -281.521985) (xy 106.162618 -281.506448)
			(xy 106.112438 -281.483536) (xy 106.066031 -281.453716) (xy 106.024339 -281.417595) (xy 105.988213 -281.375908)
			(xy 105.958387 -281.329504) (xy 105.935469 -281.279327) (xy 105.919925 -281.2264) (xy 105.912072 -281.171799)
			(xy 105.91165 -281.144218) (xy 105.911815 -281.12859) (xy 105.914355 -281.097436) (xy 105.91673 -281.081988)
			(xy 105.915643 -281.078441) (xy 105.912576 -281.071687) (xy 105.910634 -281.068526) (xy 105.867962 -281.009852)
			(xy 105.8626 -281.003224) (xy 105.848447 -280.99374) (xy 105.840276 -280.99131) (xy 105.83799 -280.990802)
			(xy 105.809696 -280.984419) (xy 105.755316 -280.964251) (xy 105.704615 -280.936084) (xy 105.658761 -280.900568)
			(xy 105.61881 -280.858521) (xy 105.585683 -280.810912) (xy 105.560144 -280.758838) (xy 105.54278 -280.703498)
			(xy 105.533991 -280.646168) (xy 105.533444 -280.617168) (xy 105.53393 -280.589917) (xy 105.541686 -280.535969)
			(xy 105.557041 -280.483674) (xy 105.579683 -280.434097) (xy 105.609149 -280.388247) (xy 105.64484 -280.347056)
			(xy 105.686031 -280.311365) (xy 105.731881 -280.281899) (xy 105.781458 -280.259257) (xy 105.833753 -280.243902)
			(xy 105.887701 -280.236146) (xy 105.942203 -280.236146) (xy 105.996151 -280.243902) (xy 106.048446 -280.259257)
			(xy 106.098023 -280.281899) (xy 106.143873 -280.311365) (xy 106.185064 -280.347056) (xy 106.220755 -280.388247)
			(xy 106.250221 -280.434097) (xy 106.272863 -280.483674) (xy 106.288218 -280.535969) (xy 106.295974 -280.589917)
			(xy 106.29646 -280.617168) (xy 106.296423 -280.627921) (xy 106.295279 -280.649397) (xy 106.294174 -280.660094)
			(xy 106.293675 -280.668922) (xy 106.297968 -280.686062) (xy 106.302556 -280.693622) (xy 106.345482 -280.752804)
			(xy 106.350562 -280.758392) (xy 106.360468 -280.763218) (xy 106.39552 -280.770838) (xy 106.397298 -280.77033)
			(xy 106.402601 -280.768863) (xy 106.412464 -280.763992) (xy 106.416856 -280.760678) (xy 106.430318 -280.75001)
			(xy 106.430826 -280.749502) (xy 106.478324 -280.71064) (xy 106.486721 -280.703023) (xy 106.49647 -280.682589)
			(xy 106.49712 -280.67127) (xy 106.49712 -280.370026) (xy 106.496633 -280.360064) (xy 106.489046 -280.34164)
			(xy 106.482388 -280.334212) (xy 106.328718 -280.180542) (xy 106.206544 -280.058114) (xy 106.200188 -280.052483)
			(xy 106.184742 -280.045457) (xy 106.176318 -280.044398) (xy 106.171492 -280.044144) (xy 105.730802 -280.044144)
			(xy 105.700886 -280.043538) (xy 105.641793 -280.034152) (xy 105.584889 -280.015657) (xy 105.53157 -279.988506)
			(xy 105.483143 -279.953365) (xy 105.461562 -279.932638) (xy 105.158032 -279.629108) (xy 105.137253 -279.607494)
			(xy 105.102016 -279.558988) (xy 105.074798 -279.505569) (xy 105.056268 -279.448551) (xy 105.046884 -279.389337)
			(xy 105.046272 -279.35936) (xy 105.046272 -278.863552) (xy 105.046826 -278.83357) (xy 105.056203 -278.774345)
			(xy 105.074733 -278.717317) (xy 105.10196 -278.663892) (xy 105.137214 -278.615386) (xy 105.158032 -278.593804)
			(xy 106.976926 -276.77491) (xy 106.981916 -276.769412) (xy 106.988765 -276.756247) (xy 106.990388 -276.749002)
			(xy 106.991404 -276.73935) (xy 106.991404 -268.59738) (xy 106.991956 -268.567398) (xy 107.00133 -268.508171)
			(xy 107.019858 -268.451141) (xy 107.047085 -268.397714) (xy 107.082338 -268.349208) (xy 107.103164 -268.327632)
			(xy 109.0168 -266.413996) (xy 109.038415 -266.393219) (xy 109.086922 -266.357986) (xy 109.140341 -266.330772)
			(xy 109.197359 -266.312246) (xy 109.256572 -266.302863) (xy 109.286548 -266.302236) (xy 111.385604 -266.302236)
			(xy 111.395256 -266.30122) (xy 111.402501 -266.299594) (xy 111.415674 -266.292757) (xy 111.421164 -266.287758)
			(xy 113.84915 -263.859772) (xy 113.870765 -263.838993) (xy 113.919271 -263.803756) (xy 113.97269 -263.776537)
			(xy 114.029707 -263.758004) (xy 114.088921 -263.748615) (xy 114.118898 -263.748012) (xy 114.831114 -263.748012)
			(xy 114.858363 -263.748499) (xy 114.912306 -263.756257) (xy 114.964597 -263.771612) (xy 115.01417 -263.794253)
			(xy 115.060016 -263.823718) (xy 115.101202 -263.859408) (xy 115.13689 -263.900596) (xy 115.166354 -263.946443)
			(xy 115.188992 -263.996016) (xy 115.204346 -264.048307) (xy 115.212102 -264.102251) (xy 115.212102 -264.156749)
			(xy 115.204346 -264.210693) (xy 115.188992 -264.262984) (xy 115.166354 -264.312557) (xy 115.13689 -264.358404)
			(xy 115.101202 -264.399592) (xy 115.060016 -264.435282) (xy 115.01417 -264.464747) (xy 114.964597 -264.487388)
			(xy 114.912306 -264.502743) (xy 114.858363 -264.510501) (xy 114.831114 -264.511028) (xy 114.297968 -264.511028)
			(xy 114.291958 -264.511193) (xy 114.280274 -264.514015) (xy 114.274854 -264.516616) (xy 114.271381 -264.518458)
			(xy 114.265006 -264.523055) (xy 114.262154 -264.52576) (xy 111.834422 -266.953492) (xy 111.812807 -266.974271)
			(xy 111.764302 -267.009507) (xy 111.710883 -267.036726) (xy 111.653865 -267.055256) (xy 111.594651 -267.064642)
			(xy 111.564674 -267.065252) (xy 109.465618 -267.065252) (xy 109.459609 -267.065422) (xy 109.447929 -267.06825)
			(xy 109.442504 -267.07084) (xy 109.43903 -267.07268) (xy 109.432651 -267.077274) (xy 109.429804 -267.079984)
			(xy 107.769152 -268.740636) (xy 107.766447 -268.743488) (xy 107.761857 -268.749867) (xy 107.760008 -268.753336)
			(xy 107.757424 -268.758763) (xy 107.754598 -268.770442) (xy 107.75442 -268.77645) (xy 107.75442 -276.051264)
			(xy 109.061504 -276.051264) (xy 109.061948 -276.023893) (xy 109.069771 -275.969713) (xy 109.085265 -275.917209)
			(xy 109.108112 -275.867463) (xy 109.137841 -275.821497) (xy 109.155484 -275.800566) (xy 109.155738 -275.800312)
			(xy 109.16133 -275.793229) (xy 109.167572 -275.776309) (xy 109.16793 -275.767292) (xy 109.16793 -275.700236)
			(xy 109.167549 -275.691222) (xy 109.161317 -275.674305) (xy 109.155738 -275.667216) (xy 109.155484 -275.667216)
			(xy 109.155484 -275.666962) (xy 109.13781 -275.646057) (xy 109.10809 -275.600083) (xy 109.085249 -275.550332)
			(xy 109.069757 -275.497826) (xy 109.061933 -275.443645) (xy 109.061937 -275.388901) (xy 109.069769 -275.334721)
			(xy 109.085268 -275.282217) (xy 109.108116 -275.232469) (xy 109.137843 -275.1865) (xy 109.155484 -275.165566)
			(xy 109.155738 -275.165312) (xy 109.16133 -275.158229) (xy 109.167572 -275.141309) (xy 109.16793 -275.132292)
			(xy 109.16793 -275.065236) (xy 109.167549 -275.056222) (xy 109.161317 -275.039305) (xy 109.155738 -275.032216)
			(xy 109.155484 -275.032216) (xy 109.155484 -275.031962) (xy 109.137858 -275.011019) (xy 109.108145 -274.965049)
			(xy 109.085307 -274.915304) (xy 109.069812 -274.862806) (xy 109.06198 -274.808632) (xy 109.061504 -274.781264)
			(xy 109.061944 -274.754011) (xy 109.069706 -274.700061) (xy 109.085066 -274.647765) (xy 109.107713 -274.598187)
			(xy 109.137184 -274.552336) (xy 109.17288 -274.511146) (xy 109.214075 -274.475455) (xy 109.259929 -274.44599)
			(xy 109.30951 -274.42335) (xy 109.361808 -274.407996) (xy 109.415759 -274.400241) (xy 109.443012 -274.399756)
			(xy 109.470383 -274.400201) (xy 109.524564 -274.408022) (xy 109.577068 -274.423515) (xy 109.626814 -274.446362)
			(xy 109.67278 -274.476092) (xy 109.69371 -274.493736) (xy 109.693964 -274.49399) (xy 109.701058 -274.499567)
			(xy 109.717969 -274.50582) (xy 109.726984 -274.506182) (xy 109.79404 -274.506182) (xy 109.803059 -274.505848)
			(xy 109.819976 -274.499585) (xy 109.82706 -274.49399) (xy 109.82706 -274.493736) (xy 109.827314 -274.493736)
			(xy 109.848272 -274.476129) (xy 109.894237 -274.446411) (xy 109.943978 -274.423569) (xy 109.996473 -274.40807)
			(xy 110.050645 -274.400234) (xy 110.078012 -274.399756) (xy 110.105262 -274.400267) (xy 110.159207 -274.408024)
			(xy 110.211499 -274.423379) (xy 110.261074 -274.446018) (xy 110.306922 -274.475483) (xy 110.348112 -274.511171)
			(xy 110.383803 -274.552358) (xy 110.41327 -274.598205) (xy 110.435913 -274.647779) (xy 110.451271 -274.70007)
			(xy 110.459032 -274.754014) (xy 110.45952 -274.781264) (xy 110.459052 -274.808634) (xy 110.451238 -274.862814)
			(xy 110.43575 -274.915318) (xy 110.412908 -274.965065) (xy 110.383182 -275.011031) (xy 110.36554 -275.031962)
			(xy 110.365286 -275.032216) (xy 110.359685 -275.039293) (xy 110.353447 -275.056217) (xy 110.353094 -275.065236)
			(xy 110.353094 -275.132292) (xy 110.353456 -275.141308) (xy 110.3597 -275.158225) (xy 110.365286 -275.165312)
			(xy 110.36554 -275.165312) (xy 110.36554 -275.165566) (xy 110.383147 -275.186527) (xy 110.412876 -275.232489)
			(xy 110.435725 -275.28223) (xy 110.451226 -275.334728) (xy 110.459058 -275.388904) (xy 110.459062 -275.443642)
			(xy 110.451237 -275.497819) (xy 110.435744 -275.550319) (xy 110.412902 -275.600064) (xy 110.38318 -275.64603)
			(xy 110.36554 -275.666962) (xy 110.365286 -275.667216) (xy 110.359685 -275.674293) (xy 110.353447 -275.691217)
			(xy 110.353094 -275.700236) (xy 110.353094 -275.767292) (xy 110.353456 -275.776308) (xy 110.3597 -275.793225)
			(xy 110.365286 -275.800312) (xy 110.36554 -275.800312) (xy 110.36554 -275.800566) (xy 110.383147 -275.821527)
			(xy 110.412876 -275.867489) (xy 110.435725 -275.91723) (xy 110.451226 -275.969728) (xy 110.459058 -276.023904)
			(xy 110.459062 -276.078642) (xy 110.451237 -276.132819) (xy 110.435744 -276.185319) (xy 110.412902 -276.235064)
			(xy 110.38318 -276.28103) (xy 110.36554 -276.301962) (xy 110.365286 -276.302216) (xy 110.359685 -276.309293)
			(xy 110.353447 -276.326217) (xy 110.353094 -276.335236) (xy 110.353094 -276.402292) (xy 110.353456 -276.411308)
			(xy 110.3597 -276.428225) (xy 110.365286 -276.435312) (xy 110.36554 -276.435312) (xy 110.36554 -276.43582)
			(xy 110.38169 -276.454875) (xy 110.409357 -276.496465) (xy 110.431359 -276.54131) (xy 110.439708 -276.564852)
			(xy 110.443518 -276.576282) (xy 110.460028 -276.593046) (xy 110.547912 -276.622764) (xy 110.559214 -276.626032)
			(xy 110.582519 -276.622965) (xy 110.592616 -276.616922) (xy 110.59287 -276.616668) (xy 110.616626 -276.601325)
			(xy 110.667684 -276.577015) (xy 110.721771 -276.560506) (xy 110.777701 -276.552158) (xy 110.805976 -276.551644)
			(xy 110.833224 -276.5522) (xy 110.887167 -276.559952) (xy 110.939458 -276.575302) (xy 110.989031 -276.597937)
			(xy 111.03488 -276.627396) (xy 111.076069 -276.66308) (xy 111.111761 -276.704263) (xy 111.141229 -276.750105)
			(xy 111.163873 -276.799675) (xy 111.179232 -276.851962) (xy 111.186994 -276.905904) (xy 111.187484 -276.933152)
			(xy 111.187056 -276.959467) (xy 111.179814 -277.011598) (xy 111.165488 -277.062241) (xy 111.144348 -277.11044)
			(xy 111.116794 -277.155283) (xy 111.083349 -277.195921) (xy 111.064294 -277.214076) (xy 111.0569 -277.221604)
			(xy 111.048372 -277.240879) (xy 111.047784 -277.251414) (xy 111.047784 -277.32609) (xy 111.04831 -277.33664)
			(xy 111.056848 -277.355935) (xy 111.064294 -277.363428) (xy 111.083355 -277.381578) (xy 111.116812 -277.422209)
			(xy 111.14437 -277.46705) (xy 111.165508 -277.515252) (xy 111.179824 -277.565901) (xy 111.187047 -277.618036)
			(xy 111.187484 -277.644352) (xy 111.187 -277.671605) (xy 111.179249 -277.725556) (xy 111.163898 -277.777855)
			(xy 111.141259 -277.827437) (xy 111.111794 -277.873291) (xy 111.076102 -277.914485) (xy 111.03491 -277.950179)
			(xy 110.989058 -277.979648) (xy 110.939478 -278.002289) (xy 110.88718 -278.017644) (xy 110.833229 -278.025398)
			(xy 110.805976 -278.02586) (xy 110.779505 -278.025464) (xy 110.72707 -278.018167) (xy 110.676147 -278.003687)
			(xy 110.627717 -277.982304) (xy 110.582709 -277.954428) (xy 110.541989 -277.920596) (xy 110.506339 -277.881457)
			(xy 110.476445 -277.837763) (xy 110.452882 -277.790355) (xy 110.436101 -277.740144) (xy 110.430818 -277.714202)
			(xy 110.428532 -277.701756) (xy 110.413292 -277.682452) (xy 110.31347 -277.638002) (xy 110.288578 -277.63978)
			(xy 110.27791 -277.646384) (xy 110.255311 -277.659729) (xy 110.207243 -277.680797) (xy 110.156742 -277.695082)
			(xy 110.104761 -277.702314) (xy 110.07852 -277.702772) (xy 110.078012 -277.702772) (xy 110.050758 -277.702333)
			(xy 109.996804 -277.694577) (xy 109.944504 -277.679221) (xy 109.894921 -277.656577) (xy 109.849066 -277.627107)
			(xy 109.807872 -277.591411) (xy 109.772179 -277.550215) (xy 109.742711 -277.504358) (xy 109.720071 -277.454774)
			(xy 109.704718 -277.402472) (xy 109.696965 -277.348518) (xy 109.696504 -277.321264) (xy 109.696948 -277.293893)
			(xy 109.704771 -277.239713) (xy 109.720265 -277.187209) (xy 109.743112 -277.137463) (xy 109.772841 -277.091497)
			(xy 109.790484 -277.070566) (xy 109.790738 -277.070312) (xy 109.79633 -277.063229) (xy 109.802572 -277.046309)
			(xy 109.80293 -277.037292) (xy 109.80293 -276.970236) (xy 109.802549 -276.961222) (xy 109.796317 -276.944305)
			(xy 109.790738 -276.937216) (xy 109.790484 -276.937216) (xy 109.790484 -276.936962) (xy 109.772858 -276.916019)
			(xy 109.743145 -276.870049) (xy 109.720307 -276.820304) (xy 109.704812 -276.767806) (xy 109.69698 -276.713632)
			(xy 109.696504 -276.686264) (xy 109.697083 -276.656788) (xy 109.706142 -276.598536) (xy 109.724056 -276.542372)
			(xy 109.750396 -276.489632) (xy 109.784537 -276.441572) (xy 109.804708 -276.420072) (xy 109.811249 -276.412742)
			(xy 109.81869 -276.394578) (xy 109.819186 -276.384766) (xy 109.819186 -276.331426) (xy 109.81182 -276.324568)
			(xy 109.804477 -276.318045) (xy 109.786323 -276.310594) (xy 109.776514 -276.31009) (xy 109.74451 -276.31009)
			(xy 109.734698 -276.310593) (xy 109.716533 -276.318027) (xy 109.709204 -276.324568) (xy 109.687705 -276.344742)
			(xy 109.639645 -276.378886) (xy 109.586906 -276.405232) (xy 109.530741 -276.423153) (xy 109.472489 -276.432223)
			(xy 109.443012 -276.432772) (xy 109.415758 -276.432333) (xy 109.361804 -276.424577) (xy 109.309504 -276.409221)
			(xy 109.259921 -276.386577) (xy 109.214066 -276.357107) (xy 109.172872 -276.321411) (xy 109.137179 -276.280215)
			(xy 109.107711 -276.234358) (xy 109.085071 -276.184774) (xy 109.069718 -276.132472) (xy 109.061965 -276.078518)
			(xy 109.061504 -276.051264) (xy 107.75442 -276.051264) (xy 107.75442 -276.91842) (xy 107.753868 -276.948402)
			(xy 107.744495 -277.00763) (xy 107.725968 -277.064661) (xy 107.698742 -277.118089) (xy 107.66349 -277.166597)
			(xy 107.64266 -277.188168) (xy 105.82402 -279.006808) (xy 105.821315 -279.00966) (xy 105.816724 -279.016039)
			(xy 105.814876 -279.019508) (xy 105.81229 -279.024934) (xy 105.80946 -279.036614) (xy 105.809288 -279.042622)
			(xy 105.809288 -279.180544) (xy 105.81005 -279.189942) (xy 105.811524 -279.196423) (xy 105.817322 -279.208378)
			(xy 105.82148 -279.213564) (xy 105.875582 -279.26792) (xy 105.882188 -279.27362) (xy 105.898157 -279.280621)
			(xy 105.906824 -279.281636) (xy 106.35107 -279.281636) (xy 106.380987 -279.28224) (xy 106.440083 -279.291622)
			(xy 106.49699 -279.310113) (xy 106.550312 -279.337261) (xy 106.598744 -279.372399) (xy 106.62031 -279.393142)
			(xy 106.842814 -279.615646) (xy 106.849752 -279.622113) (xy 106.86707 -279.629812) (xy 106.886003 -279.630667)
			(xy 106.903944 -279.62456) (xy 106.911394 -279.618694) (xy 106.985562 -279.544526) (xy 106.987972 -279.541747)
			(xy 106.99205 -279.535626) (xy 106.99369 -279.532334) (xy 106.995927 -279.527219) (xy 106.998357 -279.516325)
			(xy 106.998516 -279.510744) (xy 106.998516 -278.650446) (xy 106.999126 -278.620531) (xy 107.008519 -278.561442)
			(xy 107.027019 -278.504543) (xy 107.054173 -278.451228) (xy 107.089315 -278.402805) (xy 107.110022 -278.381206)
			(xy 107.417616 -278.073612) (xy 107.439229 -278.05283) (xy 107.487733 -278.017585) (xy 107.541151 -277.990357)
			(xy 107.59817 -277.971818) (xy 107.657386 -277.962422) (xy 107.687364 -277.961852) (xy 108.485178 -277.961852)
			(xy 108.515159 -277.962408) (xy 108.574382 -277.971789) (xy 108.631408 -277.990322) (xy 108.684831 -278.017551)
			(xy 108.733334 -278.052805) (xy 108.754926 -278.073612) (xy 109.822488 -279.141428) (xy 109.828123 -279.146618)
			(xy 109.841682 -279.15373) (xy 109.849158 -279.155398) (xy 109.858302 -279.15616) (xy 111.750094 -279.15616)
			(xy 111.755676 -279.156014) (xy 111.766571 -279.153577) (xy 111.771684 -279.151334) (xy 111.774976 -279.149694)
			(xy 111.78109 -279.145608) (xy 111.783876 -279.143206) (xy 112.85347 -278.073612) (xy 112.875084 -278.052833)
			(xy 112.92359 -278.017595) (xy 112.977009 -277.990375) (xy 113.034027 -277.971843) (xy 113.093241 -277.962456)
			(xy 113.123218 -277.961852) (xy 113.797842 -277.961852) (xy 113.827824 -277.962405) (xy 113.88705 -277.971781)
			(xy 113.94408 -277.99031) (xy 113.997506 -278.017536) (xy 114.046014 -278.052787) (xy 114.06759 -278.073612)
			(xy 114.519456 -278.525478) (xy 117.572536 -278.525478) (xy 117.572536 -263.787636) (xy 117.573022 -263.760403)
			(xy 117.580773 -263.706491) (xy 117.596118 -263.654231) (xy 117.618744 -263.604687) (xy 117.648191 -263.558867)
			(xy 117.683858 -263.517704) (xy 117.725021 -263.482037) (xy 117.770841 -263.45259) (xy 117.820385 -263.429964)
			(xy 117.872645 -263.414619) (xy 117.926557 -263.406868) (xy 117.981023 -263.406868) (xy 118.034935 -263.414619)
			(xy 118.087195 -263.429964) (xy 118.136739 -263.45259) (xy 118.182559 -263.482037) (xy 118.223722 -263.517704)
			(xy 118.259389 -263.558867) (xy 118.288836 -263.604687) (xy 118.311462 -263.654231) (xy 118.326807 -263.706491)
			(xy 118.334558 -263.760403) (xy 118.335044 -263.787636) (xy 118.335044 -263.82091) (xy 119.443752 -263.82091)
			(xy 119.447823 -263.765288) (xy 119.459949 -263.710851) (xy 119.479872 -263.65876) (xy 119.507168 -263.610125)
			(xy 119.541254 -263.565982) (xy 119.581403 -263.527273) (xy 119.626761 -263.494822) (xy 119.676361 -263.469321)
			(xy 119.729145 -263.451314) (xy 119.783988 -263.441184) (xy 119.839722 -263.439147) (xy 119.895159 -263.445247)
			(xy 119.949116 -263.459353) (xy 120.000445 -263.481165) (xy 120.048051 -263.510219) (xy 120.090919 -263.545894)
			(xy 120.128136 -263.587431) (xy 120.158909 -263.633944) (xy 120.182581 -263.684441) (xy 120.198649 -263.737848)
			(xy 120.206769 -263.793024) (xy 120.207278 -263.82091) (xy 120.206769 -263.848796) (xy 120.198649 -263.903972)
			(xy 120.182581 -263.957379) (xy 120.158909 -264.007876) (xy 120.128136 -264.054389) (xy 120.090919 -264.095926)
			(xy 120.050552 -264.12952) (xy 122.980194 -264.12952) (xy 122.984265 -264.073898) (xy 122.996391 -264.019461)
			(xy 123.016314 -263.96737) (xy 123.04361 -263.918735) (xy 123.077696 -263.874592) (xy 123.117845 -263.835883)
			(xy 123.163203 -263.803432) (xy 123.212803 -263.777931) (xy 123.265587 -263.759924) (xy 123.32043 -263.749794)
			(xy 123.376164 -263.747757) (xy 123.431601 -263.753857) (xy 123.485558 -263.767963) (xy 123.536887 -263.789775)
			(xy 123.584493 -263.818829) (xy 123.627361 -263.854504) (xy 123.664578 -263.896041) (xy 123.695351 -263.942554)
			(xy 123.719023 -263.993051) (xy 123.735091 -264.046458) (xy 123.743211 -264.101634) (xy 123.74372 -264.12952)
			(xy 123.743211 -264.157406) (xy 123.735091 -264.212582) (xy 123.719023 -264.265989) (xy 123.695351 -264.316486)
			(xy 123.664578 -264.362999) (xy 123.627361 -264.404536) (xy 123.584493 -264.440211) (xy 123.536887 -264.469265)
			(xy 123.485558 -264.491077) (xy 123.431601 -264.505183) (xy 123.376164 -264.511283) (xy 123.32043 -264.509246)
			(xy 123.265587 -264.499116) (xy 123.212803 -264.481109) (xy 123.163203 -264.455608) (xy 123.117845 -264.423157)
			(xy 123.077696 -264.384448) (xy 123.04361 -264.340305) (xy 123.016314 -264.29167) (xy 122.996391 -264.239579)
			(xy 122.984265 -264.185142) (xy 122.980194 -264.12952) (xy 120.050552 -264.12952) (xy 120.048051 -264.131601)
			(xy 120.000445 -264.160655) (xy 119.949116 -264.182467) (xy 119.895159 -264.196573) (xy 119.839722 -264.202673)
			(xy 119.783988 -264.200636) (xy 119.729145 -264.190506) (xy 119.676361 -264.172499) (xy 119.626761 -264.146998)
			(xy 119.581403 -264.114547) (xy 119.541254 -264.075838) (xy 119.507168 -264.031695) (xy 119.479872 -263.98306)
			(xy 119.459949 -263.930969) (xy 119.447823 -263.876532) (xy 119.443752 -263.82091) (xy 118.335044 -263.82091)
			(xy 118.335044 -264.93597) (xy 120.417334 -264.93597) (xy 120.421405 -264.880348) (xy 120.433531 -264.825911)
			(xy 120.453454 -264.77382) (xy 120.48075 -264.725185) (xy 120.514836 -264.681042) (xy 120.554985 -264.642333)
			(xy 120.600343 -264.609882) (xy 120.649943 -264.584381) (xy 120.702727 -264.566374) (xy 120.75757 -264.556244)
			(xy 120.813304 -264.554207) (xy 120.868741 -264.560307) (xy 120.922698 -264.574413) (xy 120.974027 -264.596225)
			(xy 121.021633 -264.625279) (xy 121.064501 -264.660954) (xy 121.101718 -264.702491) (xy 121.132491 -264.749004)
			(xy 121.156163 -264.799501) (xy 121.172231 -264.852908) (xy 121.180351 -264.908084) (xy 121.18086 -264.93597)
			(xy 121.180351 -264.963856) (xy 121.172231 -265.019032) (xy 121.156163 -265.072439) (xy 121.132491 -265.122936)
			(xy 121.101718 -265.169449) (xy 121.064501 -265.210986) (xy 121.021633 -265.246661) (xy 120.974027 -265.275715)
			(xy 120.922698 -265.297527) (xy 120.868741 -265.311633) (xy 120.813304 -265.317733) (xy 120.75757 -265.315696)
			(xy 120.702727 -265.305566) (xy 120.649943 -265.287559) (xy 120.600343 -265.262058) (xy 120.554985 -265.229607)
			(xy 120.514836 -265.190898) (xy 120.48075 -265.146755) (xy 120.453454 -265.09812) (xy 120.433531 -265.046029)
			(xy 120.421405 -264.991592) (xy 120.417334 -264.93597) (xy 118.335044 -264.93597) (xy 118.335044 -265.834114)
			(xy 119.246394 -265.834114) (xy 119.250465 -265.778492) (xy 119.262591 -265.724055) (xy 119.282514 -265.671964)
			(xy 119.30981 -265.623329) (xy 119.343896 -265.579186) (xy 119.384045 -265.540477) (xy 119.429403 -265.508026)
			(xy 119.479003 -265.482525) (xy 119.531787 -265.464518) (xy 119.58663 -265.454388) (xy 119.642364 -265.452351)
			(xy 119.697801 -265.458451) (xy 119.751758 -265.472557) (xy 119.803087 -265.494369) (xy 119.850693 -265.523423)
			(xy 119.893561 -265.559098) (xy 119.930778 -265.600635) (xy 119.961551 -265.647148) (xy 119.985223 -265.697645)
			(xy 120.001291 -265.751052) (xy 120.009411 -265.806228) (xy 120.00992 -265.834114) (xy 120.009411 -265.862)
			(xy 120.001291 -265.917176) (xy 119.985223 -265.970583) (xy 119.961551 -266.02108) (xy 119.930778 -266.067593)
			(xy 119.893561 -266.10913) (xy 119.850693 -266.144805) (xy 119.803087 -266.173859) (xy 119.751758 -266.195671)
			(xy 119.697801 -266.209777) (xy 119.642364 -266.215877) (xy 119.58663 -266.21384) (xy 119.531787 -266.20371)
			(xy 119.479003 -266.185703) (xy 119.429403 -266.160202) (xy 119.384045 -266.127751) (xy 119.343896 -266.089042)
			(xy 119.30981 -266.044899) (xy 119.282514 -265.996264) (xy 119.262591 -265.944173) (xy 119.250465 -265.889736)
			(xy 119.246394 -265.834114) (xy 118.335044 -265.834114) (xy 118.335044 -269.417038) (xy 124.88545 -269.417038)
			(xy 124.885949 -269.388298) (xy 124.89458 -269.33147) (xy 124.911636 -269.27658) (xy 124.936733 -269.224869)
			(xy 124.969302 -269.177507) (xy 124.988574 -269.15618) (xy 124.995178 -269.149322) (xy 125.00229 -269.131288)
			(xy 125.00229 -269.042388) (xy 124.995178 -269.024354) (xy 124.988574 -269.017496) (xy 124.969327 -268.996148)
			(xy 124.936756 -268.948792) (xy 124.911659 -268.897086) (xy 124.894602 -268.8422) (xy 124.885974 -268.785376)
			(xy 124.88545 -268.756638) (xy 124.886013 -268.72939) (xy 124.893764 -268.675447) (xy 124.909112 -268.623156)
			(xy 124.931746 -268.573582) (xy 124.961204 -268.527733) (xy 124.996887 -268.486544) (xy 125.038069 -268.450852)
			(xy 125.083912 -268.421384) (xy 125.133481 -268.39874) (xy 125.185769 -268.383381) (xy 125.23971 -268.375619)
			(xy 125.266958 -268.37513) (xy 125.294328 -268.375613) (xy 125.348506 -268.383426) (xy 125.40101 -268.398911)
			(xy 125.450757 -268.421749) (xy 125.496724 -268.45147) (xy 125.517656 -268.46911) (xy 125.51791 -268.469364)
			(xy 125.524984 -268.474968) (xy 125.541911 -268.481203) (xy 125.55093 -268.481556) (xy 125.617986 -268.481556)
			(xy 125.627003 -268.481202) (xy 125.643921 -268.474953) (xy 125.651006 -268.469364) (xy 125.651006 -268.46911)
			(xy 125.65126 -268.46911) (xy 125.672193 -268.451469) (xy 125.718161 -268.421745) (xy 125.767907 -268.398899)
			(xy 125.820409 -268.383403) (xy 125.874587 -268.375574) (xy 125.929329 -268.375574) (xy 125.983507 -268.383403)
			(xy 126.036009 -268.398899) (xy 126.085755 -268.421745) (xy 126.131723 -268.451469) (xy 126.152656 -268.46911)
			(xy 126.15291 -268.469364) (xy 126.159984 -268.474968) (xy 126.176911 -268.481203) (xy 126.18593 -268.481556)
			(xy 126.252986 -268.481556) (xy 126.262003 -268.481202) (xy 126.278921 -268.474953) (xy 126.286006 -268.469364)
			(xy 126.286006 -268.46911) (xy 126.28626 -268.46911) (xy 126.307193 -268.451469) (xy 126.353161 -268.421745)
			(xy 126.402907 -268.398899) (xy 126.455409 -268.383403) (xy 126.509587 -268.375574) (xy 126.564329 -268.375574)
			(xy 126.618507 -268.383403) (xy 126.671009 -268.398899) (xy 126.720755 -268.421745) (xy 126.766723 -268.451469)
			(xy 126.787656 -268.46911) (xy 126.78791 -268.469364) (xy 126.794984 -268.474968) (xy 126.811911 -268.481203)
			(xy 126.82093 -268.481556) (xy 126.887986 -268.481556) (xy 126.897003 -268.481202) (xy 126.913921 -268.474953)
			(xy 126.921006 -268.469364) (xy 126.921006 -268.46911) (xy 126.92126 -268.46911) (xy 126.942193 -268.451469)
			(xy 126.988161 -268.421745) (xy 127.037907 -268.398899) (xy 127.090409 -268.383403) (xy 127.144587 -268.375574)
			(xy 127.199329 -268.375574) (xy 127.253507 -268.383403) (xy 127.306009 -268.398899) (xy 127.355755 -268.421745)
			(xy 127.401723 -268.451469) (xy 127.422656 -268.46911) (xy 127.42291 -268.469364) (xy 127.429984 -268.474968)
			(xy 127.446911 -268.481203) (xy 127.45593 -268.481556) (xy 127.522986 -268.481556) (xy 127.532003 -268.481202)
			(xy 127.548921 -268.474953) (xy 127.556006 -268.469364) (xy 127.556006 -268.46911) (xy 127.55626 -268.46911)
			(xy 127.577198 -268.451478) (xy 127.623169 -268.421765) (xy 127.672915 -268.398927) (xy 127.725414 -268.383434)
			(xy 127.779589 -268.375605) (xy 127.806958 -268.37513) (xy 127.834212 -268.375594) (xy 127.888164 -268.383347)
			(xy 127.940465 -268.398699) (xy 127.990047 -268.42134) (xy 128.035902 -268.450807) (xy 128.077096 -268.486501)
			(xy 128.112791 -268.527695) (xy 128.142258 -268.573549) (xy 128.164899 -268.623132) (xy 128.180252 -268.675432)
			(xy 128.188005 -268.729384) (xy 128.188466 -268.756638) (xy 128.187948 -268.785377) (xy 128.179321 -268.842204)
			(xy 128.162269 -268.897094) (xy 128.137177 -268.948805) (xy 128.104612 -268.996168) (xy 128.085342 -269.017496)
			(xy 128.078738 -269.024354) (xy 128.071626 -269.042388) (xy 128.071626 -269.131288) (xy 128.078738 -269.149322)
			(xy 128.085342 -269.15618) (xy 128.104627 -269.177494) (xy 128.137192 -269.224859) (xy 128.162282 -269.276574)
			(xy 128.17933 -269.331468) (xy 128.187948 -269.388298) (xy 128.188466 -269.417038) (xy 128.18808 -269.444294)
			(xy 128.180317 -269.49825) (xy 128.164954 -269.550552) (xy 128.142304 -269.600135) (xy 128.112828 -269.64599)
			(xy 128.077126 -269.687183) (xy 128.035926 -269.722876) (xy 127.990064 -269.752343) (xy 127.940477 -269.774982)
			(xy 127.888171 -269.790334) (xy 127.834214 -269.798086) (xy 127.806958 -269.798546) (xy 127.779588 -269.798059)
			(xy 127.72541 -269.790248) (xy 127.672906 -269.774765) (xy 127.623159 -269.751927) (xy 127.577192 -269.722206)
			(xy 127.55626 -269.704566) (xy 127.556006 -269.704312) (xy 127.548921 -269.698723) (xy 127.532003 -269.692477)
			(xy 127.522986 -269.69212) (xy 127.45593 -269.69212) (xy 127.446914 -269.692487) (xy 127.429997 -269.698727)
			(xy 127.42291 -269.704312) (xy 127.422656 -269.704566) (xy 127.401723 -269.722207) (xy 127.355755 -269.751931)
			(xy 127.306009 -269.774777) (xy 127.253507 -269.790273) (xy 127.199329 -269.798102) (xy 127.144587 -269.798102)
			(xy 127.090409 -269.790273) (xy 127.037907 -269.774777) (xy 126.988161 -269.751931) (xy 126.942193 -269.722207)
			(xy 126.92126 -269.704566) (xy 126.921006 -269.704312) (xy 126.913921 -269.698723) (xy 126.897003 -269.692477)
			(xy 126.887986 -269.69212) (xy 126.82093 -269.69212) (xy 126.811914 -269.692487) (xy 126.794997 -269.698727)
			(xy 126.78791 -269.704312) (xy 126.78791 -269.704566) (xy 126.787656 -269.704566) (xy 126.766723 -269.722207)
			(xy 126.720755 -269.751931) (xy 126.671009 -269.774777) (xy 126.618507 -269.790273) (xy 126.564329 -269.798102)
			(xy 126.509587 -269.798102) (xy 126.455409 -269.790273) (xy 126.402907 -269.774777) (xy 126.353161 -269.751931)
			(xy 126.307193 -269.722207) (xy 126.28626 -269.704566) (xy 126.286006 -269.704312) (xy 126.278921 -269.698723)
			(xy 126.262003 -269.692477) (xy 126.252986 -269.69212) (xy 126.18593 -269.69212) (xy 126.176914 -269.692487)
			(xy 126.159997 -269.698727) (xy 126.15291 -269.704312) (xy 126.15291 -269.704566) (xy 126.152656 -269.704566)
			(xy 126.131723 -269.722207) (xy 126.085755 -269.751931) (xy 126.036009 -269.774777) (xy 125.983507 -269.790273)
			(xy 125.929329 -269.798102) (xy 125.874587 -269.798102) (xy 125.820409 -269.790273) (xy 125.767907 -269.774777)
			(xy 125.718161 -269.751931) (xy 125.672193 -269.722207) (xy 125.65126 -269.704566) (xy 125.651006 -269.704312)
			(xy 125.643921 -269.698723) (xy 125.627003 -269.692477) (xy 125.617986 -269.69212) (xy 125.55093 -269.69212)
			(xy 125.541914 -269.692487) (xy 125.524997 -269.698727) (xy 125.51791 -269.704312) (xy 125.51791 -269.704566)
			(xy 125.517656 -269.704566) (xy 125.496709 -269.722187) (xy 125.450741 -269.751903) (xy 125.400997 -269.774743)
			(xy 125.3485 -269.790238) (xy 125.294326 -269.79807) (xy 125.266958 -269.798546) (xy 125.239707 -269.798061)
			(xy 125.185762 -269.7903) (xy 125.133469 -269.774942) (xy 125.083894 -269.752298) (xy 125.038046 -269.722831)
			(xy 124.996857 -269.68714) (xy 124.961166 -269.645951) (xy 124.9317 -269.600102) (xy 124.909057 -269.550527)
			(xy 124.893699 -269.498234) (xy 124.885938 -269.444289) (xy 124.88545 -269.417038) (xy 118.335044 -269.417038)
			(xy 118.335044 -277.634192) (xy 120.08485 -277.634192) (xy 120.085348 -277.606122) (xy 120.093588 -277.550589)
			(xy 120.109875 -277.496862) (xy 120.133856 -277.446101) (xy 120.165015 -277.3994) (xy 120.202679 -277.357769)
			(xy 120.224042 -277.339552) (xy 120.232678 -277.33244) (xy 120.24233 -277.312628) (xy 120.24487 -277.213568)
			(xy 120.23598 -277.193248) (xy 120.227852 -277.185882) (xy 120.208519 -277.167737) (xy 120.174597 -277.126988)
			(xy 120.146643 -277.081936) (xy 120.125194 -277.033447) (xy 120.110665 -276.982456) (xy 120.103334 -276.929944)
			(xy 120.102884 -276.903434) (xy 120.103387 -276.876182) (xy 120.111139 -276.822233) (xy 120.12649 -276.769937)
			(xy 120.149128 -276.720357) (xy 120.178592 -276.674504) (xy 120.214282 -276.633311) (xy 120.255471 -276.597617)
			(xy 120.30132 -276.568148) (xy 120.350897 -276.545505) (xy 120.403192 -276.530148) (xy 120.45714 -276.52239)
			(xy 120.484392 -276.521926) (xy 120.510644 -276.52235) (xy 120.562654 -276.529537) (xy 120.613186 -276.543791)
			(xy 120.661285 -276.564842) (xy 120.706042 -276.592292) (xy 120.74661 -276.625622) (xy 120.782223 -276.664202)
			(xy 120.797574 -276.685502) (xy 120.802902 -276.692457) (xy 120.817178 -276.702589) (xy 120.834029 -276.707332)
			(xy 120.842786 -276.707092) (xy 120.94337 -276.69998) (xy 120.965468 -276.685248) (xy 120.971564 -276.67331)
			(xy 120.983825 -276.650017) (xy 121.013792 -276.606742) (xy 121.049423 -276.567996) (xy 121.09004 -276.534514)
			(xy 121.134873 -276.506933) (xy 121.183072 -276.485774) (xy 121.233721 -276.47144) (xy 121.285859 -276.464203)
			(xy 121.312178 -276.46376) (xy 121.345706 -276.465284) (xy 121.355779 -276.465774) (xy 121.374985 -276.459662)
			(xy 121.390363 -276.446633) (xy 121.399547 -276.428692) (xy 121.401125 -276.408599) (xy 121.394855 -276.389444)
			(xy 121.381699 -276.374175) (xy 121.372884 -276.369272) (xy 121.351374 -276.358095) (xy 121.311121 -276.331087)
			(xy 121.29262 -276.315424) (xy 121.292366 -276.31517) (xy 121.285267 -276.309602) (xy 121.26836 -276.303345)
			(xy 121.259346 -276.302978) (xy 121.19229 -276.302978) (xy 121.183273 -276.303335) (xy 121.166357 -276.309583)
			(xy 121.15927 -276.31517) (xy 121.15927 -276.315424) (xy 121.159016 -276.315424) (xy 121.138092 -276.333073)
			(xy 121.092116 -276.362782) (xy 121.042367 -276.385616) (xy 120.989865 -276.401105) (xy 120.935688 -276.408931)
			(xy 120.908318 -276.409404) (xy 120.881065 -276.408928) (xy 120.827115 -276.401173) (xy 120.774817 -276.385819)
			(xy 120.725237 -276.363179) (xy 120.679383 -276.333712) (xy 120.63819 -276.29802) (xy 120.602496 -276.256828)
			(xy 120.573028 -276.210976) (xy 120.550386 -276.161396) (xy 120.53503 -276.109099) (xy 120.527273 -276.055149)
			(xy 120.52681 -276.027896) (xy 120.527271 -276.000526) (xy 120.53509 -275.946346) (xy 120.55058 -275.893843)
			(xy 120.573423 -275.844096) (xy 120.603148 -275.79813) (xy 120.62079 -275.777198) (xy 120.621044 -275.776944)
			(xy 120.626624 -275.769853) (xy 120.632873 -275.752939) (xy 120.633236 -275.743924) (xy 120.633236 -275.676868)
			(xy 120.632887 -275.667851) (xy 120.626633 -275.650934) (xy 120.621044 -275.643848) (xy 120.62079 -275.643848)
			(xy 120.62079 -275.643594) (xy 120.603147 -275.622664) (xy 120.573425 -275.576695) (xy 120.550582 -275.526948)
			(xy 120.535088 -275.474446) (xy 120.52726 -275.420267) (xy 120.527261 -275.365527) (xy 120.535089 -275.311349)
			(xy 120.550584 -275.258847) (xy 120.573428 -275.2091) (xy 120.603151 -275.163131) (xy 120.62079 -275.142198)
			(xy 120.621044 -275.141944) (xy 120.626624 -275.134853) (xy 120.632873 -275.117939) (xy 120.633236 -275.108924)
			(xy 120.633236 -275.041868) (xy 120.632887 -275.032851) (xy 120.626633 -275.015934) (xy 120.621044 -275.008848)
			(xy 120.62079 -275.008848) (xy 120.62079 -275.008594) (xy 120.603133 -274.987676) (xy 120.573424 -274.941699)
			(xy 120.550592 -274.891948) (xy 120.535105 -274.839444) (xy 120.527282 -274.785266) (xy 120.52681 -274.757896)
			(xy 120.527252 -274.730642) (xy 120.53501 -274.67669) (xy 120.550367 -274.62439) (xy 120.573011 -274.574809)
			(xy 120.602481 -274.528955) (xy 120.638177 -274.487762) (xy 120.679373 -274.452068) (xy 120.725228 -274.422601)
			(xy 120.774811 -274.399959) (xy 120.827111 -274.384605) (xy 120.881064 -274.37685) (xy 120.908318 -274.376388)
			(xy 120.935688 -274.376846) (xy 120.989868 -274.384667) (xy 121.042371 -274.400158) (xy 121.092118 -274.423001)
			(xy 121.138084 -274.452726) (xy 121.159016 -274.470368) (xy 121.15927 -274.470622) (xy 121.166359 -274.476205)
			(xy 121.183274 -274.482453) (xy 121.19229 -274.482814) (xy 121.259346 -274.482814) (xy 121.26836 -274.482428)
			(xy 121.285277 -274.4762) (xy 121.292366 -274.470622) (xy 121.292366 -274.470368) (xy 121.29262 -274.470368)
			(xy 121.313567 -274.452748) (xy 121.359536 -274.423034) (xy 121.40928 -274.400195) (xy 121.461777 -274.3847)
			(xy 121.51595 -274.376865) (xy 121.543318 -274.376388) (xy 121.57057 -274.376861) (xy 121.624517 -274.38462)
			(xy 121.676812 -274.399977) (xy 121.726389 -274.42262) (xy 121.772239 -274.452088) (xy 121.813429 -274.487781)
			(xy 121.849121 -274.528972) (xy 121.878587 -274.574823) (xy 121.901228 -274.624401) (xy 121.916583 -274.676696)
			(xy 121.92434 -274.730644) (xy 121.924826 -274.757896) (xy 121.924376 -274.785267) (xy 121.916557 -274.839447)
			(xy 121.901065 -274.891951) (xy 121.878219 -274.941698) (xy 121.84849 -274.987664) (xy 121.830846 -275.008594)
			(xy 121.830592 -275.008848) (xy 121.82502 -275.015945) (xy 121.818765 -275.032854) (xy 121.8184 -275.041868)
			(xy 121.8184 -275.108924) (xy 121.818746 -275.117942) (xy 121.825001 -275.134859) (xy 121.830592 -275.141944)
			(xy 121.830846 -275.141944) (xy 121.830846 -275.142198) (xy 121.848484 -275.163133) (xy 121.878211 -275.2091)
			(xy 121.901058 -275.258846) (xy 121.916556 -275.311348) (xy 121.924385 -275.365526) (xy 121.924386 -275.420268)
			(xy 121.916557 -275.474447) (xy 121.90106 -275.526949) (xy 121.878214 -275.576695) (xy 121.848488 -275.622662)
			(xy 121.830846 -275.643594) (xy 121.830592 -275.643848) (xy 121.82502 -275.650945) (xy 121.818765 -275.667854)
			(xy 121.8184 -275.676868) (xy 121.8184 -275.743924) (xy 121.818746 -275.752942) (xy 121.825001 -275.769859)
			(xy 121.830592 -275.776944) (xy 121.830846 -275.776944) (xy 121.830846 -275.777198) (xy 121.848489 -275.798127)
			(xy 121.878202 -275.8441) (xy 121.901038 -275.893848) (xy 121.916528 -275.94635) (xy 121.924354 -276.000526)
			(xy 121.924826 -276.027896) (xy 121.924546 -276.046184) (xy 124.460254 -276.046184) (xy 124.460698 -276.018813)
			(xy 124.468519 -275.964632) (xy 124.484012 -275.912128) (xy 124.506859 -275.862382) (xy 124.53659 -275.816416)
			(xy 124.554234 -275.795486) (xy 124.554488 -275.795232) (xy 124.560066 -275.788139) (xy 124.566318 -275.771227)
			(xy 124.56668 -275.762212) (xy 124.56668 -275.695156) (xy 124.5663 -275.686141) (xy 124.560069 -275.669224)
			(xy 124.554488 -275.662136) (xy 124.554234 -275.662136) (xy 124.554234 -275.661882) (xy 124.536625 -275.640925)
			(xy 124.506908 -275.59496) (xy 124.484065 -275.545219) (xy 124.468567 -275.492723) (xy 124.460732 -275.438552)
			(xy 124.460254 -275.411184) (xy 124.460763 -275.383934) (xy 124.46852 -275.329989) (xy 124.483876 -275.277697)
			(xy 124.506516 -275.228122) (xy 124.53598 -275.182274) (xy 124.571669 -275.141085) (xy 124.612856 -275.105394)
			(xy 124.658703 -275.075927) (xy 124.708277 -275.053283) (xy 124.760568 -275.037925) (xy 124.814512 -275.030164)
			(xy 124.841762 -275.029676) (xy 124.869132 -275.030146) (xy 124.923312 -275.03796) (xy 124.975816 -275.053447)
			(xy 125.025563 -275.076288) (xy 125.071529 -275.106014) (xy 125.09246 -275.123656) (xy 125.092714 -275.12391)
			(xy 125.099792 -275.12951) (xy 125.116715 -275.135748) (xy 125.125734 -275.136102) (xy 125.19279 -275.136102)
			(xy 125.201806 -275.13574) (xy 125.218723 -275.129496) (xy 125.22581 -275.12391) (xy 125.22581 -275.123656)
			(xy 125.226064 -275.123656) (xy 125.246997 -275.106015) (xy 125.292965 -275.076291) (xy 125.342711 -275.053445)
			(xy 125.395213 -275.037949) (xy 125.449391 -275.03012) (xy 125.504133 -275.03012) (xy 125.558311 -275.037949)
			(xy 125.610813 -275.053445) (xy 125.660559 -275.076291) (xy 125.706527 -275.106015) (xy 125.72746 -275.123656)
			(xy 125.727714 -275.12391) (xy 125.734792 -275.12951) (xy 125.751715 -275.135748) (xy 125.760734 -275.136102)
			(xy 125.82779 -275.136102) (xy 125.836806 -275.13574) (xy 125.853723 -275.129496) (xy 125.86081 -275.12391)
			(xy 125.86081 -275.123656) (xy 125.861064 -275.123656) (xy 125.881997 -275.106015) (xy 125.927965 -275.076291)
			(xy 125.977711 -275.053445) (xy 126.030213 -275.037949) (xy 126.084391 -275.03012) (xy 126.139133 -275.03012)
			(xy 126.193311 -275.037949) (xy 126.245813 -275.053445) (xy 126.295559 -275.076291) (xy 126.341527 -275.106015)
			(xy 126.36246 -275.123656) (xy 126.362714 -275.12391) (xy 126.369792 -275.12951) (xy 126.386715 -275.135748)
			(xy 126.395734 -275.136102) (xy 126.46279 -275.136102) (xy 126.471806 -275.13574) (xy 126.488723 -275.129496)
			(xy 126.49581 -275.12391) (xy 126.49581 -275.123656) (xy 126.496064 -275.123656) (xy 126.516997 -275.106015)
			(xy 126.562965 -275.076291) (xy 126.612711 -275.053445) (xy 126.665213 -275.037949) (xy 126.719391 -275.03012)
			(xy 126.774133 -275.03012) (xy 126.828311 -275.037949) (xy 126.880813 -275.053445) (xy 126.930559 -275.076291)
			(xy 126.976527 -275.106015) (xy 126.99746 -275.123656) (xy 126.997714 -275.12391) (xy 127.004792 -275.12951)
			(xy 127.021715 -275.135748) (xy 127.030734 -275.136102) (xy 127.09779 -275.136102) (xy 127.106806 -275.13574)
			(xy 127.123723 -275.129496) (xy 127.13081 -275.12391) (xy 127.13081 -275.123656) (xy 127.131064 -275.123656)
			(xy 127.151993 -275.106013) (xy 127.197967 -275.076303) (xy 127.247716 -275.053469) (xy 127.300217 -275.037978)
			(xy 127.354393 -275.03015) (xy 127.381762 -275.029676) (xy 127.409013 -275.030191) (xy 127.462961 -275.037942)
			(xy 127.515257 -275.053292) (xy 127.564836 -275.075929) (xy 127.610689 -275.105392) (xy 127.651882 -275.14108)
			(xy 127.687576 -275.182268) (xy 127.717045 -275.228116) (xy 127.739689 -275.277692) (xy 127.755047 -275.329986)
			(xy 127.762806 -275.383933) (xy 127.76327 -275.411184) (xy 127.762802 -275.438554) (xy 127.754986 -275.492734)
			(xy 127.739497 -275.545237) (xy 127.716656 -275.594984) (xy 127.686931 -275.640951) (xy 127.66929 -275.661882)
			(xy 127.669036 -275.662136) (xy 127.663463 -275.669231) (xy 127.65721 -275.686142) (xy 127.656844 -275.695156)
			(xy 127.656844 -275.762212) (xy 127.657186 -275.771231) (xy 127.663443 -275.788148) (xy 127.669036 -275.795232)
			(xy 127.66929 -275.795232) (xy 127.66929 -275.795486) (xy 127.686934 -275.816414) (xy 127.716646 -275.862388)
			(xy 127.739481 -275.912136) (xy 127.754971 -275.964638) (xy 127.762797 -276.018815) (xy 127.76327 -276.046184)
			(xy 127.76283 -276.073438) (xy 127.755074 -276.127392) (xy 127.739718 -276.179693) (xy 127.717075 -276.229275)
			(xy 127.687605 -276.27513) (xy 127.651908 -276.316324) (xy 127.610713 -276.352018) (xy 127.564856 -276.381485)
			(xy 127.515272 -276.404126) (xy 127.46297 -276.419479) (xy 127.409016 -276.427231) (xy 127.381762 -276.427692)
			(xy 127.354393 -276.427192) (xy 127.300215 -276.419382) (xy 127.247712 -276.403901) (xy 127.197965 -276.381067)
			(xy 127.151997 -276.35135) (xy 127.131064 -276.333712) (xy 127.13081 -276.333458) (xy 127.123728 -276.327864)
			(xy 127.106808 -276.321623) (xy 127.09779 -276.321266) (xy 127.030734 -276.321266) (xy 127.02172 -276.321647)
			(xy 127.004803 -276.327879) (xy 126.997714 -276.333458) (xy 126.99746 -276.333712) (xy 126.976527 -276.351353)
			(xy 126.930559 -276.381077) (xy 126.880813 -276.403923) (xy 126.828311 -276.419419) (xy 126.774133 -276.427248)
			(xy 126.719391 -276.427248) (xy 126.665213 -276.419419) (xy 126.612711 -276.403923) (xy 126.562965 -276.381077)
			(xy 126.516997 -276.351353) (xy 126.496064 -276.333712) (xy 126.49581 -276.333458) (xy 126.488728 -276.327864)
			(xy 126.471808 -276.321623) (xy 126.46279 -276.321266) (xy 126.395734 -276.321266) (xy 126.38672 -276.321647)
			(xy 126.369803 -276.327879) (xy 126.362714 -276.333458) (xy 126.362714 -276.333712) (xy 126.36246 -276.333712)
			(xy 126.341527 -276.351353) (xy 126.295559 -276.381077) (xy 126.245813 -276.403923) (xy 126.193311 -276.419419)
			(xy 126.139133 -276.427248) (xy 126.084391 -276.427248) (xy 126.030213 -276.419419) (xy 125.977711 -276.403923)
			(xy 125.927965 -276.381077) (xy 125.881997 -276.351353) (xy 125.861064 -276.333712) (xy 125.86081 -276.333458)
			(xy 125.853728 -276.327864) (xy 125.836808 -276.321623) (xy 125.82779 -276.321266) (xy 125.760734 -276.321266)
			(xy 125.75172 -276.321647) (xy 125.734803 -276.327879) (xy 125.727714 -276.333458) (xy 125.727714 -276.333712)
			(xy 125.72746 -276.333712) (xy 125.706527 -276.351353) (xy 125.660559 -276.381077) (xy 125.610813 -276.403923)
			(xy 125.558311 -276.419419) (xy 125.504133 -276.427248) (xy 125.449391 -276.427248) (xy 125.395213 -276.419419)
			(xy 125.342711 -276.403923) (xy 125.292965 -276.381077) (xy 125.246997 -276.351353) (xy 125.226064 -276.333712)
			(xy 125.22581 -276.333458) (xy 125.218728 -276.327864) (xy 125.201808 -276.321623) (xy 125.19279 -276.321266)
			(xy 125.125734 -276.321266) (xy 125.11672 -276.321647) (xy 125.099803 -276.327879) (xy 125.092714 -276.333458)
			(xy 125.092714 -276.333712) (xy 125.09246 -276.333712) (xy 125.071518 -276.351338) (xy 125.025547 -276.381052)
			(xy 124.975803 -276.40389) (xy 124.923304 -276.419384) (xy 124.86913 -276.427216) (xy 124.841762 -276.427692)
			(xy 124.814509 -276.427257) (xy 124.760559 -276.419495) (xy 124.708262 -276.404135) (xy 124.658684 -276.381488)
			(xy 124.612833 -276.352016) (xy 124.571642 -276.316319) (xy 124.535951 -276.275124) (xy 124.506486 -276.229269)
			(xy 124.483846 -276.179687) (xy 124.468493 -276.127388) (xy 124.460739 -276.073437) (xy 124.460254 -276.046184)
			(xy 121.924546 -276.046184) (xy 121.924387 -276.056524) (xy 121.915839 -276.113137) (xy 121.898921 -276.167835)
			(xy 121.874013 -276.219388) (xy 121.841674 -276.266636) (xy 121.802633 -276.308517) (xy 121.757768 -276.344087)
			(xy 121.708088 -276.372547) (xy 121.654709 -276.393257) (xy 121.626884 -276.400006) (xy 121.62663 -276.400006)
			(xy 121.617871 -276.402419) (xy 121.602755 -276.41248) (xy 121.592088 -276.427174) (xy 121.589292 -276.43582)
			(xy 121.561098 -276.535388) (xy 121.56821 -276.562058) (xy 121.57837 -276.571964) (xy 121.596267 -276.58999)
			(xy 121.627628 -276.629949) (xy 121.653411 -276.673716) (xy 121.673158 -276.720517) (xy 121.686522 -276.769523)
			(xy 121.693266 -276.81987) (xy 121.693686 -276.845268) (xy 121.693215 -276.872521) (xy 121.685462 -276.926473)
			(xy 121.670109 -276.978772) (xy 121.647468 -277.028353) (xy 121.618001 -277.074208) (xy 121.582308 -277.115401)
			(xy 121.541116 -277.151095) (xy 121.495262 -277.180563) (xy 121.445681 -277.203205) (xy 121.393383 -277.21856)
			(xy 121.339431 -277.226314) (xy 121.312178 -277.226776) (xy 121.285925 -277.226374) (xy 121.233915 -277.219182)
			(xy 121.183382 -277.204925) (xy 121.135283 -277.18387) (xy 121.090527 -277.156417) (xy 121.049959 -277.123084)
			(xy 121.014347 -277.084501) (xy 120.998996 -277.0632) (xy 120.993685 -277.05623) (xy 120.979402 -277.046101)
			(xy 120.962543 -277.041365) (xy 120.953784 -277.04161) (xy 120.8532 -277.048722) (xy 120.831102 -277.063454)
			(xy 120.825006 -277.075392) (xy 120.812694 -277.098751) (xy 120.782606 -277.142141) (xy 120.746822 -277.180968)
			(xy 120.726708 -277.198074) (xy 120.718072 -277.205186) (xy 120.70842 -277.224998) (xy 120.70588 -277.324058)
			(xy 120.71477 -277.344378) (xy 120.722898 -277.351744) (xy 120.742185 -277.369935) (xy 120.776113 -277.410673)
			(xy 120.804075 -277.455716) (xy 120.825531 -277.504195) (xy 120.84007 -277.555179) (xy 120.847411 -277.607684)
			(xy 120.847866 -277.634192) (xy 120.84738 -277.661443) (xy 120.839624 -277.715391) (xy 120.834827 -277.731728)
			(xy 120.970292 -277.731728) (xy 120.974363 -277.676106) (xy 120.986489 -277.621669) (xy 121.006412 -277.569578)
			(xy 121.033708 -277.520943) (xy 121.067794 -277.4768) (xy 121.107943 -277.438091) (xy 121.153301 -277.40564)
			(xy 121.202901 -277.380139) (xy 121.255685 -277.362132) (xy 121.310528 -277.352002) (xy 121.366262 -277.349965)
			(xy 121.421699 -277.356065) (xy 121.475656 -277.370171) (xy 121.526985 -277.391983) (xy 121.574591 -277.421037)
			(xy 121.617459 -277.456712) (xy 121.654676 -277.498249) (xy 121.685449 -277.544762) (xy 121.709121 -277.595259)
			(xy 121.723891 -277.644352) (xy 127.083566 -277.644352) (xy 127.084012 -277.618037) (xy 127.091253 -277.565908)
			(xy 127.105577 -277.515266) (xy 127.126713 -277.467067) (xy 127.154263 -277.422224) (xy 127.187704 -277.381585)
			(xy 127.206756 -277.363428) (xy 127.214141 -277.355892) (xy 127.222676 -277.336623) (xy 127.223266 -277.32609)
			(xy 127.223266 -277.251414) (xy 127.222753 -277.240862) (xy 127.214208 -277.221566) (xy 127.206756 -277.214076)
			(xy 127.187687 -277.195934) (xy 127.154233 -277.1553) (xy 127.126677 -277.110457) (xy 127.105541 -277.062254)
			(xy 127.091226 -277.011604) (xy 127.084004 -276.959469) (xy 127.083566 -276.933152) (xy 127.084052 -276.905901)
			(xy 127.091808 -276.851953) (xy 127.107163 -276.799658) (xy 127.129805 -276.750081) (xy 127.159271 -276.704231)
			(xy 127.194962 -276.66304) (xy 127.236153 -276.627349) (xy 127.282003 -276.597883) (xy 127.33158 -276.575241)
			(xy 127.383875 -276.559886) (xy 127.437823 -276.55213) (xy 127.492325 -276.55213) (xy 127.546273 -276.559886)
			(xy 127.598568 -276.575241) (xy 127.648145 -276.597883) (xy 127.693995 -276.627349) (xy 127.735186 -276.66304)
			(xy 127.770877 -276.704231) (xy 127.800343 -276.750081) (xy 127.822985 -276.799658) (xy 127.83834 -276.851953)
			(xy 127.846096 -276.905901) (xy 127.846582 -276.933152) (xy 127.846155 -276.959467) (xy 127.838913 -277.011598)
			(xy 127.824586 -277.062242) (xy 127.803446 -277.110441) (xy 127.775893 -277.155283) (xy 127.742447 -277.195921)
			(xy 127.723392 -277.214076) (xy 127.715998 -277.221604) (xy 127.70747 -277.240879) (xy 127.706882 -277.251414)
			(xy 127.706882 -277.32609) (xy 127.707408 -277.33664) (xy 127.715946 -277.355935) (xy 127.723392 -277.363428)
			(xy 127.742453 -277.381579) (xy 127.77591 -277.422209) (xy 127.803468 -277.46705) (xy 127.824606 -277.515252)
			(xy 127.838922 -277.565901) (xy 127.846145 -277.618036) (xy 127.846582 -277.644352) (xy 127.846096 -277.671603)
			(xy 127.83834 -277.725551) (xy 127.822985 -277.777846) (xy 127.800343 -277.827423) (xy 127.770877 -277.873273)
			(xy 127.735186 -277.914464) (xy 127.693995 -277.950155) (xy 127.648145 -277.979621) (xy 127.598568 -278.002263)
			(xy 127.546273 -278.017618) (xy 127.492325 -278.025374) (xy 127.437823 -278.025374) (xy 127.383875 -278.017618)
			(xy 127.33158 -278.002263) (xy 127.282003 -277.979621) (xy 127.236153 -277.950155) (xy 127.194962 -277.914464)
			(xy 127.159271 -277.873273) (xy 127.129805 -277.827423) (xy 127.107163 -277.777846) (xy 127.091808 -277.725551)
			(xy 127.084052 -277.671603) (xy 127.083566 -277.644352) (xy 121.723891 -277.644352) (xy 121.725189 -277.648666)
			(xy 121.733309 -277.703842) (xy 121.733818 -277.731728) (xy 121.733309 -277.759614) (xy 121.725189 -277.81479)
			(xy 121.709121 -277.868197) (xy 121.685449 -277.918694) (xy 121.654676 -277.965207) (xy 121.617459 -278.006744)
			(xy 121.574591 -278.042419) (xy 121.526985 -278.071473) (xy 121.475656 -278.093285) (xy 121.421699 -278.107391)
			(xy 121.366262 -278.113491) (xy 121.310528 -278.111454) (xy 121.255685 -278.101324) (xy 121.202901 -278.083317)
			(xy 121.153301 -278.057816) (xy 121.107943 -278.025365) (xy 121.067794 -277.986656) (xy 121.033708 -277.942513)
			(xy 121.006412 -277.893878) (xy 120.986489 -277.841787) (xy 120.974363 -277.78735) (xy 120.970292 -277.731728)
			(xy 120.834827 -277.731728) (xy 120.824269 -277.767686) (xy 120.801627 -277.817263) (xy 120.772161 -277.863113)
			(xy 120.73647 -277.904304) (xy 120.695279 -277.939995) (xy 120.649429 -277.969461) (xy 120.599852 -277.992103)
			(xy 120.547557 -278.007458) (xy 120.493609 -278.015214) (xy 120.439107 -278.015214) (xy 120.385159 -278.007458)
			(xy 120.332864 -277.992103) (xy 120.283287 -277.969461) (xy 120.237437 -277.939995) (xy 120.196246 -277.904304)
			(xy 120.160555 -277.863113) (xy 120.131089 -277.817263) (xy 120.108447 -277.767686) (xy 120.093092 -277.715391)
			(xy 120.085336 -277.661443) (xy 120.08485 -277.634192) (xy 118.335044 -277.634192) (xy 118.335044 -278.3459)
			(xy 118.335458 -278.355971) (xy 118.343185 -278.374569) (xy 118.35003 -278.381968) (xy 119.234712 -279.26665)
			(xy 119.24212 -279.273481) (xy 119.260713 -279.281208) (xy 119.27078 -279.281636) (xy 123.010168 -279.281636)
			(xy 123.040087 -279.282226) (xy 123.099187 -279.291592) (xy 123.156097 -279.310083) (xy 123.209415 -279.337243)
			(xy 123.257832 -279.372406) (xy 123.279408 -279.393142) (xy 123.501658 -279.615646) (xy 123.509092 -279.622362)
			(xy 123.527592 -279.629998) (xy 123.547606 -279.629998) (xy 123.566106 -279.622362) (xy 123.57354 -279.615646)
			(xy 123.642628 -279.546812) (xy 123.649346 -279.53935) (xy 123.656922 -279.520776) (xy 123.65736 -279.510744)
			(xy 123.65736 -278.650954) (xy 123.657921 -278.620975) (xy 123.667319 -278.561759) (xy 123.68586 -278.50474)
			(xy 123.71309 -278.451322) (xy 123.748337 -278.402819) (xy 123.76912 -278.381206) (xy 124.076714 -278.073612)
			(xy 124.098289 -278.052785) (xy 124.146796 -278.017534) (xy 124.200224 -277.990309) (xy 124.257253 -277.97178)
			(xy 124.31648 -277.962405) (xy 124.346462 -277.961852) (xy 125.144276 -277.961852) (xy 125.174253 -277.962459)
			(xy 125.233467 -277.971846) (xy 125.290485 -277.990377) (xy 125.343904 -278.017596) (xy 125.392409 -278.052833)
			(xy 125.414024 -278.073612) (xy 126.481332 -279.141174) (xy 126.48873 -279.148017) (xy 126.507331 -279.155736)
			(xy 126.5174 -279.15616) (xy 128.409192 -279.15616) (xy 128.419262 -279.155741) (xy 128.437861 -279.148017)
			(xy 128.44526 -279.141174) (xy 129.512568 -278.073612) (xy 129.534163 -278.052807) (xy 129.582665 -278.017553)
			(xy 129.636087 -277.990324) (xy 129.693112 -277.97179) (xy 129.752335 -277.962409) (xy 129.782316 -277.961852)
			(xy 130.45694 -277.961852) (xy 130.486918 -277.962419) (xy 130.546134 -277.971816) (xy 130.603153 -277.990356)
			(xy 130.656571 -278.017584) (xy 130.705075 -278.052829) (xy 130.726688 -278.073612) (xy 131.228338 -278.575262)
			(xy 131.249065 -278.596843) (xy 131.284206 -278.64527) (xy 131.311357 -278.698589) (xy 131.329852 -278.755493)
			(xy 131.339238 -278.814586) (xy 131.339844 -278.844502) (xy 131.339844 -279.21077) (xy 131.340274 -279.220839)
			(xy 131.34799 -279.239438) (xy 131.35483 -279.246838) (xy 131.967986 -279.85974) (xy 131.988524 -279.881042)
			(xy 132.023382 -279.928854) (xy 132.05043 -279.98148) (xy 132.069019 -280.037655) (xy 132.074412 -280.06675)
			(xy 132.074412 -280.067004) (xy 132.076856 -280.078022) (xy 132.089795 -280.096482) (xy 132.099304 -280.102564)
			(xy 132.17779 -280.147522) (xy 132.200396 -280.149046) (xy 132.211064 -280.144982) (xy 132.238792 -280.134928)
			(xy 132.29646 -280.122559) (xy 132.325872 -280.120344) (xy 132.326126 -280.120344) (xy 132.337402 -280.119001)
			(xy 132.357188 -280.10792) (xy 132.364226 -280.099008) (xy 132.417058 -280.02484) (xy 132.420868 -280.002234)
			(xy 132.41782 -279.991058) (xy 132.411057 -279.965556) (xy 132.403789 -279.913298) (xy 132.403342 -279.886918)
			(xy 132.403828 -279.859667) (xy 132.411584 -279.805719) (xy 132.426939 -279.753424) (xy 132.449581 -279.703847)
			(xy 132.479047 -279.657997) (xy 132.514738 -279.616806) (xy 132.555929 -279.581115) (xy 132.601779 -279.551649)
			(xy 132.651356 -279.529007) (xy 132.703651 -279.513652) (xy 132.757599 -279.505896) (xy 132.812101 -279.505896)
			(xy 132.866049 -279.513652) (xy 132.918344 -279.529007) (xy 132.967921 -279.551649) (xy 133.013771 -279.581115)
			(xy 133.054962 -279.616806) (xy 133.090653 -279.657997) (xy 133.120119 -279.703847) (xy 133.142761 -279.753424)
			(xy 133.158116 -279.805719) (xy 133.165872 -279.859667) (xy 133.166358 -279.886918) (xy 133.165866 -279.915792)
			(xy 133.157183 -279.972884) (xy 133.139987 -280.028013) (xy 133.114672 -280.079917) (xy 133.081817 -280.127408)
			(xy 133.042175 -280.169401) (xy 132.996652 -280.204933) (xy 132.94629 -280.233192) (xy 132.892242 -280.253531)
			(xy 132.835745 -280.265485) (xy 132.806948 -280.267664) (xy 132.806694 -280.267664) (xy 132.795427 -280.269051)
			(xy 132.77564 -280.280104) (xy 132.768594 -280.289) (xy 132.715762 -280.363168) (xy 132.711952 -280.385774)
			(xy 132.715 -280.39695) (xy 132.721765 -280.422452) (xy 132.729032 -280.47471) (xy 132.729478 -280.50109)
			(xy 132.72871 -280.535173) (xy 132.716578 -280.602251) (xy 132.705348 -280.63444) (xy 132.70103 -280.64587)
			(xy 132.70357 -280.669492) (xy 132.760974 -280.758138) (xy 132.781802 -280.77033) (xy 132.79374 -280.771092)
			(xy 132.822349 -280.773546) (xy 132.878415 -280.785926) (xy 132.931995 -280.806566) (xy 132.981878 -280.835)
			(xy 133.026939 -280.870584) (xy 133.06616 -280.912518) (xy 133.098658 -280.959854) (xy 133.123698 -281.011523)
			(xy 133.125308 -281.01671) (xy 133.856982 -281.01671) (xy 133.861053 -280.961088) (xy 133.873179 -280.906651)
			(xy 133.893102 -280.85456) (xy 133.920398 -280.805925) (xy 133.954484 -280.761782) (xy 133.994633 -280.723073)
			(xy 134.039991 -280.690622) (xy 134.089591 -280.665121) (xy 134.142375 -280.647114) (xy 134.197218 -280.636984)
			(xy 134.252952 -280.634947) (xy 134.308389 -280.641047) (xy 134.362346 -280.655153) (xy 134.413675 -280.676965)
			(xy 134.461281 -280.706019) (xy 134.504149 -280.741694) (xy 134.541366 -280.783231) (xy 134.572139 -280.829744)
			(xy 134.595811 -280.880241) (xy 134.611879 -280.933648) (xy 134.619999 -280.988824) (xy 134.620508 -281.01671)
			(xy 134.619999 -281.044596) (xy 134.611879 -281.099772) (xy 134.595811 -281.153179) (xy 134.572139 -281.203676)
			(xy 134.541366 -281.250189) (xy 134.504149 -281.291726) (xy 134.461281 -281.327401) (xy 134.413675 -281.356455)
			(xy 134.362346 -281.378267) (xy 134.308389 -281.392373) (xy 134.252952 -281.398473) (xy 134.197218 -281.396436)
			(xy 134.142375 -281.386306) (xy 134.089591 -281.368299) (xy 134.039991 -281.342798) (xy 133.994633 -281.310347)
			(xy 133.954484 -281.271638) (xy 133.920398 -281.227495) (xy 133.893102 -281.17886) (xy 133.873179 -281.126769)
			(xy 133.861053 -281.072332) (xy 133.856982 -281.01671) (xy 133.125308 -281.01671) (xy 133.140715 -281.066361)
			(xy 133.149325 -281.123129) (xy 133.149848 -281.151838) (xy 133.149362 -281.179089) (xy 133.141606 -281.233037)
			(xy 133.126251 -281.285332) (xy 133.103609 -281.334909) (xy 133.074143 -281.380759) (xy 133.038452 -281.42195)
			(xy 132.997261 -281.457641) (xy 132.951411 -281.487107) (xy 132.901834 -281.509749) (xy 132.849539 -281.525104)
			(xy 132.795591 -281.53286) (xy 132.741089 -281.53286) (xy 132.687141 -281.525104) (xy 132.634846 -281.509749)
			(xy 132.585269 -281.487107) (xy 132.539419 -281.457641) (xy 132.498228 -281.42195) (xy 132.462537 -281.380759)
			(xy 132.433071 -281.334909) (xy 132.410429 -281.285332) (xy 132.395074 -281.233037) (xy 132.387318 -281.179089)
			(xy 132.386832 -281.151838) (xy 132.387581 -281.117754) (xy 132.399725 -281.050676) (xy 132.410962 -281.018488)
			(xy 132.41528 -281.007058) (xy 132.41274 -280.983436) (xy 132.355336 -280.89479) (xy 132.334508 -280.882598)
			(xy 132.32257 -280.881836) (xy 132.291201 -280.879157) (xy 132.229921 -280.864728) (xy 132.20065 -280.853134)
			(xy 132.190744 -280.848816) (xy 132.169154 -280.849324) (xy 132.081016 -280.891234) (xy 132.067046 -280.90749)
			(xy 132.063998 -280.918158) (xy 132.05582 -280.944122) (xy 132.033169 -280.993619) (xy 132.00371 -281.039392)
			(xy 131.968041 -281.08051) (xy 131.926887 -281.116138) (xy 131.881084 -281.145552) (xy 131.831565 -281.168153)
			(xy 131.779334 -281.183483) (xy 131.725455 -281.191229) (xy 131.698238 -281.191716) (xy 131.674882 -281.191348)
			(xy 131.628524 -281.185619) (xy 131.605782 -281.180286) (xy 131.596384 -281.177746) (xy 131.576826 -281.18054)
			(xy 131.498594 -281.225498) (xy 131.486402 -281.240992) (xy 131.483862 -281.25039) (xy 131.47583 -281.276519)
			(xy 131.45326 -281.326307) (xy 131.423819 -281.372366) (xy 131.388108 -281.413755) (xy 131.346859 -281.449626)
			(xy 131.300915 -281.479246) (xy 131.251216 -281.50201) (xy 131.198777 -281.517452) (xy 131.144672 -281.525255)
			(xy 131.11734 -281.525726) (xy 131.090089 -281.525208) (xy 131.036141 -281.517456) (xy 130.983845 -281.502106)
			(xy 130.934266 -281.47947) (xy 130.888414 -281.450008) (xy 130.847221 -281.41432) (xy 130.811527 -281.373133)
			(xy 130.782058 -281.327285) (xy 130.759414 -281.277709) (xy 130.744056 -281.225416) (xy 130.736297 -281.171469)
			(xy 130.735832 -281.144218) (xy 130.735889 -281.133592) (xy 130.737032 -281.112371) (xy 130.738118 -281.1018)
			(xy 130.739134 -281.092402) (xy 130.734308 -281.074114) (xy 130.688334 -281.010614) (xy 130.682506 -281.003327)
			(xy 130.666881 -280.993161) (xy 130.657854 -280.990802) (xy 130.6576 -280.990802) (xy 130.6293 -280.984437)
			(xy 130.574912 -280.964276) (xy 130.524204 -280.936113) (xy 130.478344 -280.900597) (xy 130.43839 -280.858547)
			(xy 130.405263 -280.810934) (xy 130.379727 -280.758853) (xy 130.36237 -280.703506) (xy 130.353593 -280.64617)
			(xy 130.353054 -280.617168) (xy 130.35354 -280.589917) (xy 130.361296 -280.535969) (xy 130.376651 -280.483674)
			(xy 130.399293 -280.434097) (xy 130.428759 -280.388247) (xy 130.46445 -280.347056) (xy 130.505641 -280.311365)
			(xy 130.551491 -280.281899) (xy 130.601068 -280.259257) (xy 130.653363 -280.243902) (xy 130.707311 -280.236146)
			(xy 130.761813 -280.236146) (xy 130.815761 -280.243902) (xy 130.868056 -280.259257) (xy 130.917633 -280.281899)
			(xy 130.963483 -280.311365) (xy 131.004674 -280.347056) (xy 131.040365 -280.388247) (xy 131.069831 -280.434097)
			(xy 131.092473 -280.483674) (xy 131.107828 -280.535969) (xy 131.115584 -280.589917) (xy 131.11607 -280.617168)
			(xy 131.116012 -280.627794) (xy 131.114869 -280.649015) (xy 131.113784 -280.659586) (xy 131.112768 -280.668984)
			(xy 131.117594 -280.687272) (xy 131.163568 -280.750772) (xy 131.169398 -280.758057) (xy 131.185022 -280.768225)
			(xy 131.194048 -280.770584) (xy 131.195064 -280.770584) (xy 131.20614 -280.772254) (xy 131.227883 -280.76697)
			(xy 131.236974 -280.760424) (xy 131.298188 -280.71064) (xy 131.306599 -280.703028) (xy 131.31637 -280.682595)
			(xy 131.316984 -280.67127) (xy 131.316984 -280.308558) (xy 131.316585 -280.298486) (xy 131.308846 -280.279888)
			(xy 131.301998 -280.27249) (xy 130.688842 -279.659588) (xy 130.668136 -279.637988) (xy 130.632993 -279.589565)
			(xy 130.605839 -279.536251) (xy 130.587338 -279.479352) (xy 130.577946 -279.420263) (xy 130.577336 -279.390348)
			(xy 130.577336 -279.02408) (xy 130.576938 -279.014007) (xy 130.5692 -278.995409) (xy 130.56235 -278.988012)
			(xy 130.313938 -278.739854) (xy 130.306485 -278.73309) (xy 130.287921 -278.725372) (xy 130.27787 -278.724868)
			(xy 129.961386 -278.724868) (xy 129.951313 -278.725268) (xy 129.932715 -278.733004) (xy 129.925318 -278.739854)
			(xy 128.85801 -279.807162) (xy 128.836445 -279.827906) (xy 128.788013 -279.863044) (xy 128.73469 -279.890191)
			(xy 128.677783 -279.908682) (xy 128.618687 -279.918064) (xy 128.58877 -279.918668) (xy 126.337822 -279.918668)
			(xy 126.307903 -279.918083) (xy 126.248802 -279.908716) (xy 126.191893 -279.890224) (xy 126.138574 -279.863062)
			(xy 126.090158 -279.827898) (xy 126.068582 -279.807162) (xy 125.001274 -278.739854) (xy 124.993882 -278.733004)
			(xy 124.975276 -278.725291) (xy 124.965206 -278.724868) (xy 124.525532 -278.724868) (xy 124.515462 -278.725292)
			(xy 124.496863 -278.733012) (xy 124.489464 -278.739854) (xy 124.435362 -278.793956) (xy 124.428602 -278.801412)
			(xy 124.420881 -278.819973) (xy 124.420376 -278.830024) (xy 124.420376 -279.414732) (xy 124.420998 -279.42615)
			(xy 124.430907 -279.446726) (xy 124.439426 -279.454356) (xy 124.509784 -279.511252) (xy 124.532136 -279.516332)
			(xy 124.543312 -279.514046) (xy 124.563197 -279.510012) (xy 124.603542 -279.505691) (xy 124.62383 -279.50541)
			(xy 124.624338 -279.50541) (xy 124.651591 -279.505843) (xy 124.705542 -279.513605) (xy 124.757838 -279.528966)
			(xy 124.807417 -279.551612) (xy 124.853268 -279.581084) (xy 124.894458 -279.616781) (xy 124.930149 -279.657977)
			(xy 124.959614 -279.703832) (xy 124.982254 -279.753414) (xy 124.997607 -279.805713) (xy 125.005361 -279.859665)
			(xy 125.005846 -279.886918) (xy 125.005365 -279.915793) (xy 124.996681 -279.972886) (xy 124.979485 -280.028015)
			(xy 124.954169 -280.07992) (xy 124.921313 -280.127412) (xy 124.88167 -280.169405) (xy 124.836145 -280.204937)
			(xy 124.785782 -280.233195) (xy 124.731732 -280.253533) (xy 124.675233 -280.265486) (xy 124.646436 -280.267664)
			(xy 124.646182 -280.267664) (xy 124.634914 -280.269045) (xy 124.615128 -280.280102) (xy 124.608082 -280.289)
			(xy 124.55525 -280.363168) (xy 124.55144 -280.385774) (xy 124.554488 -280.39695) (xy 124.561253 -280.422452)
			(xy 124.56852 -280.47471) (xy 124.568966 -280.50109) (xy 124.568199 -280.535173) (xy 124.556067 -280.602251)
			(xy 124.544836 -280.63444) (xy 124.540518 -280.64587) (xy 124.543058 -280.669492) (xy 124.600462 -280.758138)
			(xy 124.62129 -280.77033) (xy 124.633228 -280.771092) (xy 124.661836 -280.773556) (xy 124.717902 -280.785935)
			(xy 124.771482 -280.806573) (xy 124.821365 -280.835005) (xy 124.866426 -280.870589) (xy 124.905648 -280.912521)
			(xy 124.938145 -280.959856) (xy 124.95745 -280.999692) (xy 125.69647 -280.999692) (xy 125.700541 -280.94407)
			(xy 125.712667 -280.889633) (xy 125.73259 -280.837542) (xy 125.759886 -280.788907) (xy 125.793972 -280.744764)
			(xy 125.834121 -280.706055) (xy 125.879479 -280.673604) (xy 125.929079 -280.648103) (xy 125.981863 -280.630096)
			(xy 126.036706 -280.619966) (xy 126.09244 -280.617929) (xy 126.147877 -280.624029) (xy 126.201834 -280.638135)
			(xy 126.253163 -280.659947) (xy 126.300769 -280.689001) (xy 126.343637 -280.724676) (xy 126.380854 -280.766213)
			(xy 126.411627 -280.812726) (xy 126.435299 -280.863223) (xy 126.451367 -280.91663) (xy 126.459487 -280.971806)
			(xy 126.459996 -280.999692) (xy 126.459487 -281.027578) (xy 126.451367 -281.082754) (xy 126.435299 -281.136161)
			(xy 126.411627 -281.186658) (xy 126.380854 -281.233171) (xy 126.343637 -281.274708) (xy 126.300769 -281.310383)
			(xy 126.253163 -281.339437) (xy 126.201834 -281.361249) (xy 126.147877 -281.375355) (xy 126.09244 -281.381455)
			(xy 126.036706 -281.379418) (xy 125.981863 -281.369288) (xy 125.929079 -281.351281) (xy 125.879479 -281.32578)
			(xy 125.834121 -281.293329) (xy 125.793972 -281.25462) (xy 125.759886 -281.210477) (xy 125.73259 -281.161842)
			(xy 125.712667 -281.109751) (xy 125.700541 -281.055314) (xy 125.69647 -280.999692) (xy 124.95745 -280.999692)
			(xy 124.963185 -281.011525) (xy 124.980203 -281.066362) (xy 124.988813 -281.12313) (xy 124.989336 -281.151838)
			(xy 124.98885 -281.179089) (xy 124.981094 -281.233037) (xy 124.965739 -281.285332) (xy 124.943097 -281.334909)
			(xy 124.913631 -281.380759) (xy 124.87794 -281.42195) (xy 124.836749 -281.457641) (xy 124.790899 -281.487107)
			(xy 124.741322 -281.509749) (xy 124.689027 -281.525104) (xy 124.635079 -281.53286) (xy 124.580577 -281.53286)
			(xy 124.526629 -281.525104) (xy 124.474334 -281.509749) (xy 124.424757 -281.487107) (xy 124.378907 -281.457641)
			(xy 124.337716 -281.42195) (xy 124.302025 -281.380759) (xy 124.272559 -281.334909) (xy 124.249917 -281.285332)
			(xy 124.234562 -281.233037) (xy 124.226806 -281.179089) (xy 124.22632 -281.151838) (xy 124.22707 -281.117754)
			(xy 124.239214 -281.050676) (xy 124.25045 -281.018488) (xy 124.254768 -281.007058) (xy 124.252228 -280.983436)
			(xy 124.194824 -280.89479) (xy 124.173996 -280.882598) (xy 124.162058 -280.881836) (xy 124.130688 -280.87916)
			(xy 124.069409 -280.864729) (xy 124.040138 -280.853134) (xy 124.030232 -280.848816) (xy 124.008642 -280.849324)
			(xy 123.920504 -280.891234) (xy 123.906534 -280.90749) (xy 123.903486 -280.918158) (xy 123.895318 -280.944126)
			(xy 123.872667 -280.993623) (xy 123.843206 -281.039397) (xy 123.807536 -281.080515) (xy 123.76638 -281.116143)
			(xy 123.720577 -281.145556) (xy 123.671056 -281.168157) (xy 123.618824 -281.183485) (xy 123.564943 -281.19123)
			(xy 123.537726 -281.191716) (xy 123.51437 -281.19135) (xy 123.468011 -281.18562) (xy 123.44527 -281.180286)
			(xy 123.435872 -281.177746) (xy 123.416314 -281.18054) (xy 123.338082 -281.225498) (xy 123.32589 -281.240992)
			(xy 123.32335 -281.25039) (xy 123.315328 -281.276523) (xy 123.292757 -281.326311) (xy 123.263315 -281.372371)
			(xy 123.227604 -281.413759) (xy 123.186353 -281.449631) (xy 123.140408 -281.479251) (xy 123.090707 -281.502014)
			(xy 123.038267 -281.517454) (xy 122.984161 -281.525256) (xy 122.956828 -281.525726) (xy 122.929577 -281.525219)
			(xy 122.875628 -281.517466) (xy 122.823332 -281.502114) (xy 122.773753 -281.479477) (xy 122.727901 -281.450013)
			(xy 122.686709 -281.414324) (xy 122.651015 -281.373136) (xy 122.621546 -281.327287) (xy 122.598902 -281.277711)
			(xy 122.583544 -281.225417) (xy 122.575785 -281.171469) (xy 122.57532 -281.144218) (xy 122.575377 -281.133592)
			(xy 122.57652 -281.112371) (xy 122.577606 -281.1018) (xy 122.578622 -281.092402) (xy 122.573796 -281.074114)
			(xy 122.527822 -281.010614) (xy 122.521998 -281.003323) (xy 122.50637 -280.993159) (xy 122.497342 -280.990802)
			(xy 122.497088 -280.990802) (xy 122.468786 -280.984445) (xy 122.414398 -280.964282) (xy 122.36369 -280.936118)
			(xy 122.317831 -280.900601) (xy 122.277877 -280.85855) (xy 122.24475 -280.810936) (xy 122.219214 -280.758854)
			(xy 122.201858 -280.703507) (xy 122.193081 -280.64617) (xy 122.192542 -280.617168) (xy 122.193028 -280.589917)
			(xy 122.200784 -280.535969) (xy 122.216139 -280.483674) (xy 122.238781 -280.434097) (xy 122.268247 -280.388247)
			(xy 122.303938 -280.347056) (xy 122.345129 -280.311365) (xy 122.390979 -280.281899) (xy 122.440556 -280.259257)
			(xy 122.492851 -280.243902) (xy 122.546799 -280.236146) (xy 122.601301 -280.236146) (xy 122.655249 -280.243902)
			(xy 122.707544 -280.259257) (xy 122.757121 -280.281899) (xy 122.802971 -280.311365) (xy 122.844162 -280.347056)
			(xy 122.879853 -280.388247) (xy 122.909319 -280.434097) (xy 122.931961 -280.483674) (xy 122.947316 -280.535969)
			(xy 122.955072 -280.589917) (xy 122.955558 -280.617168) (xy 122.9555 -280.627794) (xy 122.954357 -280.649015)
			(xy 122.953272 -280.659586) (xy 122.952256 -280.668984) (xy 122.957082 -280.687272) (xy 123.003056 -280.750772)
			(xy 123.00889 -280.758053) (xy 123.024511 -280.768223) (xy 123.033536 -280.770584) (xy 123.034552 -280.770584)
			(xy 123.045628 -280.772247) (xy 123.067371 -280.766968) (xy 123.076462 -280.760424) (xy 123.137676 -280.71064)
			(xy 123.146085 -280.703026) (xy 123.155858 -280.682595) (xy 123.156472 -280.67127) (xy 123.156472 -280.370026)
			(xy 123.156041 -280.359957) (xy 123.148325 -280.341359) (xy 123.141486 -280.333958) (xy 122.866658 -280.05913)
			(xy 122.859263 -280.052283) (xy 122.84066 -280.044567) (xy 122.83059 -280.044144) (xy 119.091202 -280.044144)
			(xy 119.061282 -280.043579) (xy 119.00218 -280.034208) (xy 118.94527 -280.015711) (xy 118.891952 -279.988545)
			(xy 118.843537 -279.953376) (xy 118.821962 -279.932638) (xy 117.684042 -278.794718) (xy 117.663302 -278.773149)
			(xy 117.628164 -278.724718) (xy 117.601016 -278.671396) (xy 117.582524 -278.61449) (xy 117.573141 -278.555395)
			(xy 117.572536 -278.525478) (xy 114.519456 -278.525478) (xy 114.56924 -278.575262) (xy 114.590017 -278.596878)
			(xy 114.625252 -278.645384) (xy 114.652469 -278.698803) (xy 114.670999 -278.75582) (xy 114.680386 -278.815034)
			(xy 114.681 -278.84501) (xy 114.681 -279.21077) (xy 114.682016 -279.220422) (xy 114.683639 -279.227668)
			(xy 114.690474 -279.240844) (xy 114.695478 -279.24633) (xy 115.308888 -279.85974) (xy 115.3294 -279.881064)
			(xy 115.364248 -279.928878) (xy 115.391299 -279.981497) (xy 115.409905 -280.037661) (xy 115.415314 -280.06675)
			(xy 115.415822 -280.069036) (xy 115.418547 -280.079163) (xy 115.430744 -280.096199) (xy 115.439444 -280.102056)
			(xy 115.508532 -280.14168) (xy 115.513621 -280.144377) (xy 115.524646 -280.147701) (xy 115.530376 -280.148284)
			(xy 115.541298 -280.149046) (xy 115.551966 -280.144982) (xy 115.561618 -280.141426) (xy 115.585494 -280.133806)
			(xy 115.605388 -280.128531) (xy 115.645989 -280.12178) (xy 115.66652 -280.120344) (xy 115.668044 -280.120344)
			(xy 115.678281 -280.118976) (xy 115.69649 -280.10927) (xy 115.70335 -280.101548) (xy 115.751102 -280.034492)
			(xy 115.754327 -280.029652) (xy 115.758697 -280.018877) (xy 115.759738 -280.013156) (xy 115.761008 -280.006044)
			(xy 115.759484 -279.994106) (xy 115.758976 -279.992328) (xy 115.758722 -279.991058) (xy 115.751951 -279.965557)
			(xy 115.744681 -279.913299) (xy 115.744244 -279.886918) (xy 115.74473 -279.859667) (xy 115.752486 -279.805719)
			(xy 115.767841 -279.753424) (xy 115.790483 -279.703847) (xy 115.819949 -279.657997) (xy 115.85564 -279.616806)
			(xy 115.896831 -279.581115) (xy 115.942681 -279.551649) (xy 115.992258 -279.529007) (xy 116.044553 -279.513652)
			(xy 116.098501 -279.505896) (xy 116.153003 -279.505896) (xy 116.206951 -279.513652) (xy 116.259246 -279.529007)
			(xy 116.308823 -279.551649) (xy 116.354673 -279.581115) (xy 116.395864 -279.616806) (xy 116.431555 -279.657997)
			(xy 116.461021 -279.703847) (xy 116.483663 -279.753424) (xy 116.499018 -279.805719) (xy 116.506774 -279.859667)
			(xy 116.50726 -279.886918) (xy 116.50672 -279.915784) (xy 116.498003 -279.972853) (xy 116.480786 -280.027958)
			(xy 116.455461 -280.079839) (xy 116.422608 -280.127311) (xy 116.382976 -280.16929) (xy 116.337471 -280.204818)
			(xy 116.287132 -280.233084) (xy 116.233109 -280.253441) (xy 116.176634 -280.265424) (xy 116.14785 -280.267664)
			(xy 116.14658 -280.267664) (xy 116.136341 -280.269028) (xy 116.118126 -280.27873) (xy 116.111274 -280.28646)
			(xy 116.063522 -280.353516) (xy 116.060302 -280.358358) (xy 116.055941 -280.369134) (xy 116.054886 -280.374852)
			(xy 116.053616 -280.381964) (xy 116.05514 -280.393902) (xy 116.055648 -280.39568) (xy 116.055902 -280.39695)
			(xy 116.062672 -280.422451) (xy 116.06994 -280.474709) (xy 116.07038 -280.50109) (xy 116.0696 -280.535171)
			(xy 116.05746 -280.602245) (xy 116.04625 -280.63444) (xy 116.044297 -280.640195) (xy 116.042896 -280.652264)
			(xy 116.043456 -280.658316) (xy 116.044726 -280.669492) (xy 116.088922 -280.737818) (xy 116.092308 -280.742704)
			(xy 116.100909 -280.750906) (xy 116.10594 -280.754074) (xy 116.134388 -280.770838) (xy 116.140484 -280.7716)
			(xy 116.168762 -280.774444) (xy 116.224087 -280.787442) (xy 116.276871 -280.808503) (xy 116.325947 -280.837162)
			(xy 116.370228 -280.872785) (xy 116.408735 -280.914583) (xy 116.440614 -280.961631) (xy 116.46516 -281.012888)
			(xy 116.481831 -281.067219) (xy 116.490256 -281.123422) (xy 116.49075 -281.151838) (xy 116.490243 -281.180016)
			(xy 116.481954 -281.235761) (xy 116.465562 -281.289681) (xy 116.441422 -281.340606) (xy 116.410059 -281.38743)
			(xy 116.372155 -281.429136) (xy 116.328532 -281.464818) (xy 116.280139 -281.4937) (xy 116.254276 -281.504898)
			(xy 116.244624 -281.508962) (xy 116.237004 -281.516836) (xy 116.234464 -281.51963) (xy 116.2304 -281.524456)
			(xy 116.225066 -281.535378) (xy 116.217446 -281.572208) (xy 116.21643 -281.583892) (xy 116.217155 -281.593647)
			(xy 116.224981 -281.611555) (xy 116.23167 -281.61869) (xy 116.231924 -281.618944) (xy 116.235988 -281.622754)
			(xy 116.346732 -281.733498) (xy 116.364766 -281.751786) (xy 116.3709 -281.75678) (xy 116.385383 -281.763119)
			(xy 116.393214 -281.764232) (xy 116.402358 -281.764486) (xy 116.47932 -281.758644) (xy 116.484924 -281.75804)
			(xy 116.495692 -281.75471) (xy 116.500656 -281.75204) (xy 116.5098 -281.74696) (xy 116.516404 -281.737816)
			(xy 116.534525 -281.714079) (xy 116.576904 -281.672009) (xy 116.625318 -281.637052) (xy 116.678586 -281.610061)
			(xy 116.735407 -281.591696) (xy 116.794394 -281.582404) (xy 116.824252 -281.58186) (xy 116.851899 -281.582355)
			(xy 116.906614 -281.590342) (xy 116.959604 -281.606142) (xy 117.009759 -281.629424) (xy 117.056029 -281.6597)
			(xy 117.097445 -281.696336) (xy 117.13314 -281.738567) (xy 117.162367 -281.785506) (xy 117.184514 -281.836172)
			(xy 117.199118 -281.889503) (xy 117.202966 -281.916886) (xy 117.204318 -281.925358) (xy 117.211863 -281.940753)
			(xy 117.22406 -281.952801) (xy 117.231668 -281.956764) (xy 117.237002 -281.958796) (xy 117.323108 -281.988514)
			(xy 117.332176 -281.991217) (xy 117.351072 -281.990461) (xy 117.368417 -281.982929) (xy 117.375432 -281.976576)
			(xy 117.721888 -281.63012) (xy 117.724594 -281.627269) (xy 117.729187 -281.620891) (xy 117.731032 -281.61742)
			(xy 117.73361 -281.611992) (xy 117.736423 -281.600312) (xy 117.73662 -281.594306) (xy 117.73662 -281.496516)
			(xy 117.736366 -281.491436) (xy 117.73504 -281.482066) (xy 117.726421 -281.465233) (xy 117.719602 -281.45867)
			(xy 117.66296 -281.408124) (xy 117.660674 -281.406346) (xy 117.653008 -281.40073) (xy 117.634866 -281.39512)
			(xy 117.625368 -281.395424) (xy 117.62359 -281.395678) (xy 117.612707 -281.396861) (xy 117.590849 -281.398132)
			(xy 117.579902 -281.398218) (xy 117.552648 -281.397755) (xy 117.498696 -281.389998) (xy 117.446396 -281.374642)
			(xy 117.396814 -281.351999) (xy 117.35096 -281.32253) (xy 117.309766 -281.286836) (xy 117.274071 -281.245642)
			(xy 117.244602 -281.199787) (xy 117.221959 -281.150206) (xy 117.206602 -281.097906) (xy 117.198845 -281.043954)
			(xy 117.198845 -280.989446) (xy 117.206602 -280.935494) (xy 117.221959 -280.883194) (xy 117.244602 -280.833613)
			(xy 117.274071 -280.787758) (xy 117.309766 -280.746564) (xy 117.35096 -280.71087) (xy 117.396814 -280.681401)
			(xy 117.446396 -280.658758) (xy 117.498696 -280.643402) (xy 117.552648 -280.635645) (xy 117.579902 -280.635202)
			(xy 117.607307 -280.635677) (xy 117.661551 -280.643525) (xy 117.714113 -280.659059) (xy 117.763909 -280.681958)
			(xy 117.809913 -280.711752) (xy 117.830854 -280.729436) (xy 117.83187 -280.730198) (xy 117.839272 -280.735831)
			(xy 117.85686 -280.741837) (xy 117.86616 -280.741882) (xy 117.934994 -280.739596) (xy 117.94076 -280.739274)
			(xy 117.951923 -280.736329) (xy 117.957092 -280.733754) (xy 117.966744 -280.72715) (xy 117.968014 -280.726134)
			(xy 117.969284 -280.724864) (xy 118.335044 -280.359104) (xy 118.360163 -280.334873) (xy 118.416121 -280.293162)
			(xy 118.477502 -280.259944) (xy 118.51005 -280.247344) (xy 118.536654 -280.23802) (xy 118.591486 -280.224923)
			(xy 118.647471 -280.218304) (xy 118.675658 -280.21788) (xy 120.875044 -280.21788) (xy 120.903231 -280.218309)
			(xy 120.959214 -280.224933) (xy 121.014046 -280.238028) (xy 121.040652 -280.247344) (xy 121.0732 -280.259943)
			(xy 121.134578 -280.293166) (xy 121.190537 -280.334874) (xy 121.215658 -280.359104) (xy 122.535188 -281.678888)
			(xy 122.540656 -281.683959) (xy 122.553829 -281.69093) (xy 122.561096 -281.692604) (xy 122.571002 -281.69362)
			(xy 124.506228 -281.69362) (xy 124.534415 -281.694048) (xy 124.590398 -281.700671) (xy 124.645231 -281.713765)
			(xy 124.671836 -281.723084) (xy 124.704384 -281.735683) (xy 124.765762 -281.768906) (xy 124.82172 -281.810616)
			(xy 124.846842 -281.834844) (xy 124.876052 -281.864308) (xy 124.876306 -281.864562) (xy 124.883718 -281.871246)
			(xy 124.902151 -281.878843) (xy 124.922089 -281.878843) (xy 124.940522 -281.871246) (xy 124.947934 -281.864562)
			(xy 124.952252 -281.860244) (xy 124.958348 -281.850084) (xy 124.96038 -281.844242) (xy 124.96038 -281.843988)
			(xy 124.969141 -281.818909) (xy 124.992627 -281.771259) (xy 125.02249 -281.727324) (xy 125.058154 -281.687952)
			(xy 125.098932 -281.653904) (xy 125.144035 -281.625836) (xy 125.192593 -281.604292) (xy 125.243669 -281.589685)
			(xy 125.296277 -281.5823) (xy 125.322838 -281.58186) (xy 125.350088 -281.582348) (xy 125.404034 -281.590109)
			(xy 125.456326 -281.605467) (xy 125.5059 -281.62811) (xy 125.551748 -281.657577) (xy 125.592936 -281.693268)
			(xy 125.628627 -281.734457) (xy 125.658093 -281.780305) (xy 125.680735 -281.82988) (xy 125.696092 -281.882172)
			(xy 125.703852 -281.936118) (xy 125.704346 -281.963368) (xy 125.703846 -281.991399) (xy 125.695633 -282.046856)
			(xy 125.679392 -282.100514) (xy 125.655475 -282.151219) (xy 125.624395 -282.197877) (xy 125.586822 -282.239485)
			(xy 125.543565 -282.275147) (xy 125.495555 -282.304095) (xy 125.469904 -282.315412) (xy 125.460506 -282.319222)
			(xy 125.45314 -282.326588) (xy 125.449702 -282.330273) (xy 125.444202 -282.338718) (xy 125.442218 -282.343352)
			(xy 125.41504 -282.410916) (xy 125.413252 -282.415732) (xy 125.411463 -282.425845) (xy 125.411484 -282.430982)
			(xy 125.411738 -282.440888) (xy 125.415294 -282.448762) (xy 125.416056 -282.45054) (xy 125.428935 -282.481083)
			(xy 125.447155 -282.544816) (xy 125.456498 -282.61044) (xy 125.457204 -282.64358) (xy 125.457204 -282.904438)
			(xy 126.722632 -282.904438) (xy 126.723113 -282.876864) (xy 126.731061 -282.822291) (xy 126.746782 -282.769431)
			(xy 126.769949 -282.719385) (xy 126.800079 -282.673195) (xy 126.836545 -282.631824) (xy 126.857252 -282.613608)
			(xy 126.865332 -282.606058) (xy 126.874681 -282.586042) (xy 126.875286 -282.575) (xy 126.875286 -282.497276)
			(xy 126.87468 -282.486231) (xy 126.865342 -282.46621) (xy 126.857252 -282.458668) (xy 126.836513 -282.440488)
			(xy 126.800046 -282.399111) (xy 126.769919 -282.352915) (xy 126.746759 -282.302861) (xy 126.731048 -282.249993)
			(xy 126.723114 -282.195414) (xy 126.722632 -282.167838) (xy 126.723113 -282.140264) (xy 126.731061 -282.085691)
			(xy 126.746782 -282.032831) (xy 126.769949 -281.982785) (xy 126.800079 -281.936595) (xy 126.836545 -281.895224)
			(xy 126.857252 -281.877008) (xy 126.865332 -281.869458) (xy 126.874681 -281.849442) (xy 126.875286 -281.8384)
			(xy 126.875286 -281.760676) (xy 126.87468 -281.749631) (xy 126.865342 -281.72961) (xy 126.857252 -281.722068)
			(xy 126.836513 -281.703888) (xy 126.800046 -281.662511) (xy 126.769919 -281.616315) (xy 126.746759 -281.566261)
			(xy 126.731048 -281.513393) (xy 126.723114 -281.458814) (xy 126.722632 -281.431238) (xy 126.723091 -281.403984)
			(xy 126.730844 -281.350031) (xy 126.746197 -281.297731) (xy 126.768838 -281.248148) (xy 126.798306 -281.202293)
			(xy 126.834 -281.161099) (xy 126.875194 -281.125404) (xy 126.92105 -281.095937) (xy 126.970633 -281.073296)
			(xy 127.022933 -281.057943) (xy 127.076886 -281.050191) (xy 127.10414 -281.04973) (xy 127.131997 -281.050195)
			(xy 127.187117 -281.058325) (xy 127.240469 -281.074377) (xy 127.290924 -281.098011) (xy 127.337409 -281.128725)
			(xy 127.378938 -281.165868) (xy 127.414629 -281.20865) (xy 127.443726 -281.256164) (xy 127.46561 -281.307402)
			(xy 127.473202 -281.33421) (xy 127.475488 -281.3431) (xy 127.486156 -281.35834) (xy 127.558038 -281.406092)
			(xy 127.576072 -281.410156) (xy 127.585216 -281.408886) (xy 127.598233 -281.407217) (xy 127.624417 -281.405437)
			(xy 127.63754 -281.40533) (xy 127.650663 -281.405424) (xy 127.676849 -281.407203) (xy 127.689864 -281.408886)
			(xy 127.699008 -281.410156) (xy 127.717042 -281.406092) (xy 127.788924 -281.35834) (xy 127.799592 -281.3431)
			(xy 127.801878 -281.33421) (xy 127.809467 -281.307399) (xy 127.83133 -281.256149) (xy 127.860415 -281.208624)
			(xy 127.896103 -281.165835) (xy 127.937634 -281.12869) (xy 127.984126 -281.097982) (xy 128.034591 -281.074361)
			(xy 128.087954 -281.058332) (xy 128.143081 -281.050234) (xy 128.17094 -281.04973) (xy 128.198194 -281.050141)
			(xy 128.252146 -281.057904) (xy 128.304445 -281.073266) (xy 128.354025 -281.095914) (xy 128.399877 -281.125388)
			(xy 128.441068 -281.161088) (xy 128.476758 -281.202286) (xy 128.506223 -281.248144) (xy 128.528862 -281.297728)
			(xy 128.544213 -281.35003) (xy 128.551965 -281.403984) (xy 128.552448 -281.431238) (xy 128.551975 -281.458537)
			(xy 128.544199 -281.512578) (xy 128.528797 -281.564959) (xy 128.506085 -281.614608) (xy 128.476525 -281.660512)
			(xy 128.458976 -281.681428) (xy 128.452626 -281.688794) (xy 128.446276 -281.706574) (xy 128.449578 -281.795728)
			(xy 128.457452 -281.813508) (xy 128.46431 -281.820112) (xy 128.485426 -281.841756) (xy 128.521231 -281.890479)
			(xy 128.5489 -281.944242) (xy 128.555171 -281.963368) (xy 133.101332 -281.963368) (xy 133.105403 -281.907746)
			(xy 133.117529 -281.853309) (xy 133.137452 -281.801218) (xy 133.164748 -281.752583) (xy 133.198834 -281.70844)
			(xy 133.238983 -281.669731) (xy 133.284341 -281.63728) (xy 133.333941 -281.611779) (xy 133.386725 -281.593772)
			(xy 133.441568 -281.583642) (xy 133.497302 -281.581605) (xy 133.552739 -281.587705) (xy 133.606696 -281.601811)
			(xy 133.658025 -281.623623) (xy 133.705631 -281.652677) (xy 133.748499 -281.688352) (xy 133.785716 -281.729889)
			(xy 133.816489 -281.776402) (xy 133.840161 -281.826899) (xy 133.856229 -281.880306) (xy 133.864349 -281.935482)
			(xy 133.864858 -281.963368) (xy 133.864349 -281.991254) (xy 133.856229 -282.04643) (xy 133.840161 -282.099837)
			(xy 133.816489 -282.150334) (xy 133.785716 -282.196847) (xy 133.748499 -282.238384) (xy 133.705631 -282.274059)
			(xy 133.658025 -282.303113) (xy 133.606696 -282.324925) (xy 133.552739 -282.339031) (xy 133.497302 -282.345131)
			(xy 133.441568 -282.343094) (xy 133.386725 -282.332964) (xy 133.333941 -282.314957) (xy 133.284341 -282.289456)
			(xy 133.238983 -282.257005) (xy 133.198834 -282.218296) (xy 133.164748 -282.174153) (xy 133.137452 -282.125518)
			(xy 133.117529 -282.073427) (xy 133.105403 -282.01899) (xy 133.101332 -281.963368) (xy 128.555171 -281.963368)
			(xy 128.567738 -282.001697) (xy 128.577273 -282.061406) (xy 128.577848 -282.091638) (xy 128.577349 -282.119276)
			(xy 128.569357 -282.173971) (xy 128.553561 -282.226942) (xy 128.530289 -282.27708) (xy 128.50003 -282.323338)
			(xy 128.48209 -282.344368) (xy 128.473708 -282.353766) (xy 128.467866 -282.37815) (xy 128.491996 -282.47213)
			(xy 128.495693 -282.484077) (xy 128.512472 -282.502586) (xy 128.524 -282.507436) (xy 128.551411 -282.517766)
			(xy 128.602926 -282.54565) (xy 128.64957 -282.581083) (xy 128.690248 -282.623232) (xy 128.724002 -282.671106)
			(xy 128.750038 -282.723579) (xy 128.767743 -282.779416) (xy 128.776702 -282.837304) (xy 128.777238 -282.866592)
			(xy 128.776703 -282.893855) (xy 129.106847 -282.893855) (xy 129.106847 -282.839345) (xy 129.114605 -282.785391)
			(xy 129.129963 -282.733089) (xy 129.152608 -282.683506) (xy 129.18208 -282.637651) (xy 129.217777 -282.596456)
			(xy 129.258975 -282.560762) (xy 129.304832 -282.531294) (xy 129.354417 -282.508653) (xy 129.40672 -282.493299)
			(xy 129.460675 -282.485545) (xy 129.48793 -282.485084) (xy 129.515302 -282.485512) (xy 129.569483 -282.493336)
			(xy 129.621988 -282.508833) (xy 129.671734 -282.531683) (xy 129.717698 -282.561418) (xy 129.738628 -282.579064)
			(xy 129.738882 -282.579318) (xy 129.745968 -282.584905) (xy 129.762885 -282.591151) (xy 129.771902 -282.59151)
			(xy 129.838958 -282.59151) (xy 129.847973 -282.591131) (xy 129.86489 -282.584898) (xy 129.871978 -282.579318)
			(xy 129.871978 -282.579064) (xy 129.872232 -282.579064) (xy 129.893174 -282.561438) (xy 129.939145 -282.531725)
			(xy 129.98889 -282.508887) (xy 130.041388 -282.493393) (xy 130.095562 -282.485561) (xy 130.12293 -282.485084)
			(xy 130.150179 -282.485588) (xy 130.204123 -282.493348) (xy 130.256413 -282.508705) (xy 130.305985 -282.531347)
			(xy 130.351831 -282.560814) (xy 130.393017 -282.596505) (xy 130.428704 -282.637693) (xy 130.458167 -282.683541)
			(xy 130.480805 -282.733115) (xy 130.496159 -282.785407) (xy 130.503914 -282.839351) (xy 130.503914 -282.893849)
			(xy 130.496159 -282.947793) (xy 130.480805 -283.000085) (xy 130.458167 -283.049659) (xy 130.428704 -283.095507)
			(xy 130.393017 -283.136695) (xy 130.351831 -283.172386) (xy 130.305985 -283.201853) (xy 130.256413 -283.224495)
			(xy 130.204123 -283.239852) (xy 130.150179 -283.247612) (xy 130.12293 -283.2481) (xy 130.09556 -283.247616)
			(xy 130.041382 -283.239803) (xy 129.988879 -283.224318) (xy 129.939132 -283.20148) (xy 129.893164 -283.171759)
			(xy 129.872232 -283.15412) (xy 129.871978 -283.153866) (xy 129.864905 -283.14826) (xy 129.847978 -283.142026)
			(xy 129.838958 -283.141674) (xy 129.771902 -283.141674) (xy 129.762886 -283.142038) (xy 129.745969 -283.148281)
			(xy 129.738882 -283.153866) (xy 129.738882 -283.15412) (xy 129.738628 -283.15412) (xy 129.717699 -283.171763)
			(xy 129.671725 -283.201473) (xy 129.621977 -283.224308) (xy 129.569475 -283.239798) (xy 129.515299 -283.247626)
			(xy 129.48793 -283.2481) (xy 129.460675 -283.247655) (xy 129.40672 -283.239901) (xy 129.354417 -283.224547)
			(xy 129.304832 -283.201906) (xy 129.258975 -283.172438) (xy 129.217777 -283.136744) (xy 129.18208 -283.095549)
			(xy 129.152608 -283.049694) (xy 129.129963 -283.000111) (xy 129.114605 -282.947809) (xy 129.106847 -282.893855)
			(xy 128.776703 -282.893855) (xy 128.776652 -282.89643) (xy 128.767344 -282.955376) (xy 128.758696 -282.98394)
			(xy 128.755394 -282.994354) (xy 128.75768 -283.015944) (xy 128.807972 -283.100526) (xy 128.825244 -283.112972)
			(xy 128.836166 -283.115004) (xy 128.861983 -283.120344) (xy 128.911899 -283.137313) (xy 128.959003 -283.160993)
			(xy 129.002398 -283.190934) (xy 129.041256 -283.226565) (xy 129.074838 -283.267208) (xy 129.102503 -283.312087)
			(xy 129.123725 -283.360349) (xy 129.138099 -283.411073) (xy 129.145351 -283.463293) (xy 129.145792 -283.489654)
			(xy 129.145209 -283.519777) (xy 129.135733 -283.579274) (xy 129.117026 -283.636542) (xy 129.089553 -283.690159)
			(xy 129.053995 -283.738793) (xy 129.033016 -283.760418) (xy 129.026178 -283.76782) (xy 129.018456 -283.786418)
			(xy 129.01803 -283.796486) (xy 129.01803 -283.868622) (xy 129.018436 -283.878694) (xy 129.02617 -283.897292)
			(xy 129.033016 -283.90469) (xy 129.054019 -283.926293) (xy 129.089584 -283.974928) (xy 129.117059 -284.02855)
			(xy 129.135762 -284.085825) (xy 129.145227 -284.145328) (xy 129.145792 -284.175454) (xy 129.145306 -284.202705)
			(xy 129.13755 -284.256653) (xy 129.122195 -284.308948) (xy 129.099553 -284.358525) (xy 129.070087 -284.404375)
			(xy 129.034396 -284.445566) (xy 128.993205 -284.481257) (xy 128.947355 -284.510723) (xy 128.897778 -284.533365)
			(xy 128.845483 -284.54872) (xy 128.791535 -284.556476) (xy 128.737033 -284.556476) (xy 128.683085 -284.54872)
			(xy 128.63079 -284.533365) (xy 128.581213 -284.510723) (xy 128.535363 -284.481257) (xy 128.494172 -284.445566)
			(xy 128.458481 -284.404375) (xy 128.429015 -284.358525) (xy 128.406373 -284.308948) (xy 128.391018 -284.256653)
			(xy 128.383262 -284.202705) (xy 128.382776 -284.175454) (xy 128.383374 -284.145332) (xy 128.392847 -284.085836)
			(xy 128.411551 -284.028568) (xy 128.439021 -283.974951) (xy 128.474575 -283.926316) (xy 128.495552 -283.90469)
			(xy 128.502382 -283.897282) (xy 128.510109 -283.878689) (xy 128.510538 -283.868622) (xy 128.510538 -283.796486)
			(xy 128.510136 -283.786414) (xy 128.502401 -283.767815) (xy 128.495552 -283.760418) (xy 128.474564 -283.7388)
			(xy 128.438995 -283.69017) (xy 128.411515 -283.636552) (xy 128.392809 -283.57928) (xy 128.383342 -283.519779)
			(xy 128.382776 -283.489654) (xy 128.383349 -283.459815) (xy 128.392666 -283.400869) (xy 128.401318 -283.372306)
			(xy 128.40462 -283.361892) (xy 128.402334 -283.340302) (xy 128.352042 -283.25572) (xy 128.33477 -283.243274)
			(xy 128.323848 -283.241242) (xy 128.295998 -283.235391) (xy 128.242335 -283.216454) (xy 128.192078 -283.18976)
			(xy 128.146341 -283.155899) (xy 128.106139 -283.115622) (xy 128.072363 -283.069823) (xy 128.045761 -283.019516)
			(xy 128.026924 -282.965818) (xy 128.02108 -282.937966) (xy 128.01854 -282.92552) (xy 128.0033 -282.906216)
			(xy 127.902208 -282.862528) (xy 127.87757 -282.864306) (xy 127.866902 -282.871164) (xy 127.843932 -282.885202)
			(xy 127.794858 -282.907333) (xy 127.743156 -282.922329) (xy 127.689857 -282.929892) (xy 127.66294 -282.930346)
			(xy 127.644921 -282.930129) (xy 127.609046 -282.926692) (xy 127.591312 -282.923488) (xy 127.58166 -282.92171)
			(xy 127.56261 -282.925266) (xy 127.48768 -282.973272) (xy 127.47625 -282.98902) (xy 127.473964 -282.998418)
			(xy 127.466566 -283.025463) (xy 127.444939 -283.07719) (xy 127.415976 -283.125197) (xy 127.380301 -283.16845)
			(xy 127.338682 -283.206018) (xy 127.292014 -283.237092) (xy 127.241301 -283.261004) (xy 127.187636 -283.27724)
			(xy 127.132173 -283.285449) (xy 127.10414 -283.285946) (xy 127.07689 -283.285408) (xy 127.022944 -283.277657)
			(xy 126.970649 -283.262308) (xy 126.921072 -283.239673) (xy 126.875221 -283.210213) (xy 126.834028 -283.174527)
			(xy 126.798334 -283.133342) (xy 126.768864 -283.087497) (xy 126.746219 -283.037924) (xy 126.73086 -282.985633)
			(xy 126.723098 -282.931688) (xy 126.722632 -282.904438) (xy 125.457204 -282.904438) (xy 125.457204 -284.070298)
			(xy 125.457661 -284.080177) (xy 125.465099 -284.09848) (xy 125.471682 -284.105858) (xy 126.07671 -284.710886)
			(xy 126.165864 -284.800294) (xy 126.17324 -284.806559) (xy 126.191284 -284.813509) (xy 126.210619 -284.813258)
			(xy 126.219712 -284.809946) (xy 126.2253 -284.80766) (xy 126.23419 -284.804104) (xy 126.242826 -284.79115)
			(xy 126.246686 -284.784819) (xy 126.250935 -284.77062) (xy 126.251208 -284.76321) (xy 126.251208 -284.719776)
			(xy 126.250887 -284.711496) (xy 126.245571 -284.695813) (xy 126.240794 -284.689042) (xy 126.238762 -284.686756)
			(xy 126.236984 -284.684978) (xy 126.233682 -284.681168) (xy 125.93955 -284.387036) (xy 125.919273 -284.366131)
			(xy 125.883803 -284.319938) (xy 125.854672 -284.269507) (xy 125.83238 -284.215703) (xy 125.817307 -284.159447)
			(xy 125.809714 -284.101704) (xy 125.809248 -284.072584) (xy 125.809248 -284.071822) (xy 125.809372 -284.056789)
			(xy 125.811407 -284.026791) (xy 125.813312 -284.011878) (xy 125.814836 -284.001464) (xy 125.814836 -284.000956)
			(xy 125.815344 -283.997654) (xy 125.816106 -283.99359) (xy 125.816106 -283.993082) (xy 125.81763 -283.985208)
			(xy 125.81763 -283.9847) (xy 125.817884 -283.983684) (xy 125.818138 -283.982414) (xy 125.818392 -283.981398)
			(xy 125.818646 -283.980636) (xy 125.820932 -283.970984) (xy 125.821694 -283.967936) (xy 125.822202 -283.96565)
			(xy 125.822202 -283.965142) (xy 125.822456 -283.963872) (xy 125.82271 -283.96311) (xy 125.82271 -283.962856)
			(xy 125.828552 -283.942282) (xy 125.830838 -283.934916) (xy 125.832108 -283.930852) (xy 125.836934 -283.916374)
			(xy 125.838458 -283.91231) (xy 125.84176 -283.904436) (xy 125.842776 -283.902658) (xy 125.853808 -283.877085)
			(xy 125.881332 -283.828666) (xy 125.914683 -283.78406) (xy 125.933708 -283.76372) (xy 125.933962 -283.763466)
			(xy 125.938788 -283.758386) (xy 125.941328 -283.755846) (xy 125.945392 -283.751528) (xy 125.948694 -283.744162)
			(xy 125.950264 -283.740574) (xy 125.952431 -283.733049) (xy 125.953012 -283.729176) (xy 125.955298 -283.69641)
			(xy 125.955298 -283.695902) (xy 125.95606 -283.68752) (xy 125.951234 -283.670502) (xy 125.945646 -283.662374)
			(xy 125.942852 -283.658564) (xy 125.94082 -283.65577) (xy 125.934216 -283.646118) (xy 125.919551 -283.622744)
			(xy 125.896375 -283.572668) (xy 125.880651 -283.519777) (xy 125.872708 -283.465173) (xy 125.87224 -283.437584)
			(xy 125.87224 -283.431488) (xy 125.873002 -283.417772) (xy 125.875047 -283.388852) (xy 125.886785 -283.332079)
			(xy 125.906978 -283.277735) (xy 125.93516 -283.227072) (xy 125.970682 -283.181256) (xy 126.012728 -283.141341)
			(xy 126.060329 -283.108248) (xy 126.112388 -283.082737) (xy 126.167708 -283.065397) (xy 126.225015 -283.056626)
			(xy 126.254002 -283.056076) (xy 126.281104 -283.056551) (xy 126.334761 -283.064223) (xy 126.386793 -283.079412)
			(xy 126.436151 -283.101812) (xy 126.481842 -283.130972) (xy 126.522946 -283.166306) (xy 126.558636 -283.207101)
			(xy 126.588192 -283.252537) (xy 126.611021 -283.301699) (xy 126.626661 -283.353597) (xy 126.634799 -283.407185)
			(xy 126.63551 -283.434282) (xy 126.63551 -283.438092) (xy 126.634976 -283.467679) (xy 126.625884 -283.52615)
			(xy 126.607872 -283.582515) (xy 126.58137 -283.635423) (xy 126.564644 -283.659834) (xy 126.56439 -283.660088)
			(xy 126.562104 -283.66339) (xy 126.557532 -283.672026) (xy 126.555465 -283.67673) (xy 126.553026 -283.68671)
			(xy 126.552706 -283.691838) (xy 126.552706 -283.698188) (xy 126.5555 -283.730446) (xy 126.556953 -283.738486)
			(xy 126.564215 -283.753113) (xy 126.569724 -283.759148) (xy 126.576328 -283.765752) (xy 127.010414 -284.200092)
			(xy 127.030692 -284.220997) (xy 127.066165 -284.26719) (xy 127.0953 -284.31762) (xy 127.117598 -284.371424)
			(xy 127.132677 -284.42768) (xy 127.140279 -284.485423) (xy 127.140716 -284.514544) (xy 127.140716 -285.853378)
			(xy 127.142494 -285.866332) (xy 127.143002 -285.86811) (xy 127.150735 -285.898836) (xy 127.159014 -285.961652)
			(xy 127.159512 -285.993332) (xy 127.159512 -286.705548) (xy 127.158974 -286.737626) (xy 127.150442 -286.801212)
			(xy 127.142494 -286.832294) (xy 127.140716 -286.838898) (xy 127.140716 -291.507926) (xy 127.141478 -291.516054)
			(xy 127.141478 -291.516562) (xy 127.143082 -291.524079) (xy 127.150062 -291.537763) (xy 127.155194 -291.543486)
			(xy 127.279654 -291.667946) (xy 127.285331 -291.673143) (xy 127.299035 -291.680133) (xy 127.306578 -291.681662)
			(xy 127.307086 -291.681662) (xy 127.315214 -291.682424) (xy 134.236968 -291.682424) (xy 134.245096 -291.681662)
			(xy 134.245604 -291.681662) (xy 134.253124 -291.680063) (xy 134.266814 -291.673089) (xy 134.272528 -291.667946)
			(xy 134.397242 -291.543232) (xy 134.402437 -291.537554) (xy 134.409424 -291.523849) (xy 134.410958 -291.516308)
			(xy 134.410958 -291.5158) (xy 134.41172 -291.507672) (xy 134.41172 -284.719776) (xy 134.411399 -284.711496)
			(xy 134.406084 -284.695813) (xy 134.401306 -284.689042) (xy 134.399274 -284.686756) (xy 134.397496 -284.684978)
			(xy 134.394194 -284.681168) (xy 134.100062 -284.387036) (xy 134.079784 -284.366131) (xy 134.044314 -284.319939)
			(xy 134.015182 -284.269508) (xy 133.992889 -284.215703) (xy 133.977816 -284.159447) (xy 133.970222 -284.101704)
			(xy 133.96976 -284.072584) (xy 133.96976 -284.071822) (xy 133.969884 -284.056789) (xy 133.971919 -284.026791)
			(xy 133.973824 -284.011878) (xy 133.976618 -283.99359) (xy 133.976618 -283.992828) (xy 133.977126 -283.990796)
			(xy 133.977126 -283.990288) (xy 133.97738 -283.988764) (xy 133.977634 -283.987748) (xy 133.977634 -283.987494)
			(xy 133.978396 -283.983684) (xy 133.978396 -283.983176) (xy 133.980174 -283.97581) (xy 133.980174 -283.975556)
			(xy 133.981444 -283.970476) (xy 133.981444 -283.970222) (xy 133.989064 -283.942282) (xy 133.99135 -283.934916)
			(xy 133.99262 -283.930852) (xy 133.997446 -283.916374) (xy 133.99897 -283.91231) (xy 134.002272 -283.904436)
			(xy 134.003288 -283.902658) (xy 134.013793 -283.878262) (xy 134.03978 -283.831936) (xy 134.071087 -283.789024)
			(xy 134.088886 -283.769308) (xy 134.093966 -283.763974) (xy 134.0993 -283.758386) (xy 134.10565 -283.752036)
			(xy 134.10946 -283.743654) (xy 134.11111 -283.73983) (xy 134.113275 -283.731787) (xy 134.113778 -283.727652)
			(xy 134.11581 -283.69641) (xy 134.11581 -283.695902) (xy 134.116572 -283.68752) (xy 134.111746 -283.670502)
			(xy 134.106158 -283.662374) (xy 134.103364 -283.658564) (xy 134.101332 -283.65577) (xy 134.094728 -283.646118)
			(xy 134.080063 -283.622744) (xy 134.056886 -283.572669) (xy 134.041162 -283.519778) (xy 134.033218 -283.465173)
			(xy 134.032752 -283.437584) (xy 134.032752 -283.431488) (xy 134.033514 -283.417772) (xy 134.035559 -283.388853)
			(xy 134.047297 -283.33208) (xy 134.06749 -283.277737) (xy 134.095672 -283.227074) (xy 134.131195 -283.181259)
			(xy 134.173241 -283.141346) (xy 134.220842 -283.108254) (xy 134.272901 -283.082745) (xy 134.328221 -283.065406)
			(xy 134.385527 -283.056637) (xy 134.414514 -283.056076) (xy 134.441615 -283.056552) (xy 134.495271 -283.064225)
			(xy 134.547302 -283.079415) (xy 134.596659 -283.101816) (xy 134.642348 -283.130976) (xy 134.683451 -283.16631)
			(xy 134.719139 -283.207105) (xy 134.748694 -283.25254) (xy 134.771522 -283.301701) (xy 134.787161 -283.353598)
			(xy 134.795299 -283.407186) (xy 134.796022 -283.434282) (xy 134.796022 -283.438092) (xy 134.795488 -283.467679)
			(xy 134.786394 -283.526149) (xy 134.768378 -283.582512) (xy 134.741872 -283.635416) (xy 134.725156 -283.659834)
			(xy 134.724902 -283.660088) (xy 134.722616 -283.66339) (xy 134.718044 -283.672026) (xy 134.715976 -283.67673)
			(xy 134.713537 -283.68671) (xy 134.713218 -283.691838) (xy 134.713218 -283.698188) (xy 134.716012 -283.730446)
			(xy 134.717465 -283.738486) (xy 134.724729 -283.753111) (xy 134.730236 -283.759148) (xy 134.73684 -283.765752)
			(xy 135.170926 -284.200092) (xy 135.191208 -284.220995) (xy 135.226687 -284.267185) (xy 135.255828 -284.317615)
			(xy 135.27813 -284.37142) (xy 135.293213 -284.427677) (xy 135.300816 -284.485422) (xy 135.301228 -284.514544)
			(xy 135.301228 -291.713158) (xy 135.300768 -291.742277) (xy 135.293158 -291.800014) (xy 135.278074 -291.856264)
			(xy 135.255777 -291.910064) (xy 135.226646 -291.960492) (xy 135.191181 -292.006685) (xy 135.170926 -292.02761)
			(xy 134.756906 -292.44163) (xy 134.736003 -292.461912) (xy 134.689812 -292.49739) (xy 134.639383 -292.526531)
			(xy 134.585578 -292.548833) (xy 134.529321 -292.563915) (xy 134.471576 -292.571518) (xy 134.442454 -292.571932)
			(xy 127.109982 -292.571932) (xy 127.080862 -292.571475) (xy 127.023122 -292.563869) (xy 126.966869 -292.54879)
			(xy 126.913066 -292.526496) (xy 126.862634 -292.497368) (xy 126.816436 -292.461905) (xy 126.79553 -292.44163)
			(xy 126.732792 -292.379146) (xy 126.731776 -292.37813) (xy 126.724364 -292.371446) (xy 126.705931 -292.363849)
			(xy 126.685993 -292.363849) (xy 126.66756 -292.371446) (xy 126.660148 -292.37813) (xy 126.653036 -292.385242)
			(xy 126.607316 -292.430708) (xy 126.60376 -292.434264) (xy 126.596394 -292.44163) (xy 126.575491 -292.461911)
			(xy 126.5293 -292.497389) (xy 126.47887 -292.526527) (xy 126.425065 -292.548828) (xy 126.368808 -292.563909)
			(xy 126.311064 -292.57151) (xy 126.281942 -292.571932) (xy 118.61038 -292.571932) (xy 118.584415 -292.571539)
			(xy 118.532846 -292.565431) (xy 118.50751 -292.55974) (xy 118.501668 -292.558216) (xy 110.436914 -292.558216)
			(xy 110.407785 -292.557747) (xy 110.35003 -292.55011) (xy 110.293767 -292.534993) (xy 110.239962 -292.512654)
			(xy 110.189537 -292.483477) (xy 110.143357 -292.44796) (xy 110.122462 -292.42766) (xy 110.10011 -292.405308)
			(xy 110.092698 -292.398624) (xy 110.074265 -292.391027) (xy 110.054327 -292.391027) (xy 110.035894 -292.398624)
			(xy 110.028482 -292.405308) (xy 109.978698 -292.455092) (xy 109.957757 -292.475441) (xy 109.911796 -292.511459)
			(xy 109.861828 -292.541673) (xy 109.808583 -292.565643) (xy 109.780832 -292.574726) (xy 109.745898 -292.584916)
			(xy 109.67396 -292.595878) (xy 109.637576 -292.59657) (xy 109.636814 -292.59657) (xy 109.621828 -292.596316)
			(xy 102.354126 -292.596316) (xy 102.344165 -292.596804) (xy 102.325744 -292.604395) (xy 102.318312 -292.611048)
			(xy 101.66477 -293.264336) (xy 101.658092 -293.271745) (xy 101.650507 -293.290172) (xy 101.650521 -293.310098)
			(xy 101.658131 -293.328514) (xy 101.66477 -293.335964) (xy 101.924104 -293.595298) (xy 101.929782 -293.600493)
			(xy 101.943487 -293.607476) (xy 101.951028 -293.609014) (xy 101.951536 -293.609014) (xy 101.959664 -293.609776)
			(xy 134.772654 -293.609776)
		)
		(stroke
			(width 0)
			(type solid)
		)
		(fill yes)
		(layer "In7.Cu")
		(net "GND")
	)
	(gr_line
		(start 7.210552 -30.922468)
		(end 7.501382 -30.631638)
		(stroke
			(width 0.08255)
			(type default)
		)
		(layer "In7.Cu")
	)
	(gr_line
		(start 8.47979 -30.632908)
		(end 8.58012 -30.733238)
		(stroke
			(width 0.08255)
			(type default)
		)
		(layer "In7.Cu")
	)
	(gr_line
		(start 8.58012 -30.733238)
		(end 9.07542 -30.733238)
		(stroke
			(width 0.08255)
			(type default)
		)
		(layer "In7.Cu")
	)
	(gr_line
		(start 9.064752 -29.12237)
		(end 9.310116 -28.877006)
		(stroke
			(width 0.08255)
			(type default)
		)
		(layer "In7.Cu")
	)
	(gr_line
		(start 9.07542 -30.733238)
		(end 9.17575 -30.632908)
		(stroke
			(width 0.08255)
			(type default)
		)
		(layer "In7.Cu")
	)
	(gr_line
		(start 9.310116 -28.877006)
		(end 9.416796 -28.83281)
		(stroke
			(width 0.08255)
			(type default)
		)
		(layer "In7.Cu")
	)
	(gr_line
		(start 10.190226 -31.293054)
		(end 10.540746 -31.643574)
		(stroke
			(width 0.08255)
			(type default)
		)
		(layer "In7.Cu")
	)
	(gr_line
		(start 10.190226 -31.151322)
		(end 10.190226 -31.293054)
		(stroke
			(width 0.08255)
			(type default)
		)
		(layer "In7.Cu")
	)
	(gr_line
		(start 10.540746 -31.643574)
		(end 10.682478 -31.643574)
		(stroke
			(width 0.08255)
			(type default)
		)
		(layer "In7.Cu")
	)
	(gr_line
		(start 12.897104 -32.89808)
		(end 13.089636 -33.354772)
		(stroke
			(width 0.08255)
			(type default)
		)
		(layer "In7.Cu")
	)
	(gr_line
		(start 12.950698 -32.766254)
		(end 12.897104 -32.89808)
		(stroke
			(width 0.08255)
			(type default)
		)
		(layer "In7.Cu")
	)
	(gr_line
		(start 13.089636 -33.354772)
		(end 13.221208 -33.408112)
		(stroke
			(width 0.08255)
			(type default)
		)
		(layer "In7.Cu")
	)
	(gr_line
		(start 13.360654 -33.998154)
		(end 13.553186 -34.454846)
		(stroke
			(width 0.08255)
			(type default)
		)
		(layer "In7.Cu")
	)
	(gr_line
		(start 13.414248 -33.866836)
		(end 13.360654 -33.998154)
		(stroke
			(width 0.08255)
			(type default)
		)
		(layer "In7.Cu")
	)
	(gr_line
		(start 13.553186 -34.454846)
		(end 13.684758 -34.50844)
		(stroke
			(width 0.08255)
			(type default)
		)
		(layer "In7.Cu")
	)
	(gr_line
		(start 17.065498 -102.474014)
		(end 17.065498 -102.474522)
		(stroke
			(width 0.08255)
			(type default)
		)
		(layer "In7.Cu")
	)
	(gr_line
		(start 17.077436 -102.513892)
		(end 17.07769 -102.514654)
		(stroke
			(width 0.08255)
			(type default)
		)
		(layer "In7.Cu")
	)
	(gr_line
		(start 33.2105 -34.52241)
		(end 33.50133 -34.23158)
		(stroke
			(width 0.08255)
			(type default)
		)
		(layer "In7.Cu")
	)
	(gr_line
		(start 34.529268 -36.963604)
		(end 34.536888 -37.459158)
		(stroke
			(width 0.08255)
			(type default)
		)
		(layer "In7.Cu")
	)
	(gr_line
		(start 34.536888 -37.459158)
		(end 34.638996 -37.557964)
		(stroke
			(width 0.08255)
			(type default)
		)
		(layer "In7.Cu")
	)
	(gr_line
		(start 34.54781 -38.157404)
		(end 34.55543 -38.652704)
		(stroke
			(width 0.08255)
			(type default)
		)
		(layer "In7.Cu")
	)
	(gr_line
		(start 34.55543 -38.652704)
		(end 34.657538 -38.75151)
		(stroke
			(width 0.08255)
			(type default)
		)
		(layer "In7.Cu")
	)
	(gr_line
		(start 34.628328 -36.861496)
		(end 34.529268 -36.963604)
		(stroke
			(width 0.08255)
			(type default)
		)
		(layer "In7.Cu")
	)
	(gr_line
		(start 34.64687 -38.05555)
		(end 34.54781 -38.157404)
		(stroke
			(width 0.08255)
			(type default)
		)
		(layer "In7.Cu")
	)
	(gr_line
		(start 45.73397 -271.3736)
		(end 45.77969 -271.41932)
		(stroke
			(width 0.05715)
			(type default)
		)
		(layer "In7.Cu")
	)
	(gr_line
		(start 45.73397 -271.345152)
		(end 45.73397 -271.3736)
		(stroke
			(width 0.05715)
			(type default)
		)
		(layer "In7.Cu")
	)
	(gr_line
		(start 46.23562 -273.670014)
		(end 46.34992 -273.784314)
		(stroke
			(width 0.05715)
			(type default)
		)
		(layer "In7.Cu")
	)
	(gr_line
		(start 46.34992 -273.784314)
		(end 46.34992 -274.049744)
		(stroke
			(width 0.05715)
			(type default)
		)
		(layer "In7.Cu")
	)
	(gr_line
		(start 46.683676 -271.421352)
		(end 46.729396 -271.467072)
		(stroke
			(width 0.05715)
			(type default)
		)
		(layer "In7.Cu")
	)
	(gr_line
		(start 46.683676 -271.392904)
		(end 46.683676 -271.421352)
		(stroke
			(width 0.05715)
			(type default)
		)
		(layer "In7.Cu")
	)
	(gr_line
		(start 47.18558 -275.570188)
		(end 47.29988 -275.684488)
		(stroke
			(width 0.05715)
			(type default)
		)
		(layer "In7.Cu")
	)
	(gr_line
		(start 47.29988 -275.684488)
		(end 47.29988 -275.949918)
		(stroke
			(width 0.05715)
			(type default)
		)
		(layer "In7.Cu")
	)
	(gr_line
		(start 47.63389 -271.3736)
		(end 47.67961 -271.41932)
		(stroke
			(width 0.05715)
			(type default)
		)
		(layer "In7.Cu")
	)
	(gr_line
		(start 47.63389 -271.345152)
		(end 47.63389 -271.3736)
		(stroke
			(width 0.05715)
			(type default)
		)
		(layer "In7.Cu")
	)
	(gr_line
		(start 48.13554 -273.670014)
		(end 48.24984 -273.784314)
		(stroke
			(width 0.05715)
			(type default)
		)
		(layer "In7.Cu")
	)
	(gr_line
		(start 48.24984 -273.784314)
		(end 48.24984 -274.049744)
		(stroke
			(width 0.05715)
			(type default)
		)
		(layer "In7.Cu")
	)
	(gr_line
		(start 53.333904 -271.3736)
		(end 53.379624 -271.41932)
		(stroke
			(width 0.05715)
			(type default)
		)
		(layer "In7.Cu")
	)
	(gr_line
		(start 53.333904 -271.345152)
		(end 53.333904 -271.3736)
		(stroke
			(width 0.05715)
			(type default)
		)
		(layer "In7.Cu")
	)
	(gr_line
		(start 53.835554 -273.670014)
		(end 53.949854 -273.784314)
		(stroke
			(width 0.05715)
			(type default)
		)
		(layer "In7.Cu")
	)
	(gr_line
		(start 53.949854 -273.784314)
		(end 53.949854 -274.049744)
		(stroke
			(width 0.05715)
			(type default)
		)
		(layer "In7.Cu")
	)
	(gr_line
		(start 57.133998 -271.3736)
		(end 57.179718 -271.41932)
		(stroke
			(width 0.05715)
			(type default)
		)
		(layer "In7.Cu")
	)
	(gr_line
		(start 57.133998 -271.345152)
		(end 57.133998 -271.3736)
		(stroke
			(width 0.05715)
			(type default)
		)
		(layer "In7.Cu")
	)
	(gr_line
		(start 57.415938 -271.3736)
		(end 57.370218 -271.41932)
		(stroke
			(width 0.05715)
			(type default)
		)
		(layer "In7.Cu")
	)
	(gr_line
		(start 57.415938 -271.345152)
		(end 57.415938 -271.3736)
		(stroke
			(width 0.05715)
			(type default)
		)
		(layer "In7.Cu")
	)
	(gr_line
		(start 57.635648 -273.670014)
		(end 57.749948 -273.784314)
		(stroke
			(width 0.05715)
			(type default)
		)
		(layer "In7.Cu")
	)
	(gr_line
		(start 57.635648 -273.479514)
		(end 57.749948 -273.365214)
		(stroke
			(width 0.05715)
			(type default)
		)
		(layer "In7.Cu")
	)
	(gr_line
		(start 57.749948 -273.784314)
		(end 57.749948 -274.049744)
		(stroke
			(width 0.05715)
			(type default)
		)
		(layer "In7.Cu")
	)
	(gr_line
		(start 57.749948 -273.365214)
		(end 57.749948 -273.099784)
		(stroke
			(width 0.05715)
			(type default)
		)
		(layer "In7.Cu")
	)
	(gr_line
		(start 59.210448 -30.922468)
		(end 59.501278 -30.631638)
		(stroke
			(width 0.08255)
			(type default)
		)
		(layer "In7.Cu")
	)
	(gr_line
		(start 60.479686 -30.632908)
		(end 60.580016 -30.733238)
		(stroke
			(width 0.08255)
			(type default)
		)
		(layer "In7.Cu")
	)
	(gr_line
		(start 60.580016 -30.733238)
		(end 61.075316 -30.733238)
		(stroke
			(width 0.08255)
			(type default)
		)
		(layer "In7.Cu")
	)
	(gr_line
		(start 61.075316 -30.733238)
		(end 61.175646 -30.632908)
		(stroke
			(width 0.08255)
			(type default)
		)
		(layer "In7.Cu")
	)
	(gr_line
		(start 62.285118 -31.388304)
		(end 62.635638 -31.738824)
		(stroke
			(width 0.08255)
			(type default)
		)
		(layer "In7.Cu")
	)
	(gr_line
		(start 62.285118 -31.246318)
		(end 62.285118 -31.388304)
		(stroke
			(width 0.08255)
			(type default)
		)
		(layer "In7.Cu")
	)
	(gr_line
		(start 62.635638 -31.738824)
		(end 62.777624 -31.738824)
		(stroke
			(width 0.08255)
			(type default)
		)
		(layer "In7.Cu")
	)
	(gr_line
		(start 85.210396 -30.922468)
		(end 85.44941 -30.683454)
		(stroke
			(width 0.08255)
			(type default)
		)
		(layer "In7.Cu")
	)
	(gr_line
		(start 85.210396 -30.058868)
		(end 85.501226 -30.349698)
		(stroke
			(width 0.08255)
			(type default)
		)
		(layer "In7.Cu")
	)
	(gr_line
		(start 85.44941 -30.683454)
		(end 85.57133 -30.632908)
		(stroke
			(width 0.08255)
			(type default)
		)
		(layer "In7.Cu")
	)
	(gr_line
		(start 85.501226 -30.349698)
		(end 85.574378 -30.349698)
		(stroke
			(width 0.08255)
			(type default)
		)
		(layer "In7.Cu")
	)
	(gr_line
		(start 86.55685 -30.349698)
		(end 87.28075 -30.349698)
		(stroke
			(width 0.08255)
			(type default)
		)
		(layer "In7.Cu")
	)
	(gr_line
		(start 86.55812 -30.632908)
		(end 86.67115 -30.745938)
		(stroke
			(width 0.08255)
			(type default)
		)
		(layer "In7.Cu")
	)
	(gr_line
		(start 86.67115 -30.745938)
		(end 87.16645 -30.745938)
		(stroke
			(width 0.08255)
			(type default)
		)
		(layer "In7.Cu")
	)
	(gr_line
		(start 87.16645 -30.745938)
		(end 87.27948 -30.632908)
		(stroke
			(width 0.08255)
			(type default)
		)
		(layer "In7.Cu")
	)
	(gr_line
		(start 88.359488 -31.499556)
		(end 88.627966 -31.91637)
		(stroke
			(width 0.08255)
			(type default)
		)
		(layer "In7.Cu")
	)
	(gr_line
		(start 88.393524 -31.343092)
		(end 88.359488 -31.499556)
		(stroke
			(width 0.08255)
			(type default)
		)
		(layer "In7.Cu")
	)
	(gr_line
		(start 88.627966 -31.91637)
		(end 88.784176 -31.950406)
		(stroke
			(width 0.08255)
			(type default)
		)
		(layer "In7.Cu")
	)
	(gr_line
		(start 88.631014 -31.189168)
		(end 89.02319 -31.798006)
		(stroke
			(width 0.08255)
			(type default)
		)
		(layer "In7.Cu")
	)
	(gr_line
		(start 123.31065 -30.922468)
		(end 123.60148 -30.631638)
		(stroke
			(width 0.08255)
			(type default)
		)
		(layer "In7.Cu")
	)
	(gr_line
		(start 124.579888 -30.632908)
		(end 124.680218 -30.733238)
		(stroke
			(width 0.08255)
			(type default)
		)
		(layer "In7.Cu")
	)
	(gr_line
		(start 124.680218 -30.733238)
		(end 125.175518 -30.733238)
		(stroke
			(width 0.08255)
			(type default)
		)
		(layer "In7.Cu")
	)
	(gr_line
		(start 125.16485 -29.12237)
		(end 125.410214 -28.877006)
		(stroke
			(width 0.08255)
			(type default)
		)
		(layer "In7.Cu")
	)
	(gr_line
		(start 125.175518 -30.733238)
		(end 125.275848 -30.632908)
		(stroke
			(width 0.08255)
			(type default)
		)
		(layer "In7.Cu")
	)
	(gr_line
		(start 125.410214 -28.877006)
		(end 125.516894 -28.83281)
		(stroke
			(width 0.08255)
			(type default)
		)
		(layer "In7.Cu")
	)
	(gr_line
		(start 126.290324 -31.293054)
		(end 126.640844 -31.643574)
		(stroke
			(width 0.08255)
			(type default)
		)
		(layer "In7.Cu")
	)
	(gr_line
		(start 126.290324 -31.151322)
		(end 126.290324 -31.293054)
		(stroke
			(width 0.08255)
			(type default)
		)
		(layer "In7.Cu")
	)
	(gr_line
		(start 126.640844 -31.643574)
		(end 126.782576 -31.643574)
		(stroke
			(width 0.08255)
			(type default)
		)
		(layer "In7.Cu")
	)
	(gr_line
		(start 128.997202 -32.89808)
		(end 129.189734 -33.354772)
		(stroke
			(width 0.08255)
			(type default)
		)
		(layer "In7.Cu")
	)
	(gr_line
		(start 129.050796 -32.766254)
		(end 128.997202 -32.89808)
		(stroke
			(width 0.08255)
			(type default)
		)
		(layer "In7.Cu")
	)
	(gr_line
		(start 129.189734 -33.354772)
		(end 129.321306 -33.408112)
		(stroke
			(width 0.08255)
			(type default)
		)
		(layer "In7.Cu")
	)
	(gr_line
		(start 129.460752 -33.998154)
		(end 129.653284 -34.454846)
		(stroke
			(width 0.08255)
			(type default)
		)
		(layer "In7.Cu")
	)
	(gr_line
		(start 129.514346 -33.866836)
		(end 129.460752 -33.998154)
		(stroke
			(width 0.08255)
			(type default)
		)
		(layer "In7.Cu")
	)
	(gr_line
		(start 129.653284 -34.454846)
		(end 129.784856 -34.50844)
		(stroke
			(width 0.08255)
			(type default)
		)
		(layer "In7.Cu")
	)
	(gr_line
		(start 133.165596 -102.474014)
		(end 133.165596 -102.474522)
		(stroke
			(width 0.08255)
			(type default)
		)
		(layer "In7.Cu")
	)
	(gr_line
		(start 133.177534 -102.513892)
		(end 133.177788 -102.514654)
		(stroke
			(width 0.08255)
			(type default)
		)
		(layer "In7.Cu")
	)
	(gr_line
		(start 149.310598 -34.52241)
		(end 149.601428 -34.23158)
		(stroke
			(width 0.08255)
			(type default)
		)
		(layer "In7.Cu")
	)
	(gr_line
		(start 150.629366 -36.963604)
		(end 150.636986 -37.459158)
		(stroke
			(width 0.08255)
			(type default)
		)
		(layer "In7.Cu")
	)
	(gr_line
		(start 150.636986 -37.459158)
		(end 150.739094 -37.557964)
		(stroke
			(width 0.08255)
			(type default)
		)
		(layer "In7.Cu")
	)
	(gr_line
		(start 150.647908 -38.157404)
		(end 150.655528 -38.652704)
		(stroke
			(width 0.08255)
			(type default)
		)
		(layer "In7.Cu")
	)
	(gr_line
		(start 150.655528 -38.652704)
		(end 150.757636 -38.75151)
		(stroke
			(width 0.08255)
			(type default)
		)
		(layer "In7.Cu")
	)
	(gr_line
		(start 150.728426 -36.861496)
		(end 150.629366 -36.963604)
		(stroke
			(width 0.08255)
			(type default)
		)
		(layer "In7.Cu")
	)
	(gr_line
		(start 150.746968 -38.05555)
		(end 150.647908 -38.157404)
		(stroke
			(width 0.08255)
			(type default)
		)
		(layer "In7.Cu")
	)
	(gr_line
		(start 161.834068 -271.3736)
		(end 161.879788 -271.41932)
		(stroke
			(width 0.05715)
			(type default)
		)
		(layer "In7.Cu")
	)
	(gr_line
		(start 161.834068 -271.345152)
		(end 161.834068 -271.3736)
		(stroke
			(width 0.05715)
			(type default)
		)
		(layer "In7.Cu")
	)
	(gr_line
		(start 162.335718 -273.670014)
		(end 162.450018 -273.784314)
		(stroke
			(width 0.05715)
			(type default)
		)
		(layer "In7.Cu")
	)
	(gr_line
		(start 162.450018 -273.784314)
		(end 162.450018 -274.049744)
		(stroke
			(width 0.05715)
			(type default)
		)
		(layer "In7.Cu")
	)
	(gr_line
		(start 162.783774 -271.421352)
		(end 162.829494 -271.467072)
		(stroke
			(width 0.05715)
			(type default)
		)
		(layer "In7.Cu")
	)
	(gr_line
		(start 162.783774 -271.392904)
		(end 162.783774 -271.421352)
		(stroke
			(width 0.05715)
			(type default)
		)
		(layer "In7.Cu")
	)
	(gr_line
		(start 163.285678 -275.570188)
		(end 163.399978 -275.684488)
		(stroke
			(width 0.05715)
			(type default)
		)
		(layer "In7.Cu")
	)
	(gr_line
		(start 163.399978 -275.684488)
		(end 163.399978 -275.949918)
		(stroke
			(width 0.05715)
			(type default)
		)
		(layer "In7.Cu")
	)
	(gr_line
		(start 163.733988 -271.3736)
		(end 163.779708 -271.41932)
		(stroke
			(width 0.05715)
			(type default)
		)
		(layer "In7.Cu")
	)
	(gr_line
		(start 163.733988 -271.345152)
		(end 163.733988 -271.3736)
		(stroke
			(width 0.05715)
			(type default)
		)
		(layer "In7.Cu")
	)
	(gr_line
		(start 164.235638 -273.670014)
		(end 164.349938 -273.784314)
		(stroke
			(width 0.05715)
			(type default)
		)
		(layer "In7.Cu")
	)
	(gr_line
		(start 164.349938 -273.784314)
		(end 164.349938 -274.049744)
		(stroke
			(width 0.05715)
			(type default)
		)
		(layer "In7.Cu")
	)
	(gr_line
		(start 166.509954 -372.508018)
		(end 166.509954 -372.890034)
		(stroke
			(width 0.08255)
			(type default)
		)
		(layer "In7.Cu")
	)
	(gr_line
		(start 166.509954 -371.971824)
		(end 166.509954 -371.590062)
		(stroke
			(width 0.08255)
			(type default)
		)
		(layer "In7.Cu")
	)
	(gr_line
		(start 166.636954 -372.381018)
		(end 166.509954 -372.508018)
		(stroke
			(width 0.08255)
			(type default)
		)
		(layer "In7.Cu")
	)
	(gr_line
		(start 166.636954 -372.098824)
		(end 166.509954 -371.971824)
		(stroke
			(width 0.08255)
			(type default)
		)
		(layer "In7.Cu")
	)
	(gr_line
		(start 167.62222 -368.524028)
		(end 167.626284 -368.64798)
		(stroke
			(width 0.08255)
			(type default)
		)
		(layer "In7.Cu")
	)
	(gr_line
		(start 167.96131 -368.162586)
		(end 167.62222 -368.524028)
		(stroke
			(width 0.08255)
			(type default)
		)
		(layer "In7.Cu")
	)
	(gr_line
		(start 168.085262 -368.158522)
		(end 167.96131 -368.162586)
		(stroke
			(width 0.08255)
			(type default)
		)
		(layer "In7.Cu")
	)
	(gr_line
		(start 168.292526 -368.351562)
		(end 167.832024 -368.842798)
		(stroke
			(width 0.08255)
			(type default)
		)
		(layer "In7.Cu")
	)
	(gr_line
		(start 168.710102 -370.872004)
		(end 168.710102 -370.489988)
		(stroke
			(width 0.08255)
			(type default)
		)
		(layer "In7.Cu")
	)
	(gr_line
		(start 168.837102 -370.999004)
		(end 168.710102 -370.872004)
		(stroke
			(width 0.08255)
			(type default)
		)
		(layer "In7.Cu")
	)
	(gr_line
		(start 169.434002 -271.3736)
		(end 169.479722 -271.41932)
		(stroke
			(width 0.05715)
			(type default)
		)
		(layer "In7.Cu")
	)
	(gr_line
		(start 169.434002 -271.345152)
		(end 169.434002 -271.3736)
		(stroke
			(width 0.05715)
			(type default)
		)
		(layer "In7.Cu")
	)
	(gr_line
		(start 169.935652 -273.670014)
		(end 170.049952 -273.784314)
		(stroke
			(width 0.05715)
			(type default)
		)
		(layer "In7.Cu")
	)
	(gr_line
		(start 170.049952 -273.784314)
		(end 170.049952 -274.049744)
		(stroke
			(width 0.05715)
			(type default)
		)
		(layer "In7.Cu")
	)
	(gr_line
		(start 173.10989 -370.872004)
		(end 173.10989 -370.489988)
		(stroke
			(width 0.08255)
			(type default)
		)
		(layer "In7.Cu")
	)
	(gr_line
		(start 173.234096 -271.3736)
		(end 173.279816 -271.41932)
		(stroke
			(width 0.05715)
			(type default)
		)
		(layer "In7.Cu")
	)
	(gr_line
		(start 173.234096 -271.345152)
		(end 173.234096 -271.3736)
		(stroke
			(width 0.05715)
			(type default)
		)
		(layer "In7.Cu")
	)
	(gr_line
		(start 173.23689 -370.999004)
		(end 173.10989 -370.872004)
		(stroke
			(width 0.08255)
			(type default)
		)
		(layer "In7.Cu")
	)
	(gr_line
		(start 173.516036 -271.3736)
		(end 173.470316 -271.41932)
		(stroke
			(width 0.05715)
			(type default)
		)
		(layer "In7.Cu")
	)
	(gr_line
		(start 173.516036 -271.345152)
		(end 173.516036 -271.3736)
		(stroke
			(width 0.05715)
			(type default)
		)
		(layer "In7.Cu")
	)
	(gr_line
		(start 173.735746 -273.670014)
		(end 173.850046 -273.784314)
		(stroke
			(width 0.05715)
			(type default)
		)
		(layer "In7.Cu")
	)
	(gr_line
		(start 173.735746 -273.479514)
		(end 173.850046 -273.365214)
		(stroke
			(width 0.05715)
			(type default)
		)
		(layer "In7.Cu")
	)
	(gr_line
		(start 173.850046 -273.784314)
		(end 173.850046 -274.049744)
		(stroke
			(width 0.05715)
			(type default)
		)
		(layer "In7.Cu")
	)
	(gr_line
		(start 173.850046 -273.365214)
		(end 173.850046 -273.099784)
		(stroke
			(width 0.05715)
			(type default)
		)
		(layer "In7.Cu")
	)
	(gr_line
		(start 175.310038 -371.971824)
		(end 175.310038 -371.590062)
		(stroke
			(width 0.08255)
			(type default)
		)
		(layer "In7.Cu")
	)
	(gr_line
		(start 175.310546 -30.922468)
		(end 175.601376 -30.631638)
		(stroke
			(width 0.08255)
			(type default)
		)
		(layer "In7.Cu")
	)
	(gr_line
		(start 175.437038 -372.098824)
		(end 175.310038 -371.971824)
		(stroke
			(width 0.08255)
			(type default)
		)
		(layer "In7.Cu")
	)
	(gr_line
		(start 176.579784 -30.632908)
		(end 176.680114 -30.733238)
		(stroke
			(width 0.08255)
			(type default)
		)
		(layer "In7.Cu")
	)
	(gr_line
		(start 176.680114 -30.733238)
		(end 177.175414 -30.733238)
		(stroke
			(width 0.08255)
			(type default)
		)
		(layer "In7.Cu")
	)
	(gr_line
		(start 176.73066 -365.294672)
		(end 176.730406 -365.294164)
		(stroke
			(width 0.08255)
			(type default)
		)
		(layer "In7.Cu")
	)
	(gr_line
		(start 176.779936 -365.178848)
		(end 176.731422 -365.292894)
		(stroke
			(width 0.08255)
			(type default)
		)
		(layer "In7.Cu")
	)
	(gr_line
		(start 177.175414 -30.733238)
		(end 177.275744 -30.632908)
		(stroke
			(width 0.08255)
			(type default)
		)
		(layer "In7.Cu")
	)
	(gr_line
		(start 177.239676 -364.993682)
		(end 176.779936 -365.178848)
		(stroke
			(width 0.08255)
			(type default)
		)
		(layer "In7.Cu")
	)
	(gr_line
		(start 177.353976 -365.042196)
		(end 177.239676 -364.993682)
		(stroke
			(width 0.08255)
			(type default)
		)
		(layer "In7.Cu")
	)
	(gr_line
		(start 177.877978 -364.709202)
		(end 177.815494 -364.856522)
		(stroke
			(width 0.08255)
			(type default)
		)
		(layer "In7.Cu")
	)
	(gr_line
		(start 178.207162 -363.370114)
		(end 178.160934 -363.48543)
		(stroke
			(width 0.08255)
			(type default)
		)
		(layer "In7.Cu")
	)
	(gr_line
		(start 178.337718 -364.524036)
		(end 177.877978 -364.709202)
		(stroke
			(width 0.08255)
			(type default)
		)
		(layer "In7.Cu")
	)
	(gr_line
		(start 178.385216 -31.388304)
		(end 178.735736 -31.738824)
		(stroke
			(width 0.08255)
			(type default)
		)
		(layer "In7.Cu")
	)
	(gr_line
		(start 178.385216 -31.246318)
		(end 178.385216 -31.388304)
		(stroke
			(width 0.08255)
			(type default)
		)
		(layer "In7.Cu")
	)
	(gr_line
		(start 178.485038 -364.586774)
		(end 178.337718 -364.524036)
		(stroke
			(width 0.08255)
			(type default)
		)
		(layer "In7.Cu")
	)
	(gr_line
		(start 178.662584 -363.174534)
		(end 178.207162 -363.370114)
		(stroke
			(width 0.08255)
			(type default)
		)
		(layer "In7.Cu")
	)
	(gr_line
		(start 178.735736 -31.738824)
		(end 178.877722 -31.738824)
		(stroke
			(width 0.08255)
			(type default)
		)
		(layer "In7.Cu")
	)
	(gr_line
		(start 178.778154 -363.220508)
		(end 178.662584 -363.174534)
		(stroke
			(width 0.08255)
			(type default)
		)
		(layer "In7.Cu")
	)
	(gr_line
		(start 178.890422 -363.480604)
		(end 178.271678 -363.746034)
		(stroke
			(width 0.08255)
			(type default)
		)
		(layer "In7.Cu")
	)
	(gr_line
		(start 179.00904 -364.25378)
		(end 178.946556 -364.4011)
		(stroke
			(width 0.08255)
			(type default)
		)
		(layer "In7.Cu")
	)
	(gr_line
		(start 179.281074 -362.909358)
		(end 179.234846 -363.024674)
		(stroke
			(width 0.08255)
			(type default)
		)
		(layer "In7.Cu")
	)
	(gr_line
		(start 179.46878 -364.068614)
		(end 179.00904 -364.25378)
		(stroke
			(width 0.08255)
			(type default)
		)
		(layer "In7.Cu")
	)
	(gr_line
		(start 179.6161 -364.131352)
		(end 179.46878 -364.068614)
		(stroke
			(width 0.08255)
			(type default)
		)
		(layer "In7.Cu")
	)
	(gr_line
		(start 179.736496 -362.713778)
		(end 179.281074 -362.909358)
		(stroke
			(width 0.08255)
			(type default)
		)
		(layer "In7.Cu")
	)
	(gr_line
		(start 179.852066 -362.759752)
		(end 179.736496 -362.713778)
		(stroke
			(width 0.08255)
			(type default)
		)
		(layer "In7.Cu")
	)
	(gr_line
		(start 179.964334 -363.019848)
		(end 179.34559 -363.285278)
		(stroke
			(width 0.08255)
			(type default)
		)
		(layer "In7.Cu")
	)
	(gr_line
		(start 180.140102 -363.798358)
		(end 180.077618 -363.945678)
		(stroke
			(width 0.08255)
			(type default)
		)
		(layer "In7.Cu")
	)
	(gr_line
		(start 180.3146 -362.5596)
		(end 180.3146 -362.559346)
		(stroke
			(width 0.08255)
			(type default)
		)
		(layer "In7.Cu")
	)
	(gr_line
		(start 180.507894 -362.764832)
		(end 180.501036 -362.771436)
		(stroke
			(width 0.08255)
			(type default)
		)
		(layer "In7.Cu")
	)
	(gr_line
		(start 180.599842 -363.613192)
		(end 180.140102 -363.798358)
		(stroke
			(width 0.08255)
			(type default)
		)
		(layer "In7.Cu")
	)
	(gr_line
		(start 180.691028 -362.048552)
		(end 180.686202 -362.208318)
		(stroke
			(width 0.08255)
			(type default)
		)
		(layer "In7.Cu")
	)
	(gr_line
		(start 180.747162 -363.67593)
		(end 180.599842 -363.613192)
		(stroke
			(width 0.08255)
			(type default)
		)
		(layer "In7.Cu")
	)
	(gr_line
		(start 181.052216 -361.708954)
		(end 180.691028 -362.048552)
		(stroke
			(width 0.08255)
			(type default)
		)
		(layer "In7.Cu")
	)
	(gr_line
		(start 181.207918 -363.49178)
		(end 181.207918 -363.491526)
		(stroke
			(width 0.08255)
			(type default)
		)
		(layer "In7.Cu")
	)
	(gr_line
		(start 181.212236 -361.71378)
		(end 181.052216 -361.708954)
		(stroke
			(width 0.08255)
			(type default)
		)
		(layer "In7.Cu")
	)
	(gr_line
		(start 181.407054 -361.919266)
		(end 180.879242 -362.415582)
		(stroke
			(width 0.08255)
			(type default)
		)
		(layer "In7.Cu")
	)
	(gr_line
		(start 181.57952 -361.213146)
		(end 181.57444 -361.373166)
		(stroke
			(width 0.08255)
			(type default)
		)
		(layer "In7.Cu")
	)
	(gr_line
		(start 181.940708 -360.873802)
		(end 181.57952 -361.213146)
		(stroke
			(width 0.08255)
			(type default)
		)
		(layer "In7.Cu")
	)
	(gr_line
		(start 182.100474 -360.878628)
		(end 181.940708 -360.873802)
		(stroke
			(width 0.08255)
			(type default)
		)
		(layer "In7.Cu")
	)
	(gr_line
		(start 182.2577 -362.339636)
		(end 182.253382 -362.499656)
		(stroke
			(width 0.08255)
			(type default)
		)
		(layer "In7.Cu")
	)
	(gr_line
		(start 182.295546 -361.084114)
		(end 181.767734 -361.580176)
		(stroke
			(width 0.08255)
			(type default)
		)
		(layer "In7.Cu")
	)
	(gr_line
		(start 182.467758 -360.37774)
		(end 182.462932 -360.53776)
		(stroke
			(width 0.08255)
			(type default)
		)
		(layer "In7.Cu")
	)
	(gr_line
		(start 182.617618 -361.998768)
		(end 182.2577 -362.339636)
		(stroke
			(width 0.08255)
			(type default)
		)
		(layer "In7.Cu")
	)
	(gr_line
		(start 182.777384 -362.00334)
		(end 182.617618 -361.998768)
		(stroke
			(width 0.08255)
			(type default)
		)
		(layer "In7.Cu")
	)
	(gr_line
		(start 182.778654 -362.003086)
		(end 182.779162 -362.00334)
		(stroke
			(width 0.08255)
			(type default)
		)
		(layer "In7.Cu")
	)
	(gr_line
		(start 182.828946 -360.038396)
		(end 182.467758 -360.37774)
		(stroke
			(width 0.08255)
			(type default)
		)
		(layer "In7.Cu")
	)
	(gr_line
		(start 182.988966 -360.043222)
		(end 182.828946 -360.038396)
		(stroke
			(width 0.08255)
			(type default)
		)
		(layer "In7.Cu")
	)
	(gr_line
		(start 183.138318 -361.662472)
		(end 183.138572 -361.662726)
		(stroke
			(width 0.08255)
			(type default)
		)
		(layer "In7.Cu")
	)
	(gr_line
		(start 183.14289 -361.501182)
		(end 183.138572 -361.660948)
		(stroke
			(width 0.08255)
			(type default)
		)
		(layer "In7.Cu")
	)
	(gr_line
		(start 183.183784 -360.248708)
		(end 182.655972 -360.745024)
		(stroke
			(width 0.08255)
			(type default)
		)
		(layer "In7.Cu")
	)
	(gr_line
		(start 183.35625 -359.542588)
		(end 183.35117 -359.702608)
		(stroke
			(width 0.08255)
			(type default)
		)
		(layer "In7.Cu")
	)
	(gr_line
		(start 183.502808 -361.160314)
		(end 183.14289 -361.501182)
		(stroke
			(width 0.08255)
			(type default)
		)
		(layer "In7.Cu")
	)
	(gr_line
		(start 183.662574 -361.164632)
		(end 183.502808 -361.160314)
		(stroke
			(width 0.08255)
			(type default)
		)
		(layer "In7.Cu")
	)
	(gr_line
		(start 183.664352 -361.164632)
		(end 183.664352 -361.164378)
		(stroke
			(width 0.08255)
			(type default)
		)
		(layer "In7.Cu")
	)
	(gr_line
		(start 183.717438 -359.203244)
		(end 183.35625 -359.542588)
		(stroke
			(width 0.08255)
			(type default)
		)
		(layer "In7.Cu")
	)
	(gr_line
		(start 183.838596 -364.218728)
		(end 183.823356 -364.377986)
		(stroke
			(width 0.08255)
			(type default)
		)
		(layer "In7.Cu")
	)
	(gr_line
		(start 183.877204 -359.20807)
		(end 183.717438 -359.203244)
		(stroke
			(width 0.08255)
			(type default)
		)
		(layer "In7.Cu")
	)
	(gr_line
		(start 183.948832 -357.733854)
		(end 184.239662 -358.024684)
		(stroke
			(width 0.08255)
			(type default)
		)
		(layer "In7.Cu")
	)
	(gr_line
		(start 184.023762 -360.824272)
		(end 184.023254 -360.824018)
		(stroke
			(width 0.08255)
			(type default)
		)
		(layer "In7.Cu")
	)
	(gr_line
		(start 184.02808 -360.662474)
		(end 184.023762 -360.82224)
		(stroke
			(width 0.08255)
			(type default)
		)
		(layer "In7.Cu")
	)
	(gr_line
		(start 184.072022 -359.413556)
		(end 183.544464 -359.909618)
		(stroke
			(width 0.08255)
			(type default)
		)
		(layer "In7.Cu")
	)
	(gr_line
		(start 184.220612 -363.903006)
		(end 183.838596 -364.218728)
		(stroke
			(width 0.08255)
			(type default)
		)
		(layer "In7.Cu")
	)
	(gr_line
		(start 184.239662 -354.417376)
		(end 183.948832 -354.708206)
		(stroke
			(width 0.08255)
			(type default)
		)
		(layer "In7.Cu")
	)
	(gr_line
		(start 184.380124 -363.917992)
		(end 184.220612 -363.903006)
		(stroke
			(width 0.08255)
			(type default)
		)
		(layer "In7.Cu")
	)
	(gr_line
		(start 184.387998 -360.321606)
		(end 184.02808 -360.662474)
		(stroke
			(width 0.08255)
			(type default)
		)
		(layer "In7.Cu")
	)
	(gr_line
		(start 184.521602 -354.417376)
		(end 184.812432 -354.708206)
		(stroke
			(width 0.08255)
			(type default)
		)
		(layer "In7.Cu")
	)
	(gr_line
		(start 184.54751 -360.326178)
		(end 184.387998 -360.321606)
		(stroke
			(width 0.08255)
			(type default)
		)
		(layer "In7.Cu")
	)
	(gr_line
		(start 184.549542 -360.326178)
		(end 184.549542 -360.325924)
		(stroke
			(width 0.08255)
			(type default)
		)
		(layer "In7.Cu")
	)
	(gr_line
		(start 184.77865 -363.441996)
		(end 184.763664 -363.601254)
		(stroke
			(width 0.08255)
			(type default)
		)
		(layer "In7.Cu")
	)
	(gr_line
		(start 184.812432 -357.733854)
		(end 184.521602 -358.024684)
		(stroke
			(width 0.08255)
			(type default)
		)
		(layer "In7.Cu")
	)
	(gr_line
		(start 184.908698 -359.985564)
		(end 184.908952 -359.985564)
		(stroke
			(width 0.08255)
			(type default)
		)
		(layer "In7.Cu")
	)
	(gr_line
		(start 184.91327 -359.823766)
		(end 184.908952 -359.983786)
		(stroke
			(width 0.08255)
			(type default)
		)
		(layer "In7.Cu")
	)
	(gr_line
		(start 185.16092 -363.126274)
		(end 184.77865 -363.441996)
		(stroke
			(width 0.08255)
			(type default)
		)
		(layer "In7.Cu")
	)
	(gr_line
		(start 185.273188 -359.482898)
		(end 184.91327 -359.823766)
		(stroke
			(width 0.08255)
			(type default)
		)
		(layer "In7.Cu")
	)
	(gr_line
		(start 185.320178 -363.141514)
		(end 185.16092 -363.126274)
		(stroke
			(width 0.08255)
			(type default)
		)
		(layer "In7.Cu")
	)
	(gr_line
		(start 185.432954 -359.48747)
		(end 185.273188 -359.482898)
		(stroke
			(width 0.08255)
			(type default)
		)
		(layer "In7.Cu")
	)
	(gr_line
		(start 185.718704 -362.665518)
		(end 185.703718 -362.824776)
		(stroke
			(width 0.08255)
			(type default)
		)
		(layer "In7.Cu")
	)
	(gr_line
		(start 186.100974 -362.349796)
		(end 185.718704 -362.665518)
		(stroke
			(width 0.08255)
			(type default)
		)
		(layer "In7.Cu")
	)
	(gr_line
		(start 186.260232 -362.365036)
		(end 186.100974 -362.349796)
		(stroke
			(width 0.08255)
			(type default)
		)
		(layer "In7.Cu")
	)
	(gr_line
		(start 186.658758 -361.88904)
		(end 186.643772 -362.048298)
		(stroke
			(width 0.08255)
			(type default)
		)
		(layer "In7.Cu")
	)
	(gr_line
		(start 187.041028 -361.573318)
		(end 186.658758 -361.88904)
		(stroke
			(width 0.08255)
			(type default)
		)
		(layer "In7.Cu")
	)
	(gr_line
		(start 187.057792 -351.611438)
		(end 187.348622 -351.902268)
		(stroke
			(width 0.08255)
			(type default)
		)
		(layer "In7.Cu")
	)
	(gr_line
		(start 187.200286 -361.588558)
		(end 187.041028 -361.573318)
		(stroke
			(width 0.08255)
			(type default)
		)
		(layer "In7.Cu")
	)
	(gr_line
		(start 187.348622 -348.29496)
		(end 187.057792 -348.58579)
		(stroke
			(width 0.08255)
			(type default)
		)
		(layer "In7.Cu")
	)
	(gr_line
		(start 187.598812 -361.112562)
		(end 187.583826 -361.27182)
		(stroke
			(width 0.08255)
			(type default)
		)
		(layer "In7.Cu")
	)
	(gr_line
		(start 187.910216 -362.650786)
		(end 187.910216 -362.81106)
		(stroke
			(width 0.08255)
			(type default)
		)
		(layer "In7.Cu")
	)
	(gr_line
		(start 187.981082 -360.79684)
		(end 187.598812 -361.112562)
		(stroke
			(width 0.08255)
			(type default)
		)
		(layer "In7.Cu")
	)
	(gr_line
		(start 188.140086 -360.81208)
		(end 187.981082 -360.79684)
		(stroke
			(width 0.08255)
			(type default)
		)
		(layer "In7.Cu")
	)
	(gr_line
		(start 188.260736 -362.300266)
		(end 187.910216 -362.650786)
		(stroke
			(width 0.08255)
			(type default)
		)
		(layer "In7.Cu")
	)
	(gr_line
		(start 188.42101 -362.300266)
		(end 188.260736 -362.300266)
		(stroke
			(width 0.08255)
			(type default)
		)
		(layer "In7.Cu")
	)
	(gr_line
		(start 188.772546 -361.788456)
		(end 188.772546 -361.94873)
		(stroke
			(width 0.08255)
			(type default)
		)
		(layer "In7.Cu")
	)
	(gr_line
		(start 189.011814 -338.50072)
		(end 188.99378 -338.623402)
		(stroke
			(width 0.08255)
			(type default)
		)
		(layer "In7.Cu")
	)
	(gr_line
		(start 189.123066 -361.437936)
		(end 188.772546 -361.788456)
		(stroke
			(width 0.08255)
			(type default)
		)
		(layer "In7.Cu")
	)
	(gr_line
		(start 189.28334 -361.437936)
		(end 189.123066 -361.437936)
		(stroke
			(width 0.08255)
			(type default)
		)
		(layer "In7.Cu")
	)
	(gr_line
		(start 189.410086 -338.205572)
		(end 189.011814 -338.50072)
		(stroke
			(width 0.08255)
			(type default)
		)
		(layer "In7.Cu")
	)
	(gr_line
		(start 189.532768 -338.223606)
		(end 189.410086 -338.205572)
		(stroke
			(width 0.08255)
			(type default)
		)
		(layer "In7.Cu")
	)
	(gr_line
		(start 189.634876 -360.926126)
		(end 189.634876 -361.0864)
		(stroke
			(width 0.08255)
			(type default)
		)
		(layer "In7.Cu")
	)
	(gr_line
		(start 189.640972 -359.257092)
		(end 189.640972 -359.399078)
		(stroke
			(width 0.08255)
			(type default)
		)
		(layer "In7.Cu")
	)
	(gr_line
		(start 189.70244 -338.450428)
		(end 189.16142 -338.851748)
		(stroke
			(width 0.08255)
			(type default)
		)
		(layer "In7.Cu")
	)
	(gr_line
		(start 189.985396 -360.575606)
		(end 189.634876 -360.926126)
		(stroke
			(width 0.08255)
			(type default)
		)
		(layer "In7.Cu")
	)
	(gr_line
		(start 189.991492 -358.906572)
		(end 189.640972 -359.257092)
		(stroke
			(width 0.08255)
			(type default)
		)
		(layer "In7.Cu")
	)
	(gr_line
		(start 190.133478 -358.906572)
		(end 189.991492 -358.906572)
		(stroke
			(width 0.08255)
			(type default)
		)
		(layer "In7.Cu")
	)
	(gr_line
		(start 190.14567 -360.575606)
		(end 189.985396 -360.575606)
		(stroke
			(width 0.08255)
			(type default)
		)
		(layer "In7.Cu")
	)
	(gr_line
		(start 190.485268 -358.412796)
		(end 190.485268 -358.554782)
		(stroke
			(width 0.08255)
			(type default)
		)
		(layer "In7.Cu")
	)
	(gr_line
		(start 190.497206 -360.063796)
		(end 190.497206 -360.22407)
		(stroke
			(width 0.08255)
			(type default)
		)
		(layer "In7.Cu")
	)
	(gr_line
		(start 190.835788 -358.062276)
		(end 190.485268 -358.412796)
		(stroke
			(width 0.08255)
			(type default)
		)
		(layer "In7.Cu")
	)
	(gr_line
		(start 190.847726 -359.713276)
		(end 190.497206 -360.063796)
		(stroke
			(width 0.08255)
			(type default)
		)
		(layer "In7.Cu")
	)
	(gr_line
		(start 190.950088 -308.249828)
		(end 191.215518 -308.249828)
		(stroke
			(width 0.05715)
			(type default)
		)
		(layer "In7.Cu")
	)
	(gr_line
		(start 190.950088 -304.449734)
		(end 191.215518 -304.449734)
		(stroke
			(width 0.05715)
			(type default)
		)
		(layer "In7.Cu")
	)
	(gr_line
		(start 190.97752 -358.062276)
		(end 190.835788 -358.062276)
		(stroke
			(width 0.08255)
			(type default)
		)
		(layer "In7.Cu")
	)
	(gr_line
		(start 191.007746 -359.713276)
		(end 190.847726 -359.713276)
		(stroke
			(width 0.08255)
			(type default)
		)
		(layer "In7.Cu")
	)
	(gr_line
		(start 191.215518 -308.249828)
		(end 191.329818 -308.364128)
		(stroke
			(width 0.05715)
			(type default)
		)
		(layer "In7.Cu")
	)
	(gr_line
		(start 191.215518 -304.449734)
		(end 191.329818 -304.564034)
		(stroke
			(width 0.05715)
			(type default)
		)
		(layer "In7.Cu")
	)
	(gr_line
		(start 191.634618 -308.249828)
		(end 191.520318 -308.364128)
		(stroke
			(width 0.05715)
			(type default)
		)
		(layer "In7.Cu")
	)
	(gr_line
		(start 191.900048 -308.249828)
		(end 191.634618 -308.249828)
		(stroke
			(width 0.05715)
			(type default)
		)
		(layer "In7.Cu")
	)
	(gr_line
		(start 191.985392 -356.601268)
		(end 192.039748 -356.732586)
		(stroke
			(width 0.08255)
			(type default)
		)
		(layer "In7.Cu")
	)
	(gr_line
		(start 192.175638 -356.14356)
		(end 191.985392 -356.601268)
		(stroke
			(width 0.08255)
			(type default)
		)
		(layer "In7.Cu")
	)
	(gr_line
		(start 192.306956 -356.089204)
		(end 192.175638 -356.14356)
		(stroke
			(width 0.08255)
			(type default)
		)
		(layer "In7.Cu")
	)
	(gr_line
		(start 192.850008 -307.299868)
		(end 193.115438 -307.299868)
		(stroke
			(width 0.05715)
			(type default)
		)
		(layer "In7.Cu")
	)
	(gr_line
		(start 192.850008 -305.399948)
		(end 193.115438 -305.399948)
		(stroke
			(width 0.05715)
			(type default)
		)
		(layer "In7.Cu")
	)
	(gr_line
		(start 193.010282 -356.9462)
		(end 193.071496 -357.094028)
		(stroke
			(width 0.08255)
			(type default)
		)
		(layer "In7.Cu")
	)
	(gr_line
		(start 193.115438 -307.299868)
		(end 193.229738 -307.414168)
		(stroke
			(width 0.05715)
			(type default)
		)
		(layer "In7.Cu")
	)
	(gr_line
		(start 193.115438 -305.399948)
		(end 193.229738 -305.514248)
		(stroke
			(width 0.05715)
			(type default)
		)
		(layer "In7.Cu")
	)
	(gr_line
		(start 193.200274 -356.488492)
		(end 193.010282 -356.9462)
		(stroke
			(width 0.08255)
			(type default)
		)
		(layer "In7.Cu")
	)
	(gr_line
		(start 193.275712 -351.611438)
		(end 193.566542 -351.902268)
		(stroke
			(width 0.08255)
			(type default)
		)
		(layer "In7.Cu")
	)
	(gr_line
		(start 193.348102 -356.427532)
		(end 193.200274 -356.488492)
		(stroke
			(width 0.08255)
			(type default)
		)
		(layer "In7.Cu")
	)
	(gr_line
		(start 193.477896 -355.819964)
		(end 193.538856 -355.967792)
		(stroke
			(width 0.08255)
			(type default)
		)
		(layer "In7.Cu")
	)
	(gr_line
		(start 193.496692 -356.07244)
		(end 193.34988 -356.42677)
		(stroke
			(width 0.08255)
			(type default)
		)
		(layer "In7.Cu")
	)
	(gr_line
		(start 193.566542 -348.29496)
		(end 193.275712 -348.58579)
		(stroke
			(width 0.08255)
			(type default)
		)
		(layer "In7.Cu")
	)
	(gr_line
		(start 193.667634 -355.362256)
		(end 193.477896 -355.819964)
		(stroke
			(width 0.08255)
			(type default)
		)
		(layer "In7.Cu")
	)
	(gr_line
		(start 193.815462 -355.301296)
		(end 193.667634 -355.362256)
		(stroke
			(width 0.08255)
			(type default)
		)
		(layer "In7.Cu")
	)
	(gr_line
		(start 193.81724 -355.300534)
		(end 193.816986 -355.30028)
		(stroke
			(width 0.08255)
			(type default)
		)
		(layer "In7.Cu")
	)
	(gr_line
		(start 193.945256 -354.693728)
		(end 194.006216 -354.841302)
		(stroke
			(width 0.08255)
			(type default)
		)
		(layer "In7.Cu")
	)
	(gr_line
		(start 194.006724 -354.84308)
		(end 194.006978 -354.84308)
		(stroke
			(width 0.08255)
			(type default)
		)
		(layer "In7.Cu")
	)
	(gr_line
		(start 194.134994 -354.23602)
		(end 193.945256 -354.693728)
		(stroke
			(width 0.08255)
			(type default)
		)
		(layer "In7.Cu")
	)
	(gr_line
		(start 194.282568 -354.17506)
		(end 194.134994 -354.23602)
		(stroke
			(width 0.08255)
			(type default)
		)
		(layer "In7.Cu")
	)
	(gr_line
		(start 194.284092 -354.174298)
		(end 194.2846 -354.174298)
		(stroke
			(width 0.08255)
			(type default)
		)
		(layer "In7.Cu")
	)
	(gr_line
		(start 196.384672 -345.465146)
		(end 196.675502 -345.755976)
		(stroke
			(width 0.08255)
			(type default)
		)
		(layer "In7.Cu")
	)
	(gr_line
		(start 196.675502 -342.148668)
		(end 196.384672 -342.439498)
		(stroke
			(width 0.08255)
			(type default)
		)
		(layer "In7.Cu")
	)
	(gr_line
		(start 199.67448 -305.019964)
		(end 199.7202 -305.065684)
		(stroke
			(width 0.05715)
			(type default)
		)
		(layer "In7.Cu")
	)
	(gr_line
		(start 199.69988 -308.820058)
		(end 199.7456 -308.865778)
		(stroke
			(width 0.05715)
			(type default)
		)
		(layer "In7.Cu")
	)
	(gr_line
		(start 199.69988 -308.629558)
		(end 199.7456 -308.583838)
		(stroke
			(width 0.05715)
			(type default)
		)
		(layer "In7.Cu")
	)
	(gr_line
		(start 199.69988 -307.870098)
		(end 199.7456 -307.915818)
		(stroke
			(width 0.05715)
			(type default)
		)
		(layer "In7.Cu")
	)
	(gr_line
		(start 199.7202 -305.065684)
		(end 199.748648 -305.065684)
		(stroke
			(width 0.05715)
			(type default)
		)
		(layer "In7.Cu")
	)
	(gr_line
		(start 199.72528 -305.970178)
		(end 199.771 -306.015898)
		(stroke
			(width 0.05715)
			(type default)
		)
		(layer "In7.Cu")
	)
	(gr_line
		(start 199.7456 -308.865778)
		(end 199.774048 -308.865778)
		(stroke
			(width 0.05715)
			(type default)
		)
		(layer "In7.Cu")
	)
	(gr_line
		(start 199.7456 -308.583838)
		(end 199.774048 -308.583838)
		(stroke
			(width 0.05715)
			(type default)
		)
		(layer "In7.Cu")
	)
	(gr_line
		(start 199.7456 -307.915818)
		(end 199.774048 -307.915818)
		(stroke
			(width 0.05715)
			(type default)
		)
		(layer "In7.Cu")
	)
	(gr_line
		(start 199.771 -306.015898)
		(end 199.799448 -306.015898)
		(stroke
			(width 0.05715)
			(type default)
		)
		(layer "In7.Cu")
	)
	(gr_line
		(start 201.310494 -30.922468)
		(end 201.549508 -30.683454)
		(stroke
			(width 0.08255)
			(type default)
		)
		(layer "In7.Cu")
	)
	(gr_line
		(start 201.310494 -30.058868)
		(end 201.601324 -30.349698)
		(stroke
			(width 0.08255)
			(type default)
		)
		(layer "In7.Cu")
	)
	(gr_line
		(start 201.549508 -30.683454)
		(end 201.671428 -30.632908)
		(stroke
			(width 0.08255)
			(type default)
		)
		(layer "In7.Cu")
	)
	(gr_line
		(start 201.601324 -30.349698)
		(end 201.674476 -30.349698)
		(stroke
			(width 0.08255)
			(type default)
		)
		(layer "In7.Cu")
	)
	(gr_line
		(start 202.656948 -30.349698)
		(end 203.380848 -30.349698)
		(stroke
			(width 0.08255)
			(type default)
		)
		(layer "In7.Cu")
	)
	(gr_line
		(start 202.658218 -30.632908)
		(end 202.771248 -30.745938)
		(stroke
			(width 0.08255)
			(type default)
		)
		(layer "In7.Cu")
	)
	(gr_line
		(start 202.771248 -30.745938)
		(end 203.266548 -30.745938)
		(stroke
			(width 0.08255)
			(type default)
		)
		(layer "In7.Cu")
	)
	(gr_line
		(start 203.266548 -30.745938)
		(end 203.379578 -30.632908)
		(stroke
			(width 0.08255)
			(type default)
		)
		(layer "In7.Cu")
	)
	(gr_line
		(start 204.459586 -31.499556)
		(end 204.728064 -31.91637)
		(stroke
			(width 0.08255)
			(type default)
		)
		(layer "In7.Cu")
	)
	(gr_line
		(start 204.493622 -31.343092)
		(end 204.459586 -31.499556)
		(stroke
			(width 0.08255)
			(type default)
		)
		(layer "In7.Cu")
	)
	(gr_line
		(start 204.728064 -31.91637)
		(end 204.884274 -31.950406)
		(stroke
			(width 0.08255)
			(type default)
		)
		(layer "In7.Cu")
	)
	(gr_line
		(start 204.731112 -31.189168)
		(end 205.123288 -31.798006)
		(stroke
			(width 0.08255)
			(type default)
		)
		(layer "In7.Cu")
	)
	(gr_line
		(start 239.410494 -30.922468)
		(end 239.701324 -30.631638)
		(stroke
			(width 0.08255)
			(type default)
		)
		(layer "In7.Cu")
	)
	(gr_line
		(start 240.679732 -30.632908)
		(end 240.780062 -30.733238)
		(stroke
			(width 0.08255)
			(type default)
		)
		(layer "In7.Cu")
	)
	(gr_line
		(start 240.780062 -30.733238)
		(end 241.275362 -30.733238)
		(stroke
			(width 0.08255)
			(type default)
		)
		(layer "In7.Cu")
	)
	(gr_line
		(start 241.264694 -29.12237)
		(end 241.510058 -28.877006)
		(stroke
			(width 0.08255)
			(type default)
		)
		(layer "In7.Cu")
	)
	(gr_line
		(start 241.275362 -30.733238)
		(end 241.375692 -30.632908)
		(stroke
			(width 0.08255)
			(type default)
		)
		(layer "In7.Cu")
	)
	(gr_line
		(start 241.510058 -28.877006)
		(end 241.616738 -28.83281)
		(stroke
			(width 0.08255)
			(type default)
		)
		(layer "In7.Cu")
	)
	(gr_line
		(start 242.390168 -31.293054)
		(end 242.740688 -31.643574)
		(stroke
			(width 0.08255)
			(type default)
		)
		(layer "In7.Cu")
	)
	(gr_line
		(start 242.390168 -31.151322)
		(end 242.390168 -31.293054)
		(stroke
			(width 0.08255)
			(type default)
		)
		(layer "In7.Cu")
	)
	(gr_line
		(start 242.740688 -31.643574)
		(end 242.88242 -31.643574)
		(stroke
			(width 0.08255)
			(type default)
		)
		(layer "In7.Cu")
	)
	(gr_line
		(start 245.097046 -32.89808)
		(end 245.289578 -33.354772)
		(stroke
			(width 0.08255)
			(type default)
		)
		(layer "In7.Cu")
	)
	(gr_line
		(start 245.15064 -32.766254)
		(end 245.097046 -32.89808)
		(stroke
			(width 0.08255)
			(type default)
		)
		(layer "In7.Cu")
	)
	(gr_line
		(start 245.289578 -33.354772)
		(end 245.42115 -33.408112)
		(stroke
			(width 0.08255)
			(type default)
		)
		(layer "In7.Cu")
	)
	(gr_line
		(start 245.560596 -33.998154)
		(end 245.753128 -34.454846)
		(stroke
			(width 0.08255)
			(type default)
		)
		(layer "In7.Cu")
	)
	(gr_line
		(start 245.61419 -33.866836)
		(end 245.560596 -33.998154)
		(stroke
			(width 0.08255)
			(type default)
		)
		(layer "In7.Cu")
	)
	(gr_line
		(start 245.753128 -34.454846)
		(end 245.8847 -34.50844)
		(stroke
			(width 0.08255)
			(type default)
		)
		(layer "In7.Cu")
	)
	(gr_line
		(start 249.26544 -102.474014)
		(end 249.26544 -102.474522)
		(stroke
			(width 0.08255)
			(type default)
		)
		(layer "In7.Cu")
	)
	(gr_line
		(start 249.277378 -102.513892)
		(end 249.277632 -102.514654)
		(stroke
			(width 0.08255)
			(type default)
		)
		(layer "In7.Cu")
	)
	(gr_line
		(start 265.410442 -34.52241)
		(end 265.701272 -34.23158)
		(stroke
			(width 0.08255)
			(type default)
		)
		(layer "In7.Cu")
	)
	(gr_line
		(start 266.72921 -36.963604)
		(end 266.73683 -37.459158)
		(stroke
			(width 0.08255)
			(type default)
		)
		(layer "In7.Cu")
	)
	(gr_line
		(start 266.73683 -37.459158)
		(end 266.838938 -37.557964)
		(stroke
			(width 0.08255)
			(type default)
		)
		(layer "In7.Cu")
	)
	(gr_line
		(start 266.747752 -38.157404)
		(end 266.755372 -38.652704)
		(stroke
			(width 0.08255)
			(type default)
		)
		(layer "In7.Cu")
	)
	(gr_line
		(start 266.755372 -38.652704)
		(end 266.85748 -38.75151)
		(stroke
			(width 0.08255)
			(type default)
		)
		(layer "In7.Cu")
	)
	(gr_line
		(start 266.82827 -36.861496)
		(end 266.72921 -36.963604)
		(stroke
			(width 0.08255)
			(type default)
		)
		(layer "In7.Cu")
	)
	(gr_line
		(start 266.846812 -38.05555)
		(end 266.747752 -38.157404)
		(stroke
			(width 0.08255)
			(type default)
		)
		(layer "In7.Cu")
	)
	(gr_line
		(start 277.933912 -271.3736)
		(end 277.979632 -271.41932)
		(stroke
			(width 0.05715)
			(type default)
		)
		(layer "In7.Cu")
	)
	(gr_line
		(start 277.933912 -271.345152)
		(end 277.933912 -271.3736)
		(stroke
			(width 0.05715)
			(type default)
		)
		(layer "In7.Cu")
	)
	(gr_line
		(start 278.435562 -273.670014)
		(end 278.549862 -273.784314)
		(stroke
			(width 0.05715)
			(type default)
		)
		(layer "In7.Cu")
	)
	(gr_line
		(start 278.549862 -273.784314)
		(end 278.549862 -274.049744)
		(stroke
			(width 0.05715)
			(type default)
		)
		(layer "In7.Cu")
	)
	(gr_line
		(start 278.883618 -271.421352)
		(end 278.929338 -271.467072)
		(stroke
			(width 0.05715)
			(type default)
		)
		(layer "In7.Cu")
	)
	(gr_line
		(start 278.883618 -271.392904)
		(end 278.883618 -271.421352)
		(stroke
			(width 0.05715)
			(type default)
		)
		(layer "In7.Cu")
	)
	(gr_line
		(start 279.385522 -275.570188)
		(end 279.499822 -275.684488)
		(stroke
			(width 0.05715)
			(type default)
		)
		(layer "In7.Cu")
	)
	(gr_line
		(start 279.499822 -275.684488)
		(end 279.499822 -275.949918)
		(stroke
			(width 0.05715)
			(type default)
		)
		(layer "In7.Cu")
	)
	(gr_line
		(start 279.833832 -271.3736)
		(end 279.879552 -271.41932)
		(stroke
			(width 0.05715)
			(type default)
		)
		(layer "In7.Cu")
	)
	(gr_line
		(start 279.833832 -271.345152)
		(end 279.833832 -271.3736)
		(stroke
			(width 0.05715)
			(type default)
		)
		(layer "In7.Cu")
	)
	(gr_line
		(start 280.335482 -273.670014)
		(end 280.449782 -273.784314)
		(stroke
			(width 0.05715)
			(type default)
		)
		(layer "In7.Cu")
	)
	(gr_line
		(start 280.449782 -273.784314)
		(end 280.449782 -274.049744)
		(stroke
			(width 0.05715)
			(type default)
		)
		(layer "In7.Cu")
	)
	(gr_line
		(start 289.33394 -271.3736)
		(end 289.37966 -271.41932)
		(stroke
			(width 0.05715)
			(type default)
		)
		(layer "In7.Cu")
	)
	(gr_line
		(start 289.33394 -271.345152)
		(end 289.33394 -271.3736)
		(stroke
			(width 0.05715)
			(type default)
		)
		(layer "In7.Cu")
	)
	(gr_line
		(start 289.61588 -271.3736)
		(end 289.57016 -271.41932)
		(stroke
			(width 0.05715)
			(type default)
		)
		(layer "In7.Cu")
	)
	(gr_line
		(start 289.61588 -271.345152)
		(end 289.61588 -271.3736)
		(stroke
			(width 0.05715)
			(type default)
		)
		(layer "In7.Cu")
	)
	(gr_line
		(start 289.83559 -273.670014)
		(end 289.94989 -273.784314)
		(stroke
			(width 0.05715)
			(type default)
		)
		(layer "In7.Cu")
	)
	(gr_line
		(start 289.83559 -273.479514)
		(end 289.94989 -273.365214)
		(stroke
			(width 0.05715)
			(type default)
		)
		(layer "In7.Cu")
	)
	(gr_line
		(start 289.94989 -273.784314)
		(end 289.94989 -274.049744)
		(stroke
			(width 0.05715)
			(type default)
		)
		(layer "In7.Cu")
	)
	(gr_line
		(start 289.94989 -273.365214)
		(end 289.94989 -273.099784)
		(stroke
			(width 0.05715)
			(type default)
		)
		(layer "In7.Cu")
	)
	(gr_line
		(start 317.410338 -30.922468)
		(end 317.649352 -30.683454)
		(stroke
			(width 0.08255)
			(type default)
		)
		(layer "In7.Cu")
	)
	(gr_line
		(start 317.410338 -30.058868)
		(end 317.701168 -30.349698)
		(stroke
			(width 0.08255)
			(type default)
		)
		(layer "In7.Cu")
	)
	(gr_line
		(start 317.649352 -30.683454)
		(end 317.771272 -30.632908)
		(stroke
			(width 0.08255)
			(type default)
		)
		(layer "In7.Cu")
	)
	(gr_line
		(start 317.701168 -30.349698)
		(end 317.77432 -30.349698)
		(stroke
			(width 0.08255)
			(type default)
		)
		(layer "In7.Cu")
	)
	(gr_line
		(start 318.756792 -30.349698)
		(end 319.480692 -30.349698)
		(stroke
			(width 0.08255)
			(type default)
		)
		(layer "In7.Cu")
	)
	(gr_line
		(start 318.758062 -30.632908)
		(end 318.871092 -30.745938)
		(stroke
			(width 0.08255)
			(type default)
		)
		(layer "In7.Cu")
	)
	(gr_line
		(start 318.871092 -30.745938)
		(end 319.366392 -30.745938)
		(stroke
			(width 0.08255)
			(type default)
		)
		(layer "In7.Cu")
	)
	(gr_line
		(start 319.366392 -30.745938)
		(end 319.479422 -30.632908)
		(stroke
			(width 0.08255)
			(type default)
		)
		(layer "In7.Cu")
	)
	(gr_line
		(start 320.55943 -31.499556)
		(end 320.827908 -31.91637)
		(stroke
			(width 0.08255)
			(type default)
		)
		(layer "In7.Cu")
	)
	(gr_line
		(start 320.593466 -31.343092)
		(end 320.55943 -31.499556)
		(stroke
			(width 0.08255)
			(type default)
		)
		(layer "In7.Cu")
	)
	(gr_line
		(start 320.827908 -31.91637)
		(end 320.984118 -31.950406)
		(stroke
			(width 0.08255)
			(type default)
		)
		(layer "In7.Cu")
	)
	(gr_line
		(start 320.830956 -31.189168)
		(end 321.223132 -31.798006)
		(stroke
			(width 0.08255)
			(type default)
		)
		(layer "In7.Cu")
	)
	(gr_line
		(start 355.510592 -30.922468)
		(end 355.801422 -30.631638)
		(stroke
			(width 0.08255)
			(type default)
		)
		(layer "In7.Cu")
	)
	(gr_line
		(start 356.77983 -30.632908)
		(end 356.88016 -30.733238)
		(stroke
			(width 0.08255)
			(type default)
		)
		(layer "In7.Cu")
	)
	(gr_line
		(start 356.88016 -30.733238)
		(end 357.37546 -30.733238)
		(stroke
			(width 0.08255)
			(type default)
		)
		(layer "In7.Cu")
	)
	(gr_line
		(start 357.364792 -29.12237)
		(end 357.610156 -28.877006)
		(stroke
			(width 0.08255)
			(type default)
		)
		(layer "In7.Cu")
	)
	(gr_line
		(start 357.37546 -30.733238)
		(end 357.47579 -30.632908)
		(stroke
			(width 0.08255)
			(type default)
		)
		(layer "In7.Cu")
	)
	(gr_line
		(start 357.610156 -28.877006)
		(end 357.716836 -28.83281)
		(stroke
			(width 0.08255)
			(type default)
		)
		(layer "In7.Cu")
	)
	(gr_line
		(start 358.490266 -31.293054)
		(end 358.840786 -31.643574)
		(stroke
			(width 0.08255)
			(type default)
		)
		(layer "In7.Cu")
	)
	(gr_line
		(start 358.490266 -31.151322)
		(end 358.490266 -31.293054)
		(stroke
			(width 0.08255)
			(type default)
		)
		(layer "In7.Cu")
	)
	(gr_line
		(start 358.840786 -31.643574)
		(end 358.982518 -31.643574)
		(stroke
			(width 0.08255)
			(type default)
		)
		(layer "In7.Cu")
	)
	(gr_line
		(start 361.150662 -32.754824)
		(end 361.343194 -33.211516)
		(stroke
			(width 0.08255)
			(type default)
		)
		(layer "In7.Cu")
	)
	(gr_line
		(start 361.197398 -32.640016)
		(end 361.150662 -32.754824)
		(stroke
			(width 0.08255)
			(type default)
		)
		(layer "In7.Cu")
	)
	(gr_line
		(start 361.343194 -33.211516)
		(end 361.458002 -33.258506)
		(stroke
			(width 0.08255)
			(type default)
		)
		(layer "In7.Cu")
	)
	(gr_line
		(start 361.604306 -33.831784)
		(end 361.796838 -34.288476)
		(stroke
			(width 0.08255)
			(type default)
		)
		(layer "In7.Cu")
	)
	(gr_line
		(start 361.651296 -33.716976)
		(end 361.604306 -33.831784)
		(stroke
			(width 0.08255)
			(type default)
		)
		(layer "In7.Cu")
	)
	(gr_line
		(start 361.796838 -34.288476)
		(end 361.911646 -34.335466)
		(stroke
			(width 0.08255)
			(type default)
		)
		(layer "In7.Cu")
	)
	(gr_line
		(start 365.365538 -102.474014)
		(end 365.365538 -102.474522)
		(stroke
			(width 0.08255)
			(type default)
		)
		(layer "In7.Cu")
	)
	(gr_line
		(start 365.377476 -102.513892)
		(end 365.37773 -102.514654)
		(stroke
			(width 0.08255)
			(type default)
		)
		(layer "In7.Cu")
	)
	(gr_line
		(start 381.51054 -34.52241)
		(end 381.80137 -34.23158)
		(stroke
			(width 0.08255)
			(type default)
		)
		(layer "In7.Cu")
	)
	(gr_line
		(start 382.830578 -36.227004)
		(end 382.838452 -36.722558)
		(stroke
			(width 0.08255)
			(type default)
		)
		(layer "In7.Cu")
	)
	(gr_line
		(start 382.838452 -36.722558)
		(end 382.927606 -36.808664)
		(stroke
			(width 0.08255)
			(type default)
		)
		(layer "In7.Cu")
	)
	(gr_line
		(start 382.848612 -37.395404)
		(end 382.856486 -37.890704)
		(stroke
			(width 0.08255)
			(type default)
		)
		(layer "In7.Cu")
	)
	(gr_line
		(start 382.856486 -37.890704)
		(end 382.94564 -37.977064)
		(stroke
			(width 0.08255)
			(type default)
		)
		(layer "In7.Cu")
	)
	(gr_line
		(start 382.917192 -36.13785)
		(end 382.830578 -36.227004)
		(stroke
			(width 0.08255)
			(type default)
		)
		(layer "In7.Cu")
	)
	(gr_line
		(start 382.928622 -36.809934)
		(end 382.928876 -36.809934)
		(stroke
			(width 0.08255)
			(type default)
		)
		(layer "In7.Cu")
	)
	(gr_line
		(start 382.935226 -37.305996)
		(end 382.848612 -37.395404)
		(stroke
			(width 0.08255)
			(type default)
		)
		(layer "In7.Cu")
	)
	(gr_line
		(start 382.946656 -37.978334)
		(end 382.94691 -37.978334)
		(stroke
			(width 0.08255)
			(type default)
		)
		(layer "In7.Cu")
	)
	(gr_line
		(start 394.03401 -271.3736)
		(end 394.07973 -271.41932)
		(stroke
			(width 0.05715)
			(type default)
		)
		(layer "In7.Cu")
	)
	(gr_line
		(start 394.03401 -271.345152)
		(end 394.03401 -271.3736)
		(stroke
			(width 0.05715)
			(type default)
		)
		(layer "In7.Cu")
	)
	(gr_line
		(start 394.53566 -273.670014)
		(end 394.64996 -273.784314)
		(stroke
			(width 0.05715)
			(type default)
		)
		(layer "In7.Cu")
	)
	(gr_line
		(start 394.64996 -273.784314)
		(end 394.64996 -274.049744)
		(stroke
			(width 0.05715)
			(type default)
		)
		(layer "In7.Cu")
	)
	(gr_line
		(start 394.983716 -271.421352)
		(end 395.029436 -271.467072)
		(stroke
			(width 0.05715)
			(type default)
		)
		(layer "In7.Cu")
	)
	(gr_line
		(start 394.983716 -271.392904)
		(end 394.983716 -271.421352)
		(stroke
			(width 0.05715)
			(type default)
		)
		(layer "In7.Cu")
	)
	(gr_line
		(start 395.48562 -275.570188)
		(end 395.59992 -275.684488)
		(stroke
			(width 0.05715)
			(type default)
		)
		(layer "In7.Cu")
	)
	(gr_line
		(start 395.59992 -275.684488)
		(end 395.59992 -275.949918)
		(stroke
			(width 0.05715)
			(type default)
		)
		(layer "In7.Cu")
	)
	(gr_line
		(start 395.93393 -271.3736)
		(end 395.97965 -271.41932)
		(stroke
			(width 0.05715)
			(type default)
		)
		(layer "In7.Cu")
	)
	(gr_line
		(start 395.93393 -271.345152)
		(end 395.93393 -271.3736)
		(stroke
			(width 0.05715)
			(type default)
		)
		(layer "In7.Cu")
	)
	(gr_line
		(start 396.43558 -273.670014)
		(end 396.54988 -273.784314)
		(stroke
			(width 0.05715)
			(type default)
		)
		(layer "In7.Cu")
	)
	(gr_line
		(start 396.54988 -273.784314)
		(end 396.54988 -274.049744)
		(stroke
			(width 0.05715)
			(type default)
		)
		(layer "In7.Cu")
	)
	(gr_line
		(start 401.633944 -271.3736)
		(end 401.679664 -271.41932)
		(stroke
			(width 0.05715)
			(type default)
		)
		(layer "In7.Cu")
	)
	(gr_line
		(start 401.633944 -271.345152)
		(end 401.633944 -271.3736)
		(stroke
			(width 0.05715)
			(type default)
		)
		(layer "In7.Cu")
	)
	(gr_line
		(start 402.135594 -273.670014)
		(end 402.249894 -273.784314)
		(stroke
			(width 0.05715)
			(type default)
		)
		(layer "In7.Cu")
	)
	(gr_line
		(start 402.249894 -273.784314)
		(end 402.249894 -274.049744)
		(stroke
			(width 0.05715)
			(type default)
		)
		(layer "In7.Cu")
	)
	(gr_line
		(start 405.434038 -271.3736)
		(end 405.479758 -271.41932)
		(stroke
			(width 0.05715)
			(type default)
		)
		(layer "In7.Cu")
	)
	(gr_line
		(start 405.434038 -271.345152)
		(end 405.434038 -271.3736)
		(stroke
			(width 0.05715)
			(type default)
		)
		(layer "In7.Cu")
	)
	(gr_line
		(start 405.715978 -271.3736)
		(end 405.670258 -271.41932)
		(stroke
			(width 0.05715)
			(type default)
		)
		(layer "In7.Cu")
	)
	(gr_line
		(start 405.715978 -271.345152)
		(end 405.715978 -271.3736)
		(stroke
			(width 0.05715)
			(type default)
		)
		(layer "In7.Cu")
	)
	(gr_line
		(start 405.935688 -273.670014)
		(end 406.049988 -273.784314)
		(stroke
			(width 0.05715)
			(type default)
		)
		(layer "In7.Cu")
	)
	(gr_line
		(start 405.935688 -273.479514)
		(end 406.049988 -273.365214)
		(stroke
			(width 0.05715)
			(type default)
		)
		(layer "In7.Cu")
	)
	(gr_line
		(start 406.049988 -273.784314)
		(end 406.049988 -274.049744)
		(stroke
			(width 0.05715)
			(type default)
		)
		(layer "In7.Cu")
	)
	(gr_line
		(start 406.049988 -273.365214)
		(end 406.049988 -273.099784)
		(stroke
			(width 0.05715)
			(type default)
		)
		(layer "In7.Cu")
	)
	(gr_line
		(start 407.510488 -30.922468)
		(end 407.801318 -30.631638)
		(stroke
			(width 0.08255)
			(type default)
		)
		(layer "In7.Cu")
	)
	(gr_line
		(start 408.779726 -30.632908)
		(end 408.880056 -30.733238)
		(stroke
			(width 0.08255)
			(type default)
		)
		(layer "In7.Cu")
	)
	(gr_line
		(start 408.880056 -30.733238)
		(end 409.375356 -30.733238)
		(stroke
			(width 0.08255)
			(type default)
		)
		(layer "In7.Cu")
	)
	(gr_line
		(start 409.375356 -30.733238)
		(end 409.475686 -30.632908)
		(stroke
			(width 0.08255)
			(type default)
		)
		(layer "In7.Cu")
	)
	(gr_line
		(start 410.585158 -31.388304)
		(end 410.935678 -31.738824)
		(stroke
			(width 0.08255)
			(type default)
		)
		(layer "In7.Cu")
	)
	(gr_line
		(start 410.585158 -31.246318)
		(end 410.585158 -31.388304)
		(stroke
			(width 0.08255)
			(type default)
		)
		(layer "In7.Cu")
	)
	(gr_line
		(start 410.935678 -31.738824)
		(end 411.077664 -31.738824)
		(stroke
			(width 0.08255)
			(type default)
		)
		(layer "In7.Cu")
	)
	(gr_line
		(start 433.510436 -30.922468)
		(end 433.74945 -30.683454)
		(stroke
			(width 0.08255)
			(type default)
		)
		(layer "In7.Cu")
	)
	(gr_line
		(start 433.510436 -30.058868)
		(end 433.801266 -30.349698)
		(stroke
			(width 0.08255)
			(type default)
		)
		(layer "In7.Cu")
	)
	(gr_line
		(start 433.74945 -30.683454)
		(end 433.87137 -30.632908)
		(stroke
			(width 0.08255)
			(type default)
		)
		(layer "In7.Cu")
	)
	(gr_line
		(start 433.801266 -30.349698)
		(end 433.874418 -30.349698)
		(stroke
			(width 0.08255)
			(type default)
		)
		(layer "In7.Cu")
	)
	(gr_line
		(start 434.85689 -30.349698)
		(end 435.58079 -30.349698)
		(stroke
			(width 0.08255)
			(type default)
		)
		(layer "In7.Cu")
	)
	(gr_line
		(start 434.85816 -30.632908)
		(end 434.97119 -30.745938)
		(stroke
			(width 0.08255)
			(type default)
		)
		(layer "In7.Cu")
	)
	(gr_line
		(start 434.97119 -30.745938)
		(end 435.46649 -30.745938)
		(stroke
			(width 0.08255)
			(type default)
		)
		(layer "In7.Cu")
	)
	(gr_line
		(start 435.46649 -30.745938)
		(end 435.57952 -30.632908)
		(stroke
			(width 0.08255)
			(type default)
		)
		(layer "In7.Cu")
	)
	(gr_line
		(start 436.659528 -31.499556)
		(end 436.928006 -31.91637)
		(stroke
			(width 0.08255)
			(type default)
		)
		(layer "In7.Cu")
	)
	(gr_line
		(start 436.693564 -31.343092)
		(end 436.659528 -31.499556)
		(stroke
			(width 0.08255)
			(type default)
		)
		(layer "In7.Cu")
	)
	(gr_line
		(start 436.928006 -31.91637)
		(end 437.084216 -31.950406)
		(stroke
			(width 0.08255)
			(type default)
		)
		(layer "In7.Cu")
	)
	(gr_line
		(start 436.931054 -31.189168)
		(end 437.32323 -31.798006)
		(stroke
			(width 0.08255)
			(type default)
		)
		(layer "In7.Cu")
	)
	(gr_poly
		(pts
			(arc
				(start 265.615928 -377.679966)
				(mid 265.635451 -377.676065)
				(end 265.651996 -377.66498)
			)
			(arc
				(start 265.851386 -377.46559)
				(mid 265.862497 -377.449056)
				(end 265.866372 -377.429522)
			)
			(arc
				(start 265.866372 -368.884962)
				(mid 265.862471 -368.865439)
				(end 265.851386 -368.848894)
			)
			(arc
				(start 265.514582 -368.51209)
				(mid 265.498048 -368.500979)
				(end 265.478514 -368.497104)
			)
			(arc
				(start 242.901216 -368.497104)
				(mid 242.881693 -368.501005)
				(end 242.865148 -368.51209)
			)
			(arc
				(start 242.760754 -368.616484)
				(mid 242.749643 -368.633018)
				(end 242.745768 -368.652552)
			)
			(arc
				(start 242.745768 -377.268994)
				(mid 242.749669 -377.288517)
				(end 242.760754 -377.305062)
			)
			(arc
				(start 243.120672 -377.66498)
				(mid 243.137206 -377.676091)
				(end 243.15674 -377.679966)
			)
		)
		(stroke
			(width 0)
			(type solid)
		)
		(fill yes)
		(layer "In8.Cu")
		(net "P12V_STBY_R2")
	)
	(gr_poly
		(pts
			(arc
				(start 43.702986 -312.049922)
				(mid 43.296586 -312.049922)
				(end 43.702986 -312.049922)
			)
		)
		(stroke
			(width 0)
			(type solid)
		)
		(fill yes)
		(layer "In8.Cu")
		(net "P5E_PEX0_STN6_TX_DN<111>")
	)
	(gr_poly
		(pts
			(arc
				(start 43.702986 -311.099962)
				(mid 43.296586 -311.099962)
				(end 43.702986 -311.099962)
			)
		)
		(stroke
			(width 0)
			(type solid)
		)
		(fill yes)
		(layer "In8.Cu")
		(net "P5E_PEX0_STN6_TX_DP<111>")
	)
	(gr_poly
		(pts
			(arc
				(start 44.652946 -313.949842)
				(mid 44.246546 -313.949842)
				(end 44.652946 -313.949842)
			)
		)
		(stroke
			(width 0)
			(type solid)
		)
		(fill yes)
		(layer "In8.Cu")
		(net "P5E_PEX0_STN6_TX_DN<110>")
	)
	(gr_poly
		(pts
			(arc
				(start 44.652946 -312.999882)
				(mid 44.246546 -312.999882)
				(end 44.652946 -312.999882)
			)
		)
		(stroke
			(width 0)
			(type solid)
		)
		(fill yes)
		(layer "In8.Cu")
		(net "P5E_PEX0_STN6_TX_DP<110>")
	)
	(gr_poly
		(pts
			(arc
				(start 44.652946 -278.799798)
				(mid 44.246546 -278.799798)
				(end 44.652946 -278.799798)
			)
		)
		(stroke
			(width 0)
			(type solid)
		)
		(fill yes)
		(layer "In8.Cu")
		(net "P5E_PEX0_STN2_TX_DP<47>")
	)
	(gr_poly
		(pts
			(arc
				(start 44.652946 -277.849838)
				(mid 44.246546 -277.849838)
				(end 44.652946 -277.849838)
			)
		)
		(stroke
			(width 0)
			(type solid)
		)
		(fill yes)
		(layer "In8.Cu")
		(net "P5E_PEX0_STN2_TX_DN<47>")
	)
	(gr_poly
		(pts
			(arc
				(start 45.60316 -312.049922)
				(mid 45.19676 -312.049922)
				(end 45.60316 -312.049922)
			)
		)
		(stroke
			(width 0)
			(type solid)
		)
		(fill yes)
		(layer "In8.Cu")
		(net "P5E_PEX0_STN6_TX_DN<109>")
	)
	(gr_poly
		(pts
			(arc
				(start 45.60316 -311.099962)
				(mid 45.19676 -311.099962)
				(end 45.60316 -311.099962)
			)
		)
		(stroke
			(width 0)
			(type solid)
		)
		(fill yes)
		(layer "In8.Cu")
		(net "P5E_PEX0_STN6_TX_DP<109>")
	)
	(gr_poly
		(pts
			(arc
				(start 45.60316 -280.699718)
				(mid 45.19676 -280.699718)
				(end 45.60316 -280.699718)
			)
		)
		(stroke
			(width 0)
			(type solid)
		)
		(fill yes)
		(layer "In8.Cu")
		(net "P5E_PEX0_STN2_TX_DP<46>")
	)
	(gr_poly
		(pts
			(arc
				(start 45.60316 -279.749504)
				(mid 45.19676 -279.749504)
				(end 45.60316 -279.749504)
			)
		)
		(stroke
			(width 0)
			(type solid)
		)
		(fill yes)
		(layer "In8.Cu")
		(net "P5E_PEX0_STN2_TX_DN<46>")
	)
	(gr_poly
		(pts
			(arc
				(start 46.55312 -313.949842)
				(mid 46.14672 -313.949842)
				(end 46.55312 -313.949842)
			)
		)
		(stroke
			(width 0)
			(type solid)
		)
		(fill yes)
		(layer "In8.Cu")
		(net "P5E_PEX0_STN6_TX_DN<108>")
	)
	(gr_poly
		(pts
			(arc
				(start 46.55312 -312.999882)
				(mid 46.14672 -312.999882)
				(end 46.55312 -312.999882)
			)
		)
		(stroke
			(width 0)
			(type solid)
		)
		(fill yes)
		(layer "In8.Cu")
		(net "P5E_PEX0_STN6_TX_DP<108>")
	)
	(gr_poly
		(pts
			(arc
				(start 46.55312 -278.799798)
				(mid 46.14672 -278.799798)
				(end 46.55312 -278.799798)
			)
		)
		(stroke
			(width 0)
			(type solid)
		)
		(fill yes)
		(layer "In8.Cu")
		(net "P5E_PEX0_STN2_TX_DP<45>")
	)
	(gr_poly
		(pts
			(arc
				(start 46.55312 -277.849838)
				(mid 46.14672 -277.849838)
				(end 46.55312 -277.849838)
			)
		)
		(stroke
			(width 0)
			(type solid)
		)
		(fill yes)
		(layer "In8.Cu")
		(net "P5E_PEX0_STN2_TX_DN<45>")
	)
	(gr_poly
		(pts
			(arc
				(start 47.50308 -312.049922)
				(mid 47.09668 -312.049922)
				(end 47.50308 -312.049922)
			)
		)
		(stroke
			(width 0)
			(type solid)
		)
		(fill yes)
		(layer "In8.Cu")
		(net "P5E_PEX0_STN6_TX_DN<107>")
	)
	(gr_poly
		(pts
			(arc
				(start 47.50308 -311.099962)
				(mid 47.09668 -311.099962)
				(end 47.50308 -311.099962)
			)
		)
		(stroke
			(width 0)
			(type solid)
		)
		(fill yes)
		(layer "In8.Cu")
		(net "P5E_PEX0_STN6_TX_DP<107>")
	)
	(gr_poly
		(pts
			(arc
				(start 47.50308 -280.699718)
				(mid 47.09668 -280.699718)
				(end 47.50308 -280.699718)
			)
		)
		(stroke
			(width 0)
			(type solid)
		)
		(fill yes)
		(layer "In8.Cu")
		(net "P5E_PEX0_STN2_TX_DP<44>")
	)
	(gr_poly
		(pts
			(arc
				(start 47.50308 -279.749504)
				(mid 47.09668 -279.749504)
				(end 47.50308 -279.749504)
			)
		)
		(stroke
			(width 0)
			(type solid)
		)
		(fill yes)
		(layer "In8.Cu")
		(net "P5E_PEX0_STN2_TX_DN<44>")
	)
	(gr_poly
		(pts
			(arc
				(start 48.45304 -313.949842)
				(mid 48.04664 -313.949842)
				(end 48.45304 -313.949842)
			)
		)
		(stroke
			(width 0)
			(type solid)
		)
		(fill yes)
		(layer "In8.Cu")
		(net "P5E_PEX0_STN6_TX_DN<106>")
	)
	(gr_poly
		(pts
			(arc
				(start 48.45304 -312.999882)
				(mid 48.04664 -312.999882)
				(end 48.45304 -312.999882)
			)
		)
		(stroke
			(width 0)
			(type solid)
		)
		(fill yes)
		(layer "In8.Cu")
		(net "P5E_PEX0_STN6_TX_DP<106>")
	)
	(gr_poly
		(pts
			(arc
				(start 48.45304 -278.799798)
				(mid 48.04664 -278.799798)
				(end 48.45304 -278.799798)
			)
		)
		(stroke
			(width 0)
			(type solid)
		)
		(fill yes)
		(layer "In8.Cu")
		(net "P5E_PEX0_STN2_TX_DP<43>")
	)
	(gr_poly
		(pts
			(arc
				(start 48.45304 -277.849838)
				(mid 48.04664 -277.849838)
				(end 48.45304 -277.849838)
			)
		)
		(stroke
			(width 0)
			(type solid)
		)
		(fill yes)
		(layer "In8.Cu")
		(net "P5E_PEX0_STN2_TX_DN<43>")
	)
	(gr_poly
		(pts
			(arc
				(start 49.403 -312.049922)
				(mid 48.9966 -312.049922)
				(end 49.403 -312.049922)
			)
		)
		(stroke
			(width 0)
			(type solid)
		)
		(fill yes)
		(layer "In8.Cu")
		(net "P5E_PEX0_STN6_TX_DN<105>")
	)
	(gr_poly
		(pts
			(arc
				(start 49.403 -311.099962)
				(mid 48.9966 -311.099962)
				(end 49.403 -311.099962)
			)
		)
		(stroke
			(width 0)
			(type solid)
		)
		(fill yes)
		(layer "In8.Cu")
		(net "P5E_PEX0_STN6_TX_DP<105>")
	)
	(gr_poly
		(pts
			(arc
				(start 49.403 -280.699718)
				(mid 48.9966 -280.699718)
				(end 49.403 -280.699718)
			)
		)
		(stroke
			(width 0)
			(type solid)
		)
		(fill yes)
		(layer "In8.Cu")
		(net "P5E_PEX0_STN2_TX_DP<42>")
	)
	(gr_poly
		(pts
			(arc
				(start 49.403 -279.749504)
				(mid 48.9966 -279.749504)
				(end 49.403 -279.749504)
			)
		)
		(stroke
			(width 0)
			(type solid)
		)
		(fill yes)
		(layer "In8.Cu")
		(net "P5E_PEX0_STN2_TX_DN<42>")
	)
	(gr_poly
		(pts
			(arc
				(start 50.35296 -313.949842)
				(mid 49.94656 -313.949842)
				(end 50.35296 -313.949842)
			)
		)
		(stroke
			(width 0)
			(type solid)
		)
		(fill yes)
		(layer "In8.Cu")
		(net "P5E_PEX0_STN6_TX_DN<104>")
	)
	(gr_poly
		(pts
			(arc
				(start 50.35296 -312.999882)
				(mid 49.94656 -312.999882)
				(end 50.35296 -312.999882)
			)
		)
		(stroke
			(width 0)
			(type solid)
		)
		(fill yes)
		(layer "In8.Cu")
		(net "P5E_PEX0_STN6_TX_DP<104>")
	)
	(gr_poly
		(pts
			(arc
				(start 50.35296 -278.799798)
				(mid 49.94656 -278.799798)
				(end 50.35296 -278.799798)
			)
		)
		(stroke
			(width 0)
			(type solid)
		)
		(fill yes)
		(layer "In8.Cu")
		(net "P5E_PEX0_STN2_TX_DP<41>")
	)
	(gr_poly
		(pts
			(arc
				(start 50.35296 -277.849838)
				(mid 49.94656 -277.849838)
				(end 50.35296 -277.849838)
			)
		)
		(stroke
			(width 0)
			(type solid)
		)
		(fill yes)
		(layer "In8.Cu")
		(net "P5E_PEX0_STN2_TX_DN<41>")
	)
	(gr_poly
		(pts
			(arc
				(start 51.303174 -316.799722)
				(mid 50.896774 -316.799722)
				(end 51.303174 -316.799722)
			)
		)
		(stroke
			(width 0)
			(type solid)
		)
		(fill yes)
		(layer "In8.Cu")
		(net "P5E_PEX0_STN6_RX_DN<103>")
	)
	(gr_poly
		(pts
			(arc
				(start 51.303174 -315.849762)
				(mid 50.896774 -315.849762)
				(end 51.303174 -315.849762)
			)
		)
		(stroke
			(width 0)
			(type solid)
		)
		(fill yes)
		(layer "In8.Cu")
		(net "P5E_PEX0_STN6_RX_DP<103>")
	)
	(gr_poly
		(pts
			(arc
				(start 51.303174 -312.049922)
				(mid 50.896774 -312.049922)
				(end 51.303174 -312.049922)
			)
		)
		(stroke
			(width 0)
			(type solid)
		)
		(fill yes)
		(layer "In8.Cu")
		(net "P5E_PEX0_STN6_TX_DN<103>")
	)
	(gr_poly
		(pts
			(arc
				(start 51.303174 -311.099962)
				(mid 50.896774 -311.099962)
				(end 51.303174 -311.099962)
			)
		)
		(stroke
			(width 0)
			(type solid)
		)
		(fill yes)
		(layer "In8.Cu")
		(net "P5E_PEX0_STN6_TX_DP<103>")
	)
	(gr_poly
		(pts
			(arc
				(start 51.303174 -280.699718)
				(mid 50.896774 -280.699718)
				(end 51.303174 -280.699718)
			)
		)
		(stroke
			(width 0)
			(type solid)
		)
		(fill yes)
		(layer "In8.Cu")
		(net "P5E_PEX0_STN2_TX_DP<40>")
	)
	(gr_poly
		(pts
			(arc
				(start 51.303174 -279.749504)
				(mid 50.896774 -279.749504)
				(end 51.303174 -279.749504)
			)
		)
		(stroke
			(width 0)
			(type solid)
		)
		(fill yes)
		(layer "In8.Cu")
		(net "P5E_PEX0_STN2_TX_DN<40>")
	)
	(gr_poly
		(pts
			(arc
				(start 52.253134 -318.699896)
				(mid 51.846734 -318.699896)
				(end 52.253134 -318.699896)
			)
		)
		(stroke
			(width 0)
			(type solid)
		)
		(fill yes)
		(layer "In8.Cu")
		(net "P5E_PEX0_STN6_RX_DN<102>")
	)
	(gr_poly
		(pts
			(arc
				(start 52.253134 -317.749936)
				(mid 51.846734 -317.749936)
				(end 52.253134 -317.749936)
			)
		)
		(stroke
			(width 0)
			(type solid)
		)
		(fill yes)
		(layer "In8.Cu")
		(net "P5E_PEX0_STN6_RX_DP<102>")
	)
	(gr_poly
		(pts
			(arc
				(start 52.253134 -313.949842)
				(mid 51.846734 -313.949842)
				(end 52.253134 -313.949842)
			)
		)
		(stroke
			(width 0)
			(type solid)
		)
		(fill yes)
		(layer "In8.Cu")
		(net "P5E_PEX0_STN6_TX_DN<102>")
	)
	(gr_poly
		(pts
			(arc
				(start 52.253134 -312.999882)
				(mid 51.846734 -312.999882)
				(end 52.253134 -312.999882)
			)
		)
		(stroke
			(width 0)
			(type solid)
		)
		(fill yes)
		(layer "In8.Cu")
		(net "P5E_PEX0_STN6_TX_DP<102>")
	)
	(gr_poly
		(pts
			(arc
				(start 52.253134 -278.799798)
				(mid 51.846734 -278.799798)
				(end 52.253134 -278.799798)
			)
		)
		(stroke
			(width 0)
			(type solid)
		)
		(fill yes)
		(layer "In8.Cu")
		(net "P5E_PEX0_STN2_TX_DP<39>")
	)
	(gr_poly
		(pts
			(arc
				(start 52.253134 -277.849838)
				(mid 51.846734 -277.849838)
				(end 52.253134 -277.849838)
			)
		)
		(stroke
			(width 0)
			(type solid)
		)
		(fill yes)
		(layer "In8.Cu")
		(net "P5E_PEX0_STN2_TX_DN<39>")
	)
	(gr_poly
		(pts
			(arc
				(start 53.203094 -316.799722)
				(mid 52.796694 -316.799722)
				(end 53.203094 -316.799722)
			)
		)
		(stroke
			(width 0)
			(type solid)
		)
		(fill yes)
		(layer "In8.Cu")
		(net "P5E_PEX0_STN6_RX_DN<101>")
	)
	(gr_poly
		(pts
			(arc
				(start 53.203094 -315.849762)
				(mid 52.796694 -315.849762)
				(end 53.203094 -315.849762)
			)
		)
		(stroke
			(width 0)
			(type solid)
		)
		(fill yes)
		(layer "In8.Cu")
		(net "P5E_PEX0_STN6_RX_DP<101>")
	)
	(gr_poly
		(pts
			(arc
				(start 53.203094 -312.049922)
				(mid 52.796694 -312.049922)
				(end 53.203094 -312.049922)
			)
		)
		(stroke
			(width 0)
			(type solid)
		)
		(fill yes)
		(layer "In8.Cu")
		(net "P5E_PEX0_STN6_TX_DN<101>")
	)
	(gr_poly
		(pts
			(arc
				(start 53.203094 -311.099962)
				(mid 52.796694 -311.099962)
				(end 53.203094 -311.099962)
			)
		)
		(stroke
			(width 0)
			(type solid)
		)
		(fill yes)
		(layer "In8.Cu")
		(net "P5E_PEX0_STN6_TX_DP<101>")
	)
	(gr_poly
		(pts
			(arc
				(start 53.203094 -280.699718)
				(mid 52.796694 -280.699718)
				(end 53.203094 -280.699718)
			)
		)
		(stroke
			(width 0)
			(type solid)
		)
		(fill yes)
		(layer "In8.Cu")
		(net "P5E_PEX0_STN2_TX_DP<38>")
	)
	(gr_poly
		(pts
			(arc
				(start 53.203094 -279.749504)
				(mid 52.796694 -279.749504)
				(end 53.203094 -279.749504)
			)
		)
		(stroke
			(width 0)
			(type solid)
		)
		(fill yes)
		(layer "In8.Cu")
		(net "P5E_PEX0_STN2_TX_DN<38>")
	)
	(gr_poly
		(pts
			(arc
				(start 54.153054 -318.699896)
				(mid 53.746654 -318.699896)
				(end 54.153054 -318.699896)
			)
		)
		(stroke
			(width 0)
			(type solid)
		)
		(fill yes)
		(layer "In8.Cu")
		(net "P5E_PEX0_STN6_RX_DN<100>")
	)
	(gr_poly
		(pts
			(arc
				(start 54.153054 -317.749936)
				(mid 53.746654 -317.749936)
				(end 54.153054 -317.749936)
			)
		)
		(stroke
			(width 0)
			(type solid)
		)
		(fill yes)
		(layer "In8.Cu")
		(net "P5E_PEX0_STN6_RX_DP<100>")
	)
	(gr_poly
		(pts
			(arc
				(start 54.153054 -313.949842)
				(mid 53.746654 -313.949842)
				(end 54.153054 -313.949842)
			)
		)
		(stroke
			(width 0)
			(type solid)
		)
		(fill yes)
		(layer "In8.Cu")
		(net "P5E_PEX0_STN6_TX_DN<100>")
	)
	(gr_poly
		(pts
			(arc
				(start 54.153054 -312.999882)
				(mid 53.746654 -312.999882)
				(end 54.153054 -312.999882)
			)
		)
		(stroke
			(width 0)
			(type solid)
		)
		(fill yes)
		(layer "In8.Cu")
		(net "P5E_PEX0_STN6_TX_DP<100>")
	)
	(gr_poly
		(pts
			(arc
				(start 54.153054 -278.799798)
				(mid 53.746654 -278.799798)
				(end 54.153054 -278.799798)
			)
		)
		(stroke
			(width 0)
			(type solid)
		)
		(fill yes)
		(layer "In8.Cu")
		(net "P5E_PEX0_STN2_TX_DP<37>")
	)
	(gr_poly
		(pts
			(arc
				(start 54.153054 -277.849838)
				(mid 53.746654 -277.849838)
				(end 54.153054 -277.849838)
			)
		)
		(stroke
			(width 0)
			(type solid)
		)
		(fill yes)
		(layer "In8.Cu")
		(net "P5E_PEX0_STN2_TX_DN<37>")
	)
	(gr_poly
		(pts
			(arc
				(start 55.103014 -316.799722)
				(mid 54.696614 -316.799722)
				(end 55.103014 -316.799722)
			)
		)
		(stroke
			(width 0)
			(type solid)
		)
		(fill yes)
		(layer "In8.Cu")
		(net "P5E_PEX0_STN6_RX_DN<99>")
	)
	(gr_poly
		(pts
			(arc
				(start 55.103014 -315.849762)
				(mid 54.696614 -315.849762)
				(end 55.103014 -315.849762)
			)
		)
		(stroke
			(width 0)
			(type solid)
		)
		(fill yes)
		(layer "In8.Cu")
		(net "P5E_PEX0_STN6_RX_DP<99>")
	)
	(gr_poly
		(pts
			(arc
				(start 55.103014 -312.049922)
				(mid 54.696614 -312.049922)
				(end 55.103014 -312.049922)
			)
		)
		(stroke
			(width 0)
			(type solid)
		)
		(fill yes)
		(layer "In8.Cu")
		(net "P5E_PEX0_STN6_TX_DN<99>")
	)
	(gr_poly
		(pts
			(arc
				(start 55.103014 -311.099962)
				(mid 54.696614 -311.099962)
				(end 55.103014 -311.099962)
			)
		)
		(stroke
			(width 0)
			(type solid)
		)
		(fill yes)
		(layer "In8.Cu")
		(net "P5E_PEX0_STN6_TX_DP<99>")
	)
	(gr_poly
		(pts
			(arc
				(start 55.103014 -280.699718)
				(mid 54.696614 -280.699718)
				(end 55.103014 -280.699718)
			)
		)
		(stroke
			(width 0)
			(type solid)
		)
		(fill yes)
		(layer "In8.Cu")
		(net "P5E_PEX0_STN2_TX_DP<36>")
	)
	(gr_poly
		(pts
			(arc
				(start 55.103014 -279.749504)
				(mid 54.696614 -279.749504)
				(end 55.103014 -279.749504)
			)
		)
		(stroke
			(width 0)
			(type solid)
		)
		(fill yes)
		(layer "In8.Cu")
		(net "P5E_PEX0_STN2_TX_DN<36>")
	)
	(gr_poly
		(pts
			(arc
				(start 56.052974 -318.699896)
				(mid 55.646574 -318.699896)
				(end 56.052974 -318.699896)
			)
		)
		(stroke
			(width 0)
			(type solid)
		)
		(fill yes)
		(layer "In8.Cu")
		(net "P5E_PEX0_STN6_RX_DN<98>")
	)
	(gr_poly
		(pts
			(arc
				(start 56.052974 -317.749936)
				(mid 55.646574 -317.749936)
				(end 56.052974 -317.749936)
			)
		)
		(stroke
			(width 0)
			(type solid)
		)
		(fill yes)
		(layer "In8.Cu")
		(net "P5E_PEX0_STN6_RX_DP<98>")
	)
	(gr_poly
		(pts
			(arc
				(start 56.052974 -313.949842)
				(mid 55.646574 -313.949842)
				(end 56.052974 -313.949842)
			)
		)
		(stroke
			(width 0)
			(type solid)
		)
		(fill yes)
		(layer "In8.Cu")
		(net "P5E_PEX0_STN6_TX_DN<98>")
	)
	(gr_poly
		(pts
			(arc
				(start 56.052974 -312.999882)
				(mid 55.646574 -312.999882)
				(end 56.052974 -312.999882)
			)
		)
		(stroke
			(width 0)
			(type solid)
		)
		(fill yes)
		(layer "In8.Cu")
		(net "P5E_PEX0_STN6_TX_DP<98>")
	)
	(gr_poly
		(pts
			(arc
				(start 56.052974 -278.799798)
				(mid 55.646574 -278.799798)
				(end 56.052974 -278.799798)
			)
		)
		(stroke
			(width 0)
			(type solid)
		)
		(fill yes)
		(layer "In8.Cu")
		(net "P5E_PEX0_STN2_TX_DP<35>")
	)
	(gr_poly
		(pts
			(arc
				(start 56.052974 -277.849838)
				(mid 55.646574 -277.849838)
				(end 56.052974 -277.849838)
			)
		)
		(stroke
			(width 0)
			(type solid)
		)
		(fill yes)
		(layer "In8.Cu")
		(net "P5E_PEX0_STN2_TX_DN<35>")
	)
	(gr_poly
		(pts
			(arc
				(start 57.002934 -280.699718)
				(mid 56.596534 -280.699718)
				(end 57.002934 -280.699718)
			)
		)
		(stroke
			(width 0)
			(type solid)
		)
		(fill yes)
		(layer "In8.Cu")
		(net "P5E_PEX0_STN2_TX_DP<34>")
	)
	(gr_poly
		(pts
			(arc
				(start 57.002934 -279.749504)
				(mid 56.596534 -279.749504)
				(end 57.002934 -279.749504)
			)
		)
		(stroke
			(width 0)
			(type solid)
		)
		(fill yes)
		(layer "In8.Cu")
		(net "P5E_PEX0_STN2_TX_DN<34>")
	)
	(gr_poly
		(pts
			(arc
				(start 57.003188 -316.799722)
				(mid 56.596788 -316.799722)
				(end 57.003188 -316.799722)
			)
		)
		(stroke
			(width 0)
			(type solid)
		)
		(fill yes)
		(layer "In8.Cu")
		(net "P5E_PEX0_STN6_RX_DN<97>")
	)
	(gr_poly
		(pts
			(arc
				(start 57.003188 -315.849762)
				(mid 56.596788 -315.849762)
				(end 57.003188 -315.849762)
			)
		)
		(stroke
			(width 0)
			(type solid)
		)
		(fill yes)
		(layer "In8.Cu")
		(net "P5E_PEX0_STN6_RX_DP<97>")
	)
	(gr_poly
		(pts
			(arc
				(start 57.003188 -312.049922)
				(mid 56.596788 -312.049922)
				(end 57.003188 -312.049922)
			)
		)
		(stroke
			(width 0)
			(type solid)
		)
		(fill yes)
		(layer "In8.Cu")
		(net "P5E_PEX0_STN6_TX_DN<97>")
	)
	(gr_poly
		(pts
			(arc
				(start 57.003188 -311.099962)
				(mid 56.596788 -311.099962)
				(end 57.003188 -311.099962)
			)
		)
		(stroke
			(width 0)
			(type solid)
		)
		(fill yes)
		(layer "In8.Cu")
		(net "P5E_PEX0_STN6_TX_DP<97>")
	)
	(gr_poly
		(pts
			(arc
				(start 57.953148 -318.699896)
				(mid 57.546748 -318.699896)
				(end 57.953148 -318.699896)
			)
		)
		(stroke
			(width 0)
			(type solid)
		)
		(fill yes)
		(layer "In8.Cu")
		(net "P5E_PEX0_STN6_RX_DN<96>")
	)
	(gr_poly
		(pts
			(arc
				(start 57.953148 -317.749936)
				(mid 57.546748 -317.749936)
				(end 57.953148 -317.749936)
			)
		)
		(stroke
			(width 0)
			(type solid)
		)
		(fill yes)
		(layer "In8.Cu")
		(net "P5E_PEX0_STN6_RX_DP<96>")
	)
	(gr_poly
		(pts
			(arc
				(start 57.953148 -313.949842)
				(mid 57.546748 -313.949842)
				(end 57.953148 -313.949842)
			)
		)
		(stroke
			(width 0)
			(type solid)
		)
		(fill yes)
		(layer "In8.Cu")
		(net "P5E_PEX0_STN6_TX_DN<96>")
	)
	(gr_poly
		(pts
			(arc
				(start 57.953148 -312.999882)
				(mid 57.546748 -312.999882)
				(end 57.953148 -312.999882)
			)
		)
		(stroke
			(width 0)
			(type solid)
		)
		(fill yes)
		(layer "In8.Cu")
		(net "P5E_PEX0_STN6_TX_DP<96>")
	)
	(gr_poly
		(pts
			(arc
				(start 57.953148 -278.799798)
				(mid 57.546748 -278.799798)
				(end 57.953148 -278.799798)
			)
		)
		(stroke
			(width 0)
			(type solid)
		)
		(fill yes)
		(layer "In8.Cu")
		(net "P5E_PEX0_STN2_TX_DP<33>")
	)
	(gr_poly
		(pts
			(arc
				(start 57.953148 -277.849838)
				(mid 57.546748 -277.849838)
				(end 57.953148 -277.849838)
			)
		)
		(stroke
			(width 0)
			(type solid)
		)
		(fill yes)
		(layer "In8.Cu")
		(net "P5E_PEX0_STN2_TX_DN<33>")
	)
	(gr_poly
		(pts
			(arc
				(start 58.903108 -316.799722)
				(mid 58.496708 -316.799722)
				(end 58.903108 -316.799722)
			)
		)
		(stroke
			(width 0)
			(type solid)
		)
		(fill yes)
		(layer "In8.Cu")
		(net "P5E_PEX0_STN5_RX_DN<80>")
	)
	(gr_poly
		(pts
			(arc
				(start 58.903108 -315.849762)
				(mid 58.496708 -315.849762)
				(end 58.903108 -315.849762)
			)
		)
		(stroke
			(width 0)
			(type solid)
		)
		(fill yes)
		(layer "In8.Cu")
		(net "P5E_PEX0_STN5_RX_DP<80>")
	)
	(gr_poly
		(pts
			(arc
				(start 58.903108 -280.699718)
				(mid 58.496708 -280.699718)
				(end 58.903108 -280.699718)
			)
		)
		(stroke
			(width 0)
			(type solid)
		)
		(fill yes)
		(layer "In8.Cu")
		(net "P5E_PEX0_STN2_TX_DP<32>")
	)
	(gr_poly
		(pts
			(arc
				(start 58.903108 -279.749504)
				(mid 58.496708 -279.749504)
				(end 58.903108 -279.749504)
			)
		)
		(stroke
			(width 0)
			(type solid)
		)
		(fill yes)
		(layer "In8.Cu")
		(net "P5E_PEX0_STN2_TX_DN<32>")
	)
	(gr_poly
		(pts
			(arc
				(start 59.852814 -278.799798)
				(mid 59.446414 -278.799798)
				(end 59.852814 -278.799798)
			)
		)
		(stroke
			(width 0)
			(type solid)
		)
		(fill yes)
		(layer "In8.Cu")
		(net "P5E_PEX0_STN1_TX_DP<16>")
	)
	(gr_poly
		(pts
			(arc
				(start 59.852814 -277.849838)
				(mid 59.446414 -277.849838)
				(end 59.852814 -277.849838)
			)
		)
		(stroke
			(width 0)
			(type solid)
		)
		(fill yes)
		(layer "In8.Cu")
		(net "P5E_PEX0_STN1_TX_DN<16>")
	)
	(gr_poly
		(pts
			(arc
				(start 59.853068 -318.699896)
				(mid 59.446668 -318.699896)
				(end 59.853068 -318.699896)
			)
		)
		(stroke
			(width 0)
			(type solid)
		)
		(fill yes)
		(layer "In8.Cu")
		(net "P5E_PEX0_STN5_RX_DN<81>")
	)
	(gr_poly
		(pts
			(arc
				(start 59.853068 -317.749936)
				(mid 59.446668 -317.749936)
				(end 59.853068 -317.749936)
			)
		)
		(stroke
			(width 0)
			(type solid)
		)
		(fill yes)
		(layer "In8.Cu")
		(net "P5E_PEX0_STN5_RX_DP<81>")
	)
	(gr_poly
		(pts
			(arc
				(start 60.803028 -316.799722)
				(mid 60.396628 -316.799722)
				(end 60.803028 -316.799722)
			)
		)
		(stroke
			(width 0)
			(type solid)
		)
		(fill yes)
		(layer "In8.Cu")
		(net "P5E_PEX0_STN5_RX_DN<82>")
	)
	(gr_poly
		(pts
			(arc
				(start 60.803028 -315.849762)
				(mid 60.396628 -315.849762)
				(end 60.803028 -315.849762)
			)
		)
		(stroke
			(width 0)
			(type solid)
		)
		(fill yes)
		(layer "In8.Cu")
		(net "P5E_PEX0_STN5_RX_DP<82>")
	)
	(gr_poly
		(pts
			(arc
				(start 60.803028 -280.699718)
				(mid 60.396628 -280.699718)
				(end 60.803028 -280.699718)
			)
		)
		(stroke
			(width 0)
			(type solid)
		)
		(fill yes)
		(layer "In8.Cu")
		(net "P5E_PEX0_STN1_TX_DN<17>")
	)
	(gr_poly
		(pts
			(arc
				(start 60.803028 -279.749504)
				(mid 60.396628 -279.749504)
				(end 60.803028 -279.749504)
			)
		)
		(stroke
			(width 0)
			(type solid)
		)
		(fill yes)
		(layer "In8.Cu")
		(net "P5E_PEX0_STN1_TX_DP<17>")
	)
	(gr_poly
		(pts
			(arc
				(start 61.752734 -278.799798)
				(mid 61.346334 -278.799798)
				(end 61.752734 -278.799798)
			)
		)
		(stroke
			(width 0)
			(type solid)
		)
		(fill yes)
		(layer "In8.Cu")
		(net "P5E_PEX0_STN1_TX_DP<18>")
	)
	(gr_poly
		(pts
			(arc
				(start 61.752734 -277.849838)
				(mid 61.346334 -277.849838)
				(end 61.752734 -277.849838)
			)
		)
		(stroke
			(width 0)
			(type solid)
		)
		(fill yes)
		(layer "In8.Cu")
		(net "P5E_PEX0_STN1_TX_DN<18>")
	)
	(gr_poly
		(pts
			(arc
				(start 61.752988 -318.699896)
				(mid 61.346588 -318.699896)
				(end 61.752988 -318.699896)
			)
		)
		(stroke
			(width 0)
			(type solid)
		)
		(fill yes)
		(layer "In8.Cu")
		(net "P5E_PEX0_STN5_RX_DN<83>")
	)
	(gr_poly
		(pts
			(arc
				(start 61.752988 -317.749936)
				(mid 61.346588 -317.749936)
				(end 61.752988 -317.749936)
			)
		)
		(stroke
			(width 0)
			(type solid)
		)
		(fill yes)
		(layer "In8.Cu")
		(net "P5E_PEX0_STN5_RX_DP<83>")
	)
	(gr_poly
		(pts
			(arc
				(start 62.702948 -316.799722)
				(mid 62.296548 -316.799722)
				(end 62.702948 -316.799722)
			)
		)
		(stroke
			(width 0)
			(type solid)
		)
		(fill yes)
		(layer "In8.Cu")
		(net "P5E_PEX0_STN5_RX_DN<84>")
	)
	(gr_poly
		(pts
			(arc
				(start 62.702948 -315.849762)
				(mid 62.296548 -315.849762)
				(end 62.702948 -315.849762)
			)
		)
		(stroke
			(width 0)
			(type solid)
		)
		(fill yes)
		(layer "In8.Cu")
		(net "P5E_PEX0_STN5_RX_DP<84>")
	)
	(gr_poly
		(pts
			(arc
				(start 62.702948 -280.699718)
				(mid 62.296548 -280.699718)
				(end 62.702948 -280.699718)
			)
		)
		(stroke
			(width 0)
			(type solid)
		)
		(fill yes)
		(layer "In8.Cu")
		(net "P5E_PEX0_STN1_TX_DN<19>")
	)
	(gr_poly
		(pts
			(arc
				(start 62.702948 -279.749504)
				(mid 62.296548 -279.749504)
				(end 62.702948 -279.749504)
			)
		)
		(stroke
			(width 0)
			(type solid)
		)
		(fill yes)
		(layer "In8.Cu")
		(net "P5E_PEX0_STN1_TX_DP<19>")
	)
	(gr_poly
		(pts
			(arc
				(start 63.652908 -278.799798)
				(mid 63.246508 -278.799798)
				(end 63.652908 -278.799798)
			)
		)
		(stroke
			(width 0)
			(type solid)
		)
		(fill yes)
		(layer "In8.Cu")
		(net "P5E_PEX0_STN1_TX_DP<20>")
	)
	(gr_poly
		(pts
			(arc
				(start 63.652908 -277.849838)
				(mid 63.246508 -277.849838)
				(end 63.652908 -277.849838)
			)
		)
		(stroke
			(width 0)
			(type solid)
		)
		(fill yes)
		(layer "In8.Cu")
		(net "P5E_PEX0_STN1_TX_DN<20>")
	)
	(gr_poly
		(pts
			(arc
				(start 63.653162 -318.699896)
				(mid 63.246762 -318.699896)
				(end 63.653162 -318.699896)
			)
		)
		(stroke
			(width 0)
			(type solid)
		)
		(fill yes)
		(layer "In8.Cu")
		(net "P5E_PEX0_STN5_RX_DN<85>")
	)
	(gr_poly
		(pts
			(arc
				(start 63.653162 -317.749936)
				(mid 63.246762 -317.749936)
				(end 63.653162 -317.749936)
			)
		)
		(stroke
			(width 0)
			(type solid)
		)
		(fill yes)
		(layer "In8.Cu")
		(net "P5E_PEX0_STN5_RX_DP<85>")
	)
	(gr_poly
		(pts
			(arc
				(start 64.603122 -316.799722)
				(mid 64.196722 -316.799722)
				(end 64.603122 -316.799722)
			)
		)
		(stroke
			(width 0)
			(type solid)
		)
		(fill yes)
		(layer "In8.Cu")
		(net "P5E_PEX0_STN5_RX_DN<86>")
	)
	(gr_poly
		(pts
			(arc
				(start 64.603122 -315.849762)
				(mid 64.196722 -315.849762)
				(end 64.603122 -315.849762)
			)
		)
		(stroke
			(width 0)
			(type solid)
		)
		(fill yes)
		(layer "In8.Cu")
		(net "P5E_PEX0_STN5_RX_DP<86>")
	)
	(gr_poly
		(pts
			(arc
				(start 64.603122 -280.699718)
				(mid 64.196722 -280.699718)
				(end 64.603122 -280.699718)
			)
		)
		(stroke
			(width 0)
			(type solid)
		)
		(fill yes)
		(layer "In8.Cu")
		(net "P5E_PEX0_STN1_TX_DN<21>")
	)
	(gr_poly
		(pts
			(arc
				(start 64.603122 -279.749504)
				(mid 64.196722 -279.749504)
				(end 64.603122 -279.749504)
			)
		)
		(stroke
			(width 0)
			(type solid)
		)
		(fill yes)
		(layer "In8.Cu")
		(net "P5E_PEX0_STN1_TX_DP<21>")
	)
	(gr_poly
		(pts
			(arc
				(start 65.552828 -278.799798)
				(mid 65.146428 -278.799798)
				(end 65.552828 -278.799798)
			)
		)
		(stroke
			(width 0)
			(type solid)
		)
		(fill yes)
		(layer "In8.Cu")
		(net "P5E_PEX0_STN1_TX_DP<22>")
	)
	(gr_poly
		(pts
			(arc
				(start 65.552828 -277.849838)
				(mid 65.146428 -277.849838)
				(end 65.552828 -277.849838)
			)
		)
		(stroke
			(width 0)
			(type solid)
		)
		(fill yes)
		(layer "In8.Cu")
		(net "P5E_PEX0_STN1_TX_DN<22>")
	)
	(gr_poly
		(pts
			(arc
				(start 65.553082 -318.699896)
				(mid 65.146682 -318.699896)
				(end 65.553082 -318.699896)
			)
		)
		(stroke
			(width 0)
			(type solid)
		)
		(fill yes)
		(layer "In8.Cu")
		(net "P5E_PEX0_STN5_RX_DN<87>")
	)
	(gr_poly
		(pts
			(arc
				(start 65.553082 -317.749936)
				(mid 65.146682 -317.749936)
				(end 65.553082 -317.749936)
			)
		)
		(stroke
			(width 0)
			(type solid)
		)
		(fill yes)
		(layer "In8.Cu")
		(net "P5E_PEX0_STN5_RX_DP<87>")
	)
	(gr_poly
		(pts
			(arc
				(start 66.503042 -280.699718)
				(mid 66.096642 -280.699718)
				(end 66.503042 -280.699718)
			)
		)
		(stroke
			(width 0)
			(type solid)
		)
		(fill yes)
		(layer "In8.Cu")
		(net "P5E_PEX0_STN1_TX_DN<23>")
	)
	(gr_poly
		(pts
			(arc
				(start 66.503042 -279.749504)
				(mid 66.096642 -279.749504)
				(end 66.503042 -279.749504)
			)
		)
		(stroke
			(width 0)
			(type solid)
		)
		(fill yes)
		(layer "In8.Cu")
		(net "P5E_PEX0_STN1_TX_DP<23>")
	)
	(gr_poly
		(pts
			(arc
				(start 67.452748 -278.799798)
				(mid 67.046348 -278.799798)
				(end 67.452748 -278.799798)
			)
		)
		(stroke
			(width 0)
			(type solid)
		)
		(fill yes)
		(layer "In8.Cu")
		(net "P5E_PEX0_STN1_TX_DP<24>")
	)
	(gr_poly
		(pts
			(arc
				(start 67.452748 -277.849838)
				(mid 67.046348 -277.849838)
				(end 67.452748 -277.849838)
			)
		)
		(stroke
			(width 0)
			(type solid)
		)
		(fill yes)
		(layer "In8.Cu")
		(net "P5E_PEX0_STN1_TX_DN<24>")
	)
	(gr_poly
		(pts
			(arc
				(start 68.402962 -280.699718)
				(mid 67.996562 -280.699718)
				(end 68.402962 -280.699718)
			)
		)
		(stroke
			(width 0)
			(type solid)
		)
		(fill yes)
		(layer "In8.Cu")
		(net "P5E_PEX0_STN1_TX_DN<25>")
	)
	(gr_poly
		(pts
			(arc
				(start 68.402962 -279.749504)
				(mid 67.996562 -279.749504)
				(end 68.402962 -279.749504)
			)
		)
		(stroke
			(width 0)
			(type solid)
		)
		(fill yes)
		(layer "In8.Cu")
		(net "P5E_PEX0_STN1_TX_DP<25>")
	)
	(gr_poly
		(pts
			(arc
				(start 69.352922 -278.799798)
				(mid 68.946522 -278.799798)
				(end 69.352922 -278.799798)
			)
		)
		(stroke
			(width 0)
			(type solid)
		)
		(fill yes)
		(layer "In8.Cu")
		(net "P5E_PEX0_STN1_TX_DP<26>")
	)
	(gr_poly
		(pts
			(arc
				(start 69.352922 -277.849838)
				(mid 68.946522 -277.849838)
				(end 69.352922 -277.849838)
			)
		)
		(stroke
			(width 0)
			(type solid)
		)
		(fill yes)
		(layer "In8.Cu")
		(net "P5E_PEX0_STN1_TX_DN<26>")
	)
	(gr_poly
		(pts
			(arc
				(start 70.303136 -280.699718)
				(mid 69.896736 -280.699718)
				(end 70.303136 -280.699718)
			)
		)
		(stroke
			(width 0)
			(type solid)
		)
		(fill yes)
		(layer "In8.Cu")
		(net "P5E_PEX0_STN1_TX_DN<27>")
	)
	(gr_poly
		(pts
			(arc
				(start 70.303136 -279.749504)
				(mid 69.896736 -279.749504)
				(end 70.303136 -279.749504)
			)
		)
		(stroke
			(width 0)
			(type solid)
		)
		(fill yes)
		(layer "In8.Cu")
		(net "P5E_PEX0_STN1_TX_DP<27>")
	)
	(gr_poly
		(pts
			(arc
				(start 71.252842 -278.799798)
				(mid 70.846442 -278.799798)
				(end 71.252842 -278.799798)
			)
		)
		(stroke
			(width 0)
			(type solid)
		)
		(fill yes)
		(layer "In8.Cu")
		(net "P5E_PEX0_STN1_TX_DP<28>")
	)
	(gr_poly
		(pts
			(arc
				(start 71.252842 -277.849838)
				(mid 70.846442 -277.849838)
				(end 71.252842 -277.849838)
			)
		)
		(stroke
			(width 0)
			(type solid)
		)
		(fill yes)
		(layer "In8.Cu")
		(net "P5E_PEX0_STN1_TX_DN<28>")
	)
	(gr_poly
		(pts
			(arc
				(start 72.203056 -280.699718)
				(mid 71.796656 -280.699718)
				(end 72.203056 -280.699718)
			)
		)
		(stroke
			(width 0)
			(type solid)
		)
		(fill yes)
		(layer "In8.Cu")
		(net "P5E_PEX0_STN1_TX_DN<29>")
	)
	(gr_poly
		(pts
			(arc
				(start 72.203056 -279.749504)
				(mid 71.796656 -279.749504)
				(end 72.203056 -279.749504)
			)
		)
		(stroke
			(width 0)
			(type solid)
		)
		(fill yes)
		(layer "In8.Cu")
		(net "P5E_PEX0_STN1_TX_DP<29>")
	)
	(gr_poly
		(pts
			(arc
				(start 73.152762 -278.799798)
				(mid 72.746362 -278.799798)
				(end 73.152762 -278.799798)
			)
		)
		(stroke
			(width 0)
			(type solid)
		)
		(fill yes)
		(layer "In8.Cu")
		(net "P5E_PEX0_STN1_TX_DP<30>")
	)
	(gr_poly
		(pts
			(arc
				(start 73.152762 -277.849838)
				(mid 72.746362 -277.849838)
				(end 73.152762 -277.849838)
			)
		)
		(stroke
			(width 0)
			(type solid)
		)
		(fill yes)
		(layer "In8.Cu")
		(net "P5E_PEX0_STN1_TX_DN<30>")
	)
	(gr_poly
		(pts
			(arc
				(start 74.102976 -316.799722)
				(mid 73.696576 -316.799722)
				(end 74.102976 -316.799722)
			)
		)
		(stroke
			(width 0)
			(type solid)
		)
		(fill yes)
		(layer "In8.Cu")
		(net "P5E_PEX0_STN4_RX_DN<79>")
	)
	(gr_poly
		(pts
			(arc
				(start 74.102976 -315.849762)
				(mid 73.696576 -315.849762)
				(end 74.102976 -315.849762)
			)
		)
		(stroke
			(width 0)
			(type solid)
		)
		(fill yes)
		(layer "In8.Cu")
		(net "P5E_PEX0_STN4_RX_DP<79>")
	)
	(gr_poly
		(pts
			(arc
				(start 74.102976 -312.049922)
				(mid 73.696576 -312.049922)
				(end 74.102976 -312.049922)
			)
		)
		(stroke
			(width 0)
			(type solid)
		)
		(fill yes)
		(layer "In8.Cu")
		(net "P5E_PEX0_STN4_TX_DN<79>")
	)
	(gr_poly
		(pts
			(arc
				(start 74.102976 -311.099962)
				(mid 73.696576 -311.099962)
				(end 74.102976 -311.099962)
			)
		)
		(stroke
			(width 0)
			(type solid)
		)
		(fill yes)
		(layer "In8.Cu")
		(net "P5E_PEX0_STN4_TX_DP<79>")
	)
	(gr_poly
		(pts
			(arc
				(start 74.102976 -280.699718)
				(mid 73.696576 -280.699718)
				(end 74.102976 -280.699718)
			)
		)
		(stroke
			(width 0)
			(type solid)
		)
		(fill yes)
		(layer "In8.Cu")
		(net "P5E_PEX0_STN1_TX_DN<31>")
	)
	(gr_poly
		(pts
			(arc
				(start 74.102976 -279.749504)
				(mid 73.696576 -279.749504)
				(end 74.102976 -279.749504)
			)
		)
		(stroke
			(width 0)
			(type solid)
		)
		(fill yes)
		(layer "In8.Cu")
		(net "P5E_PEX0_STN1_TX_DP<31>")
	)
	(gr_poly
		(pts
			(arc
				(start 75.052936 -287.349946)
				(mid 74.646536 -287.349946)
				(end 75.052936 -287.349946)
			)
		)
		(stroke
			(width 0)
			(type solid)
		)
		(fill yes)
		(layer "In8.Cu")
		(net "P5E_PEX0_STN0_TX_DP<1>")
	)
	(gr_poly
		(pts
			(arc
				(start 75.052936 -285.449772)
				(mid 74.646536 -285.449772)
				(end 75.052936 -285.449772)
			)
		)
		(stroke
			(width 0)
			(type solid)
		)
		(fill yes)
		(layer "In8.Cu")
		(net "P5E_PEX0_STN0_TX_DP<3>")
	)
	(gr_poly
		(pts
			(arc
				(start 75.052936 -283.549852)
				(mid 74.646536 -283.549852)
				(end 75.052936 -283.549852)
			)
		)
		(stroke
			(width 0)
			(type solid)
		)
		(fill yes)
		(layer "In8.Cu")
		(net "P5E_PEX0_STN0_TX_DP<5>")
	)
	(gr_poly
		(pts
			(arc
				(start 75.052936 -278.799798)
				(mid 74.646536 -278.799798)
				(end 75.052936 -278.799798)
			)
		)
		(stroke
			(width 0)
			(type solid)
		)
		(fill yes)
		(layer "In8.Cu")
		(net "P5E_PEX0_STN0_TX_DP<15>")
	)
	(gr_poly
		(pts
			(arc
				(start 75.052936 -277.849838)
				(mid 74.646536 -277.849838)
				(end 75.052936 -277.849838)
			)
		)
		(stroke
			(width 0)
			(type solid)
		)
		(fill yes)
		(layer "In8.Cu")
		(net "P5E_PEX0_STN0_TX_DN<15>")
	)
	(gr_poly
		(pts
			(arc
				(start 75.05319 -318.699896)
				(mid 74.64679 -318.699896)
				(end 75.05319 -318.699896)
			)
		)
		(stroke
			(width 0)
			(type solid)
		)
		(fill yes)
		(layer "In8.Cu")
		(net "P5E_PEX0_STN4_RX_DN<78>")
	)
	(gr_poly
		(pts
			(arc
				(start 75.05319 -317.749936)
				(mid 74.64679 -317.749936)
				(end 75.05319 -317.749936)
			)
		)
		(stroke
			(width 0)
			(type solid)
		)
		(fill yes)
		(layer "In8.Cu")
		(net "P5E_PEX0_STN4_RX_DP<78>")
	)
	(gr_poly
		(pts
			(arc
				(start 75.05319 -313.949842)
				(mid 74.64679 -313.949842)
				(end 75.05319 -313.949842)
			)
		)
		(stroke
			(width 0)
			(type solid)
		)
		(fill yes)
		(layer "In8.Cu")
		(net "P5E_PEX0_STN4_TX_DN<78>")
	)
	(gr_poly
		(pts
			(arc
				(start 75.05319 -312.999882)
				(mid 74.64679 -312.999882)
				(end 75.05319 -312.999882)
			)
		)
		(stroke
			(width 0)
			(type solid)
		)
		(fill yes)
		(layer "In8.Cu")
		(net "P5E_PEX0_STN4_TX_DP<78>")
	)
	(gr_poly
		(pts
			(arc
				(start 75.05319 -308.249828)
				(mid 74.64679 -308.249828)
				(end 75.05319 -308.249828)
			)
		)
		(stroke
			(width 0)
			(type solid)
		)
		(fill yes)
		(layer "In8.Cu")
		(net "P5E_PEX0_STN4_TX_DP<68>")
	)
	(gr_poly
		(pts
			(arc
				(start 75.05319 -306.349908)
				(mid 74.64679 -306.349908)
				(end 75.05319 -306.349908)
			)
		)
		(stroke
			(width 0)
			(type solid)
		)
		(fill yes)
		(layer "In8.Cu")
		(net "P5E_PEX0_STN4_TX_DP<66>")
	)
	(gr_poly
		(pts
			(arc
				(start 75.05319 -304.449734)
				(mid 74.64679 -304.449734)
				(end 75.05319 -304.449734)
			)
		)
		(stroke
			(width 0)
			(type solid)
		)
		(fill yes)
		(layer "In8.Cu")
		(net "P5E_PEX0_STN4_TX_DP<64>")
	)
	(gr_poly
		(pts
			(arc
				(start 76.00315 -316.799722)
				(mid 75.59675 -316.799722)
				(end 76.00315 -316.799722)
			)
		)
		(stroke
			(width 0)
			(type solid)
		)
		(fill yes)
		(layer "In8.Cu")
		(net "P5E_PEX0_STN4_RX_DN<77>")
	)
	(gr_poly
		(pts
			(arc
				(start 76.00315 -315.849762)
				(mid 75.59675 -315.849762)
				(end 76.00315 -315.849762)
			)
		)
		(stroke
			(width 0)
			(type solid)
		)
		(fill yes)
		(layer "In8.Cu")
		(net "P5E_PEX0_STN4_RX_DP<77>")
	)
	(gr_poly
		(pts
			(arc
				(start 76.00315 -312.049922)
				(mid 75.59675 -312.049922)
				(end 76.00315 -312.049922)
			)
		)
		(stroke
			(width 0)
			(type solid)
		)
		(fill yes)
		(layer "In8.Cu")
		(net "P5E_PEX0_STN4_TX_DN<77>")
	)
	(gr_poly
		(pts
			(arc
				(start 76.00315 -311.099962)
				(mid 75.59675 -311.099962)
				(end 76.00315 -311.099962)
			)
		)
		(stroke
			(width 0)
			(type solid)
		)
		(fill yes)
		(layer "In8.Cu")
		(net "P5E_PEX0_STN4_TX_DP<77>")
	)
	(gr_poly
		(pts
			(arc
				(start 76.00315 -308.249828)
				(mid 75.59675 -308.249828)
				(end 76.00315 -308.249828)
			)
		)
		(stroke
			(width 0)
			(type solid)
		)
		(fill yes)
		(layer "In8.Cu")
		(net "P5E_PEX0_STN4_TX_DN<68>")
	)
	(gr_poly
		(pts
			(arc
				(start 76.00315 -306.349908)
				(mid 75.59675 -306.349908)
				(end 76.00315 -306.349908)
			)
		)
		(stroke
			(width 0)
			(type solid)
		)
		(fill yes)
		(layer "In8.Cu")
		(net "P5E_PEX0_STN4_TX_DN<66>")
	)
	(gr_poly
		(pts
			(arc
				(start 76.00315 -304.449734)
				(mid 75.59675 -304.449734)
				(end 76.00315 -304.449734)
			)
		)
		(stroke
			(width 0)
			(type solid)
		)
		(fill yes)
		(layer "In8.Cu")
		(net "P5E_PEX0_STN4_TX_DN<64>")
	)
	(gr_poly
		(pts
			(arc
				(start 76.00315 -287.349946)
				(mid 75.59675 -287.349946)
				(end 76.00315 -287.349946)
			)
		)
		(stroke
			(width 0)
			(type solid)
		)
		(fill yes)
		(layer "In8.Cu")
		(net "P5E_PEX0_STN0_TX_DN<1>")
	)
	(gr_poly
		(pts
			(arc
				(start 76.00315 -285.449772)
				(mid 75.59675 -285.449772)
				(end 76.00315 -285.449772)
			)
		)
		(stroke
			(width 0)
			(type solid)
		)
		(fill yes)
		(layer "In8.Cu")
		(net "P5E_PEX0_STN0_TX_DN<3>")
	)
	(gr_poly
		(pts
			(arc
				(start 76.00315 -283.549852)
				(mid 75.59675 -283.549852)
				(end 76.00315 -283.549852)
			)
		)
		(stroke
			(width 0)
			(type solid)
		)
		(fill yes)
		(layer "In8.Cu")
		(net "P5E_PEX0_STN0_TX_DN<5>")
	)
	(gr_poly
		(pts
			(arc
				(start 76.00315 -280.699718)
				(mid 75.59675 -280.699718)
				(end 76.00315 -280.699718)
			)
		)
		(stroke
			(width 0)
			(type solid)
		)
		(fill yes)
		(layer "In8.Cu")
		(net "P5E_PEX0_STN0_TX_DN<14>")
	)
	(gr_poly
		(pts
			(arc
				(start 76.00315 -279.749504)
				(mid 75.59675 -279.749504)
				(end 76.00315 -279.749504)
			)
		)
		(stroke
			(width 0)
			(type solid)
		)
		(fill yes)
		(layer "In8.Cu")
		(net "P5E_PEX0_STN0_TX_DP<14>")
	)
	(gr_poly
		(pts
			(arc
				(start 76.952856 -278.799798)
				(mid 76.546456 -278.799798)
				(end 76.952856 -278.799798)
			)
		)
		(stroke
			(width 0)
			(type solid)
		)
		(fill yes)
		(layer "In8.Cu")
		(net "P5E_PEX0_STN0_TX_DP<13>")
	)
	(gr_poly
		(pts
			(arc
				(start 76.952856 -277.849838)
				(mid 76.546456 -277.849838)
				(end 76.952856 -277.849838)
			)
		)
		(stroke
			(width 0)
			(type solid)
		)
		(fill yes)
		(layer "In8.Cu")
		(net "P5E_PEX0_STN0_TX_DN<13>")
	)
	(gr_poly
		(pts
			(arc
				(start 76.95311 -318.699896)
				(mid 76.54671 -318.699896)
				(end 76.95311 -318.699896)
			)
		)
		(stroke
			(width 0)
			(type solid)
		)
		(fill yes)
		(layer "In8.Cu")
		(net "P5E_PEX0_STN4_RX_DN<76>")
	)
	(gr_poly
		(pts
			(arc
				(start 76.95311 -317.749936)
				(mid 76.54671 -317.749936)
				(end 76.95311 -317.749936)
			)
		)
		(stroke
			(width 0)
			(type solid)
		)
		(fill yes)
		(layer "In8.Cu")
		(net "P5E_PEX0_STN4_RX_DP<76>")
	)
	(gr_poly
		(pts
			(arc
				(start 76.95311 -313.949842)
				(mid 76.54671 -313.949842)
				(end 76.95311 -313.949842)
			)
		)
		(stroke
			(width 0)
			(type solid)
		)
		(fill yes)
		(layer "In8.Cu")
		(net "P5E_PEX0_STN4_TX_DN<76>")
	)
	(gr_poly
		(pts
			(arc
				(start 76.95311 -312.999882)
				(mid 76.54671 -312.999882)
				(end 76.95311 -312.999882)
			)
		)
		(stroke
			(width 0)
			(type solid)
		)
		(fill yes)
		(layer "In8.Cu")
		(net "P5E_PEX0_STN4_TX_DP<76>")
	)
	(gr_poly
		(pts
			(arc
				(start 76.95311 -309.199788)
				(mid 76.54671 -309.199788)
				(end 76.95311 -309.199788)
			)
		)
		(stroke
			(width 0)
			(type solid)
		)
		(fill yes)
		(layer "In8.Cu")
		(net "P5E_PEX0_STN4_TX_DP<69>")
	)
	(gr_poly
		(pts
			(arc
				(start 76.95311 -307.299868)
				(mid 76.54671 -307.299868)
				(end 76.95311 -307.299868)
			)
		)
		(stroke
			(width 0)
			(type solid)
		)
		(fill yes)
		(layer "In8.Cu")
		(net "P5E_PEX0_STN4_TX_DP<67>")
	)
	(gr_poly
		(pts
			(arc
				(start 76.95311 -305.399948)
				(mid 76.54671 -305.399948)
				(end 76.95311 -305.399948)
			)
		)
		(stroke
			(width 0)
			(type solid)
		)
		(fill yes)
		(layer "In8.Cu")
		(net "P5E_PEX0_STN4_TX_DP<65>")
	)
	(gr_poly
		(pts
			(arc
				(start 76.95311 -288.299906)
				(mid 76.54671 -288.299906)
				(end 76.95311 -288.299906)
			)
		)
		(stroke
			(width 0)
			(type solid)
		)
		(fill yes)
		(layer "In8.Cu")
		(net "P5E_PEX0_STN0_TX_DP<0>")
	)
	(gr_poly
		(pts
			(arc
				(start 76.95311 -286.399986)
				(mid 76.54671 -286.399986)
				(end 76.95311 -286.399986)
			)
		)
		(stroke
			(width 0)
			(type solid)
		)
		(fill yes)
		(layer "In8.Cu")
		(net "P5E_PEX0_STN0_TX_DP<2>")
	)
	(gr_poly
		(pts
			(arc
				(start 76.95311 -284.499812)
				(mid 76.54671 -284.499812)
				(end 76.95311 -284.499812)
			)
		)
		(stroke
			(width 0)
			(type solid)
		)
		(fill yes)
		(layer "In8.Cu")
		(net "P5E_PEX0_STN0_TX_DP<4>")
	)
	(gr_poly
		(pts
			(arc
				(start 76.95311 -282.599892)
				(mid 76.54671 -282.599892)
				(end 76.95311 -282.599892)
			)
		)
		(stroke
			(width 0)
			(type solid)
		)
		(fill yes)
		(layer "In8.Cu")
		(net "P5E_PEX0_STN0_TX_DP<6>")
	)
	(gr_poly
		(pts
			(arc
				(start 77.90307 -316.799722)
				(mid 77.49667 -316.799722)
				(end 77.90307 -316.799722)
			)
		)
		(stroke
			(width 0)
			(type solid)
		)
		(fill yes)
		(layer "In8.Cu")
		(net "P5E_PEX0_STN4_RX_DN<75>")
	)
	(gr_poly
		(pts
			(arc
				(start 77.90307 -315.849762)
				(mid 77.49667 -315.849762)
				(end 77.90307 -315.849762)
			)
		)
		(stroke
			(width 0)
			(type solid)
		)
		(fill yes)
		(layer "In8.Cu")
		(net "P5E_PEX0_STN4_RX_DP<75>")
	)
	(gr_poly
		(pts
			(arc
				(start 77.90307 -312.049922)
				(mid 77.49667 -312.049922)
				(end 77.90307 -312.049922)
			)
		)
		(stroke
			(width 0)
			(type solid)
		)
		(fill yes)
		(layer "In8.Cu")
		(net "P5E_PEX0_STN4_TX_DN<75>")
	)
	(gr_poly
		(pts
			(arc
				(start 77.90307 -311.099962)
				(mid 77.49667 -311.099962)
				(end 77.90307 -311.099962)
			)
		)
		(stroke
			(width 0)
			(type solid)
		)
		(fill yes)
		(layer "In8.Cu")
		(net "P5E_PEX0_STN4_TX_DP<75>")
	)
	(gr_poly
		(pts
			(arc
				(start 77.90307 -309.199788)
				(mid 77.49667 -309.199788)
				(end 77.90307 -309.199788)
			)
		)
		(stroke
			(width 0)
			(type solid)
		)
		(fill yes)
		(layer "In8.Cu")
		(net "P5E_PEX0_STN4_TX_DN<69>")
	)
	(gr_poly
		(pts
			(arc
				(start 77.90307 -307.299868)
				(mid 77.49667 -307.299868)
				(end 77.90307 -307.299868)
			)
		)
		(stroke
			(width 0)
			(type solid)
		)
		(fill yes)
		(layer "In8.Cu")
		(net "P5E_PEX0_STN4_TX_DN<67>")
	)
	(gr_poly
		(pts
			(arc
				(start 77.90307 -305.399948)
				(mid 77.49667 -305.399948)
				(end 77.90307 -305.399948)
			)
		)
		(stroke
			(width 0)
			(type solid)
		)
		(fill yes)
		(layer "In8.Cu")
		(net "P5E_PEX0_STN4_TX_DN<65>")
	)
	(gr_poly
		(pts
			(arc
				(start 77.90307 -288.299906)
				(mid 77.49667 -288.299906)
				(end 77.90307 -288.299906)
			)
		)
		(stroke
			(width 0)
			(type solid)
		)
		(fill yes)
		(layer "In8.Cu")
		(net "P5E_PEX0_STN0_TX_DN<0>")
	)
	(gr_poly
		(pts
			(arc
				(start 77.90307 -286.399986)
				(mid 77.49667 -286.399986)
				(end 77.90307 -286.399986)
			)
		)
		(stroke
			(width 0)
			(type solid)
		)
		(fill yes)
		(layer "In8.Cu")
		(net "P5E_PEX0_STN0_TX_DN<2>")
	)
	(gr_poly
		(pts
			(arc
				(start 77.90307 -284.499812)
				(mid 77.49667 -284.499812)
				(end 77.90307 -284.499812)
			)
		)
		(stroke
			(width 0)
			(type solid)
		)
		(fill yes)
		(layer "In8.Cu")
		(net "P5E_PEX0_STN0_TX_DN<4>")
	)
	(gr_poly
		(pts
			(arc
				(start 77.90307 -282.599892)
				(mid 77.49667 -282.599892)
				(end 77.90307 -282.599892)
			)
		)
		(stroke
			(width 0)
			(type solid)
		)
		(fill yes)
		(layer "In8.Cu")
		(net "P5E_PEX0_STN0_TX_DN<6>")
	)
	(gr_poly
		(pts
			(arc
				(start 77.90307 -280.699718)
				(mid 77.49667 -280.699718)
				(end 77.90307 -280.699718)
			)
		)
		(stroke
			(width 0)
			(type solid)
		)
		(fill yes)
		(layer "In8.Cu")
		(net "P5E_PEX0_STN0_TX_DN<12>")
	)
	(gr_poly
		(pts
			(arc
				(start 77.90307 -279.749504)
				(mid 77.49667 -279.749504)
				(end 77.90307 -279.749504)
			)
		)
		(stroke
			(width 0)
			(type solid)
		)
		(fill yes)
		(layer "In8.Cu")
		(net "P5E_PEX0_STN0_TX_DP<12>")
	)
	(gr_poly
		(pts
			(arc
				(start 78.852776 -278.799798)
				(mid 78.446376 -278.799798)
				(end 78.852776 -278.799798)
			)
		)
		(stroke
			(width 0)
			(type solid)
		)
		(fill yes)
		(layer "In8.Cu")
		(net "P5E_PEX0_STN0_TX_DP<11>")
	)
	(gr_poly
		(pts
			(arc
				(start 78.852776 -277.849838)
				(mid 78.446376 -277.849838)
				(end 78.852776 -277.849838)
			)
		)
		(stroke
			(width 0)
			(type solid)
		)
		(fill yes)
		(layer "In8.Cu")
		(net "P5E_PEX0_STN0_TX_DN<11>")
	)
	(gr_poly
		(pts
			(arc
				(start 78.85303 -318.699896)
				(mid 78.44663 -318.699896)
				(end 78.85303 -318.699896)
			)
		)
		(stroke
			(width 0)
			(type solid)
		)
		(fill yes)
		(layer "In8.Cu")
		(net "P5E_PEX0_STN4_RX_DN<74>")
	)
	(gr_poly
		(pts
			(arc
				(start 78.85303 -317.749936)
				(mid 78.44663 -317.749936)
				(end 78.85303 -317.749936)
			)
		)
		(stroke
			(width 0)
			(type solid)
		)
		(fill yes)
		(layer "In8.Cu")
		(net "P5E_PEX0_STN4_RX_DP<74>")
	)
	(gr_poly
		(pts
			(arc
				(start 78.85303 -313.949842)
				(mid 78.44663 -313.949842)
				(end 78.85303 -313.949842)
			)
		)
		(stroke
			(width 0)
			(type solid)
		)
		(fill yes)
		(layer "In8.Cu")
		(net "P5E_PEX0_STN4_TX_DN<74>")
	)
	(gr_poly
		(pts
			(arc
				(start 78.85303 -312.999882)
				(mid 78.44663 -312.999882)
				(end 78.85303 -312.999882)
			)
		)
		(stroke
			(width 0)
			(type solid)
		)
		(fill yes)
		(layer "In8.Cu")
		(net "P5E_PEX0_STN4_TX_DP<74>")
	)
	(gr_poly
		(pts
			(arc
				(start 79.80299 -316.799722)
				(mid 79.39659 -316.799722)
				(end 79.80299 -316.799722)
			)
		)
		(stroke
			(width 0)
			(type solid)
		)
		(fill yes)
		(layer "In8.Cu")
		(net "P5E_PEX0_STN4_RX_DN<73>")
	)
	(gr_poly
		(pts
			(arc
				(start 79.80299 -315.849762)
				(mid 79.39659 -315.849762)
				(end 79.80299 -315.849762)
			)
		)
		(stroke
			(width 0)
			(type solid)
		)
		(fill yes)
		(layer "In8.Cu")
		(net "P5E_PEX0_STN4_RX_DP<73>")
	)
	(gr_poly
		(pts
			(arc
				(start 79.80299 -312.049922)
				(mid 79.39659 -312.049922)
				(end 79.80299 -312.049922)
			)
		)
		(stroke
			(width 0)
			(type solid)
		)
		(fill yes)
		(layer "In8.Cu")
		(net "P5E_PEX0_STN4_TX_DN<73>")
	)
	(gr_poly
		(pts
			(arc
				(start 79.80299 -311.099962)
				(mid 79.39659 -311.099962)
				(end 79.80299 -311.099962)
			)
		)
		(stroke
			(width 0)
			(type solid)
		)
		(fill yes)
		(layer "In8.Cu")
		(net "P5E_PEX0_STN4_TX_DP<73>")
	)
	(gr_poly
		(pts
			(arc
				(start 79.80299 -309.199788)
				(mid 79.39659 -309.199788)
				(end 79.80299 -309.199788)
			)
		)
		(stroke
			(width 0)
			(type solid)
		)
		(fill yes)
		(layer "In8.Cu")
		(net "P5E_PEX0_STN4_RX_DP<69>")
	)
	(gr_poly
		(pts
			(arc
				(start 79.80299 -307.299868)
				(mid 79.39659 -307.299868)
				(end 79.80299 -307.299868)
			)
		)
		(stroke
			(width 0)
			(type solid)
		)
		(fill yes)
		(layer "In8.Cu")
		(net "P5E_PEX0_STN4_RX_DP<67>")
	)
	(gr_poly
		(pts
			(arc
				(start 79.80299 -305.399948)
				(mid 79.39659 -305.399948)
				(end 79.80299 -305.399948)
			)
		)
		(stroke
			(width 0)
			(type solid)
		)
		(fill yes)
		(layer "In8.Cu")
		(net "P5E_PEX0_STN4_RX_DP<65>")
	)
	(gr_poly
		(pts
			(arc
				(start 79.80299 -280.699718)
				(mid 79.39659 -280.699718)
				(end 79.80299 -280.699718)
			)
		)
		(stroke
			(width 0)
			(type solid)
		)
		(fill yes)
		(layer "In8.Cu")
		(net "P5E_PEX0_STN0_TX_DP<10>")
	)
	(gr_poly
		(pts
			(arc
				(start 79.80299 -279.749758)
				(mid 79.39659 -279.749758)
				(end 79.80299 -279.749758)
			)
		)
		(stroke
			(width 0)
			(type solid)
		)
		(fill yes)
		(layer "In8.Cu")
		(net "P5E_PEX0_STN0_TX_DN<10>")
	)
	(gr_poly
		(pts
			(arc
				(start 80.75295 -318.699896)
				(mid 80.34655 -318.699896)
				(end 80.75295 -318.699896)
			)
		)
		(stroke
			(width 0)
			(type solid)
		)
		(fill yes)
		(layer "In8.Cu")
		(net "P5E_PEX0_STN4_RX_DN<72>")
	)
	(gr_poly
		(pts
			(arc
				(start 80.75295 -317.749936)
				(mid 80.34655 -317.749936)
				(end 80.75295 -317.749936)
			)
		)
		(stroke
			(width 0)
			(type solid)
		)
		(fill yes)
		(layer "In8.Cu")
		(net "P5E_PEX0_STN4_RX_DP<72>")
	)
	(gr_poly
		(pts
			(arc
				(start 80.75295 -313.949842)
				(mid 80.34655 -313.949842)
				(end 80.75295 -313.949842)
			)
		)
		(stroke
			(width 0)
			(type solid)
		)
		(fill yes)
		(layer "In8.Cu")
		(net "P5E_PEX0_STN4_TX_DN<72>")
	)
	(gr_poly
		(pts
			(arc
				(start 80.75295 -312.999882)
				(mid 80.34655 -312.999882)
				(end 80.75295 -312.999882)
			)
		)
		(stroke
			(width 0)
			(type solid)
		)
		(fill yes)
		(layer "In8.Cu")
		(net "P5E_PEX0_STN4_TX_DP<72>")
	)
	(gr_poly
		(pts
			(arc
				(start 80.75295 -309.199788)
				(mid 80.34655 -309.199788)
				(end 80.75295 -309.199788)
			)
		)
		(stroke
			(width 0)
			(type solid)
		)
		(fill yes)
		(layer "In8.Cu")
		(net "P5E_PEX0_STN4_RX_DN<69>")
	)
	(gr_poly
		(pts
			(arc
				(start 80.75295 -307.299868)
				(mid 80.34655 -307.299868)
				(end 80.75295 -307.299868)
			)
		)
		(stroke
			(width 0)
			(type solid)
		)
		(fill yes)
		(layer "In8.Cu")
		(net "P5E_PEX0_STN4_RX_DN<67>")
	)
	(gr_poly
		(pts
			(arc
				(start 80.75295 -305.399948)
				(mid 80.34655 -305.399948)
				(end 80.75295 -305.399948)
			)
		)
		(stroke
			(width 0)
			(type solid)
		)
		(fill yes)
		(layer "In8.Cu")
		(net "P5E_PEX0_STN4_RX_DN<65>")
	)
	(gr_poly
		(pts
			(arc
				(start 80.75295 -278.799798)
				(mid 80.34655 -278.799798)
				(end 80.75295 -278.799798)
			)
		)
		(stroke
			(width 0)
			(type solid)
		)
		(fill yes)
		(layer "In8.Cu")
		(net "P5E_PEX0_STN0_TX_DP<9>")
	)
	(gr_poly
		(pts
			(arc
				(start 80.75295 -277.849838)
				(mid 80.34655 -277.849838)
				(end 80.75295 -277.849838)
			)
		)
		(stroke
			(width 0)
			(type solid)
		)
		(fill yes)
		(layer "In8.Cu")
		(net "P5E_PEX0_STN0_TX_DN<9>")
	)
	(gr_poly
		(pts
			(arc
				(start 81.703164 -316.799722)
				(mid 81.296764 -316.799722)
				(end 81.703164 -316.799722)
			)
		)
		(stroke
			(width 0)
			(type solid)
		)
		(fill yes)
		(layer "In8.Cu")
		(net "P5E_PEX0_STN4_RX_DP<71>")
	)
	(gr_poly
		(pts
			(arc
				(start 81.703164 -314.899802)
				(mid 81.296764 -314.899802)
				(end 81.703164 -314.899802)
			)
		)
		(stroke
			(width 0)
			(type solid)
		)
		(fill yes)
		(layer "In8.Cu")
		(net "P5E_PEX0_STN4_TX_DP<71>")
	)
	(gr_poly
		(pts
			(arc
				(start 81.703164 -312.049922)
				(mid 81.296764 -312.049922)
				(end 81.703164 -312.049922)
			)
		)
		(stroke
			(width 0)
			(type solid)
		)
		(fill yes)
		(layer "In8.Cu")
		(net "P5E_PEX0_STN4_TX_DP<70>")
	)
	(gr_poly
		(pts
			(arc
				(start 81.703164 -310.149748)
				(mid 81.296764 -310.149748)
				(end 81.703164 -310.149748)
			)
		)
		(stroke
			(width 0)
			(type solid)
		)
		(fill yes)
		(layer "In8.Cu")
		(net "P5E_PEX0_STN4_RX_DP<70>")
	)
	(gr_poly
		(pts
			(arc
				(start 81.703164 -308.249828)
				(mid 81.296764 -308.249828)
				(end 81.703164 -308.249828)
			)
		)
		(stroke
			(width 0)
			(type solid)
		)
		(fill yes)
		(layer "In8.Cu")
		(net "P5E_PEX0_STN4_RX_DP<68>")
	)
	(gr_poly
		(pts
			(arc
				(start 81.703164 -306.349908)
				(mid 81.296764 -306.349908)
				(end 81.703164 -306.349908)
			)
		)
		(stroke
			(width 0)
			(type solid)
		)
		(fill yes)
		(layer "In8.Cu")
		(net "P5E_PEX0_STN4_RX_DP<66>")
	)
	(gr_poly
		(pts
			(arc
				(start 81.703164 -304.449734)
				(mid 81.296764 -304.449734)
				(end 81.703164 -304.449734)
			)
		)
		(stroke
			(width 0)
			(type solid)
		)
		(fill yes)
		(layer "In8.Cu")
		(net "P5E_PEX0_STN4_RX_DP<64>")
	)
	(gr_poly
		(pts
			(arc
				(start 81.703164 -279.749758)
				(mid 81.296764 -279.749758)
				(end 81.703164 -279.749758)
			)
		)
		(stroke
			(width 0)
			(type solid)
		)
		(fill yes)
		(layer "In8.Cu")
		(net "P5E_PEX0_STN0_TX_DP<7>")
	)
	(gr_poly
		(pts
			(arc
				(start 81.703164 -276.899878)
				(mid 81.296764 -276.899878)
				(end 81.703164 -276.899878)
			)
		)
		(stroke
			(width 0)
			(type solid)
		)
		(fill yes)
		(layer "In8.Cu")
		(net "P5E_PEX0_STN0_TX_DP<8>")
	)
	(gr_poly
		(pts
			(arc
				(start 82.653124 -316.799722)
				(mid 82.246724 -316.799722)
				(end 82.653124 -316.799722)
			)
		)
		(stroke
			(width 0)
			(type solid)
		)
		(fill yes)
		(layer "In8.Cu")
		(net "P5E_PEX0_STN4_RX_DN<71>")
	)
	(gr_poly
		(pts
			(arc
				(start 82.653124 -314.899802)
				(mid 82.246724 -314.899802)
				(end 82.653124 -314.899802)
			)
		)
		(stroke
			(width 0)
			(type solid)
		)
		(fill yes)
		(layer "In8.Cu")
		(net "P5E_PEX0_STN4_TX_DN<71>")
	)
	(gr_poly
		(pts
			(arc
				(start 82.653124 -312.049922)
				(mid 82.246724 -312.049922)
				(end 82.653124 -312.049922)
			)
		)
		(stroke
			(width 0)
			(type solid)
		)
		(fill yes)
		(layer "In8.Cu")
		(net "P5E_PEX0_STN4_TX_DN<70>")
	)
	(gr_poly
		(pts
			(arc
				(start 82.653124 -310.149748)
				(mid 82.246724 -310.149748)
				(end 82.653124 -310.149748)
			)
		)
		(stroke
			(width 0)
			(type solid)
		)
		(fill yes)
		(layer "In8.Cu")
		(net "P5E_PEX0_STN4_RX_DN<70>")
	)
	(gr_poly
		(pts
			(arc
				(start 82.653124 -308.249828)
				(mid 82.246724 -308.249828)
				(end 82.653124 -308.249828)
			)
		)
		(stroke
			(width 0)
			(type solid)
		)
		(fill yes)
		(layer "In8.Cu")
		(net "P5E_PEX0_STN4_RX_DN<68>")
	)
	(gr_poly
		(pts
			(arc
				(start 82.653124 -306.349908)
				(mid 82.246724 -306.349908)
				(end 82.653124 -306.349908)
			)
		)
		(stroke
			(width 0)
			(type solid)
		)
		(fill yes)
		(layer "In8.Cu")
		(net "P5E_PEX0_STN4_RX_DN<66>")
	)
	(gr_poly
		(pts
			(arc
				(start 82.653124 -304.449734)
				(mid 82.246724 -304.449734)
				(end 82.653124 -304.449734)
			)
		)
		(stroke
			(width 0)
			(type solid)
		)
		(fill yes)
		(layer "In8.Cu")
		(net "P5E_PEX0_STN4_RX_DN<64>")
	)
	(gr_poly
		(pts
			(arc
				(start 82.653124 -279.749758)
				(mid 82.246724 -279.749758)
				(end 82.653124 -279.749758)
			)
		)
		(stroke
			(width 0)
			(type solid)
		)
		(fill yes)
		(layer "In8.Cu")
		(net "P5E_PEX0_STN0_TX_DN<7>")
	)
	(gr_poly
		(pts
			(arc
				(start 82.653124 -276.899878)
				(mid 82.246724 -276.899878)
				(end 82.653124 -276.899878)
			)
		)
		(stroke
			(width 0)
			(type solid)
		)
		(fill yes)
		(layer "In8.Cu")
		(net "P5E_PEX0_STN0_TX_DN<8>")
	)
	(gr_poly
		(pts
			(arc
				(start 153.15311 -316.799722)
				(mid 152.74671 -316.799722)
				(end 153.15311 -316.799722)
			)
		)
		(stroke
			(width 0)
			(type solid)
		)
		(fill yes)
		(layer "In8.Cu")
		(net "P5E_PEX1_STN7_RX_DN<122>")
	)
	(gr_poly
		(pts
			(arc
				(start 153.15311 -314.899802)
				(mid 152.74671 -314.899802)
				(end 153.15311 -314.899802)
			)
		)
		(stroke
			(width 0)
			(type solid)
		)
		(fill yes)
		(layer "In8.Cu")
		(net "P5E_PEX1_STN7_TX_DN<122>")
	)
	(gr_poly
		(pts
			(arc
				(start 153.15311 -312.049922)
				(mid 152.74671 -312.049922)
				(end 153.15311 -312.049922)
			)
		)
		(stroke
			(width 0)
			(type solid)
		)
		(fill yes)
		(layer "In8.Cu")
		(net "P5E_PEX1_STN7_TX_DN<121>")
	)
	(gr_poly
		(pts
			(arc
				(start 153.15311 -310.149748)
				(mid 152.74671 -310.149748)
				(end 153.15311 -310.149748)
			)
		)
		(stroke
			(width 0)
			(type solid)
		)
		(fill yes)
		(layer "In8.Cu")
		(net "P5E_PEX1_STN7_RX_DN<121>")
	)
	(gr_poly
		(pts
			(arc
				(start 153.15311 -308.249828)
				(mid 152.74671 -308.249828)
				(end 153.15311 -308.249828)
			)
		)
		(stroke
			(width 0)
			(type solid)
		)
		(fill yes)
		(layer "In8.Cu")
		(net "P5E_PEX1_STN7_RX_DN<119>")
	)
	(gr_poly
		(pts
			(arc
				(start 153.15311 -306.349908)
				(mid 152.74671 -306.349908)
				(end 153.15311 -306.349908)
			)
		)
		(stroke
			(width 0)
			(type solid)
		)
		(fill yes)
		(layer "In8.Cu")
		(net "P5E_PEX1_STN7_RX_DN<117>")
	)
	(gr_poly
		(pts
			(arc
				(start 153.15311 -304.449734)
				(mid 152.74671 -304.449734)
				(end 153.15311 -304.449734)
			)
		)
		(stroke
			(width 0)
			(type solid)
		)
		(fill yes)
		(layer "In8.Cu")
		(net "P5E_PEX1_STN7_RX_DN<115>")
	)
	(gr_poly
		(pts
			(arc
				(start 153.15311 -302.549814)
				(mid 152.74671 -302.549814)
				(end 153.15311 -302.549814)
			)
		)
		(stroke
			(width 0)
			(type solid)
		)
		(fill yes)
		(layer "In8.Cu")
		(net "P5E_PEX1_STN7_RX_DN<113>")
	)
	(gr_poly
		(pts
			(arc
				(start 154.10307 -316.799722)
				(mid 153.69667 -316.799722)
				(end 154.10307 -316.799722)
			)
		)
		(stroke
			(width 0)
			(type solid)
		)
		(fill yes)
		(layer "In8.Cu")
		(net "P5E_PEX1_STN7_RX_DP<122>")
	)
	(gr_poly
		(pts
			(arc
				(start 154.10307 -314.899802)
				(mid 153.69667 -314.899802)
				(end 154.10307 -314.899802)
			)
		)
		(stroke
			(width 0)
			(type solid)
		)
		(fill yes)
		(layer "In8.Cu")
		(net "P5E_PEX1_STN7_TX_DP<122>")
	)
	(gr_poly
		(pts
			(arc
				(start 154.10307 -312.049922)
				(mid 153.69667 -312.049922)
				(end 154.10307 -312.049922)
			)
		)
		(stroke
			(width 0)
			(type solid)
		)
		(fill yes)
		(layer "In8.Cu")
		(net "P5E_PEX1_STN7_TX_DP<121>")
	)
	(gr_poly
		(pts
			(arc
				(start 154.10307 -310.149748)
				(mid 153.69667 -310.149748)
				(end 154.10307 -310.149748)
			)
		)
		(stroke
			(width 0)
			(type solid)
		)
		(fill yes)
		(layer "In8.Cu")
		(net "P5E_PEX1_STN7_RX_DP<121>")
	)
	(gr_poly
		(pts
			(arc
				(start 154.10307 -308.249828)
				(mid 153.69667 -308.249828)
				(end 154.10307 -308.249828)
			)
		)
		(stroke
			(width 0)
			(type solid)
		)
		(fill yes)
		(layer "In8.Cu")
		(net "P5E_PEX1_STN7_RX_DP<119>")
	)
	(gr_poly
		(pts
			(arc
				(start 154.10307 -306.349908)
				(mid 153.69667 -306.349908)
				(end 154.10307 -306.349908)
			)
		)
		(stroke
			(width 0)
			(type solid)
		)
		(fill yes)
		(layer "In8.Cu")
		(net "P5E_PEX1_STN7_RX_DP<117>")
	)
	(gr_poly
		(pts
			(arc
				(start 154.10307 -304.449734)
				(mid 153.69667 -304.449734)
				(end 154.10307 -304.449734)
			)
		)
		(stroke
			(width 0)
			(type solid)
		)
		(fill yes)
		(layer "In8.Cu")
		(net "P5E_PEX1_STN7_RX_DP<115>")
	)
	(gr_poly
		(pts
			(arc
				(start 154.10307 -302.549814)
				(mid 153.69667 -302.549814)
				(end 154.10307 -302.549814)
			)
		)
		(stroke
			(width 0)
			(type solid)
		)
		(fill yes)
		(layer "In8.Cu")
		(net "P5E_PEX1_STN7_RX_DP<113>")
	)
	(gr_poly
		(pts
			(arc
				(start 155.053284 -318.699896)
				(mid 154.646884 -318.699896)
				(end 155.053284 -318.699896)
			)
		)
		(stroke
			(width 0)
			(type solid)
		)
		(fill yes)
		(layer "In8.Cu")
		(net "P5E_PEX1_STN7_RX_DN<123>")
	)
	(gr_poly
		(pts
			(arc
				(start 155.053284 -317.749936)
				(mid 154.646884 -317.749936)
				(end 155.053284 -317.749936)
			)
		)
		(stroke
			(width 0)
			(type solid)
		)
		(fill yes)
		(layer "In8.Cu")
		(net "P5E_PEX1_STN7_RX_DP<123>")
	)
	(gr_poly
		(pts
			(arc
				(start 155.053284 -313.949842)
				(mid 154.646884 -313.949842)
				(end 155.053284 -313.949842)
			)
		)
		(stroke
			(width 0)
			(type solid)
		)
		(fill yes)
		(layer "In8.Cu")
		(net "P5E_PEX1_STN7_TX_DN<123>")
	)
	(gr_poly
		(pts
			(arc
				(start 155.053284 -312.999882)
				(mid 154.646884 -312.999882)
				(end 155.053284 -312.999882)
			)
		)
		(stroke
			(width 0)
			(type solid)
		)
		(fill yes)
		(layer "In8.Cu")
		(net "P5E_PEX1_STN7_TX_DP<123>")
	)
	(gr_poly
		(pts
			(arc
				(start 155.053284 -309.199788)
				(mid 154.646884 -309.199788)
				(end 155.053284 -309.199788)
			)
		)
		(stroke
			(width 0)
			(type solid)
		)
		(fill yes)
		(layer "In8.Cu")
		(net "P5E_PEX1_STN7_RX_DN<120>")
	)
	(gr_poly
		(pts
			(arc
				(start 155.053284 -307.299868)
				(mid 154.646884 -307.299868)
				(end 155.053284 -307.299868)
			)
		)
		(stroke
			(width 0)
			(type solid)
		)
		(fill yes)
		(layer "In8.Cu")
		(net "P5E_PEX1_STN7_RX_DN<118>")
	)
	(gr_poly
		(pts
			(arc
				(start 155.053284 -305.399948)
				(mid 154.646884 -305.399948)
				(end 155.053284 -305.399948)
			)
		)
		(stroke
			(width 0)
			(type solid)
		)
		(fill yes)
		(layer "In8.Cu")
		(net "P5E_PEX1_STN7_RX_DN<116>")
	)
	(gr_poly
		(pts
			(arc
				(start 155.053284 -303.499774)
				(mid 154.646884 -303.499774)
				(end 155.053284 -303.499774)
			)
		)
		(stroke
			(width 0)
			(type solid)
		)
		(fill yes)
		(layer "In8.Cu")
		(net "P5E_PEX1_STN7_RX_DN<114>")
	)
	(gr_poly
		(pts
			(arc
				(start 155.053284 -301.599854)
				(mid 154.646884 -301.599854)
				(end 155.053284 -301.599854)
			)
		)
		(stroke
			(width 0)
			(type solid)
		)
		(fill yes)
		(layer "In8.Cu")
		(net "P5E_PEX1_STN7_RX_DN<112>")
	)
	(gr_poly
		(pts
			(arc
				(start 156.003244 -316.799722)
				(mid 155.596844 -316.799722)
				(end 156.003244 -316.799722)
			)
		)
		(stroke
			(width 0)
			(type solid)
		)
		(fill yes)
		(layer "In8.Cu")
		(net "P5E_PEX1_STN7_RX_DN<124>")
	)
	(gr_poly
		(pts
			(arc
				(start 156.003244 -315.849762)
				(mid 155.596844 -315.849762)
				(end 156.003244 -315.849762)
			)
		)
		(stroke
			(width 0)
			(type solid)
		)
		(fill yes)
		(layer "In8.Cu")
		(net "P5E_PEX1_STN7_RX_DP<124>")
	)
	(gr_poly
		(pts
			(arc
				(start 156.003244 -312.049922)
				(mid 155.596844 -312.049922)
				(end 156.003244 -312.049922)
			)
		)
		(stroke
			(width 0)
			(type solid)
		)
		(fill yes)
		(layer "In8.Cu")
		(net "P5E_PEX1_STN7_TX_DN<124>")
	)
	(gr_poly
		(pts
			(arc
				(start 156.003244 -311.099962)
				(mid 155.596844 -311.099962)
				(end 156.003244 -311.099962)
			)
		)
		(stroke
			(width 0)
			(type solid)
		)
		(fill yes)
		(layer "In8.Cu")
		(net "P5E_PEX1_STN7_TX_DP<124>")
	)
	(gr_poly
		(pts
			(arc
				(start 156.003244 -309.199788)
				(mid 155.596844 -309.199788)
				(end 156.003244 -309.199788)
			)
		)
		(stroke
			(width 0)
			(type solid)
		)
		(fill yes)
		(layer "In8.Cu")
		(net "P5E_PEX1_STN7_RX_DP<120>")
	)
	(gr_poly
		(pts
			(arc
				(start 156.003244 -307.299868)
				(mid 155.596844 -307.299868)
				(end 156.003244 -307.299868)
			)
		)
		(stroke
			(width 0)
			(type solid)
		)
		(fill yes)
		(layer "In8.Cu")
		(net "P5E_PEX1_STN7_RX_DP<118>")
	)
	(gr_poly
		(pts
			(arc
				(start 156.003244 -305.399948)
				(mid 155.596844 -305.399948)
				(end 156.003244 -305.399948)
			)
		)
		(stroke
			(width 0)
			(type solid)
		)
		(fill yes)
		(layer "In8.Cu")
		(net "P5E_PEX1_STN7_RX_DP<116>")
	)
	(gr_poly
		(pts
			(arc
				(start 156.003244 -303.499774)
				(mid 155.596844 -303.499774)
				(end 156.003244 -303.499774)
			)
		)
		(stroke
			(width 0)
			(type solid)
		)
		(fill yes)
		(layer "In8.Cu")
		(net "P5E_PEX1_STN7_RX_DP<114>")
	)
	(gr_poly
		(pts
			(arc
				(start 156.003244 -301.599854)
				(mid 155.596844 -301.599854)
				(end 156.003244 -301.599854)
			)
		)
		(stroke
			(width 0)
			(type solid)
		)
		(fill yes)
		(layer "In8.Cu")
		(net "P5E_PEX1_STN7_RX_DP<112>")
	)
	(gr_poly
		(pts
			(arc
				(start 156.953204 -318.699896)
				(mid 156.546804 -318.699896)
				(end 156.953204 -318.699896)
			)
		)
		(stroke
			(width 0)
			(type solid)
		)
		(fill yes)
		(layer "In8.Cu")
		(net "P5E_PEX1_STN7_RX_DN<125>")
	)
	(gr_poly
		(pts
			(arc
				(start 156.953204 -317.749936)
				(mid 156.546804 -317.749936)
				(end 156.953204 -317.749936)
			)
		)
		(stroke
			(width 0)
			(type solid)
		)
		(fill yes)
		(layer "In8.Cu")
		(net "P5E_PEX1_STN7_RX_DP<125>")
	)
	(gr_poly
		(pts
			(arc
				(start 156.953204 -313.949842)
				(mid 156.546804 -313.949842)
				(end 156.953204 -313.949842)
			)
		)
		(stroke
			(width 0)
			(type solid)
		)
		(fill yes)
		(layer "In8.Cu")
		(net "P5E_PEX1_STN7_TX_DN<125>")
	)
	(gr_poly
		(pts
			(arc
				(start 156.953204 -312.999882)
				(mid 156.546804 -312.999882)
				(end 156.953204 -312.999882)
			)
		)
		(stroke
			(width 0)
			(type solid)
		)
		(fill yes)
		(layer "In8.Cu")
		(net "P5E_PEX1_STN7_TX_DP<125>")
	)
	(gr_poly
		(pts
			(arc
				(start 157.903164 -316.799722)
				(mid 157.496764 -316.799722)
				(end 157.903164 -316.799722)
			)
		)
		(stroke
			(width 0)
			(type solid)
		)
		(fill yes)
		(layer "In8.Cu")
		(net "P5E_PEX1_STN7_RX_DN<126>")
	)
	(gr_poly
		(pts
			(arc
				(start 157.903164 -315.849762)
				(mid 157.496764 -315.849762)
				(end 157.903164 -315.849762)
			)
		)
		(stroke
			(width 0)
			(type solid)
		)
		(fill yes)
		(layer "In8.Cu")
		(net "P5E_PEX1_STN7_RX_DP<126>")
	)
	(gr_poly
		(pts
			(arc
				(start 157.903164 -312.049922)
				(mid 157.496764 -312.049922)
				(end 157.903164 -312.049922)
			)
		)
		(stroke
			(width 0)
			(type solid)
		)
		(fill yes)
		(layer "In8.Cu")
		(net "P5E_PEX1_STN7_TX_DN<126>")
	)
	(gr_poly
		(pts
			(arc
				(start 157.903164 -311.099962)
				(mid 157.496764 -311.099962)
				(end 157.903164 -311.099962)
			)
		)
		(stroke
			(width 0)
			(type solid)
		)
		(fill yes)
		(layer "In8.Cu")
		(net "P5E_PEX1_STN7_TX_DP<126>")
	)
	(gr_poly
		(pts
			(arc
				(start 157.903164 -309.199788)
				(mid 157.496764 -309.199788)
				(end 157.903164 -309.199788)
			)
		)
		(stroke
			(width 0)
			(type solid)
		)
		(fill yes)
		(layer "In8.Cu")
		(net "P5E_PEX1_STN7_TX_DN<120>")
	)
	(gr_poly
		(pts
			(arc
				(start 157.903164 -307.299868)
				(mid 157.496764 -307.299868)
				(end 157.903164 -307.299868)
			)
		)
		(stroke
			(width 0)
			(type solid)
		)
		(fill yes)
		(layer "In8.Cu")
		(net "P5E_PEX1_STN7_TX_DN<118>")
	)
	(gr_poly
		(pts
			(arc
				(start 157.903164 -305.399948)
				(mid 157.496764 -305.399948)
				(end 157.903164 -305.399948)
			)
		)
		(stroke
			(width 0)
			(type solid)
		)
		(fill yes)
		(layer "In8.Cu")
		(net "P5E_PEX1_STN7_TX_DN<116>")
	)
	(gr_poly
		(pts
			(arc
				(start 157.903164 -303.499774)
				(mid 157.496764 -303.499774)
				(end 157.903164 -303.499774)
			)
		)
		(stroke
			(width 0)
			(type solid)
		)
		(fill yes)
		(layer "In8.Cu")
		(net "P5E_PEX1_STN7_TX_DN<114>")
	)
	(gr_poly
		(pts
			(arc
				(start 157.903164 -301.599854)
				(mid 157.496764 -301.599854)
				(end 157.903164 -301.599854)
			)
		)
		(stroke
			(width 0)
			(type solid)
		)
		(fill yes)
		(layer "In8.Cu")
		(net "P5E_PEX1_STN7_TX_DN<112>")
	)
	(gr_poly
		(pts
			(arc
				(start 158.853124 -318.699896)
				(mid 158.446724 -318.699896)
				(end 158.853124 -318.699896)
			)
		)
		(stroke
			(width 0)
			(type solid)
		)
		(fill yes)
		(layer "In8.Cu")
		(net "P5E_PEX1_STN7_RX_DN<127>")
	)
	(gr_poly
		(pts
			(arc
				(start 158.853124 -317.749936)
				(mid 158.446724 -317.749936)
				(end 158.853124 -317.749936)
			)
		)
		(stroke
			(width 0)
			(type solid)
		)
		(fill yes)
		(layer "In8.Cu")
		(net "P5E_PEX1_STN7_RX_DP<127>")
	)
	(gr_poly
		(pts
			(arc
				(start 158.853124 -313.949842)
				(mid 158.446724 -313.949842)
				(end 158.853124 -313.949842)
			)
		)
		(stroke
			(width 0)
			(type solid)
		)
		(fill yes)
		(layer "In8.Cu")
		(net "P5E_PEX1_STN7_TX_DN<127>")
	)
	(gr_poly
		(pts
			(arc
				(start 158.853124 -312.999882)
				(mid 158.446724 -312.999882)
				(end 158.853124 -312.999882)
			)
		)
		(stroke
			(width 0)
			(type solid)
		)
		(fill yes)
		(layer "In8.Cu")
		(net "P5E_PEX1_STN7_TX_DP<127>")
	)
	(gr_poly
		(pts
			(arc
				(start 158.853124 -309.199788)
				(mid 158.446724 -309.199788)
				(end 158.853124 -309.199788)
			)
		)
		(stroke
			(width 0)
			(type solid)
		)
		(fill yes)
		(layer "In8.Cu")
		(net "P5E_PEX1_STN7_TX_DP<120>")
	)
	(gr_poly
		(pts
			(arc
				(start 158.853124 -307.299868)
				(mid 158.446724 -307.299868)
				(end 158.853124 -307.299868)
			)
		)
		(stroke
			(width 0)
			(type solid)
		)
		(fill yes)
		(layer "In8.Cu")
		(net "P5E_PEX1_STN7_TX_DP<118>")
	)
	(gr_poly
		(pts
			(arc
				(start 158.853124 -305.399948)
				(mid 158.446724 -305.399948)
				(end 158.853124 -305.399948)
			)
		)
		(stroke
			(width 0)
			(type solid)
		)
		(fill yes)
		(layer "In8.Cu")
		(net "P5E_PEX1_STN7_TX_DP<116>")
	)
	(gr_poly
		(pts
			(arc
				(start 158.853124 -303.499774)
				(mid 158.446724 -303.499774)
				(end 158.853124 -303.499774)
			)
		)
		(stroke
			(width 0)
			(type solid)
		)
		(fill yes)
		(layer "In8.Cu")
		(net "P5E_PEX1_STN7_TX_DP<114>")
	)
	(gr_poly
		(pts
			(arc
				(start 158.853124 -301.599854)
				(mid 158.446724 -301.599854)
				(end 158.853124 -301.599854)
			)
		)
		(stroke
			(width 0)
			(type solid)
		)
		(fill yes)
		(layer "In8.Cu")
		(net "P5E_PEX1_STN7_TX_DP<112>")
	)
	(gr_poly
		(pts
			(arc
				(start 159.803084 -316.799722)
				(mid 159.396684 -316.799722)
				(end 159.803084 -316.799722)
			)
		)
		(stroke
			(width 0)
			(type solid)
		)
		(fill yes)
		(layer "In8.Cu")
		(net "P5E_PEX1_STN6_RX_DN<111>")
	)
	(gr_poly
		(pts
			(arc
				(start 159.803084 -315.849762)
				(mid 159.396684 -315.849762)
				(end 159.803084 -315.849762)
			)
		)
		(stroke
			(width 0)
			(type solid)
		)
		(fill yes)
		(layer "In8.Cu")
		(net "P5E_PEX1_STN6_RX_DP<111>")
	)
	(gr_poly
		(pts
			(arc
				(start 159.803084 -312.049922)
				(mid 159.396684 -312.049922)
				(end 159.803084 -312.049922)
			)
		)
		(stroke
			(width 0)
			(type solid)
		)
		(fill yes)
		(layer "In8.Cu")
		(net "P5E_PEX1_STN6_TX_DN<111>")
	)
	(gr_poly
		(pts
			(arc
				(start 159.803084 -311.099962)
				(mid 159.396684 -311.099962)
				(end 159.803084 -311.099962)
			)
		)
		(stroke
			(width 0)
			(type solid)
		)
		(fill yes)
		(layer "In8.Cu")
		(net "P5E_PEX1_STN6_TX_DP<111>")
	)
	(gr_poly
		(pts
			(arc
				(start 159.803084 -308.249828)
				(mid 159.396684 -308.249828)
				(end 159.803084 -308.249828)
			)
		)
		(stroke
			(width 0)
			(type solid)
		)
		(fill yes)
		(layer "In8.Cu")
		(net "P5E_PEX1_STN7_TX_DN<119>")
	)
	(gr_poly
		(pts
			(arc
				(start 159.803084 -306.349908)
				(mid 159.396684 -306.349908)
				(end 159.803084 -306.349908)
			)
		)
		(stroke
			(width 0)
			(type solid)
		)
		(fill yes)
		(layer "In8.Cu")
		(net "P5E_PEX1_STN7_TX_DN<117>")
	)
	(gr_poly
		(pts
			(arc
				(start 159.803084 -304.449734)
				(mid 159.396684 -304.449734)
				(end 159.803084 -304.449734)
			)
		)
		(stroke
			(width 0)
			(type solid)
		)
		(fill yes)
		(layer "In8.Cu")
		(net "P5E_PEX1_STN7_TX_DN<115>")
	)
	(gr_poly
		(pts
			(arc
				(start 159.803084 -302.549814)
				(mid 159.396684 -302.549814)
				(end 159.803084 -302.549814)
			)
		)
		(stroke
			(width 0)
			(type solid)
		)
		(fill yes)
		(layer "In8.Cu")
		(net "P5E_PEX1_STN7_TX_DN<113>")
	)
	(gr_poly
		(pts
			(arc
				(start 160.753044 -318.699896)
				(mid 160.346644 -318.699896)
				(end 160.753044 -318.699896)
			)
		)
		(stroke
			(width 0)
			(type solid)
		)
		(fill yes)
		(layer "In8.Cu")
		(net "P5E_PEX1_STN6_RX_DN<110>")
	)
	(gr_poly
		(pts
			(arc
				(start 160.753044 -317.749936)
				(mid 160.346644 -317.749936)
				(end 160.753044 -317.749936)
			)
		)
		(stroke
			(width 0)
			(type solid)
		)
		(fill yes)
		(layer "In8.Cu")
		(net "P5E_PEX1_STN6_RX_DP<110>")
	)
	(gr_poly
		(pts
			(arc
				(start 160.753044 -313.949842)
				(mid 160.346644 -313.949842)
				(end 160.753044 -313.949842)
			)
		)
		(stroke
			(width 0)
			(type solid)
		)
		(fill yes)
		(layer "In8.Cu")
		(net "P5E_PEX1_STN6_TX_DN<110>")
	)
	(gr_poly
		(pts
			(arc
				(start 160.753044 -312.999882)
				(mid 160.346644 -312.999882)
				(end 160.753044 -312.999882)
			)
		)
		(stroke
			(width 0)
			(type solid)
		)
		(fill yes)
		(layer "In8.Cu")
		(net "P5E_PEX1_STN6_TX_DP<110>")
	)
	(gr_poly
		(pts
			(arc
				(start 160.753044 -308.249828)
				(mid 160.346644 -308.249828)
				(end 160.753044 -308.249828)
			)
		)
		(stroke
			(width 0)
			(type solid)
		)
		(fill yes)
		(layer "In8.Cu")
		(net "P5E_PEX1_STN7_TX_DP<119>")
	)
	(gr_poly
		(pts
			(arc
				(start 160.753044 -306.349908)
				(mid 160.346644 -306.349908)
				(end 160.753044 -306.349908)
			)
		)
		(stroke
			(width 0)
			(type solid)
		)
		(fill yes)
		(layer "In8.Cu")
		(net "P5E_PEX1_STN7_TX_DP<117>")
	)
	(gr_poly
		(pts
			(arc
				(start 160.753044 -304.449734)
				(mid 160.346644 -304.449734)
				(end 160.753044 -304.449734)
			)
		)
		(stroke
			(width 0)
			(type solid)
		)
		(fill yes)
		(layer "In8.Cu")
		(net "P5E_PEX1_STN7_TX_DP<115>")
	)
	(gr_poly
		(pts
			(arc
				(start 160.753044 -302.549814)
				(mid 160.346644 -302.549814)
				(end 160.753044 -302.549814)
			)
		)
		(stroke
			(width 0)
			(type solid)
		)
		(fill yes)
		(layer "In8.Cu")
		(net "P5E_PEX1_STN7_TX_DP<113>")
	)
	(gr_poly
		(pts
			(arc
				(start 160.753044 -278.799798)
				(mid 160.346644 -278.799798)
				(end 160.753044 -278.799798)
			)
		)
		(stroke
			(width 0)
			(type solid)
		)
		(fill yes)
		(layer "In8.Cu")
		(net "P5E_PEX1_STN2_TX_DP<47>")
	)
	(gr_poly
		(pts
			(arc
				(start 160.753044 -277.849838)
				(mid 160.346644 -277.849838)
				(end 160.753044 -277.849838)
			)
		)
		(stroke
			(width 0)
			(type solid)
		)
		(fill yes)
		(layer "In8.Cu")
		(net "P5E_PEX1_STN2_TX_DN<47>")
	)
	(gr_poly
		(pts
			(arc
				(start 161.703258 -316.799722)
				(mid 161.296858 -316.799722)
				(end 161.703258 -316.799722)
			)
		)
		(stroke
			(width 0)
			(type solid)
		)
		(fill yes)
		(layer "In8.Cu")
		(net "P5E_PEX1_STN6_RX_DN<109>")
	)
	(gr_poly
		(pts
			(arc
				(start 161.703258 -315.849762)
				(mid 161.296858 -315.849762)
				(end 161.703258 -315.849762)
			)
		)
		(stroke
			(width 0)
			(type solid)
		)
		(fill yes)
		(layer "In8.Cu")
		(net "P5E_PEX1_STN6_RX_DP<109>")
	)
	(gr_poly
		(pts
			(arc
				(start 161.703258 -312.049922)
				(mid 161.296858 -312.049922)
				(end 161.703258 -312.049922)
			)
		)
		(stroke
			(width 0)
			(type solid)
		)
		(fill yes)
		(layer "In8.Cu")
		(net "P5E_PEX1_STN6_TX_DN<109>")
	)
	(gr_poly
		(pts
			(arc
				(start 161.703258 -311.099962)
				(mid 161.296858 -311.099962)
				(end 161.703258 -311.099962)
			)
		)
		(stroke
			(width 0)
			(type solid)
		)
		(fill yes)
		(layer "In8.Cu")
		(net "P5E_PEX1_STN6_TX_DP<109>")
	)
	(gr_poly
		(pts
			(arc
				(start 161.703258 -280.699718)
				(mid 161.296858 -280.699718)
				(end 161.703258 -280.699718)
			)
		)
		(stroke
			(width 0)
			(type solid)
		)
		(fill yes)
		(layer "In8.Cu")
		(net "P5E_PEX1_STN2_TX_DP<46>")
	)
	(gr_poly
		(pts
			(arc
				(start 161.703258 -279.749504)
				(mid 161.296858 -279.749504)
				(end 161.703258 -279.749504)
			)
		)
		(stroke
			(width 0)
			(type solid)
		)
		(fill yes)
		(layer "In8.Cu")
		(net "P5E_PEX1_STN2_TX_DN<46>")
	)
	(gr_poly
		(pts
			(arc
				(start 162.653218 -318.699896)
				(mid 162.246818 -318.699896)
				(end 162.653218 -318.699896)
			)
		)
		(stroke
			(width 0)
			(type solid)
		)
		(fill yes)
		(layer "In8.Cu")
		(net "P5E_PEX1_STN6_RX_DN<108>")
	)
	(gr_poly
		(pts
			(arc
				(start 162.653218 -317.749936)
				(mid 162.246818 -317.749936)
				(end 162.653218 -317.749936)
			)
		)
		(stroke
			(width 0)
			(type solid)
		)
		(fill yes)
		(layer "In8.Cu")
		(net "P5E_PEX1_STN6_RX_DP<108>")
	)
	(gr_poly
		(pts
			(arc
				(start 162.653218 -313.949842)
				(mid 162.246818 -313.949842)
				(end 162.653218 -313.949842)
			)
		)
		(stroke
			(width 0)
			(type solid)
		)
		(fill yes)
		(layer "In8.Cu")
		(net "P5E_PEX1_STN6_TX_DN<108>")
	)
	(gr_poly
		(pts
			(arc
				(start 162.653218 -312.999882)
				(mid 162.246818 -312.999882)
				(end 162.653218 -312.999882)
			)
		)
		(stroke
			(width 0)
			(type solid)
		)
		(fill yes)
		(layer "In8.Cu")
		(net "P5E_PEX1_STN6_TX_DP<108>")
	)
	(gr_poly
		(pts
			(arc
				(start 162.653218 -278.799798)
				(mid 162.246818 -278.799798)
				(end 162.653218 -278.799798)
			)
		)
		(stroke
			(width 0)
			(type solid)
		)
		(fill yes)
		(layer "In8.Cu")
		(net "P5E_PEX1_STN2_TX_DP<45>")
	)
	(gr_poly
		(pts
			(arc
				(start 162.653218 -277.849838)
				(mid 162.246818 -277.849838)
				(end 162.653218 -277.849838)
			)
		)
		(stroke
			(width 0)
			(type solid)
		)
		(fill yes)
		(layer "In8.Cu")
		(net "P5E_PEX1_STN2_TX_DN<45>")
	)
	(gr_poly
		(pts
			(arc
				(start 163.603178 -316.799722)
				(mid 163.196778 -316.799722)
				(end 163.603178 -316.799722)
			)
		)
		(stroke
			(width 0)
			(type solid)
		)
		(fill yes)
		(layer "In8.Cu")
		(net "P5E_PEX1_STN6_RX_DN<107>")
	)
	(gr_poly
		(pts
			(arc
				(start 163.603178 -315.849762)
				(mid 163.196778 -315.849762)
				(end 163.603178 -315.849762)
			)
		)
		(stroke
			(width 0)
			(type solid)
		)
		(fill yes)
		(layer "In8.Cu")
		(net "P5E_PEX1_STN6_RX_DP<107>")
	)
	(gr_poly
		(pts
			(arc
				(start 163.603178 -312.049922)
				(mid 163.196778 -312.049922)
				(end 163.603178 -312.049922)
			)
		)
		(stroke
			(width 0)
			(type solid)
		)
		(fill yes)
		(layer "In8.Cu")
		(net "P5E_PEX1_STN6_TX_DN<107>")
	)
	(gr_poly
		(pts
			(arc
				(start 163.603178 -311.099962)
				(mid 163.196778 -311.099962)
				(end 163.603178 -311.099962)
			)
		)
		(stroke
			(width 0)
			(type solid)
		)
		(fill yes)
		(layer "In8.Cu")
		(net "P5E_PEX1_STN6_TX_DP<107>")
	)
	(gr_poly
		(pts
			(arc
				(start 163.603178 -280.699718)
				(mid 163.196778 -280.699718)
				(end 163.603178 -280.699718)
			)
		)
		(stroke
			(width 0)
			(type solid)
		)
		(fill yes)
		(layer "In8.Cu")
		(net "P5E_PEX1_STN2_TX_DP<44>")
	)
	(gr_poly
		(pts
			(arc
				(start 163.603178 -279.749504)
				(mid 163.196778 -279.749504)
				(end 163.603178 -279.749504)
			)
		)
		(stroke
			(width 0)
			(type solid)
		)
		(fill yes)
		(layer "In8.Cu")
		(net "P5E_PEX1_STN2_TX_DN<44>")
	)
	(gr_poly
		(pts
			(arc
				(start 164.553138 -318.699896)
				(mid 164.146738 -318.699896)
				(end 164.553138 -318.699896)
			)
		)
		(stroke
			(width 0)
			(type solid)
		)
		(fill yes)
		(layer "In8.Cu")
		(net "P5E_PEX1_STN6_RX_DN<106>")
	)
	(gr_poly
		(pts
			(arc
				(start 164.553138 -317.749936)
				(mid 164.146738 -317.749936)
				(end 164.553138 -317.749936)
			)
		)
		(stroke
			(width 0)
			(type solid)
		)
		(fill yes)
		(layer "In8.Cu")
		(net "P5E_PEX1_STN6_RX_DP<106>")
	)
	(gr_poly
		(pts
			(arc
				(start 164.553138 -313.949842)
				(mid 164.146738 -313.949842)
				(end 164.553138 -313.949842)
			)
		)
		(stroke
			(width 0)
			(type solid)
		)
		(fill yes)
		(layer "In8.Cu")
		(net "P5E_PEX1_STN6_TX_DN<106>")
	)
	(gr_poly
		(pts
			(arc
				(start 164.553138 -312.999882)
				(mid 164.146738 -312.999882)
				(end 164.553138 -312.999882)
			)
		)
		(stroke
			(width 0)
			(type solid)
		)
		(fill yes)
		(layer "In8.Cu")
		(net "P5E_PEX1_STN6_TX_DP<106>")
	)
	(gr_poly
		(pts
			(arc
				(start 164.553138 -278.799798)
				(mid 164.146738 -278.799798)
				(end 164.553138 -278.799798)
			)
		)
		(stroke
			(width 0)
			(type solid)
		)
		(fill yes)
		(layer "In8.Cu")
		(net "P5E_PEX1_STN2_TX_DP<43>")
	)
	(gr_poly
		(pts
			(arc
				(start 164.553138 -277.849838)
				(mid 164.146738 -277.849838)
				(end 164.553138 -277.849838)
			)
		)
		(stroke
			(width 0)
			(type solid)
		)
		(fill yes)
		(layer "In8.Cu")
		(net "P5E_PEX1_STN2_TX_DN<43>")
	)
	(gr_poly
		(pts
			(arc
				(start 165.503098 -316.799722)
				(mid 165.096698 -316.799722)
				(end 165.503098 -316.799722)
			)
		)
		(stroke
			(width 0)
			(type solid)
		)
		(fill yes)
		(layer "In8.Cu")
		(net "P5E_PEX1_STN6_RX_DN<105>")
	)
	(gr_poly
		(pts
			(arc
				(start 165.503098 -315.849762)
				(mid 165.096698 -315.849762)
				(end 165.503098 -315.849762)
			)
		)
		(stroke
			(width 0)
			(type solid)
		)
		(fill yes)
		(layer "In8.Cu")
		(net "P5E_PEX1_STN6_RX_DP<105>")
	)
	(gr_poly
		(pts
			(arc
				(start 165.503098 -312.049922)
				(mid 165.096698 -312.049922)
				(end 165.503098 -312.049922)
			)
		)
		(stroke
			(width 0)
			(type solid)
		)
		(fill yes)
		(layer "In8.Cu")
		(net "P5E_PEX1_STN6_TX_DN<105>")
	)
	(gr_poly
		(pts
			(arc
				(start 165.503098 -311.099962)
				(mid 165.096698 -311.099962)
				(end 165.503098 -311.099962)
			)
		)
		(stroke
			(width 0)
			(type solid)
		)
		(fill yes)
		(layer "In8.Cu")
		(net "P5E_PEX1_STN6_TX_DP<105>")
	)
	(gr_poly
		(pts
			(arc
				(start 165.503098 -280.699718)
				(mid 165.096698 -280.699718)
				(end 165.503098 -280.699718)
			)
		)
		(stroke
			(width 0)
			(type solid)
		)
		(fill yes)
		(layer "In8.Cu")
		(net "P5E_PEX1_STN2_TX_DP<42>")
	)
	(gr_poly
		(pts
			(arc
				(start 165.503098 -279.749504)
				(mid 165.096698 -279.749504)
				(end 165.503098 -279.749504)
			)
		)
		(stroke
			(width 0)
			(type solid)
		)
		(fill yes)
		(layer "In8.Cu")
		(net "P5E_PEX1_STN2_TX_DN<42>")
	)
	(gr_poly
		(pts
			(arc
				(start 166.453058 -318.699896)
				(mid 166.046658 -318.699896)
				(end 166.453058 -318.699896)
			)
		)
		(stroke
			(width 0)
			(type solid)
		)
		(fill yes)
		(layer "In8.Cu")
		(net "P5E_PEX1_STN6_RX_DN<104>")
	)
	(gr_poly
		(pts
			(arc
				(start 166.453058 -317.749936)
				(mid 166.046658 -317.749936)
				(end 166.453058 -317.749936)
			)
		)
		(stroke
			(width 0)
			(type solid)
		)
		(fill yes)
		(layer "In8.Cu")
		(net "P5E_PEX1_STN6_RX_DP<104>")
	)
	(gr_poly
		(pts
			(arc
				(start 166.453058 -313.949842)
				(mid 166.046658 -313.949842)
				(end 166.453058 -313.949842)
			)
		)
		(stroke
			(width 0)
			(type solid)
		)
		(fill yes)
		(layer "In8.Cu")
		(net "P5E_PEX1_STN6_TX_DN<104>")
	)
	(gr_poly
		(pts
			(arc
				(start 166.453058 -312.999882)
				(mid 166.046658 -312.999882)
				(end 166.453058 -312.999882)
			)
		)
		(stroke
			(width 0)
			(type solid)
		)
		(fill yes)
		(layer "In8.Cu")
		(net "P5E_PEX1_STN6_TX_DP<104>")
	)
	(gr_poly
		(pts
			(arc
				(start 166.453058 -278.799798)
				(mid 166.046658 -278.799798)
				(end 166.453058 -278.799798)
			)
		)
		(stroke
			(width 0)
			(type solid)
		)
		(fill yes)
		(layer "In8.Cu")
		(net "P5E_PEX1_STN2_TX_DP<41>")
	)
	(gr_poly
		(pts
			(arc
				(start 166.453058 -277.849838)
				(mid 166.046658 -277.849838)
				(end 166.453058 -277.849838)
			)
		)
		(stroke
			(width 0)
			(type solid)
		)
		(fill yes)
		(layer "In8.Cu")
		(net "P5E_PEX1_STN2_TX_DN<41>")
	)
	(gr_poly
		(pts
			(arc
				(start 167.403272 -280.699718)
				(mid 166.996872 -280.699718)
				(end 167.403272 -280.699718)
			)
		)
		(stroke
			(width 0)
			(type solid)
		)
		(fill yes)
		(layer "In8.Cu")
		(net "P5E_PEX1_STN2_TX_DP<40>")
	)
	(gr_poly
		(pts
			(arc
				(start 167.403272 -279.749504)
				(mid 166.996872 -279.749504)
				(end 167.403272 -279.749504)
			)
		)
		(stroke
			(width 0)
			(type solid)
		)
		(fill yes)
		(layer "In8.Cu")
		(net "P5E_PEX1_STN2_TX_DN<40>")
	)
	(gr_poly
		(pts
			(arc
				(start 168.353232 -278.799798)
				(mid 167.946832 -278.799798)
				(end 168.353232 -278.799798)
			)
		)
		(stroke
			(width 0)
			(type solid)
		)
		(fill yes)
		(layer "In8.Cu")
		(net "P5E_PEX1_STN2_TX_DP<39>")
	)
	(gr_poly
		(pts
			(arc
				(start 168.353232 -277.849838)
				(mid 167.946832 -277.849838)
				(end 168.353232 -277.849838)
			)
		)
		(stroke
			(width 0)
			(type solid)
		)
		(fill yes)
		(layer "In8.Cu")
		(net "P5E_PEX1_STN2_TX_DN<39>")
	)
	(gr_poly
		(pts
			(arc
				(start 169.303192 -280.699718)
				(mid 168.896792 -280.699718)
				(end 169.303192 -280.699718)
			)
		)
		(stroke
			(width 0)
			(type solid)
		)
		(fill yes)
		(layer "In8.Cu")
		(net "P5E_PEX1_STN2_TX_DP<38>")
	)
	(gr_poly
		(pts
			(arc
				(start 169.303192 -279.749504)
				(mid 168.896792 -279.749504)
				(end 169.303192 -279.749504)
			)
		)
		(stroke
			(width 0)
			(type solid)
		)
		(fill yes)
		(layer "In8.Cu")
		(net "P5E_PEX1_STN2_TX_DN<38>")
	)
	(gr_poly
		(pts
			(arc
				(start 170.253152 -278.799798)
				(mid 169.846752 -278.799798)
				(end 170.253152 -278.799798)
			)
		)
		(stroke
			(width 0)
			(type solid)
		)
		(fill yes)
		(layer "In8.Cu")
		(net "P5E_PEX1_STN2_TX_DP<37>")
	)
	(gr_poly
		(pts
			(arc
				(start 170.253152 -277.849838)
				(mid 169.846752 -277.849838)
				(end 170.253152 -277.849838)
			)
		)
		(stroke
			(width 0)
			(type solid)
		)
		(fill yes)
		(layer "In8.Cu")
		(net "P5E_PEX1_STN2_TX_DN<37>")
	)
	(gr_poly
		(pts
			(arc
				(start 171.203112 -280.699718)
				(mid 170.796712 -280.699718)
				(end 171.203112 -280.699718)
			)
		)
		(stroke
			(width 0)
			(type solid)
		)
		(fill yes)
		(layer "In8.Cu")
		(net "P5E_PEX1_STN2_TX_DP<36>")
	)
	(gr_poly
		(pts
			(arc
				(start 171.203112 -279.749504)
				(mid 170.796712 -279.749504)
				(end 171.203112 -279.749504)
			)
		)
		(stroke
			(width 0)
			(type solid)
		)
		(fill yes)
		(layer "In8.Cu")
		(net "P5E_PEX1_STN2_TX_DN<36>")
	)
	(gr_poly
		(pts
			(arc
				(start 172.153072 -278.799798)
				(mid 171.746672 -278.799798)
				(end 172.153072 -278.799798)
			)
		)
		(stroke
			(width 0)
			(type solid)
		)
		(fill yes)
		(layer "In8.Cu")
		(net "P5E_PEX1_STN2_TX_DP<35>")
	)
	(gr_poly
		(pts
			(arc
				(start 172.153072 -277.849838)
				(mid 171.746672 -277.849838)
				(end 172.153072 -277.849838)
			)
		)
		(stroke
			(width 0)
			(type solid)
		)
		(fill yes)
		(layer "In8.Cu")
		(net "P5E_PEX1_STN2_TX_DN<35>")
	)
	(gr_poly
		(pts
			(arc
				(start 173.103032 -280.699718)
				(mid 172.696632 -280.699718)
				(end 173.103032 -280.699718)
			)
		)
		(stroke
			(width 0)
			(type solid)
		)
		(fill yes)
		(layer "In8.Cu")
		(net "P5E_PEX1_STN2_TX_DP<34>")
	)
	(gr_poly
		(pts
			(arc
				(start 173.103032 -279.749504)
				(mid 172.696632 -279.749504)
				(end 173.103032 -279.749504)
			)
		)
		(stroke
			(width 0)
			(type solid)
		)
		(fill yes)
		(layer "In8.Cu")
		(net "P5E_PEX1_STN2_TX_DN<34>")
	)
	(gr_poly
		(pts
			(arc
				(start 174.053246 -278.799798)
				(mid 173.646846 -278.799798)
				(end 174.053246 -278.799798)
			)
		)
		(stroke
			(width 0)
			(type solid)
		)
		(fill yes)
		(layer "In8.Cu")
		(net "P5E_PEX1_STN2_TX_DP<33>")
	)
	(gr_poly
		(pts
			(arc
				(start 174.053246 -277.849838)
				(mid 173.646846 -277.849838)
				(end 174.053246 -277.849838)
			)
		)
		(stroke
			(width 0)
			(type solid)
		)
		(fill yes)
		(layer "In8.Cu")
		(net "P5E_PEX1_STN2_TX_DN<33>")
	)
	(gr_poly
		(pts
			(arc
				(start 175.003206 -280.699718)
				(mid 174.596806 -280.699718)
				(end 175.003206 -280.699718)
			)
		)
		(stroke
			(width 0)
			(type solid)
		)
		(fill yes)
		(layer "In8.Cu")
		(net "P5E_PEX1_STN2_TX_DP<32>")
	)
	(gr_poly
		(pts
			(arc
				(start 175.003206 -279.749504)
				(mid 174.596806 -279.749504)
				(end 175.003206 -279.749504)
			)
		)
		(stroke
			(width 0)
			(type solid)
		)
		(fill yes)
		(layer "In8.Cu")
		(net "P5E_PEX1_STN2_TX_DN<32>")
	)
	(gr_poly
		(pts
			(arc
				(start 175.952912 -278.799798)
				(mid 175.546512 -278.799798)
				(end 175.952912 -278.799798)
			)
		)
		(stroke
			(width 0)
			(type solid)
		)
		(fill yes)
		(layer "In8.Cu")
		(net "P5E_PEX1_STN1_TX_DP<16>")
	)
	(gr_poly
		(pts
			(arc
				(start 175.952912 -277.849838)
				(mid 175.546512 -277.849838)
				(end 175.952912 -277.849838)
			)
		)
		(stroke
			(width 0)
			(type solid)
		)
		(fill yes)
		(layer "In8.Cu")
		(net "P5E_PEX1_STN1_TX_DN<16>")
	)
	(gr_poly
		(pts
			(arc
				(start 176.903126 -280.699718)
				(mid 176.496726 -280.699718)
				(end 176.903126 -280.699718)
			)
		)
		(stroke
			(width 0)
			(type solid)
		)
		(fill yes)
		(layer "In8.Cu")
		(net "P5E_PEX1_STN1_TX_DN<17>")
	)
	(gr_poly
		(pts
			(arc
				(start 176.903126 -279.749504)
				(mid 176.496726 -279.749504)
				(end 176.903126 -279.749504)
			)
		)
		(stroke
			(width 0)
			(type solid)
		)
		(fill yes)
		(layer "In8.Cu")
		(net "P5E_PEX1_STN1_TX_DP<17>")
	)
	(gr_poly
		(pts
			(arc
				(start 177.852832 -278.799798)
				(mid 177.446432 -278.799798)
				(end 177.852832 -278.799798)
			)
		)
		(stroke
			(width 0)
			(type solid)
		)
		(fill yes)
		(layer "In8.Cu")
		(net "P5E_PEX1_STN1_TX_DP<18>")
	)
	(gr_poly
		(pts
			(arc
				(start 177.852832 -277.849838)
				(mid 177.446432 -277.849838)
				(end 177.852832 -277.849838)
			)
		)
		(stroke
			(width 0)
			(type solid)
		)
		(fill yes)
		(layer "In8.Cu")
		(net "P5E_PEX1_STN1_TX_DN<18>")
	)
	(gr_poly
		(pts
			(arc
				(start 178.803046 -280.699718)
				(mid 178.396646 -280.699718)
				(end 178.803046 -280.699718)
			)
		)
		(stroke
			(width 0)
			(type solid)
		)
		(fill yes)
		(layer "In8.Cu")
		(net "P5E_PEX1_STN1_TX_DN<19>")
	)
	(gr_poly
		(pts
			(arc
				(start 178.803046 -279.749504)
				(mid 178.396646 -279.749504)
				(end 178.803046 -279.749504)
			)
		)
		(stroke
			(width 0)
			(type solid)
		)
		(fill yes)
		(layer "In8.Cu")
		(net "P5E_PEX1_STN1_TX_DP<19>")
	)
	(gr_poly
		(pts
			(arc
				(start 179.753006 -278.799798)
				(mid 179.346606 -278.799798)
				(end 179.753006 -278.799798)
			)
		)
		(stroke
			(width 0)
			(type solid)
		)
		(fill yes)
		(layer "In8.Cu")
		(net "P5E_PEX1_STN1_TX_DP<20>")
	)
	(gr_poly
		(pts
			(arc
				(start 179.753006 -277.849838)
				(mid 179.346606 -277.849838)
				(end 179.753006 -277.849838)
			)
		)
		(stroke
			(width 0)
			(type solid)
		)
		(fill yes)
		(layer "In8.Cu")
		(net "P5E_PEX1_STN1_TX_DN<20>")
	)
	(gr_poly
		(pts
			(arc
				(start 180.70322 -280.699718)
				(mid 180.29682 -280.699718)
				(end 180.70322 -280.699718)
			)
		)
		(stroke
			(width 0)
			(type solid)
		)
		(fill yes)
		(layer "In8.Cu")
		(net "P5E_PEX1_STN1_TX_DN<21>")
	)
	(gr_poly
		(pts
			(arc
				(start 180.70322 -279.749504)
				(mid 180.29682 -279.749504)
				(end 180.70322 -279.749504)
			)
		)
		(stroke
			(width 0)
			(type solid)
		)
		(fill yes)
		(layer "In8.Cu")
		(net "P5E_PEX1_STN1_TX_DP<21>")
	)
	(gr_poly
		(pts
			(arc
				(start 181.652926 -278.799798)
				(mid 181.246526 -278.799798)
				(end 181.652926 -278.799798)
			)
		)
		(stroke
			(width 0)
			(type solid)
		)
		(fill yes)
		(layer "In8.Cu")
		(net "P5E_PEX1_STN1_TX_DP<22>")
	)
	(gr_poly
		(pts
			(arc
				(start 181.652926 -277.849838)
				(mid 181.246526 -277.849838)
				(end 181.652926 -277.849838)
			)
		)
		(stroke
			(width 0)
			(type solid)
		)
		(fill yes)
		(layer "In8.Cu")
		(net "P5E_PEX1_STN1_TX_DN<22>")
	)
	(gr_poly
		(pts
			(arc
				(start 182.60314 -316.799722)
				(mid 182.19674 -316.799722)
				(end 182.60314 -316.799722)
			)
		)
		(stroke
			(width 0)
			(type solid)
		)
		(fill yes)
		(layer "In8.Cu")
		(net "P5E_PEX1_STN5_RX_DN<88>")
	)
	(gr_poly
		(pts
			(arc
				(start 182.60314 -315.849762)
				(mid 182.19674 -315.849762)
				(end 182.60314 -315.849762)
			)
		)
		(stroke
			(width 0)
			(type solid)
		)
		(fill yes)
		(layer "In8.Cu")
		(net "P5E_PEX1_STN5_RX_DP<88>")
	)
	(gr_poly
		(pts
			(arc
				(start 182.60314 -312.049922)
				(mid 182.19674 -312.049922)
				(end 182.60314 -312.049922)
			)
		)
		(stroke
			(width 0)
			(type solid)
		)
		(fill yes)
		(layer "In8.Cu")
		(net "P5E_PEX1_STN5_TX_DN<88>")
	)
	(gr_poly
		(pts
			(arc
				(start 182.60314 -311.099962)
				(mid 182.19674 -311.099962)
				(end 182.60314 -311.099962)
			)
		)
		(stroke
			(width 0)
			(type solid)
		)
		(fill yes)
		(layer "In8.Cu")
		(net "P5E_PEX1_STN5_TX_DP<88>")
	)
	(gr_poly
		(pts
			(arc
				(start 182.60314 -280.699718)
				(mid 182.19674 -280.699718)
				(end 182.60314 -280.699718)
			)
		)
		(stroke
			(width 0)
			(type solid)
		)
		(fill yes)
		(layer "In8.Cu")
		(net "P5E_PEX1_STN1_TX_DN<23>")
	)
	(gr_poly
		(pts
			(arc
				(start 182.60314 -279.749504)
				(mid 182.19674 -279.749504)
				(end 182.60314 -279.749504)
			)
		)
		(stroke
			(width 0)
			(type solid)
		)
		(fill yes)
		(layer "In8.Cu")
		(net "P5E_PEX1_STN1_TX_DP<23>")
	)
	(gr_poly
		(pts
			(arc
				(start 183.552846 -278.799798)
				(mid 183.146446 -278.799798)
				(end 183.552846 -278.799798)
			)
		)
		(stroke
			(width 0)
			(type solid)
		)
		(fill yes)
		(layer "In8.Cu")
		(net "P5E_PEX1_STN1_TX_DP<24>")
	)
	(gr_poly
		(pts
			(arc
				(start 183.552846 -277.849838)
				(mid 183.146446 -277.849838)
				(end 183.552846 -277.849838)
			)
		)
		(stroke
			(width 0)
			(type solid)
		)
		(fill yes)
		(layer "In8.Cu")
		(net "P5E_PEX1_STN1_TX_DN<24>")
	)
	(gr_poly
		(pts
			(arc
				(start 183.5531 -318.699896)
				(mid 183.1467 -318.699896)
				(end 183.5531 -318.699896)
			)
		)
		(stroke
			(width 0)
			(type solid)
		)
		(fill yes)
		(layer "In8.Cu")
		(net "P5E_PEX1_STN5_RX_DN<89>")
	)
	(gr_poly
		(pts
			(arc
				(start 183.5531 -317.749936)
				(mid 183.1467 -317.749936)
				(end 183.5531 -317.749936)
			)
		)
		(stroke
			(width 0)
			(type solid)
		)
		(fill yes)
		(layer "In8.Cu")
		(net "P5E_PEX1_STN5_RX_DP<89>")
	)
	(gr_poly
		(pts
			(arc
				(start 183.5531 -313.949842)
				(mid 183.1467 -313.949842)
				(end 183.5531 -313.949842)
			)
		)
		(stroke
			(width 0)
			(type solid)
		)
		(fill yes)
		(layer "In8.Cu")
		(net "P5E_PEX1_STN5_TX_DN<89>")
	)
	(gr_poly
		(pts
			(arc
				(start 183.5531 -312.999882)
				(mid 183.1467 -312.999882)
				(end 183.5531 -312.999882)
			)
		)
		(stroke
			(width 0)
			(type solid)
		)
		(fill yes)
		(layer "In8.Cu")
		(net "P5E_PEX1_STN5_TX_DP<89>")
	)
	(gr_poly
		(pts
			(arc
				(start 184.50306 -316.799722)
				(mid 184.09666 -316.799722)
				(end 184.50306 -316.799722)
			)
		)
		(stroke
			(width 0)
			(type solid)
		)
		(fill yes)
		(layer "In8.Cu")
		(net "P5E_PEX1_STN5_RX_DN<90>")
	)
	(gr_poly
		(pts
			(arc
				(start 184.50306 -315.849762)
				(mid 184.09666 -315.849762)
				(end 184.50306 -315.849762)
			)
		)
		(stroke
			(width 0)
			(type solid)
		)
		(fill yes)
		(layer "In8.Cu")
		(net "P5E_PEX1_STN5_RX_DP<90>")
	)
	(gr_poly
		(pts
			(arc
				(start 184.50306 -312.049922)
				(mid 184.09666 -312.049922)
				(end 184.50306 -312.049922)
			)
		)
		(stroke
			(width 0)
			(type solid)
		)
		(fill yes)
		(layer "In8.Cu")
		(net "P5E_PEX1_STN5_TX_DN<90>")
	)
	(gr_poly
		(pts
			(arc
				(start 184.50306 -311.099962)
				(mid 184.09666 -311.099962)
				(end 184.50306 -311.099962)
			)
		)
		(stroke
			(width 0)
			(type solid)
		)
		(fill yes)
		(layer "In8.Cu")
		(net "P5E_PEX1_STN5_TX_DP<90>")
	)
	(gr_poly
		(pts
			(arc
				(start 184.50306 -280.699718)
				(mid 184.09666 -280.699718)
				(end 184.50306 -280.699718)
			)
		)
		(stroke
			(width 0)
			(type solid)
		)
		(fill yes)
		(layer "In8.Cu")
		(net "P5E_PEX1_STN1_TX_DN<25>")
	)
	(gr_poly
		(pts
			(arc
				(start 184.50306 -279.749504)
				(mid 184.09666 -279.749504)
				(end 184.50306 -279.749504)
			)
		)
		(stroke
			(width 0)
			(type solid)
		)
		(fill yes)
		(layer "In8.Cu")
		(net "P5E_PEX1_STN1_TX_DP<25>")
	)
	(gr_poly
		(pts
			(arc
				(start 185.45302 -278.799798)
				(mid 185.04662 -278.799798)
				(end 185.45302 -278.799798)
			)
		)
		(stroke
			(width 0)
			(type solid)
		)
		(fill yes)
		(layer "In8.Cu")
		(net "P5E_PEX1_STN1_TX_DP<26>")
	)
	(gr_poly
		(pts
			(arc
				(start 185.45302 -277.849838)
				(mid 185.04662 -277.849838)
				(end 185.45302 -277.849838)
			)
		)
		(stroke
			(width 0)
			(type solid)
		)
		(fill yes)
		(layer "In8.Cu")
		(net "P5E_PEX1_STN1_TX_DN<26>")
	)
	(gr_poly
		(pts
			(arc
				(start 185.453274 -318.699896)
				(mid 185.046874 -318.699896)
				(end 185.453274 -318.699896)
			)
		)
		(stroke
			(width 0)
			(type solid)
		)
		(fill yes)
		(layer "In8.Cu")
		(net "P5E_PEX1_STN5_RX_DN<91>")
	)
	(gr_poly
		(pts
			(arc
				(start 185.453274 -317.749936)
				(mid 185.046874 -317.749936)
				(end 185.453274 -317.749936)
			)
		)
		(stroke
			(width 0)
			(type solid)
		)
		(fill yes)
		(layer "In8.Cu")
		(net "P5E_PEX1_STN5_RX_DP<91>")
	)
	(gr_poly
		(pts
			(arc
				(start 185.453274 -313.949842)
				(mid 185.046874 -313.949842)
				(end 185.453274 -313.949842)
			)
		)
		(stroke
			(width 0)
			(type solid)
		)
		(fill yes)
		(layer "In8.Cu")
		(net "P5E_PEX1_STN5_TX_DN<91>")
	)
	(gr_poly
		(pts
			(arc
				(start 185.453274 -312.999882)
				(mid 185.046874 -312.999882)
				(end 185.453274 -312.999882)
			)
		)
		(stroke
			(width 0)
			(type solid)
		)
		(fill yes)
		(layer "In8.Cu")
		(net "P5E_PEX1_STN5_TX_DP<91>")
	)
	(gr_poly
		(pts
			(arc
				(start 186.403234 -316.799722)
				(mid 185.996834 -316.799722)
				(end 186.403234 -316.799722)
			)
		)
		(stroke
			(width 0)
			(type solid)
		)
		(fill yes)
		(layer "In8.Cu")
		(net "P5E_PEX1_STN5_RX_DN<92>")
	)
	(gr_poly
		(pts
			(arc
				(start 186.403234 -315.849762)
				(mid 185.996834 -315.849762)
				(end 186.403234 -315.849762)
			)
		)
		(stroke
			(width 0)
			(type solid)
		)
		(fill yes)
		(layer "In8.Cu")
		(net "P5E_PEX1_STN5_RX_DP<92>")
	)
	(gr_poly
		(pts
			(arc
				(start 186.403234 -312.049922)
				(mid 185.996834 -312.049922)
				(end 186.403234 -312.049922)
			)
		)
		(stroke
			(width 0)
			(type solid)
		)
		(fill yes)
		(layer "In8.Cu")
		(net "P5E_PEX1_STN5_TX_DN<92>")
	)
	(gr_poly
		(pts
			(arc
				(start 186.403234 -311.099962)
				(mid 185.996834 -311.099962)
				(end 186.403234 -311.099962)
			)
		)
		(stroke
			(width 0)
			(type solid)
		)
		(fill yes)
		(layer "In8.Cu")
		(net "P5E_PEX1_STN5_TX_DP<92>")
	)
	(gr_poly
		(pts
			(arc
				(start 186.403234 -280.699718)
				(mid 185.996834 -280.699718)
				(end 186.403234 -280.699718)
			)
		)
		(stroke
			(width 0)
			(type solid)
		)
		(fill yes)
		(layer "In8.Cu")
		(net "P5E_PEX1_STN1_TX_DN<27>")
	)
	(gr_poly
		(pts
			(arc
				(start 186.403234 -279.749504)
				(mid 185.996834 -279.749504)
				(end 186.403234 -279.749504)
			)
		)
		(stroke
			(width 0)
			(type solid)
		)
		(fill yes)
		(layer "In8.Cu")
		(net "P5E_PEX1_STN1_TX_DP<27>")
	)
	(gr_poly
		(pts
			(arc
				(start 187.35294 -278.799798)
				(mid 186.94654 -278.799798)
				(end 187.35294 -278.799798)
			)
		)
		(stroke
			(width 0)
			(type solid)
		)
		(fill yes)
		(layer "In8.Cu")
		(net "P5E_PEX1_STN1_TX_DP<28>")
	)
	(gr_poly
		(pts
			(arc
				(start 187.35294 -277.849838)
				(mid 186.94654 -277.849838)
				(end 187.35294 -277.849838)
			)
		)
		(stroke
			(width 0)
			(type solid)
		)
		(fill yes)
		(layer "In8.Cu")
		(net "P5E_PEX1_STN1_TX_DN<28>")
	)
	(gr_poly
		(pts
			(arc
				(start 187.353194 -318.699896)
				(mid 186.946794 -318.699896)
				(end 187.353194 -318.699896)
			)
		)
		(stroke
			(width 0)
			(type solid)
		)
		(fill yes)
		(layer "In8.Cu")
		(net "P5E_PEX1_STN5_RX_DN<93>")
	)
	(gr_poly
		(pts
			(arc
				(start 187.353194 -317.749936)
				(mid 186.946794 -317.749936)
				(end 187.353194 -317.749936)
			)
		)
		(stroke
			(width 0)
			(type solid)
		)
		(fill yes)
		(layer "In8.Cu")
		(net "P5E_PEX1_STN5_RX_DP<93>")
	)
	(gr_poly
		(pts
			(arc
				(start 187.353194 -313.949842)
				(mid 186.946794 -313.949842)
				(end 187.353194 -313.949842)
			)
		)
		(stroke
			(width 0)
			(type solid)
		)
		(fill yes)
		(layer "In8.Cu")
		(net "P5E_PEX1_STN5_TX_DN<93>")
	)
	(gr_poly
		(pts
			(arc
				(start 187.353194 -312.999882)
				(mid 186.946794 -312.999882)
				(end 187.353194 -312.999882)
			)
		)
		(stroke
			(width 0)
			(type solid)
		)
		(fill yes)
		(layer "In8.Cu")
		(net "P5E_PEX1_STN5_TX_DP<93>")
	)
	(gr_poly
		(pts
			(arc
				(start 188.303154 -316.799722)
				(mid 187.896754 -316.799722)
				(end 188.303154 -316.799722)
			)
		)
		(stroke
			(width 0)
			(type solid)
		)
		(fill yes)
		(layer "In8.Cu")
		(net "P5E_PEX1_STN5_RX_DN<94>")
	)
	(gr_poly
		(pts
			(arc
				(start 188.303154 -315.849762)
				(mid 187.896754 -315.849762)
				(end 188.303154 -315.849762)
			)
		)
		(stroke
			(width 0)
			(type solid)
		)
		(fill yes)
		(layer "In8.Cu")
		(net "P5E_PEX1_STN5_RX_DP<94>")
	)
	(gr_poly
		(pts
			(arc
				(start 188.303154 -312.049922)
				(mid 187.896754 -312.049922)
				(end 188.303154 -312.049922)
			)
		)
		(stroke
			(width 0)
			(type solid)
		)
		(fill yes)
		(layer "In8.Cu")
		(net "P5E_PEX1_STN5_TX_DN<94>")
	)
	(gr_poly
		(pts
			(arc
				(start 188.303154 -311.099962)
				(mid 187.896754 -311.099962)
				(end 188.303154 -311.099962)
			)
		)
		(stroke
			(width 0)
			(type solid)
		)
		(fill yes)
		(layer "In8.Cu")
		(net "P5E_PEX1_STN5_TX_DP<94>")
	)
	(gr_poly
		(pts
			(arc
				(start 188.303154 -280.699718)
				(mid 187.896754 -280.699718)
				(end 188.303154 -280.699718)
			)
		)
		(stroke
			(width 0)
			(type solid)
		)
		(fill yes)
		(layer "In8.Cu")
		(net "P5E_PEX1_STN1_TX_DN<29>")
	)
	(gr_poly
		(pts
			(arc
				(start 188.303154 -279.749504)
				(mid 187.896754 -279.749504)
				(end 188.303154 -279.749504)
			)
		)
		(stroke
			(width 0)
			(type solid)
		)
		(fill yes)
		(layer "In8.Cu")
		(net "P5E_PEX1_STN1_TX_DP<29>")
	)
	(gr_poly
		(pts
			(arc
				(start 189.25286 -278.799798)
				(mid 188.84646 -278.799798)
				(end 189.25286 -278.799798)
			)
		)
		(stroke
			(width 0)
			(type solid)
		)
		(fill yes)
		(layer "In8.Cu")
		(net "P5E_PEX1_STN1_TX_DP<30>")
	)
	(gr_poly
		(pts
			(arc
				(start 189.25286 -277.849838)
				(mid 188.84646 -277.849838)
				(end 189.25286 -277.849838)
			)
		)
		(stroke
			(width 0)
			(type solid)
		)
		(fill yes)
		(layer "In8.Cu")
		(net "P5E_PEX1_STN1_TX_DN<30>")
	)
	(gr_poly
		(pts
			(arc
				(start 189.253114 -318.699896)
				(mid 188.846714 -318.699896)
				(end 189.253114 -318.699896)
			)
		)
		(stroke
			(width 0)
			(type solid)
		)
		(fill yes)
		(layer "In8.Cu")
		(net "P5E_PEX1_STN5_RX_DN<95>")
	)
	(gr_poly
		(pts
			(arc
				(start 189.253114 -317.749936)
				(mid 188.846714 -317.749936)
				(end 189.253114 -317.749936)
			)
		)
		(stroke
			(width 0)
			(type solid)
		)
		(fill yes)
		(layer "In8.Cu")
		(net "P5E_PEX1_STN5_RX_DP<95>")
	)
	(gr_poly
		(pts
			(arc
				(start 189.253114 -313.949842)
				(mid 188.846714 -313.949842)
				(end 189.253114 -313.949842)
			)
		)
		(stroke
			(width 0)
			(type solid)
		)
		(fill yes)
		(layer "In8.Cu")
		(net "P5E_PEX1_STN5_TX_DN<95>")
	)
	(gr_poly
		(pts
			(arc
				(start 189.253114 -312.999882)
				(mid 188.846714 -312.999882)
				(end 189.253114 -312.999882)
			)
		)
		(stroke
			(width 0)
			(type solid)
		)
		(fill yes)
		(layer "In8.Cu")
		(net "P5E_PEX1_STN5_TX_DP<95>")
	)
	(gr_poly
		(pts
			(arc
				(start 190.203074 -280.699718)
				(mid 189.796674 -280.699718)
				(end 190.203074 -280.699718)
			)
		)
		(stroke
			(width 0)
			(type solid)
		)
		(fill yes)
		(layer "In8.Cu")
		(net "P5E_PEX1_STN1_TX_DN<31>")
	)
	(gr_poly
		(pts
			(arc
				(start 190.203074 -279.749504)
				(mid 189.796674 -279.749504)
				(end 190.203074 -279.749504)
			)
		)
		(stroke
			(width 0)
			(type solid)
		)
		(fill yes)
		(layer "In8.Cu")
		(net "P5E_PEX1_STN1_TX_DP<31>")
	)
	(gr_poly
		(pts
			(arc
				(start 191.153034 -287.349946)
				(mid 190.746634 -287.349946)
				(end 191.153034 -287.349946)
			)
		)
		(stroke
			(width 0)
			(type solid)
		)
		(fill yes)
		(layer "In8.Cu")
		(net "P5E_PEX1_STN0_TX_DP<1>")
	)
	(gr_poly
		(pts
			(arc
				(start 191.153034 -285.449772)
				(mid 190.746634 -285.449772)
				(end 191.153034 -285.449772)
			)
		)
		(stroke
			(width 0)
			(type solid)
		)
		(fill yes)
		(layer "In8.Cu")
		(net "P5E_PEX1_STN0_TX_DP<3>")
	)
	(gr_poly
		(pts
			(arc
				(start 191.153034 -283.549852)
				(mid 190.746634 -283.549852)
				(end 191.153034 -283.549852)
			)
		)
		(stroke
			(width 0)
			(type solid)
		)
		(fill yes)
		(layer "In8.Cu")
		(net "P5E_PEX1_STN0_TX_DP<5>")
	)
	(gr_poly
		(pts
			(arc
				(start 191.153034 -278.799798)
				(mid 190.746634 -278.799798)
				(end 191.153034 -278.799798)
			)
		)
		(stroke
			(width 0)
			(type solid)
		)
		(fill yes)
		(layer "In8.Cu")
		(net "P5E_PEX1_STN0_TX_DP<15>")
	)
	(gr_poly
		(pts
			(arc
				(start 191.153034 -277.849838)
				(mid 190.746634 -277.849838)
				(end 191.153034 -277.849838)
			)
		)
		(stroke
			(width 0)
			(type solid)
		)
		(fill yes)
		(layer "In8.Cu")
		(net "P5E_PEX1_STN0_TX_DN<15>")
	)
	(gr_poly
		(pts
			(arc
				(start 192.103248 -287.349946)
				(mid 191.696848 -287.349946)
				(end 192.103248 -287.349946)
			)
		)
		(stroke
			(width 0)
			(type solid)
		)
		(fill yes)
		(layer "In8.Cu")
		(net "P5E_PEX1_STN0_TX_DN<1>")
	)
	(gr_poly
		(pts
			(arc
				(start 192.103248 -285.449772)
				(mid 191.696848 -285.449772)
				(end 192.103248 -285.449772)
			)
		)
		(stroke
			(width 0)
			(type solid)
		)
		(fill yes)
		(layer "In8.Cu")
		(net "P5E_PEX1_STN0_TX_DN<3>")
	)
	(gr_poly
		(pts
			(arc
				(start 192.103248 -283.549852)
				(mid 191.696848 -283.549852)
				(end 192.103248 -283.549852)
			)
		)
		(stroke
			(width 0)
			(type solid)
		)
		(fill yes)
		(layer "In8.Cu")
		(net "P5E_PEX1_STN0_TX_DN<5>")
	)
	(gr_poly
		(pts
			(arc
				(start 192.103248 -280.699718)
				(mid 191.696848 -280.699718)
				(end 192.103248 -280.699718)
			)
		)
		(stroke
			(width 0)
			(type solid)
		)
		(fill yes)
		(layer "In8.Cu")
		(net "P5E_PEX1_STN0_TX_DN<14>")
	)
	(gr_poly
		(pts
			(arc
				(start 192.103248 -279.749504)
				(mid 191.696848 -279.749504)
				(end 192.103248 -279.749504)
			)
		)
		(stroke
			(width 0)
			(type solid)
		)
		(fill yes)
		(layer "In8.Cu")
		(net "P5E_PEX1_STN0_TX_DP<14>")
	)
	(gr_poly
		(pts
			(arc
				(start 193.052954 -278.799798)
				(mid 192.646554 -278.799798)
				(end 193.052954 -278.799798)
			)
		)
		(stroke
			(width 0)
			(type solid)
		)
		(fill yes)
		(layer "In8.Cu")
		(net "P5E_PEX1_STN0_TX_DP<13>")
	)
	(gr_poly
		(pts
			(arc
				(start 193.052954 -277.849838)
				(mid 192.646554 -277.849838)
				(end 193.052954 -277.849838)
			)
		)
		(stroke
			(width 0)
			(type solid)
		)
		(fill yes)
		(layer "In8.Cu")
		(net "P5E_PEX1_STN0_TX_DN<13>")
	)
	(gr_poly
		(pts
			(arc
				(start 193.053208 -288.299906)
				(mid 192.646808 -288.299906)
				(end 193.053208 -288.299906)
			)
		)
		(stroke
			(width 0)
			(type solid)
		)
		(fill yes)
		(layer "In8.Cu")
		(net "P5E_PEX1_STN0_TX_DP<0>")
	)
	(gr_poly
		(pts
			(arc
				(start 193.053208 -286.399986)
				(mid 192.646808 -286.399986)
				(end 193.053208 -286.399986)
			)
		)
		(stroke
			(width 0)
			(type solid)
		)
		(fill yes)
		(layer "In8.Cu")
		(net "P5E_PEX1_STN0_TX_DP<2>")
	)
	(gr_poly
		(pts
			(arc
				(start 193.053208 -284.499812)
				(mid 192.646808 -284.499812)
				(end 193.053208 -284.499812)
			)
		)
		(stroke
			(width 0)
			(type solid)
		)
		(fill yes)
		(layer "In8.Cu")
		(net "P5E_PEX1_STN0_TX_DP<4>")
	)
	(gr_poly
		(pts
			(arc
				(start 193.053208 -282.599892)
				(mid 192.646808 -282.599892)
				(end 193.053208 -282.599892)
			)
		)
		(stroke
			(width 0)
			(type solid)
		)
		(fill yes)
		(layer "In8.Cu")
		(net "P5E_PEX1_STN0_TX_DP<6>")
	)
	(gr_poly
		(pts
			(arc
				(start 194.003168 -288.299906)
				(mid 193.596768 -288.299906)
				(end 194.003168 -288.299906)
			)
		)
		(stroke
			(width 0)
			(type solid)
		)
		(fill yes)
		(layer "In8.Cu")
		(net "P5E_PEX1_STN0_TX_DN<0>")
	)
	(gr_poly
		(pts
			(arc
				(start 194.003168 -286.399986)
				(mid 193.596768 -286.399986)
				(end 194.003168 -286.399986)
			)
		)
		(stroke
			(width 0)
			(type solid)
		)
		(fill yes)
		(layer "In8.Cu")
		(net "P5E_PEX1_STN0_TX_DN<2>")
	)
	(gr_poly
		(pts
			(arc
				(start 194.003168 -284.499812)
				(mid 193.596768 -284.499812)
				(end 194.003168 -284.499812)
			)
		)
		(stroke
			(width 0)
			(type solid)
		)
		(fill yes)
		(layer "In8.Cu")
		(net "P5E_PEX1_STN0_TX_DN<4>")
	)
	(gr_poly
		(pts
			(arc
				(start 194.003168 -282.599892)
				(mid 193.596768 -282.599892)
				(end 194.003168 -282.599892)
			)
		)
		(stroke
			(width 0)
			(type solid)
		)
		(fill yes)
		(layer "In8.Cu")
		(net "P5E_PEX1_STN0_TX_DN<6>")
	)
	(gr_poly
		(pts
			(arc
				(start 194.003168 -280.699718)
				(mid 193.596768 -280.699718)
				(end 194.003168 -280.699718)
			)
		)
		(stroke
			(width 0)
			(type solid)
		)
		(fill yes)
		(layer "In8.Cu")
		(net "P5E_PEX1_STN0_TX_DN<12>")
	)
	(gr_poly
		(pts
			(arc
				(start 194.003168 -279.749504)
				(mid 193.596768 -279.749504)
				(end 194.003168 -279.749504)
			)
		)
		(stroke
			(width 0)
			(type solid)
		)
		(fill yes)
		(layer "In8.Cu")
		(net "P5E_PEX1_STN0_TX_DP<12>")
	)
	(gr_poly
		(pts
			(arc
				(start 194.952874 -278.799798)
				(mid 194.546474 -278.799798)
				(end 194.952874 -278.799798)
			)
		)
		(stroke
			(width 0)
			(type solid)
		)
		(fill yes)
		(layer "In8.Cu")
		(net "P5E_PEX1_STN0_TX_DP<11>")
	)
	(gr_poly
		(pts
			(arc
				(start 194.952874 -277.849838)
				(mid 194.546474 -277.849838)
				(end 194.952874 -277.849838)
			)
		)
		(stroke
			(width 0)
			(type solid)
		)
		(fill yes)
		(layer "In8.Cu")
		(net "P5E_PEX1_STN0_TX_DN<11>")
	)
	(gr_poly
		(pts
			(arc
				(start 195.903088 -280.699718)
				(mid 195.496688 -280.699718)
				(end 195.903088 -280.699718)
			)
		)
		(stroke
			(width 0)
			(type solid)
		)
		(fill yes)
		(layer "In8.Cu")
		(net "P5E_PEX1_STN0_TX_DP<10>")
	)
	(gr_poly
		(pts
			(arc
				(start 195.903088 -279.749758)
				(mid 195.496688 -279.749758)
				(end 195.903088 -279.749758)
			)
		)
		(stroke
			(width 0)
			(type solid)
		)
		(fill yes)
		(layer "In8.Cu")
		(net "P5E_PEX1_STN0_TX_DN<10>")
	)
	(gr_poly
		(pts
			(arc
				(start 196.853048 -278.799798)
				(mid 196.446648 -278.799798)
				(end 196.853048 -278.799798)
			)
		)
		(stroke
			(width 0)
			(type solid)
		)
		(fill yes)
		(layer "In8.Cu")
		(net "P5E_PEX1_STN0_TX_DP<9>")
	)
	(gr_poly
		(pts
			(arc
				(start 196.853048 -277.849838)
				(mid 196.446648 -277.849838)
				(end 196.853048 -277.849838)
			)
		)
		(stroke
			(width 0)
			(type solid)
		)
		(fill yes)
		(layer "In8.Cu")
		(net "P5E_PEX1_STN0_TX_DN<9>")
	)
	(gr_poly
		(pts
			(arc
				(start 197.803262 -279.749758)
				(mid 197.396862 -279.749758)
				(end 197.803262 -279.749758)
			)
		)
		(stroke
			(width 0)
			(type solid)
		)
		(fill yes)
		(layer "In8.Cu")
		(net "P5E_PEX1_STN0_TX_DP<7>")
	)
	(gr_poly
		(pts
			(arc
				(start 197.803262 -276.899878)
				(mid 197.396862 -276.899878)
				(end 197.803262 -276.899878)
			)
		)
		(stroke
			(width 0)
			(type solid)
		)
		(fill yes)
		(layer "In8.Cu")
		(net "P5E_PEX1_STN0_TX_DP<8>")
	)
	(gr_poly
		(pts
			(arc
				(start 198.753222 -279.749758)
				(mid 198.346822 -279.749758)
				(end 198.753222 -279.749758)
			)
		)
		(stroke
			(width 0)
			(type solid)
		)
		(fill yes)
		(layer "In8.Cu")
		(net "P5E_PEX1_STN0_TX_DN<7>")
	)
	(gr_poly
		(pts
			(arc
				(start 198.753222 -276.899878)
				(mid 198.346822 -276.899878)
				(end 198.753222 -276.899878)
			)
		)
		(stroke
			(width 0)
			(type solid)
		)
		(fill yes)
		(layer "In8.Cu")
		(net "P5E_PEX1_STN0_TX_DN<8>")
	)
	(gr_poly
		(pts
			(arc
				(start 275.902928 -312.049922)
				(mid 275.496528 -312.049922)
				(end 275.902928 -312.049922)
			)
		)
		(stroke
			(width 0)
			(type solid)
		)
		(fill yes)
		(layer "In8.Cu")
		(net "P5E_PEX2_STN6_TX_DN<111>")
	)
	(gr_poly
		(pts
			(arc
				(start 275.902928 -311.099962)
				(mid 275.496528 -311.099962)
				(end 275.902928 -311.099962)
			)
		)
		(stroke
			(width 0)
			(type solid)
		)
		(fill yes)
		(layer "In8.Cu")
		(net "P5E_PEX2_STN6_TX_DP<111>")
	)
	(gr_poly
		(pts
			(arc
				(start 276.852888 -313.949842)
				(mid 276.446488 -313.949842)
				(end 276.852888 -313.949842)
			)
		)
		(stroke
			(width 0)
			(type solid)
		)
		(fill yes)
		(layer "In8.Cu")
		(net "P5E_PEX2_STN6_TX_DN<110>")
	)
	(gr_poly
		(pts
			(arc
				(start 276.852888 -312.999882)
				(mid 276.446488 -312.999882)
				(end 276.852888 -312.999882)
			)
		)
		(stroke
			(width 0)
			(type solid)
		)
		(fill yes)
		(layer "In8.Cu")
		(net "P5E_PEX2_STN6_TX_DP<110>")
	)
	(gr_poly
		(pts
			(arc
				(start 276.852888 -278.799798)
				(mid 276.446488 -278.799798)
				(end 276.852888 -278.799798)
			)
		)
		(stroke
			(width 0)
			(type solid)
		)
		(fill yes)
		(layer "In8.Cu")
		(net "P5E_PEX2_STN2_TX_DP<47>")
	)
	(gr_poly
		(pts
			(arc
				(start 276.852888 -277.849838)
				(mid 276.446488 -277.849838)
				(end 276.852888 -277.849838)
			)
		)
		(stroke
			(width 0)
			(type solid)
		)
		(fill yes)
		(layer "In8.Cu")
		(net "P5E_PEX2_STN2_TX_DN<47>")
	)
	(gr_poly
		(pts
			(arc
				(start 277.803102 -312.049922)
				(mid 277.396702 -312.049922)
				(end 277.803102 -312.049922)
			)
		)
		(stroke
			(width 0)
			(type solid)
		)
		(fill yes)
		(layer "In8.Cu")
		(net "P5E_PEX2_STN6_TX_DN<109>")
	)
	(gr_poly
		(pts
			(arc
				(start 277.803102 -311.099962)
				(mid 277.396702 -311.099962)
				(end 277.803102 -311.099962)
			)
		)
		(stroke
			(width 0)
			(type solid)
		)
		(fill yes)
		(layer "In8.Cu")
		(net "P5E_PEX2_STN6_TX_DP<109>")
	)
	(gr_poly
		(pts
			(arc
				(start 277.803102 -280.699464)
				(mid 277.396702 -280.699464)
				(end 277.803102 -280.699464)
			)
		)
		(stroke
			(width 0)
			(type solid)
		)
		(fill yes)
		(layer "In8.Cu")
		(net "P5E_PEX2_STN2_TX_DP<46>")
	)
	(gr_poly
		(pts
			(arc
				(start 277.803102 -279.749504)
				(mid 277.396702 -279.749504)
				(end 277.803102 -279.749504)
			)
		)
		(stroke
			(width 0)
			(type solid)
		)
		(fill yes)
		(layer "In8.Cu")
		(net "P5E_PEX2_STN2_TX_DN<46>")
	)
	(gr_poly
		(pts
			(arc
				(start 278.753062 -313.949842)
				(mid 278.346662 -313.949842)
				(end 278.753062 -313.949842)
			)
		)
		(stroke
			(width 0)
			(type solid)
		)
		(fill yes)
		(layer "In8.Cu")
		(net "P5E_PEX2_STN6_TX_DN<108>")
	)
	(gr_poly
		(pts
			(arc
				(start 278.753062 -312.999882)
				(mid 278.346662 -312.999882)
				(end 278.753062 -312.999882)
			)
		)
		(stroke
			(width 0)
			(type solid)
		)
		(fill yes)
		(layer "In8.Cu")
		(net "P5E_PEX2_STN6_TX_DP<108>")
	)
	(gr_poly
		(pts
			(arc
				(start 278.753062 -278.799798)
				(mid 278.346662 -278.799798)
				(end 278.753062 -278.799798)
			)
		)
		(stroke
			(width 0)
			(type solid)
		)
		(fill yes)
		(layer "In8.Cu")
		(net "P5E_PEX2_STN2_TX_DP<45>")
	)
	(gr_poly
		(pts
			(arc
				(start 278.753062 -277.849838)
				(mid 278.346662 -277.849838)
				(end 278.753062 -277.849838)
			)
		)
		(stroke
			(width 0)
			(type solid)
		)
		(fill yes)
		(layer "In8.Cu")
		(net "P5E_PEX2_STN2_TX_DN<45>")
	)
	(gr_poly
		(pts
			(arc
				(start 279.703022 -312.049922)
				(mid 279.296622 -312.049922)
				(end 279.703022 -312.049922)
			)
		)
		(stroke
			(width 0)
			(type solid)
		)
		(fill yes)
		(layer "In8.Cu")
		(net "P5E_PEX2_STN6_TX_DN<107>")
	)
	(gr_poly
		(pts
			(arc
				(start 279.703022 -311.099962)
				(mid 279.296622 -311.099962)
				(end 279.703022 -311.099962)
			)
		)
		(stroke
			(width 0)
			(type solid)
		)
		(fill yes)
		(layer "In8.Cu")
		(net "P5E_PEX2_STN6_TX_DP<107>")
	)
	(gr_poly
		(pts
			(arc
				(start 279.703022 -280.699464)
				(mid 279.296622 -280.699464)
				(end 279.703022 -280.699464)
			)
		)
		(stroke
			(width 0)
			(type solid)
		)
		(fill yes)
		(layer "In8.Cu")
		(net "P5E_PEX2_STN2_TX_DP<44>")
	)
	(gr_poly
		(pts
			(arc
				(start 279.703022 -279.749504)
				(mid 279.296622 -279.749504)
				(end 279.703022 -279.749504)
			)
		)
		(stroke
			(width 0)
			(type solid)
		)
		(fill yes)
		(layer "In8.Cu")
		(net "P5E_PEX2_STN2_TX_DN<44>")
	)
	(gr_poly
		(pts
			(arc
				(start 280.652982 -313.949842)
				(mid 280.246582 -313.949842)
				(end 280.652982 -313.949842)
			)
		)
		(stroke
			(width 0)
			(type solid)
		)
		(fill yes)
		(layer "In8.Cu")
		(net "P5E_PEX2_STN6_TX_DN<106>")
	)
	(gr_poly
		(pts
			(arc
				(start 280.652982 -312.999882)
				(mid 280.246582 -312.999882)
				(end 280.652982 -312.999882)
			)
		)
		(stroke
			(width 0)
			(type solid)
		)
		(fill yes)
		(layer "In8.Cu")
		(net "P5E_PEX2_STN6_TX_DP<106>")
	)
	(gr_poly
		(pts
			(arc
				(start 280.652982 -278.799798)
				(mid 280.246582 -278.799798)
				(end 280.652982 -278.799798)
			)
		)
		(stroke
			(width 0)
			(type solid)
		)
		(fill yes)
		(layer "In8.Cu")
		(net "P5E_PEX2_STN2_TX_DP<43>")
	)
	(gr_poly
		(pts
			(arc
				(start 280.652982 -277.849838)
				(mid 280.246582 -277.849838)
				(end 280.652982 -277.849838)
			)
		)
		(stroke
			(width 0)
			(type solid)
		)
		(fill yes)
		(layer "In8.Cu")
		(net "P5E_PEX2_STN2_TX_DN<43>")
	)
	(gr_poly
		(pts
			(arc
				(start 281.602942 -312.049922)
				(mid 281.196542 -312.049922)
				(end 281.602942 -312.049922)
			)
		)
		(stroke
			(width 0)
			(type solid)
		)
		(fill yes)
		(layer "In8.Cu")
		(net "P5E_PEX2_STN6_TX_DN<105>")
	)
	(gr_poly
		(pts
			(arc
				(start 281.602942 -311.099962)
				(mid 281.196542 -311.099962)
				(end 281.602942 -311.099962)
			)
		)
		(stroke
			(width 0)
			(type solid)
		)
		(fill yes)
		(layer "In8.Cu")
		(net "P5E_PEX2_STN6_TX_DP<105>")
	)
	(gr_poly
		(pts
			(arc
				(start 281.602942 -280.699464)
				(mid 281.196542 -280.699464)
				(end 281.602942 -280.699464)
			)
		)
		(stroke
			(width 0)
			(type solid)
		)
		(fill yes)
		(layer "In8.Cu")
		(net "P5E_PEX2_STN2_TX_DP<42>")
	)
	(gr_poly
		(pts
			(arc
				(start 281.602942 -279.749504)
				(mid 281.196542 -279.749504)
				(end 281.602942 -279.749504)
			)
		)
		(stroke
			(width 0)
			(type solid)
		)
		(fill yes)
		(layer "In8.Cu")
		(net "P5E_PEX2_STN2_TX_DN<42>")
	)
	(gr_poly
		(pts
			(arc
				(start 282.552902 -313.949842)
				(mid 282.146502 -313.949842)
				(end 282.552902 -313.949842)
			)
		)
		(stroke
			(width 0)
			(type solid)
		)
		(fill yes)
		(layer "In8.Cu")
		(net "P5E_PEX2_STN6_TX_DN<104>")
	)
	(gr_poly
		(pts
			(arc
				(start 282.552902 -312.999882)
				(mid 282.146502 -312.999882)
				(end 282.552902 -312.999882)
			)
		)
		(stroke
			(width 0)
			(type solid)
		)
		(fill yes)
		(layer "In8.Cu")
		(net "P5E_PEX2_STN6_TX_DP<104>")
	)
	(gr_poly
		(pts
			(arc
				(start 282.552902 -278.799798)
				(mid 282.146502 -278.799798)
				(end 282.552902 -278.799798)
			)
		)
		(stroke
			(width 0)
			(type solid)
		)
		(fill yes)
		(layer "In8.Cu")
		(net "P5E_PEX2_STN2_TX_DP<41>")
	)
	(gr_poly
		(pts
			(arc
				(start 282.552902 -277.849838)
				(mid 282.146502 -277.849838)
				(end 282.552902 -277.849838)
			)
		)
		(stroke
			(width 0)
			(type solid)
		)
		(fill yes)
		(layer "In8.Cu")
		(net "P5E_PEX2_STN2_TX_DN<41>")
	)
	(gr_poly
		(pts
			(arc
				(start 283.503116 -316.799722)
				(mid 283.096716 -316.799722)
				(end 283.503116 -316.799722)
			)
		)
		(stroke
			(width 0)
			(type solid)
		)
		(fill yes)
		(layer "In8.Cu")
		(net "P5E_PEX2_STN6_RX_DN<103>")
	)
	(gr_poly
		(pts
			(arc
				(start 283.503116 -315.849762)
				(mid 283.096716 -315.849762)
				(end 283.503116 -315.849762)
			)
		)
		(stroke
			(width 0)
			(type solid)
		)
		(fill yes)
		(layer "In8.Cu")
		(net "P5E_PEX2_STN6_RX_DP<103>")
	)
	(gr_poly
		(pts
			(arc
				(start 283.503116 -312.049922)
				(mid 283.096716 -312.049922)
				(end 283.503116 -312.049922)
			)
		)
		(stroke
			(width 0)
			(type solid)
		)
		(fill yes)
		(layer "In8.Cu")
		(net "P5E_PEX2_STN6_TX_DN<103>")
	)
	(gr_poly
		(pts
			(arc
				(start 283.503116 -311.099962)
				(mid 283.096716 -311.099962)
				(end 283.503116 -311.099962)
			)
		)
		(stroke
			(width 0)
			(type solid)
		)
		(fill yes)
		(layer "In8.Cu")
		(net "P5E_PEX2_STN6_TX_DP<103>")
	)
	(gr_poly
		(pts
			(arc
				(start 283.503116 -280.699464)
				(mid 283.096716 -280.699464)
				(end 283.503116 -280.699464)
			)
		)
		(stroke
			(width 0)
			(type solid)
		)
		(fill yes)
		(layer "In8.Cu")
		(net "P5E_PEX2_STN2_TX_DP<40>")
	)
	(gr_poly
		(pts
			(arc
				(start 283.503116 -279.749504)
				(mid 283.096716 -279.749504)
				(end 283.503116 -279.749504)
			)
		)
		(stroke
			(width 0)
			(type solid)
		)
		(fill yes)
		(layer "In8.Cu")
		(net "P5E_PEX2_STN2_TX_DN<40>")
	)
	(gr_poly
		(pts
			(arc
				(start 284.453076 -318.699896)
				(mid 284.046676 -318.699896)
				(end 284.453076 -318.699896)
			)
		)
		(stroke
			(width 0)
			(type solid)
		)
		(fill yes)
		(layer "In8.Cu")
		(net "P5E_PEX2_STN6_RX_DN<102>")
	)
	(gr_poly
		(pts
			(arc
				(start 284.453076 -317.749936)
				(mid 284.046676 -317.749936)
				(end 284.453076 -317.749936)
			)
		)
		(stroke
			(width 0)
			(type solid)
		)
		(fill yes)
		(layer "In8.Cu")
		(net "P5E_PEX2_STN6_RX_DP<102>")
	)
	(gr_poly
		(pts
			(arc
				(start 284.453076 -313.949842)
				(mid 284.046676 -313.949842)
				(end 284.453076 -313.949842)
			)
		)
		(stroke
			(width 0)
			(type solid)
		)
		(fill yes)
		(layer "In8.Cu")
		(net "P5E_PEX2_STN6_TX_DN<102>")
	)
	(gr_poly
		(pts
			(arc
				(start 284.453076 -312.999882)
				(mid 284.046676 -312.999882)
				(end 284.453076 -312.999882)
			)
		)
		(stroke
			(width 0)
			(type solid)
		)
		(fill yes)
		(layer "In8.Cu")
		(net "P5E_PEX2_STN6_TX_DP<102>")
	)
	(gr_poly
		(pts
			(arc
				(start 284.453076 -278.799798)
				(mid 284.046676 -278.799798)
				(end 284.453076 -278.799798)
			)
		)
		(stroke
			(width 0)
			(type solid)
		)
		(fill yes)
		(layer "In8.Cu")
		(net "P5E_PEX2_STN2_TX_DP<39>")
	)
	(gr_poly
		(pts
			(arc
				(start 284.453076 -277.849838)
				(mid 284.046676 -277.849838)
				(end 284.453076 -277.849838)
			)
		)
		(stroke
			(width 0)
			(type solid)
		)
		(fill yes)
		(layer "In8.Cu")
		(net "P5E_PEX2_STN2_TX_DN<39>")
	)
	(gr_poly
		(pts
			(arc
				(start 285.403036 -316.799722)
				(mid 284.996636 -316.799722)
				(end 285.403036 -316.799722)
			)
		)
		(stroke
			(width 0)
			(type solid)
		)
		(fill yes)
		(layer "In8.Cu")
		(net "P5E_PEX2_STN6_RX_DN<101>")
	)
	(gr_poly
		(pts
			(arc
				(start 285.403036 -315.849762)
				(mid 284.996636 -315.849762)
				(end 285.403036 -315.849762)
			)
		)
		(stroke
			(width 0)
			(type solid)
		)
		(fill yes)
		(layer "In8.Cu")
		(net "P5E_PEX2_STN6_RX_DP<101>")
	)
	(gr_poly
		(pts
			(arc
				(start 285.403036 -312.049922)
				(mid 284.996636 -312.049922)
				(end 285.403036 -312.049922)
			)
		)
		(stroke
			(width 0)
			(type solid)
		)
		(fill yes)
		(layer "In8.Cu")
		(net "P5E_PEX2_STN6_TX_DN<101>")
	)
	(gr_poly
		(pts
			(arc
				(start 285.403036 -311.099962)
				(mid 284.996636 -311.099962)
				(end 285.403036 -311.099962)
			)
		)
		(stroke
			(width 0)
			(type solid)
		)
		(fill yes)
		(layer "In8.Cu")
		(net "P5E_PEX2_STN6_TX_DP<101>")
	)
	(gr_poly
		(pts
			(arc
				(start 285.403036 -280.699464)
				(mid 284.996636 -280.699464)
				(end 285.403036 -280.699464)
			)
		)
		(stroke
			(width 0)
			(type solid)
		)
		(fill yes)
		(layer "In8.Cu")
		(net "P5E_PEX2_STN2_TX_DP<38>")
	)
	(gr_poly
		(pts
			(arc
				(start 285.403036 -279.749504)
				(mid 284.996636 -279.749504)
				(end 285.403036 -279.749504)
			)
		)
		(stroke
			(width 0)
			(type solid)
		)
		(fill yes)
		(layer "In8.Cu")
		(net "P5E_PEX2_STN2_TX_DN<38>")
	)
	(gr_poly
		(pts
			(arc
				(start 286.352996 -318.699896)
				(mid 285.946596 -318.699896)
				(end 286.352996 -318.699896)
			)
		)
		(stroke
			(width 0)
			(type solid)
		)
		(fill yes)
		(layer "In8.Cu")
		(net "P5E_PEX2_STN6_RX_DN<100>")
	)
	(gr_poly
		(pts
			(arc
				(start 286.352996 -317.749936)
				(mid 285.946596 -317.749936)
				(end 286.352996 -317.749936)
			)
		)
		(stroke
			(width 0)
			(type solid)
		)
		(fill yes)
		(layer "In8.Cu")
		(net "P5E_PEX2_STN6_RX_DP<100>")
	)
	(gr_poly
		(pts
			(arc
				(start 286.352996 -313.949842)
				(mid 285.946596 -313.949842)
				(end 286.352996 -313.949842)
			)
		)
		(stroke
			(width 0)
			(type solid)
		)
		(fill yes)
		(layer "In8.Cu")
		(net "P5E_PEX2_STN6_TX_DN<100>")
	)
	(gr_poly
		(pts
			(arc
				(start 286.352996 -312.999882)
				(mid 285.946596 -312.999882)
				(end 286.352996 -312.999882)
			)
		)
		(stroke
			(width 0)
			(type solid)
		)
		(fill yes)
		(layer "In8.Cu")
		(net "P5E_PEX2_STN6_TX_DP<100>")
	)
	(gr_poly
		(pts
			(arc
				(start 286.352996 -278.799798)
				(mid 285.946596 -278.799798)
				(end 286.352996 -278.799798)
			)
		)
		(stroke
			(width 0)
			(type solid)
		)
		(fill yes)
		(layer "In8.Cu")
		(net "P5E_PEX2_STN2_TX_DP<37>")
	)
	(gr_poly
		(pts
			(arc
				(start 286.352996 -277.849838)
				(mid 285.946596 -277.849838)
				(end 286.352996 -277.849838)
			)
		)
		(stroke
			(width 0)
			(type solid)
		)
		(fill yes)
		(layer "In8.Cu")
		(net "P5E_PEX2_STN2_TX_DN<37>")
	)
	(gr_poly
		(pts
			(arc
				(start 287.302956 -316.799722)
				(mid 286.896556 -316.799722)
				(end 287.302956 -316.799722)
			)
		)
		(stroke
			(width 0)
			(type solid)
		)
		(fill yes)
		(layer "In8.Cu")
		(net "P5E_PEX2_STN6_RX_DN<99>")
	)
	(gr_poly
		(pts
			(arc
				(start 287.302956 -315.849762)
				(mid 286.896556 -315.849762)
				(end 287.302956 -315.849762)
			)
		)
		(stroke
			(width 0)
			(type solid)
		)
		(fill yes)
		(layer "In8.Cu")
		(net "P5E_PEX2_STN6_RX_DP<99>")
	)
	(gr_poly
		(pts
			(arc
				(start 287.302956 -312.049922)
				(mid 286.896556 -312.049922)
				(end 287.302956 -312.049922)
			)
		)
		(stroke
			(width 0)
			(type solid)
		)
		(fill yes)
		(layer "In8.Cu")
		(net "P5E_PEX2_STN6_TX_DN<99>")
	)
	(gr_poly
		(pts
			(arc
				(start 287.302956 -311.099962)
				(mid 286.896556 -311.099962)
				(end 287.302956 -311.099962)
			)
		)
		(stroke
			(width 0)
			(type solid)
		)
		(fill yes)
		(layer "In8.Cu")
		(net "P5E_PEX2_STN6_TX_DP<99>")
	)
	(gr_poly
		(pts
			(arc
				(start 287.302956 -280.699464)
				(mid 286.896556 -280.699464)
				(end 287.302956 -280.699464)
			)
		)
		(stroke
			(width 0)
			(type solid)
		)
		(fill yes)
		(layer "In8.Cu")
		(net "P5E_PEX2_STN2_TX_DP<36>")
	)
	(gr_poly
		(pts
			(arc
				(start 287.302956 -279.749504)
				(mid 286.896556 -279.749504)
				(end 287.302956 -279.749504)
			)
		)
		(stroke
			(width 0)
			(type solid)
		)
		(fill yes)
		(layer "In8.Cu")
		(net "P5E_PEX2_STN2_TX_DN<36>")
	)
	(gr_poly
		(pts
			(arc
				(start 288.252916 -318.699896)
				(mid 287.846516 -318.699896)
				(end 288.252916 -318.699896)
			)
		)
		(stroke
			(width 0)
			(type solid)
		)
		(fill yes)
		(layer "In8.Cu")
		(net "P5E_PEX2_STN6_RX_DN<98>")
	)
	(gr_poly
		(pts
			(arc
				(start 288.252916 -317.749936)
				(mid 287.846516 -317.749936)
				(end 288.252916 -317.749936)
			)
		)
		(stroke
			(width 0)
			(type solid)
		)
		(fill yes)
		(layer "In8.Cu")
		(net "P5E_PEX2_STN6_RX_DP<98>")
	)
	(gr_poly
		(pts
			(arc
				(start 288.252916 -313.949842)
				(mid 287.846516 -313.949842)
				(end 288.252916 -313.949842)
			)
		)
		(stroke
			(width 0)
			(type solid)
		)
		(fill yes)
		(layer "In8.Cu")
		(net "P5E_PEX2_STN6_TX_DN<98>")
	)
	(gr_poly
		(pts
			(arc
				(start 288.252916 -312.999882)
				(mid 287.846516 -312.999882)
				(end 288.252916 -312.999882)
			)
		)
		(stroke
			(width 0)
			(type solid)
		)
		(fill yes)
		(layer "In8.Cu")
		(net "P5E_PEX2_STN6_TX_DP<98>")
	)
	(gr_poly
		(pts
			(arc
				(start 288.252916 -278.799798)
				(mid 287.846516 -278.799798)
				(end 288.252916 -278.799798)
			)
		)
		(stroke
			(width 0)
			(type solid)
		)
		(fill yes)
		(layer "In8.Cu")
		(net "P5E_PEX2_STN2_TX_DP<35>")
	)
	(gr_poly
		(pts
			(arc
				(start 288.252916 -277.849838)
				(mid 287.846516 -277.849838)
				(end 288.252916 -277.849838)
			)
		)
		(stroke
			(width 0)
			(type solid)
		)
		(fill yes)
		(layer "In8.Cu")
		(net "P5E_PEX2_STN2_TX_DN<35>")
	)
	(gr_poly
		(pts
			(arc
				(start 289.202876 -280.699464)
				(mid 288.796476 -280.699464)
				(end 289.202876 -280.699464)
			)
		)
		(stroke
			(width 0)
			(type solid)
		)
		(fill yes)
		(layer "In8.Cu")
		(net "P5E_PEX2_STN2_TX_DP<34>")
	)
	(gr_poly
		(pts
			(arc
				(start 289.202876 -279.749504)
				(mid 288.796476 -279.749504)
				(end 289.202876 -279.749504)
			)
		)
		(stroke
			(width 0)
			(type solid)
		)
		(fill yes)
		(layer "In8.Cu")
		(net "P5E_PEX2_STN2_TX_DN<34>")
	)
	(gr_poly
		(pts
			(arc
				(start 289.20313 -316.799722)
				(mid 288.79673 -316.799722)
				(end 289.20313 -316.799722)
			)
		)
		(stroke
			(width 0)
			(type solid)
		)
		(fill yes)
		(layer "In8.Cu")
		(net "P5E_PEX2_STN6_RX_DN<97>")
	)
	(gr_poly
		(pts
			(arc
				(start 289.20313 -315.849762)
				(mid 288.79673 -315.849762)
				(end 289.20313 -315.849762)
			)
		)
		(stroke
			(width 0)
			(type solid)
		)
		(fill yes)
		(layer "In8.Cu")
		(net "P5E_PEX2_STN6_RX_DP<97>")
	)
	(gr_poly
		(pts
			(arc
				(start 289.20313 -312.049922)
				(mid 288.79673 -312.049922)
				(end 289.20313 -312.049922)
			)
		)
		(stroke
			(width 0)
			(type solid)
		)
		(fill yes)
		(layer "In8.Cu")
		(net "P5E_PEX2_STN6_TX_DN<97>")
	)
	(gr_poly
		(pts
			(arc
				(start 289.20313 -311.099962)
				(mid 288.79673 -311.099962)
				(end 289.20313 -311.099962)
			)
		)
		(stroke
			(width 0)
			(type solid)
		)
		(fill yes)
		(layer "In8.Cu")
		(net "P5E_PEX2_STN6_TX_DP<97>")
	)
	(gr_poly
		(pts
			(arc
				(start 290.15309 -318.699896)
				(mid 289.74669 -318.699896)
				(end 290.15309 -318.699896)
			)
		)
		(stroke
			(width 0)
			(type solid)
		)
		(fill yes)
		(layer "In8.Cu")
		(net "P5E_PEX2_STN6_RX_DN<96>")
	)
	(gr_poly
		(pts
			(arc
				(start 290.15309 -317.749936)
				(mid 289.74669 -317.749936)
				(end 290.15309 -317.749936)
			)
		)
		(stroke
			(width 0)
			(type solid)
		)
		(fill yes)
		(layer "In8.Cu")
		(net "P5E_PEX2_STN6_RX_DP<96>")
	)
	(gr_poly
		(pts
			(arc
				(start 290.15309 -313.949842)
				(mid 289.74669 -313.949842)
				(end 290.15309 -313.949842)
			)
		)
		(stroke
			(width 0)
			(type solid)
		)
		(fill yes)
		(layer "In8.Cu")
		(net "P5E_PEX2_STN6_TX_DN<96>")
	)
	(gr_poly
		(pts
			(arc
				(start 290.15309 -312.999882)
				(mid 289.74669 -312.999882)
				(end 290.15309 -312.999882)
			)
		)
		(stroke
			(width 0)
			(type solid)
		)
		(fill yes)
		(layer "In8.Cu")
		(net "P5E_PEX2_STN6_TX_DP<96>")
	)
	(gr_poly
		(pts
			(arc
				(start 290.15309 -278.799798)
				(mid 289.74669 -278.799798)
				(end 290.15309 -278.799798)
			)
		)
		(stroke
			(width 0)
			(type solid)
		)
		(fill yes)
		(layer "In8.Cu")
		(net "P5E_PEX2_STN2_TX_DP<33>")
	)
	(gr_poly
		(pts
			(arc
				(start 290.15309 -277.849838)
				(mid 289.74669 -277.849838)
				(end 290.15309 -277.849838)
			)
		)
		(stroke
			(width 0)
			(type solid)
		)
		(fill yes)
		(layer "In8.Cu")
		(net "P5E_PEX2_STN2_TX_DN<33>")
	)
	(gr_poly
		(pts
			(arc
				(start 291.10305 -316.799722)
				(mid 290.69665 -316.799722)
				(end 291.10305 -316.799722)
			)
		)
		(stroke
			(width 0)
			(type solid)
		)
		(fill yes)
		(layer "In8.Cu")
		(net "P5E_PEX2_STN5_RX_DN<80>")
	)
	(gr_poly
		(pts
			(arc
				(start 291.10305 -315.849762)
				(mid 290.69665 -315.849762)
				(end 291.10305 -315.849762)
			)
		)
		(stroke
			(width 0)
			(type solid)
		)
		(fill yes)
		(layer "In8.Cu")
		(net "P5E_PEX2_STN5_RX_DP<80>")
	)
	(gr_poly
		(pts
			(arc
				(start 291.10305 -280.699464)
				(mid 290.69665 -280.699464)
				(end 291.10305 -280.699464)
			)
		)
		(stroke
			(width 0)
			(type solid)
		)
		(fill yes)
		(layer "In8.Cu")
		(net "P5E_PEX2_STN2_TX_DP<32>")
	)
	(gr_poly
		(pts
			(arc
				(start 291.10305 -279.749504)
				(mid 290.69665 -279.749504)
				(end 291.10305 -279.749504)
			)
		)
		(stroke
			(width 0)
			(type solid)
		)
		(fill yes)
		(layer "In8.Cu")
		(net "P5E_PEX2_STN2_TX_DN<32>")
	)
	(gr_poly
		(pts
			(arc
				(start 292.052756 -278.799798)
				(mid 291.646356 -278.799798)
				(end 292.052756 -278.799798)
			)
		)
		(stroke
			(width 0)
			(type solid)
		)
		(fill yes)
		(layer "In8.Cu")
		(net "P5E_PEX2_STN1_TX_DP<16>")
	)
	(gr_poly
		(pts
			(arc
				(start 292.052756 -277.849838)
				(mid 291.646356 -277.849838)
				(end 292.052756 -277.849838)
			)
		)
		(stroke
			(width 0)
			(type solid)
		)
		(fill yes)
		(layer "In8.Cu")
		(net "P5E_PEX2_STN1_TX_DN<16>")
	)
	(gr_poly
		(pts
			(arc
				(start 292.05301 -318.699896)
				(mid 291.64661 -318.699896)
				(end 292.05301 -318.699896)
			)
		)
		(stroke
			(width 0)
			(type solid)
		)
		(fill yes)
		(layer "In8.Cu")
		(net "P5E_PEX2_STN5_RX_DN<81>")
	)
	(gr_poly
		(pts
			(arc
				(start 292.05301 -317.749936)
				(mid 291.64661 -317.749936)
				(end 292.05301 -317.749936)
			)
		)
		(stroke
			(width 0)
			(type solid)
		)
		(fill yes)
		(layer "In8.Cu")
		(net "P5E_PEX2_STN5_RX_DP<81>")
	)
	(gr_poly
		(pts
			(arc
				(start 293.00297 -316.799722)
				(mid 292.59657 -316.799722)
				(end 293.00297 -316.799722)
			)
		)
		(stroke
			(width 0)
			(type solid)
		)
		(fill yes)
		(layer "In8.Cu")
		(net "P5E_PEX2_STN5_RX_DN<82>")
	)
	(gr_poly
		(pts
			(arc
				(start 293.00297 -315.849762)
				(mid 292.59657 -315.849762)
				(end 293.00297 -315.849762)
			)
		)
		(stroke
			(width 0)
			(type solid)
		)
		(fill yes)
		(layer "In8.Cu")
		(net "P5E_PEX2_STN5_RX_DP<82>")
	)
	(gr_poly
		(pts
			(arc
				(start 293.00297 -280.699464)
				(mid 292.59657 -280.699464)
				(end 293.00297 -280.699464)
			)
		)
		(stroke
			(width 0)
			(type solid)
		)
		(fill yes)
		(layer "In8.Cu")
		(net "P5E_PEX2_STN1_TX_DN<17>")
	)
	(gr_poly
		(pts
			(arc
				(start 293.00297 -279.749504)
				(mid 292.59657 -279.749504)
				(end 293.00297 -279.749504)
			)
		)
		(stroke
			(width 0)
			(type solid)
		)
		(fill yes)
		(layer "In8.Cu")
		(net "P5E_PEX2_STN1_TX_DP<17>")
	)
	(gr_poly
		(pts
			(arc
				(start 293.952676 -278.799798)
				(mid 293.546276 -278.799798)
				(end 293.952676 -278.799798)
			)
		)
		(stroke
			(width 0)
			(type solid)
		)
		(fill yes)
		(layer "In8.Cu")
		(net "P5E_PEX2_STN1_TX_DP<18>")
	)
	(gr_poly
		(pts
			(arc
				(start 293.952676 -277.849838)
				(mid 293.546276 -277.849838)
				(end 293.952676 -277.849838)
			)
		)
		(stroke
			(width 0)
			(type solid)
		)
		(fill yes)
		(layer "In8.Cu")
		(net "P5E_PEX2_STN1_TX_DN<18>")
	)
	(gr_poly
		(pts
			(arc
				(start 293.95293 -318.699896)
				(mid 293.54653 -318.699896)
				(end 293.95293 -318.699896)
			)
		)
		(stroke
			(width 0)
			(type solid)
		)
		(fill yes)
		(layer "In8.Cu")
		(net "P5E_PEX2_STN5_RX_DN<83>")
	)
	(gr_poly
		(pts
			(arc
				(start 293.95293 -317.749936)
				(mid 293.54653 -317.749936)
				(end 293.95293 -317.749936)
			)
		)
		(stroke
			(width 0)
			(type solid)
		)
		(fill yes)
		(layer "In8.Cu")
		(net "P5E_PEX2_STN5_RX_DP<83>")
	)
	(gr_poly
		(pts
			(arc
				(start 294.90289 -316.799722)
				(mid 294.49649 -316.799722)
				(end 294.90289 -316.799722)
			)
		)
		(stroke
			(width 0)
			(type solid)
		)
		(fill yes)
		(layer "In8.Cu")
		(net "P5E_PEX2_STN5_RX_DN<84>")
	)
	(gr_poly
		(pts
			(arc
				(start 294.90289 -315.849762)
				(mid 294.49649 -315.849762)
				(end 294.90289 -315.849762)
			)
		)
		(stroke
			(width 0)
			(type solid)
		)
		(fill yes)
		(layer "In8.Cu")
		(net "P5E_PEX2_STN5_RX_DP<84>")
	)
	(gr_poly
		(pts
			(arc
				(start 294.90289 -280.699464)
				(mid 294.49649 -280.699464)
				(end 294.90289 -280.699464)
			)
		)
		(stroke
			(width 0)
			(type solid)
		)
		(fill yes)
		(layer "In8.Cu")
		(net "P5E_PEX2_STN1_TX_DN<19>")
	)
	(gr_poly
		(pts
			(arc
				(start 294.90289 -279.749504)
				(mid 294.49649 -279.749504)
				(end 294.90289 -279.749504)
			)
		)
		(stroke
			(width 0)
			(type solid)
		)
		(fill yes)
		(layer "In8.Cu")
		(net "P5E_PEX2_STN1_TX_DP<19>")
	)
	(gr_poly
		(pts
			(arc
				(start 295.85285 -278.799798)
				(mid 295.44645 -278.799798)
				(end 295.85285 -278.799798)
			)
		)
		(stroke
			(width 0)
			(type solid)
		)
		(fill yes)
		(layer "In8.Cu")
		(net "P5E_PEX2_STN1_TX_DP<20>")
	)
	(gr_poly
		(pts
			(arc
				(start 295.85285 -277.849838)
				(mid 295.44645 -277.849838)
				(end 295.85285 -277.849838)
			)
		)
		(stroke
			(width 0)
			(type solid)
		)
		(fill yes)
		(layer "In8.Cu")
		(net "P5E_PEX2_STN1_TX_DN<20>")
	)
	(gr_poly
		(pts
			(arc
				(start 295.853104 -318.699896)
				(mid 295.446704 -318.699896)
				(end 295.853104 -318.699896)
			)
		)
		(stroke
			(width 0)
			(type solid)
		)
		(fill yes)
		(layer "In8.Cu")
		(net "P5E_PEX2_STN5_RX_DN<85>")
	)
	(gr_poly
		(pts
			(arc
				(start 295.853104 -317.749936)
				(mid 295.446704 -317.749936)
				(end 295.853104 -317.749936)
			)
		)
		(stroke
			(width 0)
			(type solid)
		)
		(fill yes)
		(layer "In8.Cu")
		(net "P5E_PEX2_STN5_RX_DP<85>")
	)
	(gr_poly
		(pts
			(arc
				(start 296.803064 -316.799722)
				(mid 296.396664 -316.799722)
				(end 296.803064 -316.799722)
			)
		)
		(stroke
			(width 0)
			(type solid)
		)
		(fill yes)
		(layer "In8.Cu")
		(net "P5E_PEX2_STN5_RX_DN<86>")
	)
	(gr_poly
		(pts
			(arc
				(start 296.803064 -315.849762)
				(mid 296.396664 -315.849762)
				(end 296.803064 -315.849762)
			)
		)
		(stroke
			(width 0)
			(type solid)
		)
		(fill yes)
		(layer "In8.Cu")
		(net "P5E_PEX2_STN5_RX_DP<86>")
	)
	(gr_poly
		(pts
			(arc
				(start 296.803064 -280.699464)
				(mid 296.396664 -280.699464)
				(end 296.803064 -280.699464)
			)
		)
		(stroke
			(width 0)
			(type solid)
		)
		(fill yes)
		(layer "In8.Cu")
		(net "P5E_PEX2_STN1_TX_DN<21>")
	)
	(gr_poly
		(pts
			(arc
				(start 296.803064 -279.749504)
				(mid 296.396664 -279.749504)
				(end 296.803064 -279.749504)
			)
		)
		(stroke
			(width 0)
			(type solid)
		)
		(fill yes)
		(layer "In8.Cu")
		(net "P5E_PEX2_STN1_TX_DP<21>")
	)
	(gr_poly
		(pts
			(arc
				(start 297.75277 -278.799798)
				(mid 297.34637 -278.799798)
				(end 297.75277 -278.799798)
			)
		)
		(stroke
			(width 0)
			(type solid)
		)
		(fill yes)
		(layer "In8.Cu")
		(net "P5E_PEX2_STN1_TX_DP<22>")
	)
	(gr_poly
		(pts
			(arc
				(start 297.75277 -277.849838)
				(mid 297.34637 -277.849838)
				(end 297.75277 -277.849838)
			)
		)
		(stroke
			(width 0)
			(type solid)
		)
		(fill yes)
		(layer "In8.Cu")
		(net "P5E_PEX2_STN1_TX_DN<22>")
	)
	(gr_poly
		(pts
			(arc
				(start 297.753024 -318.699896)
				(mid 297.346624 -318.699896)
				(end 297.753024 -318.699896)
			)
		)
		(stroke
			(width 0)
			(type solid)
		)
		(fill yes)
		(layer "In8.Cu")
		(net "P5E_PEX2_STN5_RX_DN<87>")
	)
	(gr_poly
		(pts
			(arc
				(start 297.753024 -317.749936)
				(mid 297.346624 -317.749936)
				(end 297.753024 -317.749936)
			)
		)
		(stroke
			(width 0)
			(type solid)
		)
		(fill yes)
		(layer "In8.Cu")
		(net "P5E_PEX2_STN5_RX_DP<87>")
	)
	(gr_poly
		(pts
			(arc
				(start 298.702984 -280.699464)
				(mid 298.296584 -280.699464)
				(end 298.702984 -280.699464)
			)
		)
		(stroke
			(width 0)
			(type solid)
		)
		(fill yes)
		(layer "In8.Cu")
		(net "P5E_PEX2_STN1_TX_DN<23>")
	)
	(gr_poly
		(pts
			(arc
				(start 298.702984 -279.749504)
				(mid 298.296584 -279.749504)
				(end 298.702984 -279.749504)
			)
		)
		(stroke
			(width 0)
			(type solid)
		)
		(fill yes)
		(layer "In8.Cu")
		(net "P5E_PEX2_STN1_TX_DP<23>")
	)
	(gr_poly
		(pts
			(arc
				(start 299.65269 -278.799798)
				(mid 299.24629 -278.799798)
				(end 299.65269 -278.799798)
			)
		)
		(stroke
			(width 0)
			(type solid)
		)
		(fill yes)
		(layer "In8.Cu")
		(net "P5E_PEX2_STN1_TX_DP<24>")
	)
	(gr_poly
		(pts
			(arc
				(start 299.65269 -277.849838)
				(mid 299.24629 -277.849838)
				(end 299.65269 -277.849838)
			)
		)
		(stroke
			(width 0)
			(type solid)
		)
		(fill yes)
		(layer "In8.Cu")
		(net "P5E_PEX2_STN1_TX_DN<24>")
	)
	(gr_poly
		(pts
			(arc
				(start 300.602904 -280.699464)
				(mid 300.196504 -280.699464)
				(end 300.602904 -280.699464)
			)
		)
		(stroke
			(width 0)
			(type solid)
		)
		(fill yes)
		(layer "In8.Cu")
		(net "P5E_PEX2_STN1_TX_DN<25>")
	)
	(gr_poly
		(pts
			(arc
				(start 300.602904 -279.749504)
				(mid 300.196504 -279.749504)
				(end 300.602904 -279.749504)
			)
		)
		(stroke
			(width 0)
			(type solid)
		)
		(fill yes)
		(layer "In8.Cu")
		(net "P5E_PEX2_STN1_TX_DP<25>")
	)
	(gr_poly
		(pts
			(arc
				(start 301.552864 -278.799798)
				(mid 301.146464 -278.799798)
				(end 301.552864 -278.799798)
			)
		)
		(stroke
			(width 0)
			(type solid)
		)
		(fill yes)
		(layer "In8.Cu")
		(net "P5E_PEX2_STN1_TX_DP<26>")
	)
	(gr_poly
		(pts
			(arc
				(start 301.552864 -277.849838)
				(mid 301.146464 -277.849838)
				(end 301.552864 -277.849838)
			)
		)
		(stroke
			(width 0)
			(type solid)
		)
		(fill yes)
		(layer "In8.Cu")
		(net "P5E_PEX2_STN1_TX_DN<26>")
	)
	(gr_poly
		(pts
			(arc
				(start 302.503078 -280.699464)
				(mid 302.096678 -280.699464)
				(end 302.503078 -280.699464)
			)
		)
		(stroke
			(width 0)
			(type solid)
		)
		(fill yes)
		(layer "In8.Cu")
		(net "P5E_PEX2_STN1_TX_DN<27>")
	)
	(gr_poly
		(pts
			(arc
				(start 302.503078 -279.749504)
				(mid 302.096678 -279.749504)
				(end 302.503078 -279.749504)
			)
		)
		(stroke
			(width 0)
			(type solid)
		)
		(fill yes)
		(layer "In8.Cu")
		(net "P5E_PEX2_STN1_TX_DP<27>")
	)
	(gr_poly
		(pts
			(arc
				(start 303.452784 -278.799798)
				(mid 303.046384 -278.799798)
				(end 303.452784 -278.799798)
			)
		)
		(stroke
			(width 0)
			(type solid)
		)
		(fill yes)
		(layer "In8.Cu")
		(net "P5E_PEX2_STN1_TX_DP<28>")
	)
	(gr_poly
		(pts
			(arc
				(start 303.452784 -277.849838)
				(mid 303.046384 -277.849838)
				(end 303.452784 -277.849838)
			)
		)
		(stroke
			(width 0)
			(type solid)
		)
		(fill yes)
		(layer "In8.Cu")
		(net "P5E_PEX2_STN1_TX_DN<28>")
	)
	(gr_poly
		(pts
			(arc
				(start 304.402998 -280.699464)
				(mid 303.996598 -280.699464)
				(end 304.402998 -280.699464)
			)
		)
		(stroke
			(width 0)
			(type solid)
		)
		(fill yes)
		(layer "In8.Cu")
		(net "P5E_PEX2_STN1_TX_DN<29>")
	)
	(gr_poly
		(pts
			(arc
				(start 304.402998 -279.749504)
				(mid 303.996598 -279.749504)
				(end 304.402998 -279.749504)
			)
		)
		(stroke
			(width 0)
			(type solid)
		)
		(fill yes)
		(layer "In8.Cu")
		(net "P5E_PEX2_STN1_TX_DP<29>")
	)
	(gr_poly
		(pts
			(arc
				(start 305.352704 -278.799798)
				(mid 304.946304 -278.799798)
				(end 305.352704 -278.799798)
			)
		)
		(stroke
			(width 0)
			(type solid)
		)
		(fill yes)
		(layer "In8.Cu")
		(net "P5E_PEX2_STN1_TX_DP<30>")
	)
	(gr_poly
		(pts
			(arc
				(start 305.352704 -277.849838)
				(mid 304.946304 -277.849838)
				(end 305.352704 -277.849838)
			)
		)
		(stroke
			(width 0)
			(type solid)
		)
		(fill yes)
		(layer "In8.Cu")
		(net "P5E_PEX2_STN1_TX_DN<30>")
	)
	(gr_poly
		(pts
			(arc
				(start 306.302918 -316.799722)
				(mid 305.896518 -316.799722)
				(end 306.302918 -316.799722)
			)
		)
		(stroke
			(width 0)
			(type solid)
		)
		(fill yes)
		(layer "In8.Cu")
		(net "P5E_PEX2_STN4_RX_DN<79>")
	)
	(gr_poly
		(pts
			(arc
				(start 306.302918 -315.849762)
				(mid 305.896518 -315.849762)
				(end 306.302918 -315.849762)
			)
		)
		(stroke
			(width 0)
			(type solid)
		)
		(fill yes)
		(layer "In8.Cu")
		(net "P5E_PEX2_STN4_RX_DP<79>")
	)
	(gr_poly
		(pts
			(arc
				(start 306.302918 -312.049922)
				(mid 305.896518 -312.049922)
				(end 306.302918 -312.049922)
			)
		)
		(stroke
			(width 0)
			(type solid)
		)
		(fill yes)
		(layer "In8.Cu")
		(net "P5E_PEX2_STN4_TX_DN<79>")
	)
	(gr_poly
		(pts
			(arc
				(start 306.302918 -311.099962)
				(mid 305.896518 -311.099962)
				(end 306.302918 -311.099962)
			)
		)
		(stroke
			(width 0)
			(type solid)
		)
		(fill yes)
		(layer "In8.Cu")
		(net "P5E_PEX2_STN4_TX_DP<79>")
	)
	(gr_poly
		(pts
			(arc
				(start 306.302918 -280.699464)
				(mid 305.896518 -280.699464)
				(end 306.302918 -280.699464)
			)
		)
		(stroke
			(width 0)
			(type solid)
		)
		(fill yes)
		(layer "In8.Cu")
		(net "P5E_PEX2_STN1_TX_DN<31>")
	)
	(gr_poly
		(pts
			(arc
				(start 306.302918 -279.749504)
				(mid 305.896518 -279.749504)
				(end 306.302918 -279.749504)
			)
		)
		(stroke
			(width 0)
			(type solid)
		)
		(fill yes)
		(layer "In8.Cu")
		(net "P5E_PEX2_STN1_TX_DP<31>")
	)
	(gr_poly
		(pts
			(arc
				(start 307.252878 -278.799798)
				(mid 306.846478 -278.799798)
				(end 307.252878 -278.799798)
			)
		)
		(stroke
			(width 0)
			(type solid)
		)
		(fill yes)
		(layer "In8.Cu")
		(net "P5E_PEX2_STN0_TX_DP<15>")
	)
	(gr_poly
		(pts
			(arc
				(start 307.252878 -277.849838)
				(mid 306.846478 -277.849838)
				(end 307.252878 -277.849838)
			)
		)
		(stroke
			(width 0)
			(type solid)
		)
		(fill yes)
		(layer "In8.Cu")
		(net "P5E_PEX2_STN0_TX_DN<15>")
	)
	(gr_poly
		(pts
			(arc
				(start 307.253132 -318.699896)
				(mid 306.846732 -318.699896)
				(end 307.253132 -318.699896)
			)
		)
		(stroke
			(width 0)
			(type solid)
		)
		(fill yes)
		(layer "In8.Cu")
		(net "P5E_PEX2_STN4_RX_DN<78>")
	)
	(gr_poly
		(pts
			(arc
				(start 307.253132 -317.749936)
				(mid 306.846732 -317.749936)
				(end 307.253132 -317.749936)
			)
		)
		(stroke
			(width 0)
			(type solid)
		)
		(fill yes)
		(layer "In8.Cu")
		(net "P5E_PEX2_STN4_RX_DP<78>")
	)
	(gr_poly
		(pts
			(arc
				(start 307.253132 -313.949842)
				(mid 306.846732 -313.949842)
				(end 307.253132 -313.949842)
			)
		)
		(stroke
			(width 0)
			(type solid)
		)
		(fill yes)
		(layer "In8.Cu")
		(net "P5E_PEX2_STN4_TX_DN<78>")
	)
	(gr_poly
		(pts
			(arc
				(start 307.253132 -312.999882)
				(mid 306.846732 -312.999882)
				(end 307.253132 -312.999882)
			)
		)
		(stroke
			(width 0)
			(type solid)
		)
		(fill yes)
		(layer "In8.Cu")
		(net "P5E_PEX2_STN4_TX_DP<78>")
	)
	(gr_poly
		(pts
			(arc
				(start 307.253132 -308.249828)
				(mid 306.846732 -308.249828)
				(end 307.253132 -308.249828)
			)
		)
		(stroke
			(width 0)
			(type solid)
		)
		(fill yes)
		(layer "In8.Cu")
		(net "P5E_PEX2_STN4_TX_DP<68>")
	)
	(gr_poly
		(pts
			(arc
				(start 307.253132 -306.349908)
				(mid 306.846732 -306.349908)
				(end 307.253132 -306.349908)
			)
		)
		(stroke
			(width 0)
			(type solid)
		)
		(fill yes)
		(layer "In8.Cu")
		(net "P5E_PEX2_STN4_TX_DP<66>")
	)
	(gr_poly
		(pts
			(arc
				(start 307.253132 -304.449734)
				(mid 306.846732 -304.449734)
				(end 307.253132 -304.449734)
			)
		)
		(stroke
			(width 0)
			(type solid)
		)
		(fill yes)
		(layer "In8.Cu")
		(net "P5E_PEX2_STN4_TX_DP<64>")
	)
	(gr_poly
		(pts
			(arc
				(start 307.253132 -287.349946)
				(mid 306.846732 -287.349946)
				(end 307.253132 -287.349946)
			)
		)
		(stroke
			(width 0)
			(type solid)
		)
		(fill yes)
		(layer "In8.Cu")
		(net "P5E_PEX2_STN0_TX_DP<1>")
	)
	(gr_poly
		(pts
			(arc
				(start 307.253132 -285.449772)
				(mid 306.846732 -285.449772)
				(end 307.253132 -285.449772)
			)
		)
		(stroke
			(width 0)
			(type solid)
		)
		(fill yes)
		(layer "In8.Cu")
		(net "P5E_PEX2_STN0_TX_DP<3>")
	)
	(gr_poly
		(pts
			(arc
				(start 307.253132 -283.549852)
				(mid 306.846732 -283.549852)
				(end 307.253132 -283.549852)
			)
		)
		(stroke
			(width 0)
			(type solid)
		)
		(fill yes)
		(layer "In8.Cu")
		(net "P5E_PEX2_STN0_TX_DP<5>")
	)
	(gr_poly
		(pts
			(arc
				(start 308.203092 -316.799722)
				(mid 307.796692 -316.799722)
				(end 308.203092 -316.799722)
			)
		)
		(stroke
			(width 0)
			(type solid)
		)
		(fill yes)
		(layer "In8.Cu")
		(net "P5E_PEX2_STN4_RX_DN<77>")
	)
	(gr_poly
		(pts
			(arc
				(start 308.203092 -315.849762)
				(mid 307.796692 -315.849762)
				(end 308.203092 -315.849762)
			)
		)
		(stroke
			(width 0)
			(type solid)
		)
		(fill yes)
		(layer "In8.Cu")
		(net "P5E_PEX2_STN4_RX_DP<77>")
	)
	(gr_poly
		(pts
			(arc
				(start 308.203092 -312.049922)
				(mid 307.796692 -312.049922)
				(end 308.203092 -312.049922)
			)
		)
		(stroke
			(width 0)
			(type solid)
		)
		(fill yes)
		(layer "In8.Cu")
		(net "P5E_PEX2_STN4_TX_DN<77>")
	)
	(gr_poly
		(pts
			(arc
				(start 308.203092 -311.099962)
				(mid 307.796692 -311.099962)
				(end 308.203092 -311.099962)
			)
		)
		(stroke
			(width 0)
			(type solid)
		)
		(fill yes)
		(layer "In8.Cu")
		(net "P5E_PEX2_STN4_TX_DP<77>")
	)
	(gr_poly
		(pts
			(arc
				(start 308.203092 -308.249828)
				(mid 307.796692 -308.249828)
				(end 308.203092 -308.249828)
			)
		)
		(stroke
			(width 0)
			(type solid)
		)
		(fill yes)
		(layer "In8.Cu")
		(net "P5E_PEX2_STN4_TX_DN<68>")
	)
	(gr_poly
		(pts
			(arc
				(start 308.203092 -306.349908)
				(mid 307.796692 -306.349908)
				(end 308.203092 -306.349908)
			)
		)
		(stroke
			(width 0)
			(type solid)
		)
		(fill yes)
		(layer "In8.Cu")
		(net "P5E_PEX2_STN4_TX_DN<66>")
	)
	(gr_poly
		(pts
			(arc
				(start 308.203092 -304.449734)
				(mid 307.796692 -304.449734)
				(end 308.203092 -304.449734)
			)
		)
		(stroke
			(width 0)
			(type solid)
		)
		(fill yes)
		(layer "In8.Cu")
		(net "P5E_PEX2_STN4_TX_DN<64>")
	)
	(gr_poly
		(pts
			(arc
				(start 308.203092 -287.349946)
				(mid 307.796692 -287.349946)
				(end 308.203092 -287.349946)
			)
		)
		(stroke
			(width 0)
			(type solid)
		)
		(fill yes)
		(layer "In8.Cu")
		(net "P5E_PEX2_STN0_TX_DN<1>")
	)
	(gr_poly
		(pts
			(arc
				(start 308.203092 -285.449772)
				(mid 307.796692 -285.449772)
				(end 308.203092 -285.449772)
			)
		)
		(stroke
			(width 0)
			(type solid)
		)
		(fill yes)
		(layer "In8.Cu")
		(net "P5E_PEX2_STN0_TX_DN<3>")
	)
	(gr_poly
		(pts
			(arc
				(start 308.203092 -283.549852)
				(mid 307.796692 -283.549852)
				(end 308.203092 -283.549852)
			)
		)
		(stroke
			(width 0)
			(type solid)
		)
		(fill yes)
		(layer "In8.Cu")
		(net "P5E_PEX2_STN0_TX_DN<5>")
	)
	(gr_poly
		(pts
			(arc
				(start 308.203092 -280.699464)
				(mid 307.796692 -280.699464)
				(end 308.203092 -280.699464)
			)
		)
		(stroke
			(width 0)
			(type solid)
		)
		(fill yes)
		(layer "In8.Cu")
		(net "P5E_PEX2_STN0_TX_DN<14>")
	)
	(gr_poly
		(pts
			(arc
				(start 308.203092 -279.749504)
				(mid 307.796692 -279.749504)
				(end 308.203092 -279.749504)
			)
		)
		(stroke
			(width 0)
			(type solid)
		)
		(fill yes)
		(layer "In8.Cu")
		(net "P5E_PEX2_STN0_TX_DP<14>")
	)
	(gr_poly
		(pts
			(arc
				(start 309.152798 -278.799798)
				(mid 308.746398 -278.799798)
				(end 309.152798 -278.799798)
			)
		)
		(stroke
			(width 0)
			(type solid)
		)
		(fill yes)
		(layer "In8.Cu")
		(net "P5E_PEX2_STN0_TX_DP<13>")
	)
	(gr_poly
		(pts
			(arc
				(start 309.152798 -277.849838)
				(mid 308.746398 -277.849838)
				(end 309.152798 -277.849838)
			)
		)
		(stroke
			(width 0)
			(type solid)
		)
		(fill yes)
		(layer "In8.Cu")
		(net "P5E_PEX2_STN0_TX_DN<13>")
	)
	(gr_poly
		(pts
			(arc
				(start 309.153052 -318.699896)
				(mid 308.746652 -318.699896)
				(end 309.153052 -318.699896)
			)
		)
		(stroke
			(width 0)
			(type solid)
		)
		(fill yes)
		(layer "In8.Cu")
		(net "P5E_PEX2_STN4_RX_DN<76>")
	)
	(gr_poly
		(pts
			(arc
				(start 309.153052 -317.749936)
				(mid 308.746652 -317.749936)
				(end 309.153052 -317.749936)
			)
		)
		(stroke
			(width 0)
			(type solid)
		)
		(fill yes)
		(layer "In8.Cu")
		(net "P5E_PEX2_STN4_RX_DP<76>")
	)
	(gr_poly
		(pts
			(arc
				(start 309.153052 -313.949842)
				(mid 308.746652 -313.949842)
				(end 309.153052 -313.949842)
			)
		)
		(stroke
			(width 0)
			(type solid)
		)
		(fill yes)
		(layer "In8.Cu")
		(net "P5E_PEX2_STN4_TX_DN<76>")
	)
	(gr_poly
		(pts
			(arc
				(start 309.153052 -312.999882)
				(mid 308.746652 -312.999882)
				(end 309.153052 -312.999882)
			)
		)
		(stroke
			(width 0)
			(type solid)
		)
		(fill yes)
		(layer "In8.Cu")
		(net "P5E_PEX2_STN4_TX_DP<76>")
	)
	(gr_poly
		(pts
			(arc
				(start 309.153052 -309.199788)
				(mid 308.746652 -309.199788)
				(end 309.153052 -309.199788)
			)
		)
		(stroke
			(width 0)
			(type solid)
		)
		(fill yes)
		(layer "In8.Cu")
		(net "P5E_PEX2_STN4_TX_DP<69>")
	)
	(gr_poly
		(pts
			(arc
				(start 309.153052 -307.299868)
				(mid 308.746652 -307.299868)
				(end 309.153052 -307.299868)
			)
		)
		(stroke
			(width 0)
			(type solid)
		)
		(fill yes)
		(layer "In8.Cu")
		(net "P5E_PEX2_STN4_TX_DP<67>")
	)
	(gr_poly
		(pts
			(arc
				(start 309.153052 -305.399948)
				(mid 308.746652 -305.399948)
				(end 309.153052 -305.399948)
			)
		)
		(stroke
			(width 0)
			(type solid)
		)
		(fill yes)
		(layer "In8.Cu")
		(net "P5E_PEX2_STN4_TX_DP<65>")
	)
	(gr_poly
		(pts
			(arc
				(start 309.153052 -288.299906)
				(mid 308.746652 -288.299906)
				(end 309.153052 -288.299906)
			)
		)
		(stroke
			(width 0)
			(type solid)
		)
		(fill yes)
		(layer "In8.Cu")
		(net "P5E_PEX2_STN0_TX_DP<0>")
	)
	(gr_poly
		(pts
			(arc
				(start 309.153052 -286.399986)
				(mid 308.746652 -286.399986)
				(end 309.153052 -286.399986)
			)
		)
		(stroke
			(width 0)
			(type solid)
		)
		(fill yes)
		(layer "In8.Cu")
		(net "P5E_PEX2_STN0_TX_DP<2>")
	)
	(gr_poly
		(pts
			(arc
				(start 309.153052 -284.499812)
				(mid 308.746652 -284.499812)
				(end 309.153052 -284.499812)
			)
		)
		(stroke
			(width 0)
			(type solid)
		)
		(fill yes)
		(layer "In8.Cu")
		(net "P5E_PEX2_STN0_TX_DP<4>")
	)
	(gr_poly
		(pts
			(arc
				(start 309.153052 -282.599892)
				(mid 308.746652 -282.599892)
				(end 309.153052 -282.599892)
			)
		)
		(stroke
			(width 0)
			(type solid)
		)
		(fill yes)
		(layer "In8.Cu")
		(net "P5E_PEX2_STN0_TX_DP<6>")
	)
	(gr_poly
		(pts
			(arc
				(start 310.103012 -316.799722)
				(mid 309.696612 -316.799722)
				(end 310.103012 -316.799722)
			)
		)
		(stroke
			(width 0)
			(type solid)
		)
		(fill yes)
		(layer "In8.Cu")
		(net "P5E_PEX2_STN4_RX_DN<75>")
	)
	(gr_poly
		(pts
			(arc
				(start 310.103012 -315.849762)
				(mid 309.696612 -315.849762)
				(end 310.103012 -315.849762)
			)
		)
		(stroke
			(width 0)
			(type solid)
		)
		(fill yes)
		(layer "In8.Cu")
		(net "P5E_PEX2_STN4_RX_DP<75>")
	)
	(gr_poly
		(pts
			(arc
				(start 310.103012 -312.049922)
				(mid 309.696612 -312.049922)
				(end 310.103012 -312.049922)
			)
		)
		(stroke
			(width 0)
			(type solid)
		)
		(fill yes)
		(layer "In8.Cu")
		(net "P5E_PEX2_STN4_TX_DN<75>")
	)
	(gr_poly
		(pts
			(arc
				(start 310.103012 -311.099962)
				(mid 309.696612 -311.099962)
				(end 310.103012 -311.099962)
			)
		)
		(stroke
			(width 0)
			(type solid)
		)
		(fill yes)
		(layer "In8.Cu")
		(net "P5E_PEX2_STN4_TX_DP<75>")
	)
	(gr_poly
		(pts
			(arc
				(start 310.103012 -309.199788)
				(mid 309.696612 -309.199788)
				(end 310.103012 -309.199788)
			)
		)
		(stroke
			(width 0)
			(type solid)
		)
		(fill yes)
		(layer "In8.Cu")
		(net "P5E_PEX2_STN4_TX_DN<69>")
	)
	(gr_poly
		(pts
			(arc
				(start 310.103012 -307.299868)
				(mid 309.696612 -307.299868)
				(end 310.103012 -307.299868)
			)
		)
		(stroke
			(width 0)
			(type solid)
		)
		(fill yes)
		(layer "In8.Cu")
		(net "P5E_PEX2_STN4_TX_DN<67>")
	)
	(gr_poly
		(pts
			(arc
				(start 310.103012 -305.399948)
				(mid 309.696612 -305.399948)
				(end 310.103012 -305.399948)
			)
		)
		(stroke
			(width 0)
			(type solid)
		)
		(fill yes)
		(layer "In8.Cu")
		(net "P5E_PEX2_STN4_TX_DN<65>")
	)
	(gr_poly
		(pts
			(arc
				(start 310.103012 -288.299906)
				(mid 309.696612 -288.299906)
				(end 310.103012 -288.299906)
			)
		)
		(stroke
			(width 0)
			(type solid)
		)
		(fill yes)
		(layer "In8.Cu")
		(net "P5E_PEX2_STN0_TX_DN<0>")
	)
	(gr_poly
		(pts
			(arc
				(start 310.103012 -286.399986)
				(mid 309.696612 -286.399986)
				(end 310.103012 -286.399986)
			)
		)
		(stroke
			(width 0)
			(type solid)
		)
		(fill yes)
		(layer "In8.Cu")
		(net "P5E_PEX2_STN0_TX_DN<2>")
	)
	(gr_poly
		(pts
			(arc
				(start 310.103012 -284.499812)
				(mid 309.696612 -284.499812)
				(end 310.103012 -284.499812)
			)
		)
		(stroke
			(width 0)
			(type solid)
		)
		(fill yes)
		(layer "In8.Cu")
		(net "P5E_PEX2_STN0_TX_DN<4>")
	)
	(gr_poly
		(pts
			(arc
				(start 310.103012 -282.599892)
				(mid 309.696612 -282.599892)
				(end 310.103012 -282.599892)
			)
		)
		(stroke
			(width 0)
			(type solid)
		)
		(fill yes)
		(layer "In8.Cu")
		(net "P5E_PEX2_STN0_TX_DN<6>")
	)
	(gr_poly
		(pts
			(arc
				(start 310.103012 -280.699464)
				(mid 309.696612 -280.699464)
				(end 310.103012 -280.699464)
			)
		)
		(stroke
			(width 0)
			(type solid)
		)
		(fill yes)
		(layer "In8.Cu")
		(net "P5E_PEX2_STN0_TX_DN<12>")
	)
	(gr_poly
		(pts
			(arc
				(start 310.103012 -279.749504)
				(mid 309.696612 -279.749504)
				(end 310.103012 -279.749504)
			)
		)
		(stroke
			(width 0)
			(type solid)
		)
		(fill yes)
		(layer "In8.Cu")
		(net "P5E_PEX2_STN0_TX_DP<12>")
	)
	(gr_poly
		(pts
			(arc
				(start 311.052718 -278.799798)
				(mid 310.646318 -278.799798)
				(end 311.052718 -278.799798)
			)
		)
		(stroke
			(width 0)
			(type solid)
		)
		(fill yes)
		(layer "In8.Cu")
		(net "P5E_PEX2_STN0_TX_DP<11>")
	)
	(gr_poly
		(pts
			(arc
				(start 311.052718 -277.849838)
				(mid 310.646318 -277.849838)
				(end 311.052718 -277.849838)
			)
		)
		(stroke
			(width 0)
			(type solid)
		)
		(fill yes)
		(layer "In8.Cu")
		(net "P5E_PEX2_STN0_TX_DN<11>")
	)
	(gr_poly
		(pts
			(arc
				(start 311.052972 -318.699896)
				(mid 310.646572 -318.699896)
				(end 311.052972 -318.699896)
			)
		)
		(stroke
			(width 0)
			(type solid)
		)
		(fill yes)
		(layer "In8.Cu")
		(net "P5E_PEX2_STN4_RX_DN<74>")
	)
	(gr_poly
		(pts
			(arc
				(start 311.052972 -317.749936)
				(mid 310.646572 -317.749936)
				(end 311.052972 -317.749936)
			)
		)
		(stroke
			(width 0)
			(type solid)
		)
		(fill yes)
		(layer "In8.Cu")
		(net "P5E_PEX2_STN4_RX_DP<74>")
	)
	(gr_poly
		(pts
			(arc
				(start 311.052972 -313.949842)
				(mid 310.646572 -313.949842)
				(end 311.052972 -313.949842)
			)
		)
		(stroke
			(width 0)
			(type solid)
		)
		(fill yes)
		(layer "In8.Cu")
		(net "P5E_PEX2_STN4_TX_DN<74>")
	)
	(gr_poly
		(pts
			(arc
				(start 311.052972 -312.999882)
				(mid 310.646572 -312.999882)
				(end 311.052972 -312.999882)
			)
		)
		(stroke
			(width 0)
			(type solid)
		)
		(fill yes)
		(layer "In8.Cu")
		(net "P5E_PEX2_STN4_TX_DP<74>")
	)
	(gr_poly
		(pts
			(arc
				(start 312.002932 -316.799722)
				(mid 311.596532 -316.799722)
				(end 312.002932 -316.799722)
			)
		)
		(stroke
			(width 0)
			(type solid)
		)
		(fill yes)
		(layer "In8.Cu")
		(net "P5E_PEX2_STN4_RX_DN<73>")
	)
	(gr_poly
		(pts
			(arc
				(start 312.002932 -315.849762)
				(mid 311.596532 -315.849762)
				(end 312.002932 -315.849762)
			)
		)
		(stroke
			(width 0)
			(type solid)
		)
		(fill yes)
		(layer "In8.Cu")
		(net "P5E_PEX2_STN4_RX_DP<73>")
	)
	(gr_poly
		(pts
			(arc
				(start 312.002932 -312.049922)
				(mid 311.596532 -312.049922)
				(end 312.002932 -312.049922)
			)
		)
		(stroke
			(width 0)
			(type solid)
		)
		(fill yes)
		(layer "In8.Cu")
		(net "P5E_PEX2_STN4_TX_DN<73>")
	)
	(gr_poly
		(pts
			(arc
				(start 312.002932 -311.099962)
				(mid 311.596532 -311.099962)
				(end 312.002932 -311.099962)
			)
		)
		(stroke
			(width 0)
			(type solid)
		)
		(fill yes)
		(layer "In8.Cu")
		(net "P5E_PEX2_STN4_TX_DP<73>")
	)
	(gr_poly
		(pts
			(arc
				(start 312.002932 -309.199788)
				(mid 311.596532 -309.199788)
				(end 312.002932 -309.199788)
			)
		)
		(stroke
			(width 0)
			(type solid)
		)
		(fill yes)
		(layer "In8.Cu")
		(net "P5E_PEX2_STN4_RX_DP<69>")
	)
	(gr_poly
		(pts
			(arc
				(start 312.002932 -307.299868)
				(mid 311.596532 -307.299868)
				(end 312.002932 -307.299868)
			)
		)
		(stroke
			(width 0)
			(type solid)
		)
		(fill yes)
		(layer "In8.Cu")
		(net "P5E_PEX2_STN4_RX_DP<67>")
	)
	(gr_poly
		(pts
			(arc
				(start 312.002932 -305.399948)
				(mid 311.596532 -305.399948)
				(end 312.002932 -305.399948)
			)
		)
		(stroke
			(width 0)
			(type solid)
		)
		(fill yes)
		(layer "In8.Cu")
		(net "P5E_PEX2_STN4_RX_DP<65>")
	)
	(gr_poly
		(pts
			(arc
				(start 312.002932 -280.699718)
				(mid 311.596532 -280.699718)
				(end 312.002932 -280.699718)
			)
		)
		(stroke
			(width 0)
			(type solid)
		)
		(fill yes)
		(layer "In8.Cu")
		(net "P5E_PEX2_STN0_TX_DP<10>")
	)
	(gr_poly
		(pts
			(arc
				(start 312.002932 -279.749758)
				(mid 311.596532 -279.749758)
				(end 312.002932 -279.749758)
			)
		)
		(stroke
			(width 0)
			(type solid)
		)
		(fill yes)
		(layer "In8.Cu")
		(net "P5E_PEX2_STN0_TX_DN<10>")
	)
	(gr_poly
		(pts
			(arc
				(start 312.952892 -318.699896)
				(mid 312.546492 -318.699896)
				(end 312.952892 -318.699896)
			)
		)
		(stroke
			(width 0)
			(type solid)
		)
		(fill yes)
		(layer "In8.Cu")
		(net "P5E_PEX2_STN4_RX_DN<72>")
	)
	(gr_poly
		(pts
			(arc
				(start 312.952892 -317.749936)
				(mid 312.546492 -317.749936)
				(end 312.952892 -317.749936)
			)
		)
		(stroke
			(width 0)
			(type solid)
		)
		(fill yes)
		(layer "In8.Cu")
		(net "P5E_PEX2_STN4_RX_DP<72>")
	)
	(gr_poly
		(pts
			(arc
				(start 312.952892 -313.949842)
				(mid 312.546492 -313.949842)
				(end 312.952892 -313.949842)
			)
		)
		(stroke
			(width 0)
			(type solid)
		)
		(fill yes)
		(layer "In8.Cu")
		(net "P5E_PEX2_STN4_TX_DN<72>")
	)
	(gr_poly
		(pts
			(arc
				(start 312.952892 -312.999882)
				(mid 312.546492 -312.999882)
				(end 312.952892 -312.999882)
			)
		)
		(stroke
			(width 0)
			(type solid)
		)
		(fill yes)
		(layer "In8.Cu")
		(net "P5E_PEX2_STN4_TX_DP<72>")
	)
	(gr_poly
		(pts
			(arc
				(start 312.952892 -309.199788)
				(mid 312.546492 -309.199788)
				(end 312.952892 -309.199788)
			)
		)
		(stroke
			(width 0)
			(type solid)
		)
		(fill yes)
		(layer "In8.Cu")
		(net "P5E_PEX2_STN4_RX_DN<69>")
	)
	(gr_poly
		(pts
			(arc
				(start 312.952892 -307.299868)
				(mid 312.546492 -307.299868)
				(end 312.952892 -307.299868)
			)
		)
		(stroke
			(width 0)
			(type solid)
		)
		(fill yes)
		(layer "In8.Cu")
		(net "P5E_PEX2_STN4_RX_DN<67>")
	)
	(gr_poly
		(pts
			(arc
				(start 312.952892 -305.399948)
				(mid 312.546492 -305.399948)
				(end 312.952892 -305.399948)
			)
		)
		(stroke
			(width 0)
			(type solid)
		)
		(fill yes)
		(layer "In8.Cu")
		(net "P5E_PEX2_STN4_RX_DN<65>")
	)
	(gr_poly
		(pts
			(arc
				(start 312.952892 -278.799798)
				(mid 312.546492 -278.799798)
				(end 312.952892 -278.799798)
			)
		)
		(stroke
			(width 0)
			(type solid)
		)
		(fill yes)
		(layer "In8.Cu")
		(net "P5E_PEX2_STN0_TX_DP<9>")
	)
	(gr_poly
		(pts
			(arc
				(start 312.952892 -277.849838)
				(mid 312.546492 -277.849838)
				(end 312.952892 -277.849838)
			)
		)
		(stroke
			(width 0)
			(type solid)
		)
		(fill yes)
		(layer "In8.Cu")
		(net "P5E_PEX2_STN0_TX_DN<9>")
	)
	(gr_poly
		(pts
			(arc
				(start 313.903106 -316.799722)
				(mid 313.496706 -316.799722)
				(end 313.903106 -316.799722)
			)
		)
		(stroke
			(width 0)
			(type solid)
		)
		(fill yes)
		(layer "In8.Cu")
		(net "P5E_PEX2_STN4_RX_DP<71>")
	)
	(gr_poly
		(pts
			(arc
				(start 313.903106 -314.899802)
				(mid 313.496706 -314.899802)
				(end 313.903106 -314.899802)
			)
		)
		(stroke
			(width 0)
			(type solid)
		)
		(fill yes)
		(layer "In8.Cu")
		(net "P5E_PEX2_STN4_TX_DP<71>")
	)
	(gr_poly
		(pts
			(arc
				(start 313.903106 -312.049922)
				(mid 313.496706 -312.049922)
				(end 313.903106 -312.049922)
			)
		)
		(stroke
			(width 0)
			(type solid)
		)
		(fill yes)
		(layer "In8.Cu")
		(net "P5E_PEX2_STN4_TX_DP<70>")
	)
	(gr_poly
		(pts
			(arc
				(start 313.903106 -310.149748)
				(mid 313.496706 -310.149748)
				(end 313.903106 -310.149748)
			)
		)
		(stroke
			(width 0)
			(type solid)
		)
		(fill yes)
		(layer "In8.Cu")
		(net "P5E_PEX2_STN4_RX_DP<70>")
	)
	(gr_poly
		(pts
			(arc
				(start 313.903106 -308.249828)
				(mid 313.496706 -308.249828)
				(end 313.903106 -308.249828)
			)
		)
		(stroke
			(width 0)
			(type solid)
		)
		(fill yes)
		(layer "In8.Cu")
		(net "P5E_PEX2_STN4_RX_DP<68>")
	)
	(gr_poly
		(pts
			(arc
				(start 313.903106 -306.349908)
				(mid 313.496706 -306.349908)
				(end 313.903106 -306.349908)
			)
		)
		(stroke
			(width 0)
			(type solid)
		)
		(fill yes)
		(layer "In8.Cu")
		(net "P5E_PEX2_STN4_RX_DP<66>")
	)
	(gr_poly
		(pts
			(arc
				(start 313.903106 -304.449734)
				(mid 313.496706 -304.449734)
				(end 313.903106 -304.449734)
			)
		)
		(stroke
			(width 0)
			(type solid)
		)
		(fill yes)
		(layer "In8.Cu")
		(net "P5E_PEX2_STN4_RX_DP<64>")
	)
	(gr_poly
		(pts
			(arc
				(start 313.903106 -279.749758)
				(mid 313.496706 -279.749758)
				(end 313.903106 -279.749758)
			)
		)
		(stroke
			(width 0)
			(type solid)
		)
		(fill yes)
		(layer "In8.Cu")
		(net "P5E_PEX2_STN0_TX_DP<7>")
	)
	(gr_poly
		(pts
			(arc
				(start 313.903106 -276.899878)
				(mid 313.496706 -276.899878)
				(end 313.903106 -276.899878)
			)
		)
		(stroke
			(width 0)
			(type solid)
		)
		(fill yes)
		(layer "In8.Cu")
		(net "P5E_PEX2_STN0_TX_DP<8>")
	)
	(gr_poly
		(pts
			(arc
				(start 314.853066 -316.799722)
				(mid 314.446666 -316.799722)
				(end 314.853066 -316.799722)
			)
		)
		(stroke
			(width 0)
			(type solid)
		)
		(fill yes)
		(layer "In8.Cu")
		(net "P5E_PEX2_STN4_RX_DN<71>")
	)
	(gr_poly
		(pts
			(arc
				(start 314.853066 -314.899802)
				(mid 314.446666 -314.899802)
				(end 314.853066 -314.899802)
			)
		)
		(stroke
			(width 0)
			(type solid)
		)
		(fill yes)
		(layer "In8.Cu")
		(net "P5E_PEX2_STN4_TX_DN<71>")
	)
	(gr_poly
		(pts
			(arc
				(start 314.853066 -312.049922)
				(mid 314.446666 -312.049922)
				(end 314.853066 -312.049922)
			)
		)
		(stroke
			(width 0)
			(type solid)
		)
		(fill yes)
		(layer "In8.Cu")
		(net "P5E_PEX2_STN4_TX_DN<70>")
	)
	(gr_poly
		(pts
			(arc
				(start 314.853066 -310.149748)
				(mid 314.446666 -310.149748)
				(end 314.853066 -310.149748)
			)
		)
		(stroke
			(width 0)
			(type solid)
		)
		(fill yes)
		(layer "In8.Cu")
		(net "P5E_PEX2_STN4_RX_DN<70>")
	)
	(gr_poly
		(pts
			(arc
				(start 314.853066 -308.249828)
				(mid 314.446666 -308.249828)
				(end 314.853066 -308.249828)
			)
		)
		(stroke
			(width 0)
			(type solid)
		)
		(fill yes)
		(layer "In8.Cu")
		(net "P5E_PEX2_STN4_RX_DN<68>")
	)
	(gr_poly
		(pts
			(arc
				(start 314.853066 -306.349908)
				(mid 314.446666 -306.349908)
				(end 314.853066 -306.349908)
			)
		)
		(stroke
			(width 0)
			(type solid)
		)
		(fill yes)
		(layer "In8.Cu")
		(net "P5E_PEX2_STN4_RX_DN<66>")
	)
	(gr_poly
		(pts
			(arc
				(start 314.853066 -304.449734)
				(mid 314.446666 -304.449734)
				(end 314.853066 -304.449734)
			)
		)
		(stroke
			(width 0)
			(type solid)
		)
		(fill yes)
		(layer "In8.Cu")
		(net "P5E_PEX2_STN4_RX_DN<64>")
	)
	(gr_poly
		(pts
			(arc
				(start 314.853066 -279.749758)
				(mid 314.446666 -279.749758)
				(end 314.853066 -279.749758)
			)
		)
		(stroke
			(width 0)
			(type solid)
		)
		(fill yes)
		(layer "In8.Cu")
		(net "P5E_PEX2_STN0_TX_DN<7>")
	)
	(gr_poly
		(pts
			(arc
				(start 314.853066 -276.899878)
				(mid 314.446666 -276.899878)
				(end 314.853066 -276.899878)
			)
		)
		(stroke
			(width 0)
			(type solid)
		)
		(fill yes)
		(layer "In8.Cu")
		(net "P5E_PEX2_STN0_TX_DN<8>")
	)
	(gr_poly
		(pts
			(arc
				(start 385.353052 -316.799722)
				(mid 384.946652 -316.799722)
				(end 385.353052 -316.799722)
			)
		)
		(stroke
			(width 0)
			(type solid)
		)
		(fill yes)
		(layer "In8.Cu")
		(net "P5E_PEX3_STN7_RX_DN<122>")
	)
	(gr_poly
		(pts
			(arc
				(start 385.353052 -314.899802)
				(mid 384.946652 -314.899802)
				(end 385.353052 -314.899802)
			)
		)
		(stroke
			(width 0)
			(type solid)
		)
		(fill yes)
		(layer "In8.Cu")
		(net "P5E_PEX3_STN7_TX_DN<122>")
	)
	(gr_poly
		(pts
			(arc
				(start 385.353052 -312.049922)
				(mid 384.946652 -312.049922)
				(end 385.353052 -312.049922)
			)
		)
		(stroke
			(width 0)
			(type solid)
		)
		(fill yes)
		(layer "In8.Cu")
		(net "P5E_PEX3_STN7_TX_DN<121>")
	)
	(gr_poly
		(pts
			(arc
				(start 385.353052 -310.149748)
				(mid 384.946652 -310.149748)
				(end 385.353052 -310.149748)
			)
		)
		(stroke
			(width 0)
			(type solid)
		)
		(fill yes)
		(layer "In8.Cu")
		(net "P5E_PEX3_STN7_RX_DN<121>")
	)
	(gr_poly
		(pts
			(arc
				(start 385.353052 -308.249828)
				(mid 384.946652 -308.249828)
				(end 385.353052 -308.249828)
			)
		)
		(stroke
			(width 0)
			(type solid)
		)
		(fill yes)
		(layer "In8.Cu")
		(net "P5E_PEX3_STN7_RX_DN<119>")
	)
	(gr_poly
		(pts
			(arc
				(start 385.353052 -306.349908)
				(mid 384.946652 -306.349908)
				(end 385.353052 -306.349908)
			)
		)
		(stroke
			(width 0)
			(type solid)
		)
		(fill yes)
		(layer "In8.Cu")
		(net "P5E_PEX3_STN7_RX_DN<117>")
	)
	(gr_poly
		(pts
			(arc
				(start 385.353052 -304.449734)
				(mid 384.946652 -304.449734)
				(end 385.353052 -304.449734)
			)
		)
		(stroke
			(width 0)
			(type solid)
		)
		(fill yes)
		(layer "In8.Cu")
		(net "P5E_PEX3_STN7_RX_DN<115>")
	)
	(gr_poly
		(pts
			(arc
				(start 385.353052 -302.549814)
				(mid 384.946652 -302.549814)
				(end 385.353052 -302.549814)
			)
		)
		(stroke
			(width 0)
			(type solid)
		)
		(fill yes)
		(layer "In8.Cu")
		(net "P5E_PEX3_STN7_RX_DN<113>")
	)
	(gr_poly
		(pts
			(arc
				(start 386.303012 -316.799722)
				(mid 385.896612 -316.799722)
				(end 386.303012 -316.799722)
			)
		)
		(stroke
			(width 0)
			(type solid)
		)
		(fill yes)
		(layer "In8.Cu")
		(net "P5E_PEX3_STN7_RX_DP<122>")
	)
	(gr_poly
		(pts
			(arc
				(start 386.303012 -314.899802)
				(mid 385.896612 -314.899802)
				(end 386.303012 -314.899802)
			)
		)
		(stroke
			(width 0)
			(type solid)
		)
		(fill yes)
		(layer "In8.Cu")
		(net "P5E_PEX3_STN7_TX_DP<122>")
	)
	(gr_poly
		(pts
			(arc
				(start 386.303012 -312.049922)
				(mid 385.896612 -312.049922)
				(end 386.303012 -312.049922)
			)
		)
		(stroke
			(width 0)
			(type solid)
		)
		(fill yes)
		(layer "In8.Cu")
		(net "P5E_PEX3_STN7_TX_DP<121>")
	)
	(gr_poly
		(pts
			(arc
				(start 386.303012 -310.149748)
				(mid 385.896612 -310.149748)
				(end 386.303012 -310.149748)
			)
		)
		(stroke
			(width 0)
			(type solid)
		)
		(fill yes)
		(layer "In8.Cu")
		(net "P5E_PEX3_STN7_RX_DP<121>")
	)
	(gr_poly
		(pts
			(arc
				(start 386.303012 -308.249828)
				(mid 385.896612 -308.249828)
				(end 386.303012 -308.249828)
			)
		)
		(stroke
			(width 0)
			(type solid)
		)
		(fill yes)
		(layer "In8.Cu")
		(net "P5E_PEX3_STN7_RX_DP<119>")
	)
	(gr_poly
		(pts
			(arc
				(start 386.303012 -306.349908)
				(mid 385.896612 -306.349908)
				(end 386.303012 -306.349908)
			)
		)
		(stroke
			(width 0)
			(type solid)
		)
		(fill yes)
		(layer "In8.Cu")
		(net "P5E_PEX3_STN7_RX_DP<117>")
	)
	(gr_poly
		(pts
			(arc
				(start 386.303012 -304.449734)
				(mid 385.896612 -304.449734)
				(end 386.303012 -304.449734)
			)
		)
		(stroke
			(width 0)
			(type solid)
		)
		(fill yes)
		(layer "In8.Cu")
		(net "P5E_PEX3_STN7_RX_DP<115>")
	)
	(gr_poly
		(pts
			(arc
				(start 386.303012 -302.549814)
				(mid 385.896612 -302.549814)
				(end 386.303012 -302.549814)
			)
		)
		(stroke
			(width 0)
			(type solid)
		)
		(fill yes)
		(layer "In8.Cu")
		(net "P5E_PEX3_STN7_RX_DP<113>")
	)
	(gr_poly
		(pts
			(arc
				(start 387.253226 -318.699896)
				(mid 386.846826 -318.699896)
				(end 387.253226 -318.699896)
			)
		)
		(stroke
			(width 0)
			(type solid)
		)
		(fill yes)
		(layer "In8.Cu")
		(net "P5E_PEX3_STN7_RX_DN<123>")
	)
	(gr_poly
		(pts
			(arc
				(start 387.253226 -317.749936)
				(mid 386.846826 -317.749936)
				(end 387.253226 -317.749936)
			)
		)
		(stroke
			(width 0)
			(type solid)
		)
		(fill yes)
		(layer "In8.Cu")
		(net "P5E_PEX3_STN7_RX_DP<123>")
	)
	(gr_poly
		(pts
			(arc
				(start 387.253226 -313.949842)
				(mid 386.846826 -313.949842)
				(end 387.253226 -313.949842)
			)
		)
		(stroke
			(width 0)
			(type solid)
		)
		(fill yes)
		(layer "In8.Cu")
		(net "P5E_PEX3_STN7_TX_DN<123>")
	)
	(gr_poly
		(pts
			(arc
				(start 387.253226 -312.999882)
				(mid 386.846826 -312.999882)
				(end 387.253226 -312.999882)
			)
		)
		(stroke
			(width 0)
			(type solid)
		)
		(fill yes)
		(layer "In8.Cu")
		(net "P5E_PEX3_STN7_TX_DP<123>")
	)
	(gr_poly
		(pts
			(arc
				(start 387.253226 -309.199788)
				(mid 386.846826 -309.199788)
				(end 387.253226 -309.199788)
			)
		)
		(stroke
			(width 0)
			(type solid)
		)
		(fill yes)
		(layer "In8.Cu")
		(net "P5E_PEX3_STN7_RX_DN<120>")
	)
	(gr_poly
		(pts
			(arc
				(start 387.253226 -307.299868)
				(mid 386.846826 -307.299868)
				(end 387.253226 -307.299868)
			)
		)
		(stroke
			(width 0)
			(type solid)
		)
		(fill yes)
		(layer "In8.Cu")
		(net "P5E_PEX3_STN7_RX_DN<118>")
	)
	(gr_poly
		(pts
			(arc
				(start 387.253226 -305.399948)
				(mid 386.846826 -305.399948)
				(end 387.253226 -305.399948)
			)
		)
		(stroke
			(width 0)
			(type solid)
		)
		(fill yes)
		(layer "In8.Cu")
		(net "P5E_PEX3_STN7_RX_DN<116>")
	)
	(gr_poly
		(pts
			(arc
				(start 387.253226 -303.499774)
				(mid 386.846826 -303.499774)
				(end 387.253226 -303.499774)
			)
		)
		(stroke
			(width 0)
			(type solid)
		)
		(fill yes)
		(layer "In8.Cu")
		(net "P5E_PEX3_STN7_RX_DN<114>")
	)
	(gr_poly
		(pts
			(arc
				(start 387.253226 -301.599854)
				(mid 386.846826 -301.599854)
				(end 387.253226 -301.599854)
			)
		)
		(stroke
			(width 0)
			(type solid)
		)
		(fill yes)
		(layer "In8.Cu")
		(net "P5E_PEX3_STN7_RX_DN<112>")
	)
	(gr_poly
		(pts
			(arc
				(start 388.203186 -316.799722)
				(mid 387.796786 -316.799722)
				(end 388.203186 -316.799722)
			)
		)
		(stroke
			(width 0)
			(type solid)
		)
		(fill yes)
		(layer "In8.Cu")
		(net "P5E_PEX3_STN7_RX_DN<124>")
	)
	(gr_poly
		(pts
			(arc
				(start 388.203186 -315.849762)
				(mid 387.796786 -315.849762)
				(end 388.203186 -315.849762)
			)
		)
		(stroke
			(width 0)
			(type solid)
		)
		(fill yes)
		(layer "In8.Cu")
		(net "P5E_PEX3_STN7_RX_DP<124>")
	)
	(gr_poly
		(pts
			(arc
				(start 388.203186 -312.049922)
				(mid 387.796786 -312.049922)
				(end 388.203186 -312.049922)
			)
		)
		(stroke
			(width 0)
			(type solid)
		)
		(fill yes)
		(layer "In8.Cu")
		(net "P5E_PEX3_STN7_TX_DN<124>")
	)
	(gr_poly
		(pts
			(arc
				(start 388.203186 -311.099962)
				(mid 387.796786 -311.099962)
				(end 388.203186 -311.099962)
			)
		)
		(stroke
			(width 0)
			(type solid)
		)
		(fill yes)
		(layer "In8.Cu")
		(net "P5E_PEX3_STN7_TX_DP<124>")
	)
	(gr_poly
		(pts
			(arc
				(start 388.203186 -309.199788)
				(mid 387.796786 -309.199788)
				(end 388.203186 -309.199788)
			)
		)
		(stroke
			(width 0)
			(type solid)
		)
		(fill yes)
		(layer "In8.Cu")
		(net "P5E_PEX3_STN7_RX_DP<120>")
	)
	(gr_poly
		(pts
			(arc
				(start 388.203186 -307.299868)
				(mid 387.796786 -307.299868)
				(end 388.203186 -307.299868)
			)
		)
		(stroke
			(width 0)
			(type solid)
		)
		(fill yes)
		(layer "In8.Cu")
		(net "P5E_PEX3_STN7_RX_DP<118>")
	)
	(gr_poly
		(pts
			(arc
				(start 388.203186 -305.399948)
				(mid 387.796786 -305.399948)
				(end 388.203186 -305.399948)
			)
		)
		(stroke
			(width 0)
			(type solid)
		)
		(fill yes)
		(layer "In8.Cu")
		(net "P5E_PEX3_STN7_RX_DP<116>")
	)
	(gr_poly
		(pts
			(arc
				(start 388.203186 -303.499774)
				(mid 387.796786 -303.499774)
				(end 388.203186 -303.499774)
			)
		)
		(stroke
			(width 0)
			(type solid)
		)
		(fill yes)
		(layer "In8.Cu")
		(net "P5E_PEX3_STN7_RX_DP<114>")
	)
	(gr_poly
		(pts
			(arc
				(start 388.203186 -301.599854)
				(mid 387.796786 -301.599854)
				(end 388.203186 -301.599854)
			)
		)
		(stroke
			(width 0)
			(type solid)
		)
		(fill yes)
		(layer "In8.Cu")
		(net "P5E_PEX3_STN7_RX_DP<112>")
	)
	(gr_poly
		(pts
			(arc
				(start 389.153146 -318.699896)
				(mid 388.746746 -318.699896)
				(end 389.153146 -318.699896)
			)
		)
		(stroke
			(width 0)
			(type solid)
		)
		(fill yes)
		(layer "In8.Cu")
		(net "P5E_PEX3_STN7_RX_DN<125>")
	)
	(gr_poly
		(pts
			(arc
				(start 389.153146 -317.749936)
				(mid 388.746746 -317.749936)
				(end 389.153146 -317.749936)
			)
		)
		(stroke
			(width 0)
			(type solid)
		)
		(fill yes)
		(layer "In8.Cu")
		(net "P5E_PEX3_STN7_RX_DP<125>")
	)
	(gr_poly
		(pts
			(arc
				(start 389.153146 -313.949842)
				(mid 388.746746 -313.949842)
				(end 389.153146 -313.949842)
			)
		)
		(stroke
			(width 0)
			(type solid)
		)
		(fill yes)
		(layer "In8.Cu")
		(net "P5E_PEX3_STN7_TX_DN<125>")
	)
	(gr_poly
		(pts
			(arc
				(start 389.153146 -312.999882)
				(mid 388.746746 -312.999882)
				(end 389.153146 -312.999882)
			)
		)
		(stroke
			(width 0)
			(type solid)
		)
		(fill yes)
		(layer "In8.Cu")
		(net "P5E_PEX3_STN7_TX_DP<125>")
	)
	(gr_poly
		(pts
			(arc
				(start 390.103106 -316.799722)
				(mid 389.696706 -316.799722)
				(end 390.103106 -316.799722)
			)
		)
		(stroke
			(width 0)
			(type solid)
		)
		(fill yes)
		(layer "In8.Cu")
		(net "P5E_PEX3_STN7_RX_DN<126>")
	)
	(gr_poly
		(pts
			(arc
				(start 390.103106 -315.849762)
				(mid 389.696706 -315.849762)
				(end 390.103106 -315.849762)
			)
		)
		(stroke
			(width 0)
			(type solid)
		)
		(fill yes)
		(layer "In8.Cu")
		(net "P5E_PEX3_STN7_RX_DP<126>")
	)
	(gr_poly
		(pts
			(arc
				(start 390.103106 -312.049922)
				(mid 389.696706 -312.049922)
				(end 390.103106 -312.049922)
			)
		)
		(stroke
			(width 0)
			(type solid)
		)
		(fill yes)
		(layer "In8.Cu")
		(net "P5E_PEX3_STN7_TX_DN<126>")
	)
	(gr_poly
		(pts
			(arc
				(start 390.103106 -311.099962)
				(mid 389.696706 -311.099962)
				(end 390.103106 -311.099962)
			)
		)
		(stroke
			(width 0)
			(type solid)
		)
		(fill yes)
		(layer "In8.Cu")
		(net "P5E_PEX3_STN7_TX_DP<126>")
	)
	(gr_poly
		(pts
			(arc
				(start 390.103106 -309.199788)
				(mid 389.696706 -309.199788)
				(end 390.103106 -309.199788)
			)
		)
		(stroke
			(width 0)
			(type solid)
		)
		(fill yes)
		(layer "In8.Cu")
		(net "P5E_PEX3_STN7_TX_DN<120>")
	)
	(gr_poly
		(pts
			(arc
				(start 390.103106 -307.299868)
				(mid 389.696706 -307.299868)
				(end 390.103106 -307.299868)
			)
		)
		(stroke
			(width 0)
			(type solid)
		)
		(fill yes)
		(layer "In8.Cu")
		(net "P5E_PEX3_STN7_TX_DN<118>")
	)
	(gr_poly
		(pts
			(arc
				(start 390.103106 -305.399948)
				(mid 389.696706 -305.399948)
				(end 390.103106 -305.399948)
			)
		)
		(stroke
			(width 0)
			(type solid)
		)
		(fill yes)
		(layer "In8.Cu")
		(net "P5E_PEX3_STN7_TX_DN<116>")
	)
	(gr_poly
		(pts
			(arc
				(start 390.103106 -303.499774)
				(mid 389.696706 -303.499774)
				(end 390.103106 -303.499774)
			)
		)
		(stroke
			(width 0)
			(type solid)
		)
		(fill yes)
		(layer "In8.Cu")
		(net "P5E_PEX3_STN7_TX_DN<114>")
	)
	(gr_poly
		(pts
			(arc
				(start 390.103106 -301.599854)
				(mid 389.696706 -301.599854)
				(end 390.103106 -301.599854)
			)
		)
		(stroke
			(width 0)
			(type solid)
		)
		(fill yes)
		(layer "In8.Cu")
		(net "P5E_PEX3_STN7_TX_DN<112>")
	)
	(gr_poly
		(pts
			(arc
				(start 391.053066 -318.699896)
				(mid 390.646666 -318.699896)
				(end 391.053066 -318.699896)
			)
		)
		(stroke
			(width 0)
			(type solid)
		)
		(fill yes)
		(layer "In8.Cu")
		(net "P5E_PEX3_STN7_RX_DN<127>")
	)
	(gr_poly
		(pts
			(arc
				(start 391.053066 -317.749936)
				(mid 390.646666 -317.749936)
				(end 391.053066 -317.749936)
			)
		)
		(stroke
			(width 0)
			(type solid)
		)
		(fill yes)
		(layer "In8.Cu")
		(net "P5E_PEX3_STN7_RX_DP<127>")
	)
	(gr_poly
		(pts
			(arc
				(start 391.053066 -313.949842)
				(mid 390.646666 -313.949842)
				(end 391.053066 -313.949842)
			)
		)
		(stroke
			(width 0)
			(type solid)
		)
		(fill yes)
		(layer "In8.Cu")
		(net "P5E_PEX3_STN7_TX_DN<127>")
	)
	(gr_poly
		(pts
			(arc
				(start 391.053066 -312.999882)
				(mid 390.646666 -312.999882)
				(end 391.053066 -312.999882)
			)
		)
		(stroke
			(width 0)
			(type solid)
		)
		(fill yes)
		(layer "In8.Cu")
		(net "P5E_PEX3_STN7_TX_DP<127>")
	)
	(gr_poly
		(pts
			(arc
				(start 391.053066 -309.199788)
				(mid 390.646666 -309.199788)
				(end 391.053066 -309.199788)
			)
		)
		(stroke
			(width 0)
			(type solid)
		)
		(fill yes)
		(layer "In8.Cu")
		(net "P5E_PEX3_STN7_TX_DP<120>")
	)
	(gr_poly
		(pts
			(arc
				(start 391.053066 -307.299868)
				(mid 390.646666 -307.299868)
				(end 391.053066 -307.299868)
			)
		)
		(stroke
			(width 0)
			(type solid)
		)
		(fill yes)
		(layer "In8.Cu")
		(net "P5E_PEX3_STN7_TX_DP<118>")
	)
	(gr_poly
		(pts
			(arc
				(start 391.053066 -305.399948)
				(mid 390.646666 -305.399948)
				(end 391.053066 -305.399948)
			)
		)
		(stroke
			(width 0)
			(type solid)
		)
		(fill yes)
		(layer "In8.Cu")
		(net "P5E_PEX3_STN7_TX_DP<116>")
	)
	(gr_poly
		(pts
			(arc
				(start 391.053066 -303.499774)
				(mid 390.646666 -303.499774)
				(end 391.053066 -303.499774)
			)
		)
		(stroke
			(width 0)
			(type solid)
		)
		(fill yes)
		(layer "In8.Cu")
		(net "P5E_PEX3_STN7_TX_DP<114>")
	)
	(gr_poly
		(pts
			(arc
				(start 391.053066 -301.599854)
				(mid 390.646666 -301.599854)
				(end 391.053066 -301.599854)
			)
		)
		(stroke
			(width 0)
			(type solid)
		)
		(fill yes)
		(layer "In8.Cu")
		(net "P5E_PEX3_STN7_TX_DP<112>")
	)
	(gr_poly
		(pts
			(arc
				(start 392.003026 -316.799722)
				(mid 391.596626 -316.799722)
				(end 392.003026 -316.799722)
			)
		)
		(stroke
			(width 0)
			(type solid)
		)
		(fill yes)
		(layer "In8.Cu")
		(net "P5E_PEX3_STN6_RX_DN<111>")
	)
	(gr_poly
		(pts
			(arc
				(start 392.003026 -315.849762)
				(mid 391.596626 -315.849762)
				(end 392.003026 -315.849762)
			)
		)
		(stroke
			(width 0)
			(type solid)
		)
		(fill yes)
		(layer "In8.Cu")
		(net "P5E_PEX3_STN6_RX_DP<111>")
	)
	(gr_poly
		(pts
			(arc
				(start 392.003026 -312.049922)
				(mid 391.596626 -312.049922)
				(end 392.003026 -312.049922)
			)
		)
		(stroke
			(width 0)
			(type solid)
		)
		(fill yes)
		(layer "In8.Cu")
		(net "P5E_PEX3_STN6_TX_DN<111>")
	)
	(gr_poly
		(pts
			(arc
				(start 392.003026 -311.099962)
				(mid 391.596626 -311.099962)
				(end 392.003026 -311.099962)
			)
		)
		(stroke
			(width 0)
			(type solid)
		)
		(fill yes)
		(layer "In8.Cu")
		(net "P5E_PEX3_STN6_TX_DP<111>")
	)
	(gr_poly
		(pts
			(arc
				(start 392.003026 -308.249828)
				(mid 391.596626 -308.249828)
				(end 392.003026 -308.249828)
			)
		)
		(stroke
			(width 0)
			(type solid)
		)
		(fill yes)
		(layer "In8.Cu")
		(net "P5E_PEX3_STN7_TX_DN<119>")
	)
	(gr_poly
		(pts
			(arc
				(start 392.003026 -306.349908)
				(mid 391.596626 -306.349908)
				(end 392.003026 -306.349908)
			)
		)
		(stroke
			(width 0)
			(type solid)
		)
		(fill yes)
		(layer "In8.Cu")
		(net "P5E_PEX3_STN7_TX_DN<117>")
	)
	(gr_poly
		(pts
			(arc
				(start 392.003026 -304.449734)
				(mid 391.596626 -304.449734)
				(end 392.003026 -304.449734)
			)
		)
		(stroke
			(width 0)
			(type solid)
		)
		(fill yes)
		(layer "In8.Cu")
		(net "P5E_PEX3_STN7_TX_DN<115>")
	)
	(gr_poly
		(pts
			(arc
				(start 392.003026 -302.549814)
				(mid 391.596626 -302.549814)
				(end 392.003026 -302.549814)
			)
		)
		(stroke
			(width 0)
			(type solid)
		)
		(fill yes)
		(layer "In8.Cu")
		(net "P5E_PEX3_STN7_TX_DN<113>")
	)
	(gr_poly
		(pts
			(arc
				(start 392.952986 -318.699896)
				(mid 392.546586 -318.699896)
				(end 392.952986 -318.699896)
			)
		)
		(stroke
			(width 0)
			(type solid)
		)
		(fill yes)
		(layer "In8.Cu")
		(net "P5E_PEX3_STN6_RX_DN<110>")
	)
	(gr_poly
		(pts
			(arc
				(start 392.952986 -317.749936)
				(mid 392.546586 -317.749936)
				(end 392.952986 -317.749936)
			)
		)
		(stroke
			(width 0)
			(type solid)
		)
		(fill yes)
		(layer "In8.Cu")
		(net "P5E_PEX3_STN6_RX_DP<110>")
	)
	(gr_poly
		(pts
			(arc
				(start 392.952986 -313.949842)
				(mid 392.546586 -313.949842)
				(end 392.952986 -313.949842)
			)
		)
		(stroke
			(width 0)
			(type solid)
		)
		(fill yes)
		(layer "In8.Cu")
		(net "P5E_PEX3_STN6_TX_DN<110>")
	)
	(gr_poly
		(pts
			(arc
				(start 392.952986 -312.999882)
				(mid 392.546586 -312.999882)
				(end 392.952986 -312.999882)
			)
		)
		(stroke
			(width 0)
			(type solid)
		)
		(fill yes)
		(layer "In8.Cu")
		(net "P5E_PEX3_STN6_TX_DP<110>")
	)
	(gr_poly
		(pts
			(arc
				(start 392.952986 -308.249828)
				(mid 392.546586 -308.249828)
				(end 392.952986 -308.249828)
			)
		)
		(stroke
			(width 0)
			(type solid)
		)
		(fill yes)
		(layer "In8.Cu")
		(net "P5E_PEX3_STN7_TX_DP<119>")
	)
	(gr_poly
		(pts
			(arc
				(start 392.952986 -306.349908)
				(mid 392.546586 -306.349908)
				(end 392.952986 -306.349908)
			)
		)
		(stroke
			(width 0)
			(type solid)
		)
		(fill yes)
		(layer "In8.Cu")
		(net "P5E_PEX3_STN7_TX_DP<117>")
	)
	(gr_poly
		(pts
			(arc
				(start 392.952986 -304.449734)
				(mid 392.546586 -304.449734)
				(end 392.952986 -304.449734)
			)
		)
		(stroke
			(width 0)
			(type solid)
		)
		(fill yes)
		(layer "In8.Cu")
		(net "P5E_PEX3_STN7_TX_DP<115>")
	)
	(gr_poly
		(pts
			(arc
				(start 392.952986 -302.549814)
				(mid 392.546586 -302.549814)
				(end 392.952986 -302.549814)
			)
		)
		(stroke
			(width 0)
			(type solid)
		)
		(fill yes)
		(layer "In8.Cu")
		(net "P5E_PEX3_STN7_TX_DP<113>")
	)
	(gr_poly
		(pts
			(arc
				(start 392.952986 -278.799798)
				(mid 392.546586 -278.799798)
				(end 392.952986 -278.799798)
			)
		)
		(stroke
			(width 0)
			(type solid)
		)
		(fill yes)
		(layer "In8.Cu")
		(net "P5E_PEX3_STN2_TX_DP<47>")
	)
	(gr_poly
		(pts
			(arc
				(start 392.952986 -277.849838)
				(mid 392.546586 -277.849838)
				(end 392.952986 -277.849838)
			)
		)
		(stroke
			(width 0)
			(type solid)
		)
		(fill yes)
		(layer "In8.Cu")
		(net "P5E_PEX3_STN2_TX_DN<47>")
	)
	(gr_poly
		(pts
			(arc
				(start 393.9032 -316.799722)
				(mid 393.4968 -316.799722)
				(end 393.9032 -316.799722)
			)
		)
		(stroke
			(width 0)
			(type solid)
		)
		(fill yes)
		(layer "In8.Cu")
		(net "P5E_PEX3_STN6_RX_DN<109>")
	)
	(gr_poly
		(pts
			(arc
				(start 393.9032 -315.849762)
				(mid 393.4968 -315.849762)
				(end 393.9032 -315.849762)
			)
		)
		(stroke
			(width 0)
			(type solid)
		)
		(fill yes)
		(layer "In8.Cu")
		(net "P5E_PEX3_STN6_RX_DP<109>")
	)
	(gr_poly
		(pts
			(arc
				(start 393.9032 -312.049922)
				(mid 393.4968 -312.049922)
				(end 393.9032 -312.049922)
			)
		)
		(stroke
			(width 0)
			(type solid)
		)
		(fill yes)
		(layer "In8.Cu")
		(net "P5E_PEX3_STN6_TX_DN<109>")
	)
	(gr_poly
		(pts
			(arc
				(start 393.9032 -311.099962)
				(mid 393.4968 -311.099962)
				(end 393.9032 -311.099962)
			)
		)
		(stroke
			(width 0)
			(type solid)
		)
		(fill yes)
		(layer "In8.Cu")
		(net "P5E_PEX3_STN6_TX_DP<109>")
	)
	(gr_poly
		(pts
			(arc
				(start 393.9032 -280.699464)
				(mid 393.4968 -280.699464)
				(end 393.9032 -280.699464)
			)
		)
		(stroke
			(width 0)
			(type solid)
		)
		(fill yes)
		(layer "In8.Cu")
		(net "P5E_PEX3_STN2_TX_DP<46>")
	)
	(gr_poly
		(pts
			(arc
				(start 393.9032 -279.749504)
				(mid 393.4968 -279.749504)
				(end 393.9032 -279.749504)
			)
		)
		(stroke
			(width 0)
			(type solid)
		)
		(fill yes)
		(layer "In8.Cu")
		(net "P5E_PEX3_STN2_TX_DN<46>")
	)
	(gr_poly
		(pts
			(arc
				(start 394.85316 -318.699896)
				(mid 394.44676 -318.699896)
				(end 394.85316 -318.699896)
			)
		)
		(stroke
			(width 0)
			(type solid)
		)
		(fill yes)
		(layer "In8.Cu")
		(net "P5E_PEX3_STN6_RX_DN<108>")
	)
	(gr_poly
		(pts
			(arc
				(start 394.85316 -317.749936)
				(mid 394.44676 -317.749936)
				(end 394.85316 -317.749936)
			)
		)
		(stroke
			(width 0)
			(type solid)
		)
		(fill yes)
		(layer "In8.Cu")
		(net "P5E_PEX3_STN6_RX_DP<108>")
	)
	(gr_poly
		(pts
			(arc
				(start 394.85316 -313.949842)
				(mid 394.44676 -313.949842)
				(end 394.85316 -313.949842)
			)
		)
		(stroke
			(width 0)
			(type solid)
		)
		(fill yes)
		(layer "In8.Cu")
		(net "P5E_PEX3_STN6_TX_DN<108>")
	)
	(gr_poly
		(pts
			(arc
				(start 394.85316 -312.999882)
				(mid 394.44676 -312.999882)
				(end 394.85316 -312.999882)
			)
		)
		(stroke
			(width 0)
			(type solid)
		)
		(fill yes)
		(layer "In8.Cu")
		(net "P5E_PEX3_STN6_TX_DP<108>")
	)
	(gr_poly
		(pts
			(arc
				(start 394.85316 -278.799798)
				(mid 394.44676 -278.799798)
				(end 394.85316 -278.799798)
			)
		)
		(stroke
			(width 0)
			(type solid)
		)
		(fill yes)
		(layer "In8.Cu")
		(net "P5E_PEX3_STN2_TX_DP<45>")
	)
	(gr_poly
		(pts
			(arc
				(start 394.85316 -277.849838)
				(mid 394.44676 -277.849838)
				(end 394.85316 -277.849838)
			)
		)
		(stroke
			(width 0)
			(type solid)
		)
		(fill yes)
		(layer "In8.Cu")
		(net "P5E_PEX3_STN2_TX_DN<45>")
	)
	(gr_poly
		(pts
			(arc
				(start 395.80312 -316.799722)
				(mid 395.39672 -316.799722)
				(end 395.80312 -316.799722)
			)
		)
		(stroke
			(width 0)
			(type solid)
		)
		(fill yes)
		(layer "In8.Cu")
		(net "P5E_PEX3_STN6_RX_DN<107>")
	)
	(gr_poly
		(pts
			(arc
				(start 395.80312 -315.849762)
				(mid 395.39672 -315.849762)
				(end 395.80312 -315.849762)
			)
		)
		(stroke
			(width 0)
			(type solid)
		)
		(fill yes)
		(layer "In8.Cu")
		(net "P5E_PEX3_STN6_RX_DP<107>")
	)
	(gr_poly
		(pts
			(arc
				(start 395.80312 -312.049922)
				(mid 395.39672 -312.049922)
				(end 395.80312 -312.049922)
			)
		)
		(stroke
			(width 0)
			(type solid)
		)
		(fill yes)
		(layer "In8.Cu")
		(net "P5E_PEX3_STN6_TX_DN<107>")
	)
	(gr_poly
		(pts
			(arc
				(start 395.80312 -311.099962)
				(mid 395.39672 -311.099962)
				(end 395.80312 -311.099962)
			)
		)
		(stroke
			(width 0)
			(type solid)
		)
		(fill yes)
		(layer "In8.Cu")
		(net "P5E_PEX3_STN6_TX_DP<107>")
	)
	(gr_poly
		(pts
			(arc
				(start 395.80312 -280.699464)
				(mid 395.39672 -280.699464)
				(end 395.80312 -280.699464)
			)
		)
		(stroke
			(width 0)
			(type solid)
		)
		(fill yes)
		(layer "In8.Cu")
		(net "P5E_PEX3_STN2_TX_DP<44>")
	)
	(gr_poly
		(pts
			(arc
				(start 395.80312 -279.749504)
				(mid 395.39672 -279.749504)
				(end 395.80312 -279.749504)
			)
		)
		(stroke
			(width 0)
			(type solid)
		)
		(fill yes)
		(layer "In8.Cu")
		(net "P5E_PEX3_STN2_TX_DN<44>")
	)
	(gr_poly
		(pts
			(arc
				(start 396.75308 -318.699896)
				(mid 396.34668 -318.699896)
				(end 396.75308 -318.699896)
			)
		)
		(stroke
			(width 0)
			(type solid)
		)
		(fill yes)
		(layer "In8.Cu")
		(net "P5E_PEX3_STN6_RX_DN<106>")
	)
	(gr_poly
		(pts
			(arc
				(start 396.75308 -317.749936)
				(mid 396.34668 -317.749936)
				(end 396.75308 -317.749936)
			)
		)
		(stroke
			(width 0)
			(type solid)
		)
		(fill yes)
		(layer "In8.Cu")
		(net "P5E_PEX3_STN6_RX_DP<106>")
	)
	(gr_poly
		(pts
			(arc
				(start 396.75308 -313.949842)
				(mid 396.34668 -313.949842)
				(end 396.75308 -313.949842)
			)
		)
		(stroke
			(width 0)
			(type solid)
		)
		(fill yes)
		(layer "In8.Cu")
		(net "P5E_PEX3_STN6_TX_DN<106>")
	)
	(gr_poly
		(pts
			(arc
				(start 396.75308 -312.999882)
				(mid 396.34668 -312.999882)
				(end 396.75308 -312.999882)
			)
		)
		(stroke
			(width 0)
			(type solid)
		)
		(fill yes)
		(layer "In8.Cu")
		(net "P5E_PEX3_STN6_TX_DP<106>")
	)
	(gr_poly
		(pts
			(arc
				(start 396.75308 -278.799798)
				(mid 396.34668 -278.799798)
				(end 396.75308 -278.799798)
			)
		)
		(stroke
			(width 0)
			(type solid)
		)
		(fill yes)
		(layer "In8.Cu")
		(net "P5E_PEX3_STN2_TX_DP<43>")
	)
	(gr_poly
		(pts
			(arc
				(start 396.75308 -277.849838)
				(mid 396.34668 -277.849838)
				(end 396.75308 -277.849838)
			)
		)
		(stroke
			(width 0)
			(type solid)
		)
		(fill yes)
		(layer "In8.Cu")
		(net "P5E_PEX3_STN2_TX_DN<43>")
	)
	(gr_poly
		(pts
			(arc
				(start 397.70304 -316.799722)
				(mid 397.29664 -316.799722)
				(end 397.70304 -316.799722)
			)
		)
		(stroke
			(width 0)
			(type solid)
		)
		(fill yes)
		(layer "In8.Cu")
		(net "P5E_PEX3_STN6_RX_DN<105>")
	)
	(gr_poly
		(pts
			(arc
				(start 397.70304 -315.849762)
				(mid 397.29664 -315.849762)
				(end 397.70304 -315.849762)
			)
		)
		(stroke
			(width 0)
			(type solid)
		)
		(fill yes)
		(layer "In8.Cu")
		(net "P5E_PEX3_STN6_RX_DP<105>")
	)
	(gr_poly
		(pts
			(arc
				(start 397.70304 -312.049922)
				(mid 397.29664 -312.049922)
				(end 397.70304 -312.049922)
			)
		)
		(stroke
			(width 0)
			(type solid)
		)
		(fill yes)
		(layer "In8.Cu")
		(net "P5E_PEX3_STN6_TX_DN<105>")
	)
	(gr_poly
		(pts
			(arc
				(start 397.70304 -311.099962)
				(mid 397.29664 -311.099962)
				(end 397.70304 -311.099962)
			)
		)
		(stroke
			(width 0)
			(type solid)
		)
		(fill yes)
		(layer "In8.Cu")
		(net "P5E_PEX3_STN6_TX_DP<105>")
	)
	(gr_poly
		(pts
			(arc
				(start 397.70304 -280.699464)
				(mid 397.29664 -280.699464)
				(end 397.70304 -280.699464)
			)
		)
		(stroke
			(width 0)
			(type solid)
		)
		(fill yes)
		(layer "In8.Cu")
		(net "P5E_PEX3_STN2_TX_DP<42>")
	)
	(gr_poly
		(pts
			(arc
				(start 397.70304 -279.749504)
				(mid 397.29664 -279.749504)
				(end 397.70304 -279.749504)
			)
		)
		(stroke
			(width 0)
			(type solid)
		)
		(fill yes)
		(layer "In8.Cu")
		(net "P5E_PEX3_STN2_TX_DN<42>")
	)
	(gr_poly
		(pts
			(arc
				(start 398.653 -318.699896)
				(mid 398.2466 -318.699896)
				(end 398.653 -318.699896)
			)
		)
		(stroke
			(width 0)
			(type solid)
		)
		(fill yes)
		(layer "In8.Cu")
		(net "P5E_PEX3_STN6_RX_DN<104>")
	)
	(gr_poly
		(pts
			(arc
				(start 398.653 -317.749936)
				(mid 398.2466 -317.749936)
				(end 398.653 -317.749936)
			)
		)
		(stroke
			(width 0)
			(type solid)
		)
		(fill yes)
		(layer "In8.Cu")
		(net "P5E_PEX3_STN6_RX_DP<104>")
	)
	(gr_poly
		(pts
			(arc
				(start 398.653 -313.949842)
				(mid 398.2466 -313.949842)
				(end 398.653 -313.949842)
			)
		)
		(stroke
			(width 0)
			(type solid)
		)
		(fill yes)
		(layer "In8.Cu")
		(net "P5E_PEX3_STN6_TX_DN<104>")
	)
	(gr_poly
		(pts
			(arc
				(start 398.653 -312.999882)
				(mid 398.2466 -312.999882)
				(end 398.653 -312.999882)
			)
		)
		(stroke
			(width 0)
			(type solid)
		)
		(fill yes)
		(layer "In8.Cu")
		(net "P5E_PEX3_STN6_TX_DP<104>")
	)
	(gr_poly
		(pts
			(arc
				(start 398.653 -278.799798)
				(mid 398.2466 -278.799798)
				(end 398.653 -278.799798)
			)
		)
		(stroke
			(width 0)
			(type solid)
		)
		(fill yes)
		(layer "In8.Cu")
		(net "P5E_PEX3_STN2_TX_DP<41>")
	)
	(gr_poly
		(pts
			(arc
				(start 398.653 -277.849838)
				(mid 398.2466 -277.849838)
				(end 398.653 -277.849838)
			)
		)
		(stroke
			(width 0)
			(type solid)
		)
		(fill yes)
		(layer "In8.Cu")
		(net "P5E_PEX3_STN2_TX_DN<41>")
	)
	(gr_poly
		(pts
			(arc
				(start 399.603214 -280.699464)
				(mid 399.196814 -280.699464)
				(end 399.603214 -280.699464)
			)
		)
		(stroke
			(width 0)
			(type solid)
		)
		(fill yes)
		(layer "In8.Cu")
		(net "P5E_PEX3_STN2_TX_DP<40>")
	)
	(gr_poly
		(pts
			(arc
				(start 399.603214 -279.749504)
				(mid 399.196814 -279.749504)
				(end 399.603214 -279.749504)
			)
		)
		(stroke
			(width 0)
			(type solid)
		)
		(fill yes)
		(layer "In8.Cu")
		(net "P5E_PEX3_STN2_TX_DN<40>")
	)
	(gr_poly
		(pts
			(arc
				(start 400.553174 -278.799798)
				(mid 400.146774 -278.799798)
				(end 400.553174 -278.799798)
			)
		)
		(stroke
			(width 0)
			(type solid)
		)
		(fill yes)
		(layer "In8.Cu")
		(net "P5E_PEX3_STN2_TX_DP<39>")
	)
	(gr_poly
		(pts
			(arc
				(start 400.553174 -277.849838)
				(mid 400.146774 -277.849838)
				(end 400.553174 -277.849838)
			)
		)
		(stroke
			(width 0)
			(type solid)
		)
		(fill yes)
		(layer "In8.Cu")
		(net "P5E_PEX3_STN2_TX_DN<39>")
	)
	(gr_poly
		(pts
			(arc
				(start 401.503134 -280.699464)
				(mid 401.096734 -280.699464)
				(end 401.503134 -280.699464)
			)
		)
		(stroke
			(width 0)
			(type solid)
		)
		(fill yes)
		(layer "In8.Cu")
		(net "P5E_PEX3_STN2_TX_DP<38>")
	)
	(gr_poly
		(pts
			(arc
				(start 401.503134 -279.749504)
				(mid 401.096734 -279.749504)
				(end 401.503134 -279.749504)
			)
		)
		(stroke
			(width 0)
			(type solid)
		)
		(fill yes)
		(layer "In8.Cu")
		(net "P5E_PEX3_STN2_TX_DN<38>")
	)
	(gr_poly
		(pts
			(arc
				(start 402.453094 -278.799798)
				(mid 402.046694 -278.799798)
				(end 402.453094 -278.799798)
			)
		)
		(stroke
			(width 0)
			(type solid)
		)
		(fill yes)
		(layer "In8.Cu")
		(net "P5E_PEX3_STN2_TX_DP<37>")
	)
	(gr_poly
		(pts
			(arc
				(start 402.453094 -277.849838)
				(mid 402.046694 -277.849838)
				(end 402.453094 -277.849838)
			)
		)
		(stroke
			(width 0)
			(type solid)
		)
		(fill yes)
		(layer "In8.Cu")
		(net "P5E_PEX3_STN2_TX_DN<37>")
	)
	(gr_poly
		(pts
			(arc
				(start 403.403054 -280.699464)
				(mid 402.996654 -280.699464)
				(end 403.403054 -280.699464)
			)
		)
		(stroke
			(width 0)
			(type solid)
		)
		(fill yes)
		(layer "In8.Cu")
		(net "P5E_PEX3_STN2_TX_DP<36>")
	)
	(gr_poly
		(pts
			(arc
				(start 403.403054 -279.749504)
				(mid 402.996654 -279.749504)
				(end 403.403054 -279.749504)
			)
		)
		(stroke
			(width 0)
			(type solid)
		)
		(fill yes)
		(layer "In8.Cu")
		(net "P5E_PEX3_STN2_TX_DN<36>")
	)
	(gr_poly
		(pts
			(arc
				(start 404.353014 -278.799798)
				(mid 403.946614 -278.799798)
				(end 404.353014 -278.799798)
			)
		)
		(stroke
			(width 0)
			(type solid)
		)
		(fill yes)
		(layer "In8.Cu")
		(net "P5E_PEX3_STN2_TX_DP<35>")
	)
	(gr_poly
		(pts
			(arc
				(start 404.353014 -277.849838)
				(mid 403.946614 -277.849838)
				(end 404.353014 -277.849838)
			)
		)
		(stroke
			(width 0)
			(type solid)
		)
		(fill yes)
		(layer "In8.Cu")
		(net "P5E_PEX3_STN2_TX_DN<35>")
	)
	(gr_poly
		(pts
			(arc
				(start 405.302974 -280.699464)
				(mid 404.896574 -280.699464)
				(end 405.302974 -280.699464)
			)
		)
		(stroke
			(width 0)
			(type solid)
		)
		(fill yes)
		(layer "In8.Cu")
		(net "P5E_PEX3_STN2_TX_DP<34>")
	)
	(gr_poly
		(pts
			(arc
				(start 405.302974 -279.749504)
				(mid 404.896574 -279.749504)
				(end 405.302974 -279.749504)
			)
		)
		(stroke
			(width 0)
			(type solid)
		)
		(fill yes)
		(layer "In8.Cu")
		(net "P5E_PEX3_STN2_TX_DN<34>")
	)
	(gr_poly
		(pts
			(arc
				(start 406.253188 -278.799798)
				(mid 405.846788 -278.799798)
				(end 406.253188 -278.799798)
			)
		)
		(stroke
			(width 0)
			(type solid)
		)
		(fill yes)
		(layer "In8.Cu")
		(net "P5E_PEX3_STN2_TX_DP<33>")
	)
	(gr_poly
		(pts
			(arc
				(start 406.253188 -277.849838)
				(mid 405.846788 -277.849838)
				(end 406.253188 -277.849838)
			)
		)
		(stroke
			(width 0)
			(type solid)
		)
		(fill yes)
		(layer "In8.Cu")
		(net "P5E_PEX3_STN2_TX_DN<33>")
	)
	(gr_poly
		(pts
			(arc
				(start 407.203148 -280.699464)
				(mid 406.796748 -280.699464)
				(end 407.203148 -280.699464)
			)
		)
		(stroke
			(width 0)
			(type solid)
		)
		(fill yes)
		(layer "In8.Cu")
		(net "P5E_PEX3_STN2_TX_DP<32>")
	)
	(gr_poly
		(pts
			(arc
				(start 407.203148 -279.749504)
				(mid 406.796748 -279.749504)
				(end 407.203148 -279.749504)
			)
		)
		(stroke
			(width 0)
			(type solid)
		)
		(fill yes)
		(layer "In8.Cu")
		(net "P5E_PEX3_STN2_TX_DN<32>")
	)
	(gr_poly
		(pts
			(arc
				(start 408.152854 -278.799798)
				(mid 407.746454 -278.799798)
				(end 408.152854 -278.799798)
			)
		)
		(stroke
			(width 0)
			(type solid)
		)
		(fill yes)
		(layer "In8.Cu")
		(net "P5E_PEX3_STN1_TX_DP<16>")
	)
	(gr_poly
		(pts
			(arc
				(start 408.152854 -277.849838)
				(mid 407.746454 -277.849838)
				(end 408.152854 -277.849838)
			)
		)
		(stroke
			(width 0)
			(type solid)
		)
		(fill yes)
		(layer "In8.Cu")
		(net "P5E_PEX3_STN1_TX_DN<16>")
	)
	(gr_poly
		(pts
			(arc
				(start 409.103068 -280.699464)
				(mid 408.696668 -280.699464)
				(end 409.103068 -280.699464)
			)
		)
		(stroke
			(width 0)
			(type solid)
		)
		(fill yes)
		(layer "In8.Cu")
		(net "P5E_PEX3_STN1_TX_DN<17>")
	)
	(gr_poly
		(pts
			(arc
				(start 409.103068 -279.749504)
				(mid 408.696668 -279.749504)
				(end 409.103068 -279.749504)
			)
		)
		(stroke
			(width 0)
			(type solid)
		)
		(fill yes)
		(layer "In8.Cu")
		(net "P5E_PEX3_STN1_TX_DP<17>")
	)
	(gr_poly
		(pts
			(arc
				(start 410.052774 -278.799798)
				(mid 409.646374 -278.799798)
				(end 410.052774 -278.799798)
			)
		)
		(stroke
			(width 0)
			(type solid)
		)
		(fill yes)
		(layer "In8.Cu")
		(net "P5E_PEX3_STN1_TX_DP<18>")
	)
	(gr_poly
		(pts
			(arc
				(start 410.052774 -277.849838)
				(mid 409.646374 -277.849838)
				(end 410.052774 -277.849838)
			)
		)
		(stroke
			(width 0)
			(type solid)
		)
		(fill yes)
		(layer "In8.Cu")
		(net "P5E_PEX3_STN1_TX_DN<18>")
	)
	(gr_poly
		(pts
			(arc
				(start 411.002988 -280.699464)
				(mid 410.596588 -280.699464)
				(end 411.002988 -280.699464)
			)
		)
		(stroke
			(width 0)
			(type solid)
		)
		(fill yes)
		(layer "In8.Cu")
		(net "P5E_PEX3_STN1_TX_DN<19>")
	)
	(gr_poly
		(pts
			(arc
				(start 411.002988 -279.749504)
				(mid 410.596588 -279.749504)
				(end 411.002988 -279.749504)
			)
		)
		(stroke
			(width 0)
			(type solid)
		)
		(fill yes)
		(layer "In8.Cu")
		(net "P5E_PEX3_STN1_TX_DP<19>")
	)
	(gr_poly
		(pts
			(arc
				(start 411.952948 -278.799798)
				(mid 411.546548 -278.799798)
				(end 411.952948 -278.799798)
			)
		)
		(stroke
			(width 0)
			(type solid)
		)
		(fill yes)
		(layer "In8.Cu")
		(net "P5E_PEX3_STN1_TX_DP<20>")
	)
	(gr_poly
		(pts
			(arc
				(start 411.952948 -277.849838)
				(mid 411.546548 -277.849838)
				(end 411.952948 -277.849838)
			)
		)
		(stroke
			(width 0)
			(type solid)
		)
		(fill yes)
		(layer "In8.Cu")
		(net "P5E_PEX3_STN1_TX_DN<20>")
	)
	(gr_poly
		(pts
			(arc
				(start 412.903162 -280.699464)
				(mid 412.496762 -280.699464)
				(end 412.903162 -280.699464)
			)
		)
		(stroke
			(width 0)
			(type solid)
		)
		(fill yes)
		(layer "In8.Cu")
		(net "P5E_PEX3_STN1_TX_DN<21>")
	)
	(gr_poly
		(pts
			(arc
				(start 412.903162 -279.749504)
				(mid 412.496762 -279.749504)
				(end 412.903162 -279.749504)
			)
		)
		(stroke
			(width 0)
			(type solid)
		)
		(fill yes)
		(layer "In8.Cu")
		(net "P5E_PEX3_STN1_TX_DP<21>")
	)
	(gr_poly
		(pts
			(arc
				(start 413.852868 -278.799798)
				(mid 413.446468 -278.799798)
				(end 413.852868 -278.799798)
			)
		)
		(stroke
			(width 0)
			(type solid)
		)
		(fill yes)
		(layer "In8.Cu")
		(net "P5E_PEX3_STN1_TX_DP<22>")
	)
	(gr_poly
		(pts
			(arc
				(start 413.852868 -277.849838)
				(mid 413.446468 -277.849838)
				(end 413.852868 -277.849838)
			)
		)
		(stroke
			(width 0)
			(type solid)
		)
		(fill yes)
		(layer "In8.Cu")
		(net "P5E_PEX3_STN1_TX_DN<22>")
	)
	(gr_poly
		(pts
			(arc
				(start 414.803082 -316.799722)
				(mid 414.396682 -316.799722)
				(end 414.803082 -316.799722)
			)
		)
		(stroke
			(width 0)
			(type solid)
		)
		(fill yes)
		(layer "In8.Cu")
		(net "P5E_PEX3_STN5_RX_DN<88>")
	)
	(gr_poly
		(pts
			(arc
				(start 414.803082 -315.849762)
				(mid 414.396682 -315.849762)
				(end 414.803082 -315.849762)
			)
		)
		(stroke
			(width 0)
			(type solid)
		)
		(fill yes)
		(layer "In8.Cu")
		(net "P5E_PEX3_STN5_RX_DP<88>")
	)
	(gr_poly
		(pts
			(arc
				(start 414.803082 -312.049922)
				(mid 414.396682 -312.049922)
				(end 414.803082 -312.049922)
			)
		)
		(stroke
			(width 0)
			(type solid)
		)
		(fill yes)
		(layer "In8.Cu")
		(net "P5E_PEX3_STN5_TX_DN<88>")
	)
	(gr_poly
		(pts
			(arc
				(start 414.803082 -311.099962)
				(mid 414.396682 -311.099962)
				(end 414.803082 -311.099962)
			)
		)
		(stroke
			(width 0)
			(type solid)
		)
		(fill yes)
		(layer "In8.Cu")
		(net "P5E_PEX3_STN5_TX_DP<88>")
	)
	(gr_poly
		(pts
			(arc
				(start 414.803082 -280.699464)
				(mid 414.396682 -280.699464)
				(end 414.803082 -280.699464)
			)
		)
		(stroke
			(width 0)
			(type solid)
		)
		(fill yes)
		(layer "In8.Cu")
		(net "P5E_PEX3_STN1_TX_DN<23>")
	)
	(gr_poly
		(pts
			(arc
				(start 414.803082 -279.749504)
				(mid 414.396682 -279.749504)
				(end 414.803082 -279.749504)
			)
		)
		(stroke
			(width 0)
			(type solid)
		)
		(fill yes)
		(layer "In8.Cu")
		(net "P5E_PEX3_STN1_TX_DP<23>")
	)
	(gr_poly
		(pts
			(arc
				(start 415.752788 -278.799798)
				(mid 415.346388 -278.799798)
				(end 415.752788 -278.799798)
			)
		)
		(stroke
			(width 0)
			(type solid)
		)
		(fill yes)
		(layer "In8.Cu")
		(net "P5E_PEX3_STN1_TX_DP<24>")
	)
	(gr_poly
		(pts
			(arc
				(start 415.752788 -277.849838)
				(mid 415.346388 -277.849838)
				(end 415.752788 -277.849838)
			)
		)
		(stroke
			(width 0)
			(type solid)
		)
		(fill yes)
		(layer "In8.Cu")
		(net "P5E_PEX3_STN1_TX_DN<24>")
	)
	(gr_poly
		(pts
			(arc
				(start 415.753042 -318.699896)
				(mid 415.346642 -318.699896)
				(end 415.753042 -318.699896)
			)
		)
		(stroke
			(width 0)
			(type solid)
		)
		(fill yes)
		(layer "In8.Cu")
		(net "P5E_PEX3_STN5_RX_DN<89>")
	)
	(gr_poly
		(pts
			(arc
				(start 415.753042 -317.749936)
				(mid 415.346642 -317.749936)
				(end 415.753042 -317.749936)
			)
		)
		(stroke
			(width 0)
			(type solid)
		)
		(fill yes)
		(layer "In8.Cu")
		(net "P5E_PEX3_STN5_RX_DP<89>")
	)
	(gr_poly
		(pts
			(arc
				(start 415.753042 -313.949842)
				(mid 415.346642 -313.949842)
				(end 415.753042 -313.949842)
			)
		)
		(stroke
			(width 0)
			(type solid)
		)
		(fill yes)
		(layer "In8.Cu")
		(net "P5E_PEX3_STN5_TX_DN<89>")
	)
	(gr_poly
		(pts
			(arc
				(start 415.753042 -312.999882)
				(mid 415.346642 -312.999882)
				(end 415.753042 -312.999882)
			)
		)
		(stroke
			(width 0)
			(type solid)
		)
		(fill yes)
		(layer "In8.Cu")
		(net "P5E_PEX3_STN5_TX_DP<89>")
	)
	(gr_poly
		(pts
			(arc
				(start 416.703002 -316.799722)
				(mid 416.296602 -316.799722)
				(end 416.703002 -316.799722)
			)
		)
		(stroke
			(width 0)
			(type solid)
		)
		(fill yes)
		(layer "In8.Cu")
		(net "P5E_PEX3_STN5_RX_DN<90>")
	)
	(gr_poly
		(pts
			(arc
				(start 416.703002 -315.849762)
				(mid 416.296602 -315.849762)
				(end 416.703002 -315.849762)
			)
		)
		(stroke
			(width 0)
			(type solid)
		)
		(fill yes)
		(layer "In8.Cu")
		(net "P5E_PEX3_STN5_RX_DP<90>")
	)
	(gr_poly
		(pts
			(arc
				(start 416.703002 -312.049922)
				(mid 416.296602 -312.049922)
				(end 416.703002 -312.049922)
			)
		)
		(stroke
			(width 0)
			(type solid)
		)
		(fill yes)
		(layer "In8.Cu")
		(net "P5E_PEX3_STN5_TX_DN<90>")
	)
	(gr_poly
		(pts
			(arc
				(start 416.703002 -311.099962)
				(mid 416.296602 -311.099962)
				(end 416.703002 -311.099962)
			)
		)
		(stroke
			(width 0)
			(type solid)
		)
		(fill yes)
		(layer "In8.Cu")
		(net "P5E_PEX3_STN5_TX_DP<90>")
	)
	(gr_poly
		(pts
			(arc
				(start 416.703002 -280.699464)
				(mid 416.296602 -280.699464)
				(end 416.703002 -280.699464)
			)
		)
		(stroke
			(width 0)
			(type solid)
		)
		(fill yes)
		(layer "In8.Cu")
		(net "P5E_PEX3_STN1_TX_DN<25>")
	)
	(gr_poly
		(pts
			(arc
				(start 416.703002 -279.749504)
				(mid 416.296602 -279.749504)
				(end 416.703002 -279.749504)
			)
		)
		(stroke
			(width 0)
			(type solid)
		)
		(fill yes)
		(layer "In8.Cu")
		(net "P5E_PEX3_STN1_TX_DP<25>")
	)
	(gr_poly
		(pts
			(arc
				(start 417.652962 -278.799798)
				(mid 417.246562 -278.799798)
				(end 417.652962 -278.799798)
			)
		)
		(stroke
			(width 0)
			(type solid)
		)
		(fill yes)
		(layer "In8.Cu")
		(net "P5E_PEX3_STN1_TX_DP<26>")
	)
	(gr_poly
		(pts
			(arc
				(start 417.652962 -277.849838)
				(mid 417.246562 -277.849838)
				(end 417.652962 -277.849838)
			)
		)
		(stroke
			(width 0)
			(type solid)
		)
		(fill yes)
		(layer "In8.Cu")
		(net "P5E_PEX3_STN1_TX_DN<26>")
	)
	(gr_poly
		(pts
			(arc
				(start 417.653216 -318.699896)
				(mid 417.246816 -318.699896)
				(end 417.653216 -318.699896)
			)
		)
		(stroke
			(width 0)
			(type solid)
		)
		(fill yes)
		(layer "In8.Cu")
		(net "P5E_PEX3_STN5_RX_DN<91>")
	)
	(gr_poly
		(pts
			(arc
				(start 417.653216 -317.749936)
				(mid 417.246816 -317.749936)
				(end 417.653216 -317.749936)
			)
		)
		(stroke
			(width 0)
			(type solid)
		)
		(fill yes)
		(layer "In8.Cu")
		(net "P5E_PEX3_STN5_RX_DP<91>")
	)
	(gr_poly
		(pts
			(arc
				(start 417.653216 -313.949842)
				(mid 417.246816 -313.949842)
				(end 417.653216 -313.949842)
			)
		)
		(stroke
			(width 0)
			(type solid)
		)
		(fill yes)
		(layer "In8.Cu")
		(net "P5E_PEX3_STN5_TX_DN<91>")
	)
	(gr_poly
		(pts
			(arc
				(start 417.653216 -312.999882)
				(mid 417.246816 -312.999882)
				(end 417.653216 -312.999882)
			)
		)
		(stroke
			(width 0)
			(type solid)
		)
		(fill yes)
		(layer "In8.Cu")
		(net "P5E_PEX3_STN5_TX_DP<91>")
	)
	(gr_poly
		(pts
			(arc
				(start 418.603176 -316.799722)
				(mid 418.196776 -316.799722)
				(end 418.603176 -316.799722)
			)
		)
		(stroke
			(width 0)
			(type solid)
		)
		(fill yes)
		(layer "In8.Cu")
		(net "P5E_PEX3_STN5_RX_DN<92>")
	)
	(gr_poly
		(pts
			(arc
				(start 418.603176 -315.849762)
				(mid 418.196776 -315.849762)
				(end 418.603176 -315.849762)
			)
		)
		(stroke
			(width 0)
			(type solid)
		)
		(fill yes)
		(layer "In8.Cu")
		(net "P5E_PEX3_STN5_RX_DP<92>")
	)
	(gr_poly
		(pts
			(arc
				(start 418.603176 -312.049922)
				(mid 418.196776 -312.049922)
				(end 418.603176 -312.049922)
			)
		)
		(stroke
			(width 0)
			(type solid)
		)
		(fill yes)
		(layer "In8.Cu")
		(net "P5E_PEX3_STN5_TX_DN<92>")
	)
	(gr_poly
		(pts
			(arc
				(start 418.603176 -311.099962)
				(mid 418.196776 -311.099962)
				(end 418.603176 -311.099962)
			)
		)
		(stroke
			(width 0)
			(type solid)
		)
		(fill yes)
		(layer "In8.Cu")
		(net "P5E_PEX3_STN5_TX_DP<92>")
	)
	(gr_poly
		(pts
			(arc
				(start 418.603176 -280.699464)
				(mid 418.196776 -280.699464)
				(end 418.603176 -280.699464)
			)
		)
		(stroke
			(width 0)
			(type solid)
		)
		(fill yes)
		(layer "In8.Cu")
		(net "P5E_PEX3_STN1_TX_DN<27>")
	)
	(gr_poly
		(pts
			(arc
				(start 418.603176 -279.749504)
				(mid 418.196776 -279.749504)
				(end 418.603176 -279.749504)
			)
		)
		(stroke
			(width 0)
			(type solid)
		)
		(fill yes)
		(layer "In8.Cu")
		(net "P5E_PEX3_STN1_TX_DP<27>")
	)
	(gr_poly
		(pts
			(arc
				(start 419.552882 -278.799798)
				(mid 419.146482 -278.799798)
				(end 419.552882 -278.799798)
			)
		)
		(stroke
			(width 0)
			(type solid)
		)
		(fill yes)
		(layer "In8.Cu")
		(net "P5E_PEX3_STN1_TX_DP<28>")
	)
	(gr_poly
		(pts
			(arc
				(start 419.552882 -277.849838)
				(mid 419.146482 -277.849838)
				(end 419.552882 -277.849838)
			)
		)
		(stroke
			(width 0)
			(type solid)
		)
		(fill yes)
		(layer "In8.Cu")
		(net "P5E_PEX3_STN1_TX_DN<28>")
	)
	(gr_poly
		(pts
			(arc
				(start 419.553136 -318.699896)
				(mid 419.146736 -318.699896)
				(end 419.553136 -318.699896)
			)
		)
		(stroke
			(width 0)
			(type solid)
		)
		(fill yes)
		(layer "In8.Cu")
		(net "P5E_PEX3_STN5_RX_DN<93>")
	)
	(gr_poly
		(pts
			(arc
				(start 419.553136 -317.749936)
				(mid 419.146736 -317.749936)
				(end 419.553136 -317.749936)
			)
		)
		(stroke
			(width 0)
			(type solid)
		)
		(fill yes)
		(layer "In8.Cu")
		(net "P5E_PEX3_STN5_RX_DP<93>")
	)
	(gr_poly
		(pts
			(arc
				(start 419.553136 -313.949842)
				(mid 419.146736 -313.949842)
				(end 419.553136 -313.949842)
			)
		)
		(stroke
			(width 0)
			(type solid)
		)
		(fill yes)
		(layer "In8.Cu")
		(net "P5E_PEX3_STN5_TX_DN<93>")
	)
	(gr_poly
		(pts
			(arc
				(start 419.553136 -312.999882)
				(mid 419.146736 -312.999882)
				(end 419.553136 -312.999882)
			)
		)
		(stroke
			(width 0)
			(type solid)
		)
		(fill yes)
		(layer "In8.Cu")
		(net "P5E_PEX3_STN5_TX_DP<93>")
	)
	(gr_poly
		(pts
			(arc
				(start 420.503096 -316.799722)
				(mid 420.096696 -316.799722)
				(end 420.503096 -316.799722)
			)
		)
		(stroke
			(width 0)
			(type solid)
		)
		(fill yes)
		(layer "In8.Cu")
		(net "P5E_PEX3_STN5_RX_DN<94>")
	)
	(gr_poly
		(pts
			(arc
				(start 420.503096 -315.849762)
				(mid 420.096696 -315.849762)
				(end 420.503096 -315.849762)
			)
		)
		(stroke
			(width 0)
			(type solid)
		)
		(fill yes)
		(layer "In8.Cu")
		(net "P5E_PEX3_STN5_RX_DP<94>")
	)
	(gr_poly
		(pts
			(arc
				(start 420.503096 -312.049922)
				(mid 420.096696 -312.049922)
				(end 420.503096 -312.049922)
			)
		)
		(stroke
			(width 0)
			(type solid)
		)
		(fill yes)
		(layer "In8.Cu")
		(net "P5E_PEX3_STN5_TX_DN<94>")
	)
	(gr_poly
		(pts
			(arc
				(start 420.503096 -311.099962)
				(mid 420.096696 -311.099962)
				(end 420.503096 -311.099962)
			)
		)
		(stroke
			(width 0)
			(type solid)
		)
		(fill yes)
		(layer "In8.Cu")
		(net "P5E_PEX3_STN5_TX_DP<94>")
	)
	(gr_poly
		(pts
			(arc
				(start 420.503096 -280.699464)
				(mid 420.096696 -280.699464)
				(end 420.503096 -280.699464)
			)
		)
		(stroke
			(width 0)
			(type solid)
		)
		(fill yes)
		(layer "In8.Cu")
		(net "P5E_PEX3_STN1_TX_DN<29>")
	)
	(gr_poly
		(pts
			(arc
				(start 420.503096 -279.749504)
				(mid 420.096696 -279.749504)
				(end 420.503096 -279.749504)
			)
		)
		(stroke
			(width 0)
			(type solid)
		)
		(fill yes)
		(layer "In8.Cu")
		(net "P5E_PEX3_STN1_TX_DP<29>")
	)
	(gr_poly
		(pts
			(arc
				(start 421.452802 -278.799798)
				(mid 421.046402 -278.799798)
				(end 421.452802 -278.799798)
			)
		)
		(stroke
			(width 0)
			(type solid)
		)
		(fill yes)
		(layer "In8.Cu")
		(net "P5E_PEX3_STN1_TX_DP<30>")
	)
	(gr_poly
		(pts
			(arc
				(start 421.452802 -277.849838)
				(mid 421.046402 -277.849838)
				(end 421.452802 -277.849838)
			)
		)
		(stroke
			(width 0)
			(type solid)
		)
		(fill yes)
		(layer "In8.Cu")
		(net "P5E_PEX3_STN1_TX_DN<30>")
	)
	(gr_poly
		(pts
			(arc
				(start 421.453056 -318.699896)
				(mid 421.046656 -318.699896)
				(end 421.453056 -318.699896)
			)
		)
		(stroke
			(width 0)
			(type solid)
		)
		(fill yes)
		(layer "In8.Cu")
		(net "P5E_PEX3_STN5_RX_DN<95>")
	)
	(gr_poly
		(pts
			(arc
				(start 421.453056 -317.749936)
				(mid 421.046656 -317.749936)
				(end 421.453056 -317.749936)
			)
		)
		(stroke
			(width 0)
			(type solid)
		)
		(fill yes)
		(layer "In8.Cu")
		(net "P5E_PEX3_STN5_RX_DP<95>")
	)
	(gr_poly
		(pts
			(arc
				(start 421.453056 -313.949842)
				(mid 421.046656 -313.949842)
				(end 421.453056 -313.949842)
			)
		)
		(stroke
			(width 0)
			(type solid)
		)
		(fill yes)
		(layer "In8.Cu")
		(net "P5E_PEX3_STN5_TX_DN<95>")
	)
	(gr_poly
		(pts
			(arc
				(start 421.453056 -312.999882)
				(mid 421.046656 -312.999882)
				(end 421.453056 -312.999882)
			)
		)
		(stroke
			(width 0)
			(type solid)
		)
		(fill yes)
		(layer "In8.Cu")
		(net "P5E_PEX3_STN5_TX_DP<95>")
	)
	(gr_poly
		(pts
			(arc
				(start 422.403016 -280.699464)
				(mid 421.996616 -280.699464)
				(end 422.403016 -280.699464)
			)
		)
		(stroke
			(width 0)
			(type solid)
		)
		(fill yes)
		(layer "In8.Cu")
		(net "P5E_PEX3_STN1_TX_DN<31>")
	)
	(gr_poly
		(pts
			(arc
				(start 422.403016 -279.749504)
				(mid 421.996616 -279.749504)
				(end 422.403016 -279.749504)
			)
		)
		(stroke
			(width 0)
			(type solid)
		)
		(fill yes)
		(layer "In8.Cu")
		(net "P5E_PEX3_STN1_TX_DP<31>")
	)
	(gr_poly
		(pts
			(arc
				(start 423.352976 -278.799798)
				(mid 422.946576 -278.799798)
				(end 423.352976 -278.799798)
			)
		)
		(stroke
			(width 0)
			(type solid)
		)
		(fill yes)
		(layer "In8.Cu")
		(net "P5E_PEX3_STN0_TX_DP<15>")
	)
	(gr_poly
		(pts
			(arc
				(start 423.352976 -277.849838)
				(mid 422.946576 -277.849838)
				(end 423.352976 -277.849838)
			)
		)
		(stroke
			(width 0)
			(type solid)
		)
		(fill yes)
		(layer "In8.Cu")
		(net "P5E_PEX3_STN0_TX_DN<15>")
	)
	(gr_poly
		(pts
			(arc
				(start 423.35323 -287.349946)
				(mid 422.94683 -287.349946)
				(end 423.35323 -287.349946)
			)
		)
		(stroke
			(width 0)
			(type solid)
		)
		(fill yes)
		(layer "In8.Cu")
		(net "P5E_PEX3_STN0_TX_DP<1>")
	)
	(gr_poly
		(pts
			(arc
				(start 423.35323 -285.449772)
				(mid 422.94683 -285.449772)
				(end 423.35323 -285.449772)
			)
		)
		(stroke
			(width 0)
			(type solid)
		)
		(fill yes)
		(layer "In8.Cu")
		(net "P5E_PEX3_STN0_TX_DP<3>")
	)
	(gr_poly
		(pts
			(arc
				(start 423.35323 -283.549852)
				(mid 422.94683 -283.549852)
				(end 423.35323 -283.549852)
			)
		)
		(stroke
			(width 0)
			(type solid)
		)
		(fill yes)
		(layer "In8.Cu")
		(net "P5E_PEX3_STN0_TX_DP<5>")
	)
	(gr_poly
		(pts
			(arc
				(start 424.30319 -287.349946)
				(mid 423.89679 -287.349946)
				(end 424.30319 -287.349946)
			)
		)
		(stroke
			(width 0)
			(type solid)
		)
		(fill yes)
		(layer "In8.Cu")
		(net "P5E_PEX3_STN0_TX_DN<1>")
	)
	(gr_poly
		(pts
			(arc
				(start 424.30319 -285.449772)
				(mid 423.89679 -285.449772)
				(end 424.30319 -285.449772)
			)
		)
		(stroke
			(width 0)
			(type solid)
		)
		(fill yes)
		(layer "In8.Cu")
		(net "P5E_PEX3_STN0_TX_DN<3>")
	)
	(gr_poly
		(pts
			(arc
				(start 424.30319 -283.549852)
				(mid 423.89679 -283.549852)
				(end 424.30319 -283.549852)
			)
		)
		(stroke
			(width 0)
			(type solid)
		)
		(fill yes)
		(layer "In8.Cu")
		(net "P5E_PEX3_STN0_TX_DN<5>")
	)
	(gr_poly
		(pts
			(arc
				(start 424.30319 -280.699464)
				(mid 423.89679 -280.699464)
				(end 424.30319 -280.699464)
			)
		)
		(stroke
			(width 0)
			(type solid)
		)
		(fill yes)
		(layer "In8.Cu")
		(net "P5E_PEX3_STN0_TX_DN<14>")
	)
	(gr_poly
		(pts
			(arc
				(start 424.30319 -279.749504)
				(mid 423.89679 -279.749504)
				(end 424.30319 -279.749504)
			)
		)
		(stroke
			(width 0)
			(type solid)
		)
		(fill yes)
		(layer "In8.Cu")
		(net "P5E_PEX3_STN0_TX_DP<14>")
	)
	(gr_poly
		(pts
			(arc
				(start 425.252896 -278.799798)
				(mid 424.846496 -278.799798)
				(end 425.252896 -278.799798)
			)
		)
		(stroke
			(width 0)
			(type solid)
		)
		(fill yes)
		(layer "In8.Cu")
		(net "P5E_PEX3_STN0_TX_DP<13>")
	)
	(gr_poly
		(pts
			(arc
				(start 425.252896 -277.849838)
				(mid 424.846496 -277.849838)
				(end 425.252896 -277.849838)
			)
		)
		(stroke
			(width 0)
			(type solid)
		)
		(fill yes)
		(layer "In8.Cu")
		(net "P5E_PEX3_STN0_TX_DN<13>")
	)
	(gr_poly
		(pts
			(arc
				(start 425.25315 -288.299906)
				(mid 424.84675 -288.299906)
				(end 425.25315 -288.299906)
			)
		)
		(stroke
			(width 0)
			(type solid)
		)
		(fill yes)
		(layer "In8.Cu")
		(net "P5E_PEX3_STN0_TX_DP<0>")
	)
	(gr_poly
		(pts
			(arc
				(start 425.25315 -286.399986)
				(mid 424.84675 -286.399986)
				(end 425.25315 -286.399986)
			)
		)
		(stroke
			(width 0)
			(type solid)
		)
		(fill yes)
		(layer "In8.Cu")
		(net "P5E_PEX3_STN0_TX_DP<2>")
	)
	(gr_poly
		(pts
			(arc
				(start 425.25315 -284.499812)
				(mid 424.84675 -284.499812)
				(end 425.25315 -284.499812)
			)
		)
		(stroke
			(width 0)
			(type solid)
		)
		(fill yes)
		(layer "In8.Cu")
		(net "P5E_PEX3_STN0_TX_DP<4>")
	)
	(gr_poly
		(pts
			(arc
				(start 425.25315 -282.599892)
				(mid 424.84675 -282.599892)
				(end 425.25315 -282.599892)
			)
		)
		(stroke
			(width 0)
			(type solid)
		)
		(fill yes)
		(layer "In8.Cu")
		(net "P5E_PEX3_STN0_TX_DP<6>")
	)
	(gr_poly
		(pts
			(arc
				(start 426.20311 -288.299906)
				(mid 425.79671 -288.299906)
				(end 426.20311 -288.299906)
			)
		)
		(stroke
			(width 0)
			(type solid)
		)
		(fill yes)
		(layer "In8.Cu")
		(net "P5E_PEX3_STN0_TX_DN<0>")
	)
	(gr_poly
		(pts
			(arc
				(start 426.20311 -286.399986)
				(mid 425.79671 -286.399986)
				(end 426.20311 -286.399986)
			)
		)
		(stroke
			(width 0)
			(type solid)
		)
		(fill yes)
		(layer "In8.Cu")
		(net "P5E_PEX3_STN0_TX_DN<2>")
	)
	(gr_poly
		(pts
			(arc
				(start 426.20311 -284.499812)
				(mid 425.79671 -284.499812)
				(end 426.20311 -284.499812)
			)
		)
		(stroke
			(width 0)
			(type solid)
		)
		(fill yes)
		(layer "In8.Cu")
		(net "P5E_PEX3_STN0_TX_DN<4>")
	)
	(gr_poly
		(pts
			(arc
				(start 426.20311 -282.599892)
				(mid 425.79671 -282.599892)
				(end 426.20311 -282.599892)
			)
		)
		(stroke
			(width 0)
			(type solid)
		)
		(fill yes)
		(layer "In8.Cu")
		(net "P5E_PEX3_STN0_TX_DN<6>")
	)
	(gr_poly
		(pts
			(arc
				(start 426.20311 -280.699464)
				(mid 425.79671 -280.699464)
				(end 426.20311 -280.699464)
			)
		)
		(stroke
			(width 0)
			(type solid)
		)
		(fill yes)
		(layer "In8.Cu")
		(net "P5E_PEX3_STN0_TX_DN<12>")
	)
	(gr_poly
		(pts
			(arc
				(start 426.20311 -279.749504)
				(mid 425.79671 -279.749504)
				(end 426.20311 -279.749504)
			)
		)
		(stroke
			(width 0)
			(type solid)
		)
		(fill yes)
		(layer "In8.Cu")
		(net "P5E_PEX3_STN0_TX_DP<12>")
	)
	(gr_poly
		(pts
			(arc
				(start 427.152816 -278.799798)
				(mid 426.746416 -278.799798)
				(end 427.152816 -278.799798)
			)
		)
		(stroke
			(width 0)
			(type solid)
		)
		(fill yes)
		(layer "In8.Cu")
		(net "P5E_PEX3_STN0_TX_DP<11>")
	)
	(gr_poly
		(pts
			(arc
				(start 427.152816 -277.849838)
				(mid 426.746416 -277.849838)
				(end 427.152816 -277.849838)
			)
		)
		(stroke
			(width 0)
			(type solid)
		)
		(fill yes)
		(layer "In8.Cu")
		(net "P5E_PEX3_STN0_TX_DN<11>")
	)
	(gr_poly
		(pts
			(arc
				(start 428.10303 -280.699718)
				(mid 427.69663 -280.699718)
				(end 428.10303 -280.699718)
			)
		)
		(stroke
			(width 0)
			(type solid)
		)
		(fill yes)
		(layer "In8.Cu")
		(net "P5E_PEX3_STN0_TX_DP<10>")
	)
	(gr_poly
		(pts
			(arc
				(start 428.10303 -279.749758)
				(mid 427.69663 -279.749758)
				(end 428.10303 -279.749758)
			)
		)
		(stroke
			(width 0)
			(type solid)
		)
		(fill yes)
		(layer "In8.Cu")
		(net "P5E_PEX3_STN0_TX_DN<10>")
	)
	(gr_poly
		(pts
			(arc
				(start 429.05299 -278.799798)
				(mid 428.64659 -278.799798)
				(end 429.05299 -278.799798)
			)
		)
		(stroke
			(width 0)
			(type solid)
		)
		(fill yes)
		(layer "In8.Cu")
		(net "P5E_PEX3_STN0_TX_DP<9>")
	)
	(gr_poly
		(pts
			(arc
				(start 429.05299 -277.849838)
				(mid 428.64659 -277.849838)
				(end 429.05299 -277.849838)
			)
		)
		(stroke
			(width 0)
			(type solid)
		)
		(fill yes)
		(layer "In8.Cu")
		(net "P5E_PEX3_STN0_TX_DN<9>")
	)
	(gr_poly
		(pts
			(arc
				(start 430.003204 -279.749758)
				(mid 429.596804 -279.749758)
				(end 430.003204 -279.749758)
			)
		)
		(stroke
			(width 0)
			(type solid)
		)
		(fill yes)
		(layer "In8.Cu")
		(net "P5E_PEX3_STN0_TX_DP<7>")
	)
	(gr_poly
		(pts
			(arc
				(start 430.003204 -276.899878)
				(mid 429.596804 -276.899878)
				(end 430.003204 -276.899878)
			)
		)
		(stroke
			(width 0)
			(type solid)
		)
		(fill yes)
		(layer "In8.Cu")
		(net "P5E_PEX3_STN0_TX_DP<8>")
	)
	(gr_poly
		(pts
			(arc
				(start 430.953164 -279.749758)
				(mid 430.546764 -279.749758)
				(end 430.953164 -279.749758)
			)
		)
		(stroke
			(width 0)
			(type solid)
		)
		(fill yes)
		(layer "In8.Cu")
		(net "P5E_PEX3_STN0_TX_DN<7>")
	)
	(gr_poly
		(pts
			(arc
				(start 430.953164 -276.899878)
				(mid 430.546764 -276.899878)
				(end 430.953164 -276.899878)
			)
		)
		(stroke
			(width 0)
			(type solid)
		)
		(fill yes)
		(layer "In8.Cu")
		(net "P5E_PEX3_STN0_TX_DN<8>")
	)
	(gr_poly
		(pts
			(arc
				(start 241.741198 -376.399806)
				(mid 241.763367 -376.39459)
				(end 241.781076 -376.380248)
			)
			(arc
				(start 241.781076 -376.380248)
				(mid 241.793461 -376.365378)
				(end 241.80673 -376.351292)
			)
			(xy 242.08994 -376.068082)
			(arc
				(start 242.09502 -376.063002)
				(mid 242.106647 -376.046325)
				(end 242.110768 -376.026426)
			)
			(arc
				(start 242.110768 -368.666268)
				(mid 242.106867 -368.646745)
				(end 242.095782 -368.6302)
			)
			(arc
				(start 241.977672 -368.51209)
				(mid 241.961138 -368.500979)
				(end 241.941604 -368.497104)
			)
			(arc
				(start 236.370368 -368.497104)
				(mid 236.350845 -368.501005)
				(end 236.3343 -368.51209)
			)
			(arc
				(start 236.123734 -368.722656)
				(mid 236.112623 -368.73919)
				(end 236.108748 -368.758724)
			)
			(arc
				(start 236.108748 -376.146314)
				(mid 236.112649 -376.165837)
				(end 236.123734 -376.182382)
			)
			(arc
				(start 236.326172 -376.38482)
				(mid 236.342706 -376.395931)
				(end 236.36224 -376.399806)
			)
		)
		(stroke
			(width 0)
			(type solid)
		)
		(fill yes)
		(layer "In8.Cu")
		(net "P12V_STBY_R1")
	)
	(gr_poly
		(pts
			(arc
				(start 235.60151 -413.087058)
				(mid 235.621033 -413.083157)
				(end 235.637578 -413.072072)
			)
			(arc
				(start 236.756956 -411.952694)
				(mid 236.768067 -411.93616)
				(end 236.771942 -411.916626)
			)
			(arc
				(start 236.771942 -402.84527)
				(mid 236.796095 -402.723754)
				(end 236.864906 -402.620734)
			)
			(arc
				(start 238.766604 -400.719036)
				(mid 238.869636 -400.650255)
				(end 238.99114 -400.626072)
			)
			(arc
				(start 242.910868 -400.626072)
				(mid 242.930391 -400.622171)
				(end 242.946936 -400.611086)
			)
			(arc
				(start 243.79682 -399.761202)
				(mid 243.807931 -399.744668)
				(end 243.811806 -399.725134)
			)
			(arc
				(start 243.811806 -392.09472)
				(mid 243.835959 -391.973204)
				(end 243.90477 -391.870184)
			)
			(arc
				(start 244.93093 -390.844024)
				(mid 245.033962 -390.775243)
				(end 245.155466 -390.75106)
			)
			(arc
				(start 259.056124 -390.75106)
				(mid 259.075647 -390.747159)
				(end 259.092192 -390.736074)
			)
			(arc
				(start 262.00481 -387.823456)
				(mid 262.015921 -387.806922)
				(end 262.019796 -387.787388)
			)
			(arc
				(start 262.019796 -379.197616)
				(mid 262.015895 -379.178093)
				(end 262.00481 -379.161548)
			)
			(arc
				(start 261.967472 -379.12421)
				(mid 261.950938 -379.113099)
				(end 261.931404 -379.109224)
			)
			(arc
				(start 240.584482 -379.109224)
				(mid 240.564959 -379.113125)
				(end 240.548414 -379.12421)
			)
			(arc
				(start 239.998504 -379.67412)
				(mid 239.895472 -379.742901)
				(end 239.773968 -379.767084)
			)
			(arc
				(start 237.129066 -379.767084)
				(mid 237.00755 -379.742931)
				(end 236.90453 -379.67412)
			)
			(arc
				(start 232.953814 -375.723404)
				(mid 232.885033 -375.620372)
				(end 232.86085 -375.498868)
			)
			(arc
				(start 232.86085 -372.11508)
				(mid 232.856949 -372.095557)
				(end 232.845864 -372.079012)
			)
			(arc
				(start 232.203752 -371.4369)
				(mid 232.134971 -371.333868)
				(end 232.110788 -371.212364)
			)
			(arc
				(start 232.110788 -371.075712)
				(mid 232.106887 -371.056189)
				(end 232.095802 -371.039644)
			)
			(arc
				(start 232.035858 -370.9797)
				(mid 231.967077 -370.876668)
				(end 231.942894 -370.755164)
			)
			(arc
				(start 231.942894 -367.397792)
				(mid 231.938993 -367.378269)
				(end 231.927908 -367.361724)
			)
			(arc
				(start 231.89057 -367.324386)
				(mid 231.874036 -367.313275)
				(end 231.854502 -367.3094)
			)
			(arc
				(start 228.741986 -367.3094)
				(mid 228.722463 -367.313301)
				(end 228.705918 -367.324386)
			)
			(arc
				(start 228.66858 -367.361724)
				(mid 228.657469 -367.378258)
				(end 228.653594 -367.397792)
			)
			(arc
				(start 228.653594 -370.74856)
				(mid 228.629441 -370.870076)
				(end 228.56063 -370.973096)
			)
			(arc
				(start 228.481128 -371.052598)
				(mid 228.470017 -371.069132)
				(end 228.466142 -371.088666)
			)
			(arc
				(start 228.466142 -371.354096)
				(mid 228.441989 -371.475612)
				(end 228.373178 -371.578632)
			)
			(arc
				(start 227.178362 -372.773448)
				(mid 227.167251 -372.789982)
				(end 227.163376 -372.809516)
			)
			(arc
				(start 227.163376 -374.166384)
				(mid 227.139223 -374.2879)
				(end 227.070412 -374.39092)
			)
			(arc
				(start 225.794062 -375.66727)
				(mid 225.69103 -375.736051)
				(end 225.569526 -375.760234)
			)
			(arc
				(start 223.648016 -375.760234)
				(mid 223.5265 -375.736081)
				(end 223.42348 -375.66727)
			)
			(arc
				(start 221.55531 -373.7991)
				(mid 221.486529 -373.696068)
				(end 221.462346 -373.574564)
			)
			(arc
				(start 221.462346 -371.091714)
				(mid 221.458445 -371.072191)
				(end 221.44736 -371.055646)
			)
			(arc
				(start 221.361508 -370.969794)
				(mid 221.292727 -370.866762)
				(end 221.268544 -370.745258)
			)
			(arc
				(start 221.268544 -367.391442)
				(mid 221.264643 -367.371919)
				(end 221.253558 -367.355374)
			)
			(arc
				(start 221.225872 -367.327688)
				(mid 221.209338 -367.316577)
				(end 221.189804 -367.312702)
			)
			(arc
				(start 218.110308 -367.312702)
				(mid 218.090785 -367.316603)
				(end 218.07424 -367.327688)
			)
			(arc
				(start 217.967306 -367.434622)
				(mid 217.956195 -367.451156)
				(end 217.95232 -367.47069)
			)
			(arc
				(start 217.95232 -370.719096)
				(mid 217.928167 -370.840612)
				(end 217.859356 -370.943632)
			)
			(arc
				(start 216.82964 -371.973348)
				(mid 216.726608 -372.042129)
				(end 216.605104 -372.066312)
			)
			(arc
				(start 210.424014 -372.066312)
				(mid 210.302498 -372.042159)
				(end 210.199478 -371.973348)
			)
			(arc
				(start 210.067906 -371.841776)
				(mid 209.999125 -371.738744)
				(end 209.974942 -371.61724)
			)
			(arc
				(start 209.974942 -371.309138)
				(mid 209.971041 -371.289615)
				(end 209.959956 -371.27307)
			)
			(arc
				(start 209.949034 -371.262148)
				(mid 209.9325 -371.251037)
				(end 209.912966 -371.247162)
			)
			(arc
				(start 209.559144 -371.247162)
				(mid 209.437628 -371.223009)
				(end 209.334608 -371.154198)
			)
			(arc
				(start 208.669382 -370.488972)
				(mid 208.652848 -370.477861)
				(end 208.633314 -370.473986)
			)
			(arc
				(start 208.394554 -370.473986)
				(mid 208.273038 -370.449833)
				(end 208.170018 -370.381022)
			)
			(arc
				(start 208.11744 -370.328444)
				(mid 208.048659 -370.225412)
				(end 208.024476 -370.103908)
			)
			(arc
				(start 208.024476 -367.401348)
				(mid 208.020575 -367.381825)
				(end 208.00949 -367.36528)
			)
			(arc
				(start 207.981804 -367.337594)
				(mid 207.96527 -367.326483)
				(end 207.945736 -367.322608)
			)
			(arc
				(start 204.823822 -367.322608)
				(mid 204.804299 -367.326509)
				(end 204.787754 -367.337594)
			)
			(arc
				(start 204.740002 -367.385346)
				(mid 204.728891 -367.40188)
				(end 204.725016 -367.421414)
			)
			(arc
				(start 204.725016 -370.796312)
				(mid 204.728917 -370.815835)
				(end 204.740002 -370.83238)
			)
			(arc
				(start 204.77353 -370.865908)
				(mid 204.842311 -370.96894)
				(end 204.866494 -371.090444)
			)
			(arc
				(start 204.866494 -374.47474)
				(mid 204.870058 -374.493432)
				(end 204.88021 -374.509538)
			)
			(arc
				(start 204.88021 -374.509538)
				(mid 204.94326 -374.609679)
				(end 204.9653 -374.725946)
			)
			(arc
				(start 204.9653 -387.02361)
				(mid 204.969201 -387.043133)
				(end 204.980286 -387.059678)
			)
			(arc
				(start 207.47482 -389.554212)
				(mid 207.543601 -389.657244)
				(end 207.567784 -389.778748)
			)
			(arc
				(start 207.567784 -411.696662)
				(mid 207.571685 -411.716185)
				(end 207.58277 -411.73273)
			)
			(arc
				(start 208.922112 -413.072072)
				(mid 208.938646 -413.083183)
				(end 208.95818 -413.087058)
			)
		)
		(stroke
			(width 0)
			(type solid)
		)
		(fill yes)
		(layer "In8.Cu")
		(net "P12V_STBY")
	)
	(gr_poly
		(pts
			(xy 465.600034 -461.99552) (xy 465.655841 -461.994997) (xy 465.767141 -461.986654) (xy 465.877508 -461.970017)
			(xy 465.986322 -461.945179) (xy 466.092976 -461.912278) (xy 466.196873 -461.8715) (xy 466.297432 -461.823072)
			(xy 466.394091 -461.767264) (xy 466.48631 -461.70439) (xy 466.573572 -461.6348) (xy 466.65539 -461.558883)
			(xy 466.731306 -461.477065) (xy 466.800896 -461.389802) (xy 466.86377 -461.297583) (xy 466.919577 -461.200923)
			(xy 466.968004 -461.100364) (xy 467.008782 -460.996466) (xy 467.041681 -460.889812) (xy 467.066519 -460.780998)
			(xy 467.083155 -460.670631) (xy 467.091497 -460.559331) (xy 467.09203 -460.503524) (xy 467.09203 -422.58996)
			(xy 467.091507 -422.534153) (xy 467.083163 -422.422853) (xy 467.066526 -422.312487) (xy 467.041687 -422.203672)
			(xy 467.008787 -422.097019) (xy 466.968009 -421.993121) (xy 466.91958 -421.892562) (xy 466.863773 -421.795903)
			(xy 466.800898 -421.703684) (xy 466.731308 -421.616422) (xy 466.655392 -421.534604) (xy 466.573573 -421.458688)
			(xy 466.486311 -421.389098) (xy 466.394092 -421.326224) (xy 466.297433 -421.270417) (xy 466.196873 -421.221989)
			(xy 466.092976 -421.181211) (xy 465.986322 -421.148311) (xy 465.877508 -421.123473) (xy 465.767141 -421.106836)
			(xy 465.655841 -421.098493) (xy 465.600034 -421.097964) (xy 447.939922 -421.097964) (xy 447.884114 -421.098485)
			(xy 447.77281 -421.106824) (xy 447.66244 -421.123458) (xy 447.553622 -421.148293) (xy 447.446964 -421.181191)
			(xy 447.343062 -421.221967) (xy 447.242499 -421.270394) (xy 447.145835 -421.3262) (xy 447.053613 -421.389074)
			(xy 446.966346 -421.458664) (xy 446.884524 -421.53458) (xy 446.808604 -421.616399) (xy 446.739011 -421.703663)
			(xy 446.676133 -421.795883) (xy 446.620323 -421.892544) (xy 446.571892 -421.993106) (xy 446.531111 -422.097005)
			(xy 446.498209 -422.203662) (xy 446.47337 -422.312479) (xy 446.456731 -422.422848) (xy 446.448387 -422.534152)
			(xy 446.447926 -422.58996) (xy 446.447926 -429.090074) (xy 446.447433 -429.160429) (xy 446.439545 -429.300916)
			(xy 446.423792 -429.440741) (xy 446.400224 -429.579462) (xy 446.368915 -429.716643) (xy 446.329963 -429.851854)
			(xy 446.283491 -429.984667) (xy 446.229646 -430.114666) (xy 446.168596 -430.241441) (xy 446.100533 -430.364593)
			(xy 446.025673 -430.483736) (xy 445.94425 -430.598494) (xy 445.856521 -430.708505) (xy 445.762761 -430.813425)
			(xy 445.663266 -430.912922) (xy 445.558348 -431.006684) (xy 445.448338 -431.094416) (xy 445.333582 -431.175842)
			(xy 445.214442 -431.250705) (xy 445.091291 -431.31877) (xy 444.964517 -431.379823) (xy 444.834519 -431.433671)
			(xy 444.701707 -431.480146) (xy 444.566498 -431.519101) (xy 444.429317 -431.550413) (xy 444.290596 -431.573985)
			(xy 444.150772 -431.589741) (xy 444.010285 -431.597632) (xy 443.93993 -431.59807) (xy 371.24005 -431.59807)
			(xy 371.169695 -431.597587) (xy 371.029207 -431.5897) (xy 370.889383 -431.573948) (xy 370.750661 -431.550381)
			(xy 370.613479 -431.519072) (xy 370.478269 -431.480121) (xy 370.345455 -431.433649) (xy 370.215456 -431.379804)
			(xy 370.088681 -431.318754) (xy 369.965528 -431.250691) (xy 369.846385 -431.175831) (xy 369.731628 -431.094407)
			(xy 369.621616 -431.006677) (xy 369.516697 -430.912917) (xy 369.4172 -430.813421) (xy 369.323438 -430.708502)
			(xy 369.235707 -430.598492) (xy 369.154283 -430.483735) (xy 369.079421 -430.364593) (xy 369.011357 -430.241441)
			(xy 368.950306 -430.114666) (xy 368.896459 -429.984667) (xy 368.849986 -429.851854) (xy 368.811034 -429.716644)
			(xy 368.779724 -429.579463) (xy 368.756155 -429.440741) (xy 368.740402 -429.300917) (xy 368.732514 -429.160429)
			(xy 368.732054 -429.090074) (xy 368.732054 -422.58996) (xy 368.731543 -422.534154) (xy 368.7232 -422.422854)
			(xy 368.706562 -422.31249) (xy 368.681723 -422.203677) (xy 368.648822 -422.097024) (xy 368.608042 -421.993129)
			(xy 368.559613 -421.892571) (xy 368.503804 -421.795914) (xy 368.440929 -421.703697) (xy 368.371337 -421.616438)
			(xy 368.29542 -421.534622) (xy 368.2136 -421.458709) (xy 368.126337 -421.389123) (xy 368.034117 -421.326252)
			(xy 367.937456 -421.270449) (xy 367.836896 -421.222025) (xy 367.732998 -421.181251) (xy 367.626344 -421.148356)
			(xy 367.51753 -421.123523) (xy 367.407164 -421.106891) (xy 367.295864 -421.098554) (xy 367.240058 -421.097964)
			(xy 359.940098 -421.097964) (xy 359.88429 -421.098486) (xy 359.772988 -421.106827) (xy 359.662619 -421.123462)
			(xy 359.553802 -421.148298) (xy 359.447146 -421.181197) (xy 359.343246 -421.221974) (xy 359.242684 -421.270401)
			(xy 359.146022 -421.326208) (xy 359.053801 -421.389082) (xy 358.966536 -421.458672) (xy 358.884716 -421.534589)
			(xy 358.808797 -421.616407) (xy 358.739205 -421.70367) (xy 358.676328 -421.79589) (xy 358.620519 -421.892551)
			(xy 358.572089 -421.993111) (xy 358.53131 -422.09701) (xy 358.498408 -422.203666) (xy 358.473569 -422.312482)
			(xy 358.456931 -422.42285) (xy 358.448587 -422.534152) (xy 358.448102 -422.58996) (xy 358.448102 -429.090074)
			(xy 358.447618 -429.160429) (xy 358.43973 -429.300916) (xy 358.423977 -429.440741) (xy 358.400409 -429.579462)
			(xy 358.369099 -429.716643) (xy 358.330147 -429.851853) (xy 358.283675 -429.984667) (xy 358.229829 -430.114665)
			(xy 358.168779 -430.24144) (xy 358.100716 -430.364593) (xy 358.025856 -430.483735) (xy 357.944432 -430.598492)
			(xy 357.856702 -430.708504) (xy 357.762942 -430.813423) (xy 357.663446 -430.91292) (xy 357.558528 -431.006682)
			(xy 357.448518 -431.094413) (xy 357.333762 -431.175838) (xy 357.21462 -431.2507) (xy 357.091469 -431.318764)
			(xy 356.964695 -431.379816) (xy 356.834697 -431.433664) (xy 356.701884 -431.480138) (xy 356.566674 -431.519091)
			(xy 356.429493 -431.550403) (xy 356.290772 -431.573973) (xy 356.150948 -431.589728) (xy 356.010461 -431.597618)
			(xy 355.940106 -431.59807) (xy 283.239972 -431.59807) (xy 283.169619 -431.597576) (xy 283.029135 -431.589685)
			(xy 282.889313 -431.573929) (xy 282.750596 -431.550359) (xy 282.613418 -431.519047) (xy 282.478212 -431.480093)
			(xy 282.345402 -431.43362) (xy 282.215407 -431.379772) (xy 282.088636 -431.318721) (xy 281.965488 -431.250657)
			(xy 281.84635 -431.175796) (xy 281.731596 -431.094372) (xy 281.621589 -431.006642) (xy 281.516674 -430.912882)
			(xy 281.417181 -430.813387) (xy 281.323423 -430.70847) (xy 281.235695 -430.598461) (xy 281.154274 -430.483705)
			(xy 281.079415 -430.364565) (xy 281.011354 -430.241416) (xy 280.950306 -430.114643) (xy 280.896461 -429.984647)
			(xy 280.84999 -429.851837) (xy 280.811039 -429.71663) (xy 280.779731 -429.579451) (xy 280.756163 -429.440733)
			(xy 280.740411 -429.300912) (xy 280.732523 -429.160427) (xy 280.731976 -429.090074) (xy 280.731976 -422.58996)
			(xy 280.731453 -422.534154) (xy 280.723109 -422.422855) (xy 280.706471 -422.31249) (xy 280.681633 -422.203678)
			(xy 280.648732 -422.097025) (xy 280.607953 -421.99313) (xy 280.559525 -421.892573) (xy 280.503717 -421.795915)
			(xy 280.440842 -421.703699) (xy 280.371251 -421.616439) (xy 280.295334 -421.534623) (xy 280.213516 -421.45871)
			(xy 280.126253 -421.389123) (xy 280.034034 -421.326251) (xy 279.937374 -421.270447) (xy 279.836815 -421.222023)
			(xy 279.732918 -421.181248) (xy 279.626264 -421.148352) (xy 279.517451 -421.123517) (xy 279.407085 -421.106884)
			(xy 279.295786 -421.098545) (xy 279.23998 -421.097964) (xy 276.880066 -421.097964) (xy 276.824259 -421.098487)
			(xy 276.712958 -421.10683) (xy 276.602591 -421.123467) (xy 276.493777 -421.148305) (xy 276.387122 -421.181205)
			(xy 276.283225 -421.221984) (xy 276.182665 -421.270412) (xy 276.086005 -421.326219) (xy 275.993786 -421.389094)
			(xy 275.906523 -421.458684) (xy 275.824704 -421.5346) (xy 275.748787 -421.616418) (xy 275.679197 -421.703681)
			(xy 275.616322 -421.7959) (xy 275.560514 -421.892559) (xy 275.512086 -421.993119) (xy 275.471307 -422.097017)
			(xy 275.438407 -422.203671) (xy 275.413568 -422.312485) (xy 275.396931 -422.422852) (xy 275.388587 -422.534153)
			(xy 275.38807 -422.58996) (xy 275.38807 -430.55794) (xy 275.387576 -430.628293) (xy 275.379684 -430.768777)
			(xy 275.363928 -430.908597) (xy 275.340357 -431.047314) (xy 275.309045 -431.184492) (xy 275.27009 -431.319698)
			(xy 275.223616 -431.452506) (xy 275.169769 -431.582501) (xy 275.108717 -431.709271) (xy 275.040653 -431.832419)
			(xy 274.965792 -431.951557) (xy 274.884368 -432.066309) (xy 274.796638 -432.176316) (xy 274.702878 -432.281231)
			(xy 274.603383 -432.380723) (xy 274.498466 -432.474481) (xy 274.388457 -432.562208) (xy 274.273702 -432.643629)
			(xy 274.154562 -432.718487) (xy 274.031412 -432.786547) (xy 273.90464 -432.847596) (xy 273.774645 -432.90144)
			(xy 273.641835 -432.94791) (xy 273.506628 -432.986861) (xy 273.36945 -433.018169) (xy 273.230732 -433.041737)
			(xy 273.090911 -433.05749) (xy 272.950427 -433.065377) (xy 272.880074 -433.065936) (xy 202.360022 -433.065936)
			(xy 202.289667 -433.065443) (xy 202.14918 -433.057555) (xy 202.009355 -433.041802) (xy 201.870634 -433.018234)
			(xy 201.733452 -432.986924) (xy 201.598242 -432.947972) (xy 201.465429 -432.9015) (xy 201.33543 -432.847655)
			(xy 201.208655 -432.786605) (xy 201.085502 -432.718542) (xy 200.96636 -432.643682) (xy 200.851602 -432.562259)
			(xy 200.74159 -432.47453) (xy 200.63667 -432.38077) (xy 200.537173 -432.281275) (xy 200.44341 -432.176357)
			(xy 200.355678 -432.066348) (xy 200.274252 -431.951592) (xy 200.199389 -431.832451) (xy 200.131324 -431.7093)
			(xy 200.070271 -431.582527) (xy 200.016422 -431.452529) (xy 199.969947 -431.319717) (xy 199.930991 -431.184508)
			(xy 199.899679 -431.047327) (xy 199.876107 -430.908606) (xy 199.86035 -430.768782) (xy 199.852458 -430.628295)
			(xy 199.852026 -430.55794) (xy 199.852026 -422.58996) (xy 199.851503 -422.534154) (xy 199.843159 -422.422853)
			(xy 199.826522 -422.312487) (xy 199.801683 -422.203673) (xy 199.768783 -422.097019) (xy 199.728004 -421.993122)
			(xy 199.679576 -421.892563) (xy 199.623769 -421.795904) (xy 199.560894 -421.703685) (xy 199.491304 -421.616423)
			(xy 199.415387 -421.534606) (xy 199.333569 -421.45869) (xy 199.246306 -421.3891) (xy 199.154088 -421.326226)
			(xy 199.057428 -421.270419) (xy 198.956869 -421.221992) (xy 198.852972 -421.181214) (xy 198.746318 -421.148314)
			(xy 198.637503 -421.123476) (xy 198.527137 -421.10684) (xy 198.415836 -421.098497) (xy 198.36003 -421.097964)
			(xy 188.36005 -421.097964) (xy 188.304244 -421.098488) (xy 188.192943 -421.106832) (xy 188.082578 -421.12347)
			(xy 187.973764 -421.148309) (xy 187.86711 -421.18121) (xy 187.763214 -421.221988) (xy 187.662655 -421.270417)
			(xy 187.565996 -421.326225) (xy 187.473778 -421.389099) (xy 187.386516 -421.458689) (xy 187.304699 -421.534606)
			(xy 187.228783 -421.616424) (xy 187.159193 -421.703686) (xy 187.096319 -421.795905) (xy 187.040512 -421.892564)
			(xy 186.992084 -421.993123) (xy 186.951306 -422.09702) (xy 186.918406 -422.203673) (xy 186.893568 -422.312487)
			(xy 186.876931 -422.422853) (xy 186.868587 -422.534154) (xy 186.868054 -422.58996) (xy 186.868054 -429.090074)
			(xy 186.86757 -429.160428) (xy 186.859682 -429.300915) (xy 186.843929 -429.440738) (xy 186.820361 -429.579458)
			(xy 186.789051 -429.716639) (xy 186.750099 -429.851848) (xy 186.703626 -429.98466) (xy 186.64978 -430.114658)
			(xy 186.58873 -430.241431) (xy 186.520667 -430.364582) (xy 186.445806 -430.483723) (xy 186.364382 -430.598479)
			(xy 186.276652 -430.708489) (xy 186.182891 -430.813407) (xy 186.083395 -430.912902) (xy 185.978477 -431.006662)
			(xy 185.868467 -431.094392) (xy 185.75371 -431.175815) (xy 185.634569 -431.250675) (xy 185.511417 -431.318737)
			(xy 185.384643 -431.379787) (xy 185.254645 -431.433632) (xy 185.121833 -431.480104) (xy 184.986623 -431.519055)
			(xy 184.849443 -431.550364) (xy 184.710722 -431.573931) (xy 184.570899 -431.589684) (xy 184.430412 -431.597571)
			(xy 184.360058 -431.59807) (xy 111.660178 -431.59807) (xy 111.589825 -431.597585) (xy 111.449339 -431.589694)
			(xy 111.309518 -431.573939) (xy 111.170799 -431.550369) (xy 111.033621 -431.519057) (xy 110.898414 -431.480103)
			(xy 110.765603 -431.43363) (xy 110.635608 -431.379782) (xy 110.508836 -431.318731) (xy 110.385687 -431.250667)
			(xy 110.266548 -431.175806) (xy 110.151794 -431.094382) (xy 110.041786 -431.006651) (xy 109.93687 -430.912891)
			(xy 109.837376 -430.813395) (xy 109.743618 -430.708478) (xy 109.65589 -430.598468) (xy 109.574468 -430.483712)
			(xy 109.499608 -430.364572) (xy 109.431547 -430.241421) (xy 109.370498 -430.114648) (xy 109.316653 -429.984652)
			(xy 109.270182 -429.851841) (xy 109.231231 -429.716633) (xy 109.199922 -429.579454) (xy 109.176354 -429.440735)
			(xy 109.160602 -429.300913) (xy 109.152714 -429.160427) (xy 109.152182 -429.090074) (xy 109.152182 -422.58996)
			(xy 109.151659 -422.534154) (xy 109.143315 -422.422855) (xy 109.126678 -422.31249) (xy 109.101839 -422.203677)
			(xy 109.068938 -422.097025) (xy 109.02816 -421.993129) (xy 108.979731 -421.892571) (xy 108.923923 -421.795914)
			(xy 108.861048 -421.703697) (xy 108.791457 -421.616437) (xy 108.715541 -421.534621) (xy 108.633722 -421.458707)
			(xy 108.546459 -421.38912) (xy 108.45424 -421.326248) (xy 108.357581 -421.270444) (xy 108.257021 -421.222019)
			(xy 108.153124 -421.181244) (xy 108.046471 -421.148347) (xy 107.937657 -421.123512) (xy 107.827292 -421.106879)
			(xy 107.715992 -421.098539) (xy 107.660186 -421.097964) (xy 100.359972 -421.097964) (xy 100.304165 -421.098487)
			(xy 100.192864 -421.106829) (xy 100.082497 -421.123466) (xy 99.973681 -421.148304) (xy 99.867027 -421.181204)
			(xy 99.763129 -421.221982) (xy 99.662568 -421.27041) (xy 99.565908 -421.326217) (xy 99.473689 -421.389091)
			(xy 99.386425 -421.458681) (xy 99.304606 -421.534598) (xy 99.228689 -421.616416) (xy 99.159099 -421.703679)
			(xy 99.096223 -421.795898) (xy 99.040415 -421.892558) (xy 98.991987 -421.993118) (xy 98.951208 -422.097015)
			(xy 98.918307 -422.20367) (xy 98.893468 -422.312485) (xy 98.876831 -422.422852) (xy 98.868487 -422.534153)
			(xy 98.867976 -422.58996) (xy 98.867976 -429.090074) (xy 98.867492 -429.160428) (xy 98.859604 -429.300915)
			(xy 98.843851 -429.440739) (xy 98.820283 -429.57946) (xy 98.788973 -429.716641) (xy 98.750021 -429.85185)
			(xy 98.703549 -429.984663) (xy 98.649703 -430.114661) (xy 98.588652 -430.241435) (xy 98.520589 -430.364587)
			(xy 98.445729 -430.483729) (xy 98.364305 -430.598485) (xy 98.276575 -430.708496) (xy 98.182814 -430.813414)
			(xy 98.083319 -430.91291) (xy 97.9784 -431.006671) (xy 97.86839 -431.094401) (xy 97.753634 -431.175825)
			(xy 97.634492 -431.250686) (xy 97.511341 -431.31875) (xy 97.384567 -431.3798) (xy 97.254569 -431.433647)
			(xy 97.121756 -431.480119) (xy 96.986547 -431.519072) (xy 96.849366 -431.550382) (xy 96.710645 -431.57395)
			(xy 96.570821 -431.589704) (xy 96.430334 -431.597592) (xy 96.35998 -431.59807) (xy 23.6601 -431.59807)
			(xy 23.589746 -431.597586) (xy 23.44926 -431.589696) (xy 23.309437 -431.573942) (xy 23.170718 -431.550372)
			(xy 23.033539 -431.519062) (xy 22.89833 -431.480109) (xy 22.765519 -431.433636) (xy 22.635522 -431.379789)
			(xy 22.50875 -431.318738) (xy 22.385599 -431.250675) (xy 22.266459 -431.175813) (xy 22.151704 -431.094389)
			(xy 22.041695 -431.006659) (xy 21.936778 -430.912899) (xy 21.837283 -430.813403) (xy 21.743524 -430.708485)
			(xy 21.655795 -430.598475) (xy 21.574372 -430.483719) (xy 21.499512 -430.364578) (xy 21.43145 -430.241427)
			(xy 21.370401 -430.114654) (xy 21.316555 -429.984657) (xy 21.270083 -429.851845) (xy 21.231132 -429.716636)
			(xy 21.199823 -429.579456) (xy 21.176255 -429.440737) (xy 21.160502 -429.300914) (xy 21.152614 -429.160428)
			(xy 21.152104 -429.090074) (xy 21.152104 -422.58996) (xy 21.151595 -422.534153) (xy 21.143254 -422.42285)
			(xy 21.126618 -422.312481) (xy 21.101782 -422.203665) (xy 21.068883 -422.097009) (xy 21.028105 -421.993109)
			(xy 20.979677 -421.892548) (xy 20.92387 -421.795886) (xy 20.860995 -421.703666) (xy 20.791404 -421.616402)
			(xy 20.715486 -421.534582) (xy 20.633667 -421.458665) (xy 20.546403 -421.389074) (xy 20.454182 -421.326199)
			(xy 20.357521 -421.270392) (xy 20.256959 -421.221964) (xy 20.153059 -421.181187) (xy 20.046403 -421.148288)
			(xy 19.937587 -421.123451) (xy 19.827218 -421.106816) (xy 19.715915 -421.098475) (xy 19.660108 -421.097964)
			(xy 1.999996 -421.097964) (xy 1.944189 -421.098486) (xy 1.832887 -421.106827) (xy 1.72252 -421.123463)
			(xy 1.613705 -421.148299) (xy 1.50705 -421.181198) (xy 1.403151 -421.221976) (xy 1.302591 -421.270403)
			(xy 1.20593 -421.32621) (xy 1.113711 -421.389085) (xy 1.026448 -421.458675) (xy 0.944629 -421.534592)
			(xy 0.868712 -421.616411) (xy 0.799122 -421.703674) (xy 0.736248 -421.795894) (xy 0.680441 -421.892554)
			(xy 0.632014 -421.993115) (xy 0.591237 -422.097013) (xy 0.558338 -422.203669) (xy 0.533502 -422.312484)
			(xy 0.516867 -422.422851) (xy 0.508526 -422.534153) (xy 0.508 -422.58996) (xy 0.508 -457.5681) (xy 2.904225 -457.5681)
			(xy 2.904225 -457.43896) (xy 2.912175 -457.310065) (xy 2.928045 -457.181905) (xy 2.951774 -457.054964)
			(xy 2.983273 -456.929725) (xy 3.022422 -456.806662) (xy 3.069073 -456.686243) (xy 3.123048 -456.568924)
			(xy 3.184143 -456.45515) (xy 3.252126 -456.345353) (xy 3.32674 -456.23995) (xy 3.407701 -456.13934)
			(xy 3.494701 -456.043905) (xy 3.587412 -455.954006) (xy 3.685482 -455.869985) (xy 3.788537 -455.792161)
			(xy 3.896188 -455.720829) (xy 4.008027 -455.656259) (xy 4.123628 -455.598697) (xy 4.242553 -455.54836)
			(xy 4.364352 -455.50544) (xy 4.488562 -455.470099) (xy 4.614711 -455.442472) (xy 4.742323 -455.422663)
			(xy 4.870912 -455.410747) (xy 4.99999 -455.406771) (xy 5.129068 -455.410747) (xy 5.257657 -455.422663)
			(xy 5.385269 -455.442472) (xy 5.511418 -455.470099) (xy 5.635628 -455.50544) (xy 5.757427 -455.54836)
			(xy 5.876352 -455.598697) (xy 5.991953 -455.656259) (xy 6.103792 -455.720829) (xy 6.211443 -455.792161)
			(xy 6.314498 -455.869985) (xy 6.412568 -455.954006) (xy 6.505279 -456.043905) (xy 6.592279 -456.13934)
			(xy 6.67324 -456.23995) (xy 6.747854 -456.345353) (xy 6.815837 -456.45515) (xy 6.876932 -456.568924)
			(xy 6.930907 -456.686243) (xy 6.977558 -456.806662) (xy 7.016707 -456.929725) (xy 7.048206 -457.054964)
			(xy 7.071935 -457.181905) (xy 7.087805 -457.310065) (xy 7.095755 -457.43896) (xy 7.096252 -457.50353)
			(xy 7.095755 -457.5681) (xy 460.504275 -457.5681) (xy 460.504275 -457.43896) (xy 460.512225 -457.310065)
			(xy 460.528095 -457.181905) (xy 460.551824 -457.054964) (xy 460.583323 -456.929725) (xy 460.622472 -456.806662)
			(xy 460.669123 -456.686243) (xy 460.723098 -456.568924) (xy 460.784193 -456.45515) (xy 460.852176 -456.345353)
			(xy 460.92679 -456.23995) (xy 461.007751 -456.13934) (xy 461.094751 -456.043905) (xy 461.187462 -455.954006)
			(xy 461.285532 -455.869985) (xy 461.388587 -455.792161) (xy 461.496238 -455.720829) (xy 461.608077 -455.656259)
			(xy 461.723678 -455.598697) (xy 461.842603 -455.54836) (xy 461.964402 -455.50544) (xy 462.088612 -455.470099)
			(xy 462.214761 -455.442472) (xy 462.342373 -455.422663) (xy 462.470962 -455.410747) (xy 462.60004 -455.406771)
			(xy 462.729118 -455.410747) (xy 462.857707 -455.422663) (xy 462.985319 -455.442472) (xy 463.111468 -455.470099)
			(xy 463.235678 -455.50544) (xy 463.357477 -455.54836) (xy 463.476402 -455.598697) (xy 463.592003 -455.656259)
			(xy 463.703842 -455.720829) (xy 463.811493 -455.792161) (xy 463.914548 -455.869985) (xy 464.012618 -455.954006)
			(xy 464.105329 -456.043905) (xy 464.192329 -456.13934) (xy 464.27329 -456.23995) (xy 464.347904 -456.345353)
			(xy 464.415887 -456.45515) (xy 464.476982 -456.568924) (xy 464.530957 -456.686243) (xy 464.577608 -456.806662)
			(xy 464.616757 -456.929725) (xy 464.648256 -457.054964) (xy 464.671985 -457.181905) (xy 464.687855 -457.310065)
			(xy 464.695805 -457.43896) (xy 464.696302 -457.50353) (xy 464.695805 -457.5681) (xy 464.687855 -457.696995)
			(xy 464.671985 -457.825155) (xy 464.648256 -457.952096) (xy 464.616757 -458.077335) (xy 464.577608 -458.200398)
			(xy 464.530957 -458.320817) (xy 464.476982 -458.438136) (xy 464.415887 -458.55191) (xy 464.347904 -458.661707)
			(xy 464.27329 -458.76711) (xy 464.192329 -458.86772) (xy 464.105329 -458.963155) (xy 464.012618 -459.053054)
			(xy 463.914548 -459.137075) (xy 463.811493 -459.214899) (xy 463.703842 -459.286231) (xy 463.592003 -459.350801)
			(xy 463.476402 -459.408363) (xy 463.357477 -459.4587) (xy 463.235678 -459.50162) (xy 463.111468 -459.536961)
			(xy 462.985319 -459.564588) (xy 462.857707 -459.584397) (xy 462.729118 -459.596313) (xy 462.60004 -459.60029)
			(xy 462.470962 -459.596313) (xy 462.342373 -459.584397) (xy 462.214761 -459.564588) (xy 462.088612 -459.536961)
			(xy 461.964402 -459.50162) (xy 461.842603 -459.4587) (xy 461.723678 -459.408363) (xy 461.608077 -459.350801)
			(xy 461.496238 -459.286231) (xy 461.388587 -459.214899) (xy 461.285532 -459.137075) (xy 461.187462 -459.053054)
			(xy 461.094751 -458.963155) (xy 461.007751 -458.86772) (xy 460.92679 -458.76711) (xy 460.852176 -458.661707)
			(xy 460.784193 -458.55191) (xy 460.723098 -458.438136) (xy 460.669123 -458.320817) (xy 460.622472 -458.200398)
			(xy 460.583323 -458.077335) (xy 460.551824 -457.952096) (xy 460.528095 -457.825155) (xy 460.512225 -457.696995)
			(xy 460.504275 -457.5681) (xy 7.095755 -457.5681) (xy 7.087805 -457.696995) (xy 7.071935 -457.825155)
			(xy 7.048206 -457.952096) (xy 7.016707 -458.077335) (xy 6.977558 -458.200398) (xy 6.930907 -458.320817)
			(xy 6.876932 -458.438136) (xy 6.815837 -458.55191) (xy 6.747854 -458.661707) (xy 6.67324 -458.76711)
			(xy 6.592279 -458.86772) (xy 6.505279 -458.963155) (xy 6.412568 -459.053054) (xy 6.314498 -459.137075)
			(xy 6.211443 -459.214899) (xy 6.103792 -459.286231) (xy 5.991953 -459.350801) (xy 5.876352 -459.408363)
			(xy 5.757427 -459.4587) (xy 5.635628 -459.50162) (xy 5.511418 -459.536961) (xy 5.385269 -459.564588)
			(xy 5.257657 -459.584397) (xy 5.129068 -459.596313) (xy 4.99999 -459.60029) (xy 4.870912 -459.596313)
			(xy 4.742323 -459.584397) (xy 4.614711 -459.564588) (xy 4.488562 -459.536961) (xy 4.364352 -459.50162)
			(xy 4.242553 -459.4587) (xy 4.123628 -459.408363) (xy 4.008027 -459.350801) (xy 3.896188 -459.286231)
			(xy 3.788537 -459.214899) (xy 3.685482 -459.137075) (xy 3.587412 -459.053054) (xy 3.494701 -458.963155)
			(xy 3.407701 -458.86772) (xy 3.32674 -458.76711) (xy 3.252126 -458.661707) (xy 3.184143 -458.55191)
			(xy 3.123048 -458.438136) (xy 3.069073 -458.320817) (xy 3.022422 -458.200398) (xy 2.983273 -458.077335)
			(xy 2.951774 -457.952096) (xy 2.928045 -457.825155) (xy 2.912175 -457.696995) (xy 2.904225 -457.5681)
			(xy 0.508 -457.5681) (xy 0.508 -460.503524) (xy 0.508522 -460.559331) (xy 0.516863 -460.670633) (xy 0.533498 -460.781)
			(xy 0.558335 -460.889816) (xy 0.591234 -460.996471) (xy 0.632011 -461.10037) (xy 0.680438 -461.20093)
			(xy 0.736246 -461.297591) (xy 0.79912 -461.389811) (xy 0.86871 -461.477074) (xy 0.944627 -461.558893)
			(xy 1.026446 -461.63481) (xy 1.113709 -461.7044) (xy 1.205929 -461.767274) (xy 1.30259 -461.823082)
			(xy 1.40315 -461.871509) (xy 1.507049 -461.912286) (xy 1.613704 -461.945185) (xy 1.72252 -461.970022)
			(xy 1.832887 -461.986657) (xy 1.944189 -461.994998) (xy 1.999996 -461.99552)
		)
		(stroke
			(width 0)
			(type solid)
		)
		(fill yes)
		(layer "In8.Cu")
		(net "COUPON_GND1")
	)
	(gr_poly
		(pts
			(xy 13.96492 -10.342118) (xy 14.020727 -10.341596) (xy 14.132028 -10.333253) (xy 14.242395 -10.316617)
			(xy 14.35121 -10.29178) (xy 14.457865 -10.25888) (xy 14.561763 -10.218102) (xy 14.662323 -10.169674)
			(xy 14.758983 -10.113867) (xy 14.851203 -10.050993) (xy 14.938466 -9.981402) (xy 15.020284 -9.905486)
			(xy 15.096201 -9.823667) (xy 15.165791 -9.736404) (xy 15.228666 -9.644185) (xy 15.284473 -9.547525)
			(xy 15.332901 -9.446965) (xy 15.373679 -9.343067) (xy 15.406579 -9.236412) (xy 15.431417 -9.127597)
			(xy 15.448053 -9.01723) (xy 15.456395 -8.905929) (xy 15.456916 -8.850122) (xy 15.456916 0) (xy 15.4574 0.070354)
			(xy 15.46529 0.21084) (xy 15.481044 0.350663) (xy 15.504614 0.489383) (xy 15.535924 0.626563) (xy 15.574877 0.761771)
			(xy 15.62135 0.894583) (xy 15.675197 1.02458) (xy 15.736248 1.151353) (xy 15.804311 1.274504) (xy 15.879172 1.393644)
			(xy 15.960596 1.5084) (xy 16.048326 1.618409) (xy 16.142086 1.723327) (xy 16.241582 1.822822) (xy 16.3465 1.916582)
			(xy 16.45651 2.004311) (xy 16.571266 2.085734) (xy 16.690407 2.160595) (xy 16.813558 2.228658) (xy 16.940331 2.289708)
			(xy 17.070328 2.343554) (xy 17.20314 2.390026) (xy 17.338349 2.428979) (xy 17.475529 2.460289) (xy 17.614249 2.483858)
			(xy 17.754072 2.499611) (xy 17.894558 2.5075) (xy 17.964912 2.507996) (xy 33.96488 2.507996) (xy 34.035234 2.507512)
			(xy 34.175722 2.499624) (xy 34.315546 2.48387) (xy 34.454267 2.460302) (xy 34.591448 2.428992) (xy 34.726657 2.39004)
			(xy 34.85947 2.343568) (xy 34.989468 2.289721) (xy 35.116243 2.228671) (xy 35.239395 2.160608) (xy 35.358537 2.085747)
			(xy 35.473294 2.004324) (xy 35.583304 1.916594) (xy 35.688223 1.822833) (xy 35.78772 1.723338) (xy 35.881481 1.61842)
			(xy 35.969212 1.50841) (xy 36.050636 1.393653) (xy 36.125498 1.274512) (xy 36.193562 1.151361) (xy 36.254613 1.024587)
			(xy 36.30846 0.894589) (xy 36.354934 0.761776) (xy 36.393887 0.626567) (xy 36.425198 0.489386) (xy 36.448768 0.350666)
			(xy 36.464522 0.210842) (xy 36.472412 0.070354) (xy 36.472876 0) (xy 36.472876 -8.850122) (xy 36.473399 -8.905929)
			(xy 36.481741 -9.01723) (xy 36.498377 -9.127597) (xy 36.523215 -9.236413) (xy 36.556114 -9.343067)
			(xy 36.596892 -9.446965) (xy 36.64532 -9.547526) (xy 36.701127 -9.644186) (xy 36.764002 -9.736405)
			(xy 36.833592 -9.823668) (xy 36.909508 -9.905487) (xy 36.991327 -9.981404) (xy 37.07859 -10.050995)
			(xy 37.170809 -10.113869) (xy 37.267469 -10.169677) (xy 37.368029 -10.218105) (xy 37.471927 -10.258884)
			(xy 37.578582 -10.291784) (xy 37.687397 -10.316622) (xy 37.797764 -10.333258) (xy 37.909065 -10.341601)
			(xy 37.964872 -10.342118) (xy 39.965122 -10.342118) (xy 40.020929 -10.341595) (xy 40.13223 -10.333253)
			(xy 40.242597 -10.316617) (xy 40.351412 -10.291779) (xy 40.458067 -10.258879) (xy 40.561964 -10.218102)
			(xy 40.662525 -10.169674) (xy 40.759184 -10.113866) (xy 40.851404 -10.050992) (xy 40.938667 -9.981402)
			(xy 41.020485 -9.905485) (xy 41.096402 -9.823667) (xy 41.165992 -9.736404) (xy 41.228866 -9.644184)
			(xy 41.284674 -9.547525) (xy 41.333102 -9.446964) (xy 41.373879 -9.343067) (xy 41.406779 -9.236412)
			(xy 41.431617 -9.127597) (xy 41.448253 -9.01723) (xy 41.456595 -8.905929) (xy 41.457118 -8.850122)
			(xy 41.457118 0) (xy 41.457602 0.070354) (xy 41.465492 0.21084) (xy 41.481246 0.350663) (xy 41.504816 0.489383)
			(xy 41.536126 0.626563) (xy 41.575079 0.761771) (xy 41.621552 0.894583) (xy 41.675399 1.02458) (xy 41.73645 1.151353)
			(xy 41.804513 1.274503) (xy 41.879374 1.393644) (xy 41.960798 1.508399) (xy 42.048528 1.618409) (xy 42.142288 1.723326)
			(xy 42.241784 1.822821) (xy 42.346702 1.916581) (xy 42.456712 2.00431) (xy 42.571468 2.085733) (xy 42.690609 2.160594)
			(xy 42.81376 2.228657) (xy 42.940533 2.289707) (xy 43.07053 2.343553) (xy 43.203342 2.390025) (xy 43.338551 2.428977)
			(xy 43.475731 2.460287) (xy 43.614451 2.483856) (xy 43.754274 2.499609) (xy 43.89476 2.507498) (xy 43.965114 2.507996)
			(xy 59.965082 2.507996) (xy 60.035436 2.507512) (xy 60.175924 2.499624) (xy 60.315748 2.48387) (xy 60.454468 2.460301)
			(xy 60.591649 2.428992) (xy 60.726859 2.390039) (xy 60.859672 2.343567) (xy 60.98967 2.289721) (xy 61.116444 2.22867)
			(xy 61.239596 2.160607) (xy 61.358738 2.085747) (xy 61.473495 2.004323) (xy 61.583505 1.916593) (xy 61.688424 1.822833)
			(xy 61.78792 1.723337) (xy 61.881681 1.618419) (xy 61.969412 1.508409) (xy 62.050837 1.393653) (xy 62.125698 1.274512)
			(xy 62.193762 1.15136) (xy 62.254813 1.024586) (xy 62.308661 0.894588) (xy 62.355134 0.761776) (xy 62.394087 0.626567)
			(xy 62.425398 0.489386) (xy 62.448968 0.350665) (xy 62.464722 0.210842) (xy 62.472612 0.070354) (xy 62.473078 0)
			(xy 62.473078 -8.850122) (xy 62.473601 -8.905929) (xy 62.481943 -9.01723) (xy 62.498579 -9.127597)
			(xy 62.523417 -9.236412) (xy 62.556316 -9.343067) (xy 62.597094 -9.446965) (xy 62.645522 -9.547525)
			(xy 62.701329 -9.644185) (xy 62.764204 -9.736405) (xy 62.833794 -9.823668) (xy 62.909711 -9.905487)
			(xy 62.991529 -9.981403) (xy 63.078792 -10.050994) (xy 63.171011 -10.113868) (xy 63.267671 -10.169676)
			(xy 63.368231 -10.218104) (xy 63.472129 -10.258882) (xy 63.578784 -10.291782) (xy 63.687599 -10.31662)
			(xy 63.797966 -10.333257) (xy 63.909267 -10.341599) (xy 63.965074 -10.342118) (xy 65.96507 -10.342118)
			(xy 66.020879 -10.34161) (xy 66.132184 -10.333271) (xy 66.242554 -10.316637) (xy 66.351373 -10.291802)
			(xy 66.458032 -10.258905) (xy 66.561934 -10.218128) (xy 66.662499 -10.169702) (xy 66.759163 -10.113895)
			(xy 66.851386 -10.05102) (xy 66.938653 -9.98143) (xy 67.020476 -9.905512) (xy 67.096396 -9.823693)
			(xy 67.165989 -9.736428) (xy 67.228867 -9.644207) (xy 67.284677 -9.547545) (xy 67.333108 -9.446982)
			(xy 67.373888 -9.343081) (xy 67.406789 -9.236424) (xy 67.431628 -9.127605) (xy 67.448265 -9.017235)
			(xy 67.456608 -8.905931) (xy 67.457066 -8.850122) (xy 67.457066 0) (xy 67.457559 0.070354) (xy 67.465449 0.210841)
			(xy 67.481203 0.350665) (xy 67.504772 0.489385) (xy 67.536082 0.626565) (xy 67.575035 0.761774) (xy 67.621508 0.894587)
			(xy 67.675354 1.024584) (xy 67.736404 1.151358) (xy 67.804467 1.27451) (xy 67.879328 1.393651) (xy 67.960751 1.508408)
			(xy 68.04848 1.618419) (xy 68.14224 1.723337) (xy 68.241735 1.822834) (xy 68.346652 1.916595) (xy 68.456662 2.004326)
			(xy 68.571417 2.085751) (xy 68.690557 2.160614) (xy 68.813708 2.228678) (xy 68.940481 2.289731) (xy 69.070478 2.343579)
			(xy 69.203289 2.390053) (xy 69.338498 2.429008) (xy 69.475678 2.46032) (xy 69.614398 2.483892) (xy 69.754221 2.499648)
			(xy 69.894708 2.50754) (xy 69.965062 2.507996) (xy 85.96503 2.507996) (xy 86.035383 2.507502) (xy 86.175868 2.499611)
			(xy 86.31569 2.483855) (xy 86.454408 2.460284) (xy 86.591586 2.428973) (xy 86.726793 2.390019) (xy 86.859603 2.343545)
			(xy 86.989598 2.289698) (xy 87.11637 2.228647) (xy 87.239519 2.160584) (xy 87.358658 2.085722) (xy 87.473412 2.004299)
			(xy 87.58342 1.916569) (xy 87.688336 1.822809) (xy 87.78783 1.723314) (xy 87.881588 1.618397) (xy 87.969317 1.508388)
			(xy 88.050739 1.393633) (xy 88.125599 1.274493) (xy 88.193661 1.151343) (xy 88.254711 1.024571) (xy 88.308556 0.894575)
			(xy 88.355028 0.761764) (xy 88.39398 0.626557) (xy 88.42529 0.489378) (xy 88.448859 0.35066) (xy 88.464613 0.210838)
			(xy 88.472503 0.070353) (xy 88.473026 0) (xy 88.473026 -8.850122) (xy 88.473549 -8.905928) (xy 88.481891 -9.017228)
			(xy 88.498528 -9.127594) (xy 88.523365 -9.236408) (xy 88.556265 -9.343061) (xy 88.597043 -9.446957)
			(xy 88.645472 -9.547516) (xy 88.701279 -9.644174) (xy 88.764154 -9.736392) (xy 88.833745 -9.823653)
			(xy 88.909662 -9.90547) (xy 88.99148 -9.981384) (xy 89.078743 -10.050972) (xy 89.170963 -10.113844)
			(xy 89.267623 -10.169649) (xy 89.368183 -10.218074) (xy 89.472081 -10.258849) (xy 89.578735 -10.291746)
			(xy 89.687549 -10.316581) (xy 89.797915 -10.333214) (xy 89.909216 -10.341553) (xy 89.965022 -10.342118)
			(xy 91.965018 -10.342118) (xy 92.020825 -10.341596) (xy 92.132127 -10.333254) (xy 92.242494 -10.316617)
			(xy 92.351309 -10.29178) (xy 92.457964 -10.258881) (xy 92.561862 -10.218103) (xy 92.662422 -10.169675)
			(xy 92.759082 -10.113868) (xy 92.851302 -10.050993) (xy 92.938565 -9.981403) (xy 93.020384 -9.905487)
			(xy 93.096301 -9.823668) (xy 93.165891 -9.736405) (xy 93.228766 -9.644186) (xy 93.284573 -9.547526)
			(xy 93.333001 -9.446965) (xy 93.373779 -9.343067) (xy 93.406679 -9.236413) (xy 93.431517 -9.127597)
			(xy 93.448153 -9.01723) (xy 93.456495 -8.905929) (xy 93.457014 -8.850122) (xy 93.457014 0) (xy 93.457498 0.070354)
			(xy 93.465388 0.21084) (xy 93.481142 0.350663) (xy 93.504712 0.489383) (xy 93.536022 0.626563) (xy 93.574975 0.761771)
			(xy 93.621448 0.894583) (xy 93.675295 1.02458) (xy 93.736346 1.151353) (xy 93.804409 1.274504) (xy 93.87927 1.393645)
			(xy 93.960694 1.5084) (xy 94.048424 1.61841) (xy 94.142184 1.723327) (xy 94.24168 1.822823) (xy 94.346598 1.916583)
			(xy 94.456608 2.004312) (xy 94.571364 2.085735) (xy 94.690505 2.160596) (xy 94.813655 2.228659) (xy 94.940429 2.289709)
			(xy 95.070426 2.343555) (xy 95.203238 2.390028) (xy 95.338447 2.42898) (xy 95.475627 2.46029) (xy 95.614347 2.483859)
			(xy 95.75417 2.499613) (xy 95.894656 2.507502) (xy 95.96501 2.507996) (xy 124.06503 2.507996) (xy 124.135383 2.507502)
			(xy 124.275868 2.499611) (xy 124.41569 2.483855) (xy 124.554408 2.460284) (xy 124.691586 2.428973)
			(xy 124.826793 2.390019) (xy 124.959603 2.343545) (xy 125.089598 2.289698) (xy 125.21637 2.228647)
			(xy 125.339519 2.160584) (xy 125.458658 2.085722) (xy 125.573412 2.004299) (xy 125.68342 1.916569)
			(xy 125.788336 1.822809) (xy 125.88783 1.723314) (xy 125.981588 1.618397) (xy 126.069317 1.508388)
			(xy 126.150739 1.393633) (xy 126.225599 1.274493) (xy 126.293661 1.151343) (xy 126.354711 1.024571)
			(xy 126.408556 0.894575) (xy 126.455028 0.761764) (xy 126.49398 0.626557) (xy 126.52529 0.489378)
			(xy 126.548859 0.35066) (xy 126.564613 0.210838) (xy 126.572503 0.070353) (xy 126.573026 0) (xy 126.573026 -8.850122)
			(xy 126.573549 -8.905928) (xy 126.581891 -9.017228) (xy 126.598528 -9.127594) (xy 126.623365 -9.236408)
			(xy 126.656265 -9.343061) (xy 126.697043 -9.446957) (xy 126.745472 -9.547516) (xy 126.801279 -9.644174)
			(xy 126.864154 -9.736392) (xy 126.933745 -9.823653) (xy 127.009662 -9.90547) (xy 127.09148 -9.981384)
			(xy 127.178743 -10.050972) (xy 127.270963 -10.113844) (xy 127.367623 -10.169649) (xy 127.468183 -10.218074)
			(xy 127.572081 -10.258849) (xy 127.678735 -10.291746) (xy 127.787549 -10.316581) (xy 127.897915 -10.333214)
			(xy 128.009216 -10.341553) (xy 128.065022 -10.342118) (xy 130.065018 -10.342118) (xy 130.120825 -10.341596)
			(xy 130.232127 -10.333254) (xy 130.342494 -10.316617) (xy 130.451309 -10.29178) (xy 130.557964 -10.258881)
			(xy 130.661862 -10.218103) (xy 130.762422 -10.169675) (xy 130.859082 -10.113868) (xy 130.951302 -10.050993)
			(xy 131.038565 -9.981403) (xy 131.120384 -9.905487) (xy 131.196301 -9.823668) (xy 131.265891 -9.736405)
			(xy 131.328766 -9.644186) (xy 131.384573 -9.547526) (xy 131.433001 -9.446965) (xy 131.473779 -9.343067)
			(xy 131.506679 -9.236413) (xy 131.531517 -9.127597) (xy 131.548153 -9.01723) (xy 131.556495 -8.905929)
			(xy 131.557014 -8.850122) (xy 131.557014 0) (xy 131.557498 0.070354) (xy 131.565388 0.21084) (xy 131.581142 0.350663)
			(xy 131.604712 0.489383) (xy 131.636022 0.626563) (xy 131.674975 0.761771) (xy 131.721448 0.894583)
			(xy 131.775295 1.02458) (xy 131.836346 1.151353) (xy 131.904409 1.274504) (xy 131.97927 1.393645)
			(xy 132.060694 1.5084) (xy 132.148424 1.61841) (xy 132.242184 1.723327) (xy 132.34168 1.822823) (xy 132.446598 1.916583)
			(xy 132.556608 2.004312) (xy 132.671364 2.085735) (xy 132.790505 2.160596) (xy 132.913655 2.228659)
			(xy 133.040429 2.289709) (xy 133.170426 2.343555) (xy 133.303238 2.390028) (xy 133.438447 2.42898)
			(xy 133.575627 2.46029) (xy 133.714347 2.483859) (xy 133.85417 2.499613) (xy 133.994656 2.507502)
			(xy 134.06501 2.507996) (xy 150.064978 2.507996) (xy 150.135332 2.507512) (xy 150.27582 2.499624)
			(xy 150.415644 2.483871) (xy 150.554365 2.460302) (xy 150.691546 2.428993) (xy 150.826756 2.39004)
			(xy 150.959569 2.343568) (xy 151.089567 2.289722) (xy 151.216342 2.228672) (xy 151.339494 2.160609)
			(xy 151.458636 2.085748) (xy 151.573393 2.004324) (xy 151.683404 1.916594) (xy 151.788322 1.822834)
			(xy 151.887819 1.723338) (xy 151.98158 1.61842) (xy 152.069311 1.50841) (xy 152.150736 1.393654)
			(xy 152.225598 1.274513) (xy 152.293661 1.151361) (xy 152.354713 1.024587) (xy 152.40856 0.894589)
			(xy 152.455034 0.761777) (xy 152.493987 0.626567) (xy 152.525298 0.489386) (xy 152.548868 0.350666)
			(xy 152.564622 0.210842) (xy 152.572512 0.070354) (xy 152.572974 0) (xy 152.572974 -8.850122) (xy 152.573497 -8.905929)
			(xy 152.581839 -9.017231) (xy 152.598475 -9.127598) (xy 152.623313 -9.236413) (xy 152.656212 -9.343068)
			(xy 152.69699 -9.446966) (xy 152.745418 -9.547526) (xy 152.801225 -9.644186) (xy 152.8641 -9.736406)
			(xy 152.93369 -9.823669) (xy 153.009606 -9.905488) (xy 153.091425 -9.981405) (xy 153.178688 -10.050995)
			(xy 153.270907 -10.11387) (xy 153.367567 -10.169678) (xy 153.468127 -10.218107) (xy 153.572025 -10.258885)
			(xy 153.67868 -10.291785) (xy 153.787495 -10.316623) (xy 153.897862 -10.33326) (xy 154.009163 -10.341603)
			(xy 154.06497 -10.342118) (xy 156.064966 -10.342118) (xy 156.120775 -10.34161) (xy 156.23208 -10.333271)
			(xy 156.342451 -10.316638) (xy 156.45127 -10.291803) (xy 156.557929 -10.258906) (xy 156.661832 -10.21813)
			(xy 156.762396 -10.169703) (xy 156.859061 -10.113896) (xy 156.951284 -10.051022) (xy 157.038552 -9.981431)
			(xy 157.120374 -9.905514) (xy 157.196295 -9.823694) (xy 157.265888 -9.736429) (xy 157.328766 -9.644208)
			(xy 157.384577 -9.547546) (xy 157.433007 -9.446983) (xy 157.473787 -9.343082) (xy 157.506689 -9.236424)
			(xy 157.531528 -9.127606) (xy 157.548165 -9.017236) (xy 157.556508 -8.905931) (xy 157.556962 -8.850122)
			(xy 157.556962 0) (xy 157.557455 0.070354) (xy 157.565345 0.210841) (xy 157.581099 0.350665) (xy 157.604668 0.489385)
			(xy 157.635978 0.626566) (xy 157.674931 0.761775) (xy 157.721404 0.894587) (xy 157.77525 1.024585)
			(xy 157.8363 1.151359) (xy 157.904363 1.274511) (xy 157.979224 1.393652) (xy 158.060647 1.508409)
			(xy 158.148376 1.61842) (xy 158.242136 1.723339) (xy 158.341631 1.822835) (xy 158.446548 1.916597)
			(xy 158.556557 2.004328) (xy 158.671313 2.085753) (xy 158.790453 2.160616) (xy 158.913604 2.22868)
			(xy 159.040377 2.289733) (xy 159.170374 2.343581) (xy 159.303185 2.390056) (xy 159.438394 2.429011)
			(xy 159.575574 2.460324) (xy 159.714294 2.483895) (xy 159.854117 2.499652) (xy 159.994604 2.507544)
			(xy 160.064958 2.507996) (xy 176.064926 2.507996) (xy 176.135279 2.507502) (xy 176.275764 2.499611)
			(xy 176.415586 2.483856) (xy 176.554304 2.460285) (xy 176.691483 2.428974) (xy 176.82669 2.39002)
			(xy 176.9595 2.343547) (xy 177.089496 2.289699) (xy 177.216267 2.228648) (xy 177.339416 2.160585)
			(xy 177.458556 2.085724) (xy 177.57331 2.0043) (xy 177.683318 1.91657) (xy 177.788234 1.822811) (xy 177.887728 1.723315)
			(xy 177.981487 1.618398) (xy 178.069216 1.508389) (xy 178.150638 1.393634) (xy 178.225498 1.274494)
			(xy 178.29356 1.151344) (xy 178.35461 1.024572) (xy 178.408456 0.894576) (xy 178.454928 0.761765)
			(xy 178.49388 0.626558) (xy 178.52519 0.489379) (xy 178.548759 0.35066) (xy 178.564513 0.210838)
			(xy 178.572403 0.070353) (xy 178.572922 0) (xy 178.572922 -8.850122) (xy 178.573445 -8.905928) (xy 178.581787 -9.017229)
			(xy 178.598424 -9.127594) (xy 178.623261 -9.236408) (xy 178.656161 -9.343061) (xy 178.696939 -9.446958)
			(xy 178.745367 -9.547517) (xy 178.801175 -9.644175) (xy 178.86405 -9.736393) (xy 178.93364 -9.823654)
			(xy 179.009557 -9.905471) (xy 179.091376 -9.981386) (xy 179.178639 -10.050974) (xy 179.270859 -10.113846)
			(xy 179.367519 -10.169651) (xy 179.468079 -10.218077) (xy 179.571976 -10.258852) (xy 179.678631 -10.291749)
			(xy 179.787445 -10.316584) (xy 179.897811 -10.333218) (xy 180.009112 -10.341557) (xy 180.064918 -10.342118)
			(xy 182.064914 -10.342118) (xy 182.120721 -10.341596) (xy 182.232023 -10.333254) (xy 182.34239 -10.316618)
			(xy 182.451206 -10.291781) (xy 182.557861 -10.258882) (xy 182.661759 -10.218104) (xy 182.76232 -10.169676)
			(xy 182.85898 -10.113869) (xy 182.9512 -10.050995) (xy 183.038463 -9.981405) (xy 183.120282 -9.905488)
			(xy 183.196199 -9.823669) (xy 183.26579 -9.736406) (xy 183.328665 -9.644187) (xy 183.384473 -9.547527)
			(xy 183.432901 -9.446966) (xy 183.473679 -9.343068) (xy 183.506579 -9.236413) (xy 183.531416 -9.127598)
			(xy 183.548053 -9.017231) (xy 183.556395 -8.905929) (xy 183.55691 -8.850122) (xy 183.55691 0) (xy 183.557394 0.070354)
			(xy 183.565284 0.21084) (xy 183.581038 0.350664) (xy 183.604608 0.489383) (xy 183.635918 0.626563)
			(xy 183.674871 0.761772) (xy 183.721344 0.894584) (xy 183.775191 1.024581) (xy 183.836242 1.151354)
			(xy 183.904305 1.274505) (xy 183.979166 1.393646) (xy 184.06059 1.508401) (xy 184.14832 1.618411)
			(xy 184.24208 1.723329) (xy 184.341576 1.822824) (xy 184.446493 1.916584) (xy 184.556503 2.004314)
			(xy 184.671259 2.085737) (xy 184.7904 2.160598) (xy 184.913551 2.228661) (xy 185.040325 2.289712)
			(xy 185.170322 2.343558) (xy 185.303134 2.390031) (xy 185.438342 2.428983) (xy 185.575523 2.460294)
			(xy 185.714242 2.483863) (xy 185.854066 2.499617) (xy 185.994552 2.507506) (xy 186.064906 2.507996)
			(xy 202.064874 2.507996) (xy 202.135228 2.507512) (xy 202.275716 2.499624) (xy 202.41554 2.483871)
			(xy 202.554261 2.460303) (xy 202.691443 2.428993) (xy 202.826653 2.390041) (xy 202.959466 2.343569)
			(xy 203.089464 2.289723) (xy 203.216239 2.228673) (xy 203.339391 2.16061) (xy 203.458534 2.085749)
			(xy 203.573291 2.004326) (xy 203.683302 1.916596) (xy 203.788221 1.822836) (xy 203.887718 1.72334)
			(xy 203.981479 1.618422) (xy 204.06921 1.508412) (xy 204.150635 1.393655) (xy 204.225497 1.274514)
			(xy 204.293561 1.151362) (xy 204.354613 1.024588) (xy 204.40846 0.89459) (xy 204.454933 0.761778)
			(xy 204.493887 0.626568) (xy 204.525198 0.489387) (xy 204.548768 0.350666) (xy 204.564522 0.210842)
			(xy 204.572412 0.070354) (xy 204.57287 0) (xy 204.57287 -8.850122) (xy 204.573393 -8.905929) (xy 204.581735 -9.017231)
			(xy 204.598371 -9.127598) (xy 204.623209 -9.236413) (xy 204.656108 -9.343068) (xy 204.696886 -9.446966)
			(xy 204.745314 -9.547527) (xy 204.801121 -9.644187) (xy 204.863996 -9.736407) (xy 204.933586 -9.82367)
			(xy 205.009502 -9.905489) (xy 205.091321 -9.981407) (xy 205.178583 -10.050997) (xy 205.270803 -10.113872)
			(xy 205.367463 -10.16968) (xy 205.468023 -10.218109) (xy 205.571921 -10.258888) (xy 205.678575 -10.291788)
			(xy 205.78739 -10.316626) (xy 205.897757 -10.333264) (xy 206.009059 -10.341607) (xy 206.064866 -10.342118)
			(xy 208.065116 -10.342118) (xy 208.120923 -10.341596) (xy 208.232225 -10.333254) (xy 208.342592 -10.316618)
			(xy 208.451407 -10.29178) (xy 208.558062 -10.258881) (xy 208.66196 -10.218103) (xy 208.762521 -10.169676)
			(xy 208.859181 -10.113868) (xy 208.951401 -10.050994) (xy 209.038664 -9.981404) (xy 209.120483 -9.905487)
			(xy 209.1964 -9.823669) (xy 209.26599 -9.736406) (xy 209.328865 -9.644186) (xy 209.384673 -9.547526)
			(xy 209.433101 -9.446966) (xy 209.473879 -9.343068) (xy 209.506779 -9.236413) (xy 209.531617 -9.127598)
			(xy 209.548253 -9.017231) (xy 209.556595 -8.905929) (xy 209.557112 -8.850122) (xy 209.557112 0) (xy 209.557596 0.070354)
			(xy 209.565486 0.21084) (xy 209.58124 0.350663) (xy 209.60481 0.489383) (xy 209.63612 0.626563) (xy 209.675073 0.761772)
			(xy 209.721546 0.894583) (xy 209.775393 1.02458) (xy 209.836444 1.151354) (xy 209.904507 1.274505)
			(xy 209.979368 1.393645) (xy 210.060792 1.508401) (xy 210.148522 1.618411) (xy 210.242282 1.723328)
			(xy 210.341778 1.822823) (xy 210.446696 1.916583) (xy 210.556706 2.004313) (xy 210.671462 2.085736)
			(xy 210.790602 2.160597) (xy 210.913753 2.22866) (xy 211.040527 2.289711) (xy 211.170524 2.343557)
			(xy 211.303336 2.390029) (xy 211.438545 2.428982) (xy 211.575725 2.460292) (xy 211.714444 2.483861)
			(xy 211.854268 2.499615) (xy 211.994754 2.507504) (xy 212.065108 2.507996) (xy 240.164874 2.507996)
			(xy 240.235228 2.507512) (xy 240.375716 2.499624) (xy 240.51554 2.483871) (xy 240.654261 2.460303)
			(xy 240.791443 2.428993) (xy 240.926653 2.390041) (xy 241.059466 2.343569) (xy 241.189464 2.289723)
			(xy 241.316239 2.228673) (xy 241.439391 2.16061) (xy 241.558534 2.085749) (xy 241.673291 2.004326)
			(xy 241.783302 1.916596) (xy 241.888221 1.822836) (xy 241.987718 1.72334) (xy 242.081479 1.618422)
			(xy 242.16921 1.508412) (xy 242.250635 1.393655) (xy 242.325497 1.274514) (xy 242.393561 1.151362)
			(xy 242.454613 1.024588) (xy 242.50846 0.89459) (xy 242.554933 0.761778) (xy 242.593887 0.626568)
			(xy 242.625198 0.489387) (xy 242.648768 0.350666) (xy 242.664522 0.210842) (xy 242.672412 0.070354)
			(xy 242.67287 0) (xy 242.67287 -8.850122) (xy 242.673393 -8.905929) (xy 242.681735 -9.017231) (xy 242.698371 -9.127598)
			(xy 242.723209 -9.236413) (xy 242.756108 -9.343068) (xy 242.796886 -9.446966) (xy 242.845314 -9.547527)
			(xy 242.901121 -9.644187) (xy 242.963996 -9.736407) (xy 243.033586 -9.82367) (xy 243.109502 -9.905489)
			(xy 243.191321 -9.981407) (xy 243.278583 -10.050997) (xy 243.370803 -10.113872) (xy 243.467463 -10.16968)
			(xy 243.568023 -10.218109) (xy 243.671921 -10.258888) (xy 243.778575 -10.291788) (xy 243.88739 -10.316626)
			(xy 243.997757 -10.333264) (xy 244.109059 -10.341607) (xy 244.164866 -10.342118) (xy 246.165116 -10.342118)
			(xy 246.220923 -10.341596) (xy 246.332225 -10.333254) (xy 246.442592 -10.316618) (xy 246.551407 -10.29178)
			(xy 246.658062 -10.258881) (xy 246.76196 -10.218103) (xy 246.862521 -10.169676) (xy 246.959181 -10.113868)
			(xy 247.051401 -10.050994) (xy 247.138664 -9.981404) (xy 247.220483 -9.905487) (xy 247.2964 -9.823669)
			(xy 247.36599 -9.736406) (xy 247.428865 -9.644186) (xy 247.484673 -9.547526) (xy 247.533101 -9.446966)
			(xy 247.573879 -9.343068) (xy 247.606779 -9.236413) (xy 247.631617 -9.127598) (xy 247.648253 -9.017231)
			(xy 247.656595 -8.905929) (xy 247.657112 -8.850122) (xy 247.657112 0) (xy 247.657596 0.070354) (xy 247.665486 0.21084)
			(xy 247.68124 0.350663) (xy 247.70481 0.489383) (xy 247.73612 0.626563) (xy 247.775073 0.761772)
			(xy 247.821546 0.894583) (xy 247.875393 1.02458) (xy 247.936444 1.151354) (xy 248.004507 1.274505)
			(xy 248.079368 1.393645) (xy 248.160792 1.508401) (xy 248.248522 1.618411) (xy 248.342282 1.723328)
			(xy 248.441778 1.822823) (xy 248.546696 1.916583) (xy 248.656706 2.004313) (xy 248.771462 2.085736)
			(xy 248.890602 2.160597) (xy 249.013753 2.22866) (xy 249.140527 2.289711) (xy 249.270524 2.343557)
			(xy 249.403336 2.390029) (xy 249.538545 2.428982) (xy 249.675725 2.460292) (xy 249.814444 2.483861)
			(xy 249.954268 2.499615) (xy 250.094754 2.507504) (xy 250.165108 2.507996) (xy 266.165076 2.507996)
			(xy 266.23543 2.507512) (xy 266.375918 2.499624) (xy 266.515742 2.483871) (xy 266.654463 2.460303)
			(xy 266.791644 2.428993) (xy 266.926854 2.390041) (xy 267.059667 2.343569) (xy 267.189666 2.289723)
			(xy 267.31644 2.228672) (xy 267.439593 2.160609) (xy 267.558735 2.085749) (xy 267.673492 2.004325)
			(xy 267.783503 1.916595) (xy 267.888422 1.822835) (xy 267.987918 1.723339) (xy 268.08168 1.618421)
			(xy 268.169411 1.508411) (xy 268.250835 1.393655) (xy 268.325697 1.274513) (xy 268.393761 1.151362)
			(xy 268.454813 1.024588) (xy 268.50866 0.89459) (xy 268.555134 0.761777) (xy 268.594087 0.626568)
			(xy 268.625398 0.489387) (xy 268.648968 0.350666) (xy 268.664722 0.210842) (xy 268.672612 0.070354)
			(xy 268.673072 0) (xy 268.673072 -8.850122) (xy 268.673595 -8.905929) (xy 268.681937 -9.017231) (xy 268.698573 -9.127598)
			(xy 268.723411 -9.236413) (xy 268.75631 -9.343068) (xy 268.797088 -9.446966) (xy 268.845516 -9.547526)
			(xy 268.901323 -9.644187) (xy 268.964198 -9.736406) (xy 269.033788 -9.82367) (xy 269.109704 -9.905489)
			(xy 269.191523 -9.981406) (xy 269.278786 -10.050996) (xy 269.371005 -10.113871) (xy 269.467665 -10.169679)
			(xy 269.568225 -10.218108) (xy 269.672123 -10.258886) (xy 269.778777 -10.291787) (xy 269.887592 -10.316625)
			(xy 269.997959 -10.333262) (xy 270.109261 -10.341605) (xy 270.165068 -10.342118) (xy 272.165064 -10.342118)
			(xy 272.220873 -10.34161) (xy 272.332178 -10.333272) (xy 272.442549 -10.316638) (xy 272.551368 -10.291804)
			(xy 272.658028 -10.258906) (xy 272.76193 -10.21813) (xy 272.862495 -10.169703) (xy 272.95916 -10.113897)
			(xy 273.051383 -10.051022) (xy 273.138651 -9.981432) (xy 273.220473 -9.905515) (xy 273.296394 -9.823695)
			(xy 273.365988 -9.73643) (xy 273.428866 -9.644209) (xy 273.484676 -9.547546) (xy 273.533107 -9.446983)
			(xy 273.573887 -9.343082) (xy 273.606789 -9.236425) (xy 273.631628 -9.127606) (xy 273.648265 -9.017236)
			(xy 273.656608 -8.905931) (xy 273.65706 -8.850122) (xy 273.65706 0) (xy 273.657553 0.070354) (xy 273.665443 0.210841)
			(xy 273.681197 0.350665) (xy 273.704766 0.489385) (xy 273.736076 0.626566) (xy 273.775029 0.761775)
			(xy 273.821502 0.894588) (xy 273.875348 1.024585) (xy 273.936398 1.15136) (xy 274.004461 1.274511)
			(xy 274.079321 1.393653) (xy 274.160745 1.50841) (xy 274.248474 1.618421) (xy 274.342234 1.723339)
			(xy 274.441729 1.822836) (xy 274.546646 1.916598) (xy 274.656655 2.004329) (xy 274.771411 2.085754)
			(xy 274.890551 2.160617) (xy 275.013701 2.228682) (xy 275.140474 2.289734) (xy 275.270471 2.343583)
			(xy 275.403283 2.390058) (xy 275.538492 2.429013) (xy 275.675672 2.460325) (xy 275.814392 2.483897)
			(xy 275.954215 2.499654) (xy 276.094702 2.507545) (xy 276.165056 2.507996) (xy 292.165024 2.507996)
			(xy 292.235377 2.507502) (xy 292.375862 2.499611) (xy 292.515684 2.483856) (xy 292.654403 2.460285)
			(xy 292.791581 2.428974) (xy 292.926788 2.390021) (xy 293.059599 2.343547) (xy 293.189594 2.2897)
			(xy 293.316366 2.228649) (xy 293.439515 2.160586) (xy 293.558655 2.085724) (xy 293.673409 2.004301)
			(xy 293.783417 1.916571) (xy 293.888334 1.822811) (xy 293.987828 1.723316) (xy 294.081587 1.618399)
			(xy 294.169315 1.50839) (xy 294.250738 1.393635) (xy 294.325598 1.274495) (xy 294.39366 1.151345)
			(xy 294.45471 1.024572) (xy 294.508556 0.894576) (xy 294.555028 0.761765) (xy 294.59398 0.626558)
			(xy 294.62529 0.489379) (xy 294.648859 0.35066) (xy 294.664613 0.210839) (xy 294.672503 0.070353)
			(xy 294.67302 0) (xy 294.67302 -8.850122) (xy 294.673543 -8.905928) (xy 294.681885 -9.017229) (xy 294.698522 -9.127594)
			(xy 294.723359 -9.236408) (xy 294.756259 -9.343062) (xy 294.797037 -9.446958) (xy 294.845465 -9.547517)
			(xy 294.901273 -9.644176) (xy 294.964148 -9.736394) (xy 295.033738 -9.823655) (xy 295.109655 -9.905472)
			(xy 295.191474 -9.981387) (xy 295.278737 -10.050975) (xy 295.370956 -10.113847) (xy 295.467616 -10.169652)
			(xy 295.568176 -10.218078) (xy 295.672074 -10.258853) (xy 295.778728 -10.291751) (xy 295.887543 -10.316586)
			(xy 295.997909 -10.333219) (xy 296.10921 -10.341559) (xy 296.165016 -10.342118) (xy 298.165012 -10.342118)
			(xy 298.220819 -10.341596) (xy 298.332121 -10.333254) (xy 298.442488 -10.316618) (xy 298.551304 -10.291781)
			(xy 298.657959 -10.258882) (xy 298.761858 -10.218105) (xy 298.862418 -10.169677) (xy 298.959079 -10.11387)
			(xy 299.051299 -10.050995) (xy 299.138562 -9.981405) (xy 299.220382 -9.905489) (xy 299.296299 -9.82367)
			(xy 299.365889 -9.736407) (xy 299.428764 -9.644188) (xy 299.484572 -9.547527) (xy 299.533001 -9.446967)
			(xy 299.573779 -9.343069) (xy 299.606679 -9.236414) (xy 299.631516 -9.127598) (xy 299.648153 -9.017231)
			(xy 299.656495 -8.905929) (xy 299.657008 -8.850122) (xy 299.657008 0) (xy 299.657492 0.070354) (xy 299.665382 0.21084)
			(xy 299.681136 0.350664) (xy 299.704706 0.489383) (xy 299.736016 0.626564) (xy 299.774969 0.761772)
			(xy 299.821442 0.894584) (xy 299.875289 1.024581) (xy 299.93634 1.151355) (xy 300.004403 1.274505)
			(xy 300.079264 1.393646) (xy 300.160688 1.508402) (xy 300.248418 1.618412) (xy 300.342178 1.723329)
			(xy 300.441673 1.822825) (xy 300.546591 1.916585) (xy 300.656601 2.004315) (xy 300.771357 2.085738)
			(xy 300.890498 2.160599) (xy 301.013649 2.228662) (xy 301.140423 2.289713) (xy 301.27042 2.343559)
			(xy 301.403232 2.390032) (xy 301.53844 2.428985) (xy 301.67562 2.460295) (xy 301.81434 2.483864)
			(xy 301.954163 2.499618) (xy 302.09465 2.507508) (xy 302.165004 2.507996) (xy 318.164972 2.507996)
			(xy 318.235326 2.507512) (xy 318.375814 2.499624) (xy 318.515639 2.483871) (xy 318.65436 2.460303)
			(xy 318.791541 2.428994) (xy 318.926751 2.390042) (xy 319.059564 2.34357) (xy 319.189563 2.289724)
			(xy 319.316338 2.228673) (xy 319.43949 2.160611) (xy 319.558633 2.08575) (xy 319.67339 2.004327)
			(xy 319.783401 1.916597) (xy 319.88832 1.822836) (xy 319.987817 1.723341) (xy 320.081579 1.618423)
			(xy 320.16931 1.508412) (xy 320.250734 1.393656) (xy 320.325597 1.274514) (xy 320.393661 1.151363)
			(xy 320.454712 1.024589) (xy 320.50856 0.894591) (xy 320.555033 0.761778) (xy 320.593987 0.626568)
			(xy 320.625298 0.489387) (xy 320.648868 0.350666) (xy 320.664622 0.210842) (xy 320.672512 0.070354)
			(xy 320.672968 0) (xy 320.672968 -8.850122) (xy 320.673491 -8.905929) (xy 320.681833 -9.017231) (xy 320.698469 -9.127598)
			(xy 320.723307 -9.236413) (xy 320.756206 -9.343068) (xy 320.796984 -9.446967) (xy 320.845412 -9.547527)
			(xy 320.901219 -9.644188) (xy 320.964093 -9.736408) (xy 321.033684 -9.823671) (xy 321.1096 -9.90549)
			(xy 321.191418 -9.981407) (xy 321.278681 -10.050998) (xy 321.3709 -10.113873) (xy 321.46756 -10.169682)
			(xy 321.56812 -10.21811) (xy 321.672018 -10.258889) (xy 321.778673 -10.29179) (xy 321.887488 -10.316628)
			(xy 321.997855 -10.333266) (xy 322.109157 -10.341609) (xy 322.164964 -10.342118) (xy 324.16496 -10.342118)
			(xy 324.220769 -10.34161) (xy 324.332074 -10.333272) (xy 324.442446 -10.316639) (xy 324.551265 -10.291805)
			(xy 324.657925 -10.258907) (xy 324.761827 -10.218131) (xy 324.862393 -10.169705) (xy 324.959057 -10.113898)
			(xy 325.051281 -10.051024) (xy 325.138549 -9.981433) (xy 325.220372 -9.905516) (xy 325.296293 -9.823696)
			(xy 325.365887 -9.736431) (xy 325.428765 -9.64421) (xy 325.484576 -9.547547) (xy 325.533007 -9.446984)
			(xy 325.573787 -9.343083) (xy 325.606689 -9.236425) (xy 325.631528 -9.127607) (xy 325.648165 -9.017236)
			(xy 325.656508 -8.905931) (xy 325.656956 -8.850122) (xy 325.656956 0) (xy 325.657449 0.070354) (xy 325.665339 0.210841)
			(xy 325.681093 0.350665) (xy 325.704662 0.489386) (xy 325.735972 0.626566) (xy 325.774925 0.761776)
			(xy 325.821398 0.894588) (xy 325.875244 1.024586) (xy 325.936294 1.15136) (xy 326.004357 1.274512)
			(xy 326.079217 1.393654) (xy 326.16064 1.508411) (xy 326.24837 1.618422) (xy 326.342129 1.723341)
			(xy 326.441624 1.822838) (xy 326.546542 1.916599) (xy 326.656551 2.004331) (xy 326.771306 2.085756)
			(xy 326.890447 2.160619) (xy 327.013597 2.228684) (xy 327.14037 2.289737) (xy 327.270367 2.343585)
			(xy 327.403179 2.39006) (xy 327.538387 2.429016) (xy 327.675567 2.460328) (xy 327.814287 2.4839)
			(xy 327.954111 2.499657) (xy 328.094598 2.507549) (xy 328.164952 2.507996) (xy 356.264972 2.507996)
			(xy 356.335326 2.507512) (xy 356.475814 2.499624) (xy 356.615639 2.483871) (xy 356.75436 2.460303)
			(xy 356.891541 2.428994) (xy 357.026751 2.390042) (xy 357.159564 2.34357) (xy 357.289563 2.289724)
			(xy 357.416338 2.228673) (xy 357.53949 2.160611) (xy 357.658633 2.08575) (xy 357.77339 2.004327)
			(xy 357.883401 1.916597) (xy 357.98832 1.822836) (xy 358.087817 1.723341) (xy 358.181579 1.618423)
			(xy 358.26931 1.508412) (xy 358.350734 1.393656) (xy 358.425597 1.274514) (xy 358.493661 1.151363)
			(xy 358.554712 1.024589) (xy 358.60856 0.894591) (xy 358.655033 0.761778) (xy 358.693987 0.626568)
			(xy 358.725298 0.489387) (xy 358.748868 0.350666) (xy 358.764622 0.210842) (xy 358.772512 0.070354)
			(xy 358.772968 0) (xy 358.772968 -8.850122) (xy 358.773491 -8.905929) (xy 358.781833 -9.017231) (xy 358.798469 -9.127598)
			(xy 358.823307 -9.236413) (xy 358.856206 -9.343068) (xy 358.896984 -9.446967) (xy 358.945412 -9.547527)
			(xy 359.001219 -9.644188) (xy 359.064093 -9.736408) (xy 359.133684 -9.823671) (xy 359.2096 -9.90549)
			(xy 359.291418 -9.981407) (xy 359.378681 -10.050998) (xy 359.4709 -10.113873) (xy 359.56756 -10.169682)
			(xy 359.66812 -10.21811) (xy 359.772018 -10.258889) (xy 359.878673 -10.29179) (xy 359.987488 -10.316628)
			(xy 360.097855 -10.333266) (xy 360.209157 -10.341609) (xy 360.264964 -10.342118) (xy 362.26496 -10.342118)
			(xy 362.320769 -10.34161) (xy 362.432074 -10.333272) (xy 362.542446 -10.316639) (xy 362.651265 -10.291805)
			(xy 362.757925 -10.258907) (xy 362.861827 -10.218131) (xy 362.962393 -10.169705) (xy 363.059057 -10.113898)
			(xy 363.151281 -10.051024) (xy 363.238549 -9.981433) (xy 363.320372 -9.905516) (xy 363.396293 -9.823696)
			(xy 363.465887 -9.736431) (xy 363.528765 -9.64421) (xy 363.584576 -9.547547) (xy 363.633007 -9.446984)
			(xy 363.673787 -9.343083) (xy 363.706689 -9.236425) (xy 363.731528 -9.127607) (xy 363.748165 -9.017236)
			(xy 363.756508 -8.905931) (xy 363.756956 -8.850122) (xy 363.756956 0) (xy 363.757449 0.070354) (xy 363.765339 0.210841)
			(xy 363.781093 0.350665) (xy 363.804662 0.489386) (xy 363.835972 0.626566) (xy 363.874925 0.761776)
			(xy 363.921398 0.894588) (xy 363.975244 1.024586) (xy 364.036294 1.15136) (xy 364.104357 1.274512)
			(xy 364.179217 1.393654) (xy 364.26064 1.508411) (xy 364.34837 1.618422) (xy 364.442129 1.723341)
			(xy 364.541624 1.822838) (xy 364.646542 1.916599) (xy 364.756551 2.004331) (xy 364.871306 2.085756)
			(xy 364.990447 2.160619) (xy 365.113597 2.228684) (xy 365.24037 2.289737) (xy 365.370367 2.343585)
			(xy 365.503179 2.39006) (xy 365.638387 2.429016) (xy 365.775567 2.460328) (xy 365.914287 2.4839)
			(xy 366.054111 2.499657) (xy 366.194598 2.507549) (xy 366.264952 2.507996) (xy 382.26492 2.507996)
			(xy 382.335273 2.507502) (xy 382.475759 2.499612) (xy 382.615581 2.483856) (xy 382.754299 2.460286)
			(xy 382.891478 2.428975) (xy 383.026685 2.390022) (xy 383.159496 2.343548) (xy 383.289491 2.289701)
			(xy 383.416264 2.22865) (xy 383.539413 2.160587) (xy 383.658552 2.085726) (xy 383.773307 2.004302)
			(xy 383.883316 1.916573) (xy 383.988232 1.822813) (xy 384.087726 1.723318) (xy 384.181485 1.6184)
			(xy 384.269214 1.508391) (xy 384.350637 1.393636) (xy 384.425497 1.274496) (xy 384.493559 1.151346)
			(xy 384.554609 1.024573) (xy 384.608455 0.894577) (xy 384.654928 0.761766) (xy 384.69388 0.626559)
			(xy 384.72519 0.48938) (xy 384.748759 0.350661) (xy 384.764513 0.210839) (xy 384.772403 0.070353)
			(xy 384.772916 0) (xy 384.772916 -8.850122) (xy 384.773439 -8.905928) (xy 384.781781 -9.017229) (xy 384.798418 -9.127595)
			(xy 384.823255 -9.236409) (xy 384.856155 -9.343062) (xy 384.896933 -9.446959) (xy 384.945361 -9.547518)
			(xy 385.001169 -9.644177) (xy 385.064044 -9.736395) (xy 385.133634 -9.823656) (xy 385.209551 -9.905473)
			(xy 385.29137 -9.981388) (xy 385.378633 -10.050977) (xy 385.470852 -10.113849) (xy 385.567512 -10.169655)
			(xy 385.668072 -10.218081) (xy 385.77197 -10.258856) (xy 385.878624 -10.291754) (xy 385.987439 -10.316589)
			(xy 386.097805 -10.333223) (xy 386.209106 -10.341563) (xy 386.264912 -10.342118) (xy 388.264908 -10.342118)
			(xy 388.320715 -10.341596) (xy 388.432017 -10.333255) (xy 388.542385 -10.316619) (xy 388.651201 -10.291782)
			(xy 388.757856 -10.258883) (xy 388.861755 -10.218106) (xy 388.962316 -10.169678) (xy 389.058977 -10.113871)
			(xy 389.151197 -10.050997) (xy 389.238461 -9.981407) (xy 389.32028 -9.90549) (xy 389.396198 -9.823671)
			(xy 389.465789 -9.736408) (xy 389.528664 -9.644189) (xy 389.584472 -9.547528) (xy 389.6329 -9.446968)
			(xy 389.673678 -9.343069) (xy 389.706579 -9.236414) (xy 389.731416 -9.127599) (xy 389.748053 -9.017231)
			(xy 389.756395 -8.905929) (xy 389.756904 -8.850122) (xy 389.756904 0) (xy 389.757397 0.070354) (xy 389.765287 0.21084)
			(xy 389.781041 0.350663) (xy 389.80461 0.489382) (xy 389.835921 0.626562) (xy 389.874874 0.76177)
			(xy 389.921346 0.894581) (xy 389.975193 1.024578) (xy 390.036243 1.151351) (xy 390.104306 1.274502)
			(xy 390.179167 1.393642) (xy 390.260591 1.508398) (xy 390.34832 1.618407) (xy 390.44208 1.723325)
			(xy 390.541575 1.82282) (xy 390.646493 1.91658) (xy 390.756502 2.004309) (xy 390.871258 2.085733)
			(xy 390.990398 2.160594) (xy 391.113549 2.228657) (xy 391.240322 2.289707) (xy 391.370319 2.343554)
			(xy 391.50313 2.390026) (xy 391.638338 2.428979) (xy 391.775518 2.46029) (xy 391.914237 2.483859)
			(xy 392.05406 2.499613) (xy 392.194546 2.507503) (xy 392.2649 2.507996) (xy 408.265122 2.507996)
			(xy 408.335475 2.507502) (xy 408.475961 2.499611) (xy 408.615782 2.483856) (xy 408.754501 2.460286)
			(xy 408.89168 2.428975) (xy 409.026887 2.390021) (xy 409.159697 2.343548) (xy 409.289693 2.289701)
			(xy 409.416465 2.22865) (xy 409.539614 2.160586) (xy 409.658754 2.085725) (xy 409.773508 2.004302)
			(xy 409.883516 1.916572) (xy 409.988433 1.822812) (xy 410.087927 1.723317) (xy 410.181686 1.6184)
			(xy 410.269415 1.50839) (xy 410.350837 1.393635) (xy 410.425697 1.274495) (xy 410.49376 1.151345)
			(xy 410.55481 1.024573) (xy 410.608655 0.894577) (xy 410.655128 0.761766) (xy 410.69408 0.626558)
			(xy 410.72539 0.489379) (xy 410.748959 0.350661) (xy 410.764713 0.210839) (xy 410.772603 0.070353)
			(xy 410.773118 0) (xy 410.773118 -8.850122) (xy 410.773641 -8.905928) (xy 410.781983 -9.017229) (xy 410.79862 -9.127595)
			(xy 410.823457 -9.236408) (xy 410.856357 -9.343062) (xy 410.897135 -9.446959) (xy 410.945563 -9.547518)
			(xy 411.001371 -9.644176) (xy 411.064246 -9.736394) (xy 411.133836 -9.823656) (xy 411.209753 -9.905472)
			(xy 411.291572 -9.981387) (xy 411.378835 -10.050976) (xy 411.471054 -10.113848) (xy 411.567714 -10.169653)
			(xy 411.668274 -10.218079) (xy 411.772172 -10.258855) (xy 411.878826 -10.291752) (xy 411.987641 -10.316587)
			(xy 412.098007 -10.333221) (xy 412.209308 -10.341561) (xy 412.265114 -10.342118) (xy 414.26511 -10.342118)
			(xy 414.320917 -10.341596) (xy 414.432219 -10.333254) (xy 414.542587 -10.316619) (xy 414.651402 -10.291782)
			(xy 414.758058 -10.258883) (xy 414.861956 -10.218105) (xy 414.962517 -10.169678) (xy 415.059178 -10.11387)
			(xy 415.151398 -10.050996) (xy 415.238662 -9.981406) (xy 415.320481 -9.905489) (xy 415.396398 -9.823671)
			(xy 415.465989 -9.736408) (xy 415.528864 -9.644188) (xy 415.584672 -9.547528) (xy 415.6331 -9.446967)
			(xy 415.673879 -9.343069) (xy 415.706779 -9.236414) (xy 415.731616 -9.127598) (xy 415.748253 -9.017231)
			(xy 415.756595 -8.905929) (xy 415.757106 -8.850122) (xy 415.757106 0) (xy 415.75759 0.070354) (xy 415.76548 0.210841)
			(xy 415.781234 0.350664) (xy 415.804804 0.489384) (xy 415.836114 0.626564) (xy 415.875067 0.761772)
			(xy 415.92154 0.894584) (xy 415.975387 1.024581) (xy 416.036438 1.151355) (xy 416.104501 1.274506)
			(xy 416.179362 1.393647) (xy 416.260785 1.508402) (xy 416.348515 1.618412) (xy 416.442276 1.72333)
			(xy 416.541771 1.822826) (xy 416.646689 1.916586) (xy 416.756699 2.004316) (xy 416.871455 2.085739)
			(xy 416.990596 2.1606) (xy 417.113747 2.228663) (xy 417.24052 2.289714) (xy 417.370518 2.343561)
			(xy 417.503329 2.390034) (xy 417.638538 2.428986) (xy 417.775718 2.460297) (xy 417.914438 2.483866)
			(xy 418.054261 2.49962) (xy 418.194748 2.50751) (xy 418.265102 2.507996) (xy 434.26507 2.507996)
			(xy 434.335425 2.507513) (xy 434.475912 2.499625) (xy 434.615737 2.483872) (xy 434.754458 2.460304)
			(xy 434.89164 2.428994) (xy 435.02685 2.390042) (xy 435.159663 2.34357) (xy 435.289662 2.289724)
			(xy 435.416437 2.228674) (xy 435.539589 2.160612) (xy 435.658732 2.085751) (xy 435.773489 2.004327)
			(xy 435.8835 1.916597) (xy 435.988419 1.822837) (xy 436.087916 1.723341) (xy 436.181678 1.618423)
			(xy 436.269409 1.508413) (xy 436.350834 1.393656) (xy 436.425696 1.274515) (xy 436.49376 1.151363)
			(xy 436.554812 1.024589) (xy 436.60866 0.894591) (xy 436.655133 0.761778) (xy 436.694087 0.626569)
			(xy 436.725398 0.489387) (xy 436.748967 0.350667) (xy 436.764722 0.210842) (xy 436.772612 0.070355)
			(xy 436.773066 0) (xy 436.773066 -8.850122) (xy 436.773589 -8.905929) (xy 436.781931 -9.017231) (xy 436.798567 -9.127598)
			(xy 436.823405 -9.236414) (xy 436.856304 -9.343069) (xy 436.897082 -9.446967) (xy 436.94551 -9.547528)
			(xy 437.001317 -9.644188) (xy 437.064191 -9.736408) (xy 437.133781 -9.823672) (xy 437.209698 -9.905491)
			(xy 437.291516 -9.981408) (xy 437.378779 -10.050999) (xy 437.470998 -10.113874) (xy 437.567658 -10.169683)
			(xy 437.668218 -10.218112) (xy 437.772116 -10.25889) (xy 437.878771 -10.291791) (xy 437.987586 -10.31663)
			(xy 438.097953 -10.333267) (xy 438.209255 -10.341611) (xy 438.265062 -10.342118) (xy 440.265058 -10.342118)
			(xy 440.320867 -10.34161) (xy 440.432173 -10.333272) (xy 440.542544 -10.316639) (xy 440.651364 -10.291805)
			(xy 440.758023 -10.258908) (xy 440.861926 -10.218132) (xy 440.962491 -10.169705) (xy 441.059156 -10.113899)
			(xy 441.151381 -10.051025) (xy 441.238648 -9.981434) (xy 441.320471 -9.905517) (xy 441.396392 -9.823697)
			(xy 441.465987 -9.736432) (xy 441.528865 -9.64421) (xy 441.584675 -9.547548) (xy 441.633106 -9.446985)
			(xy 441.673887 -9.343084) (xy 441.706788 -9.236425) (xy 441.731628 -9.127607) (xy 441.748265 -9.017236)
			(xy 441.756608 -8.905931) (xy 441.757054 -8.850122) (xy 441.757054 0) (xy 441.757538 0.070353) (xy 441.765428 0.210839)
			(xy 441.781182 0.350661) (xy 441.804752 0.48938) (xy 441.836062 0.626559) (xy 441.875016 0.761767)
			(xy 441.921489 0.894578) (xy 441.975336 1.024574) (xy 442.036387 1.151346) (xy 442.10445 1.274495)
			(xy 442.179312 1.393635) (xy 442.260736 1.508389) (xy 442.348466 1.618398) (xy 442.442227 1.723314)
			(xy 442.541722 1.822808) (xy 442.64664 1.916566) (xy 442.756651 2.004294) (xy 442.871407 2.085716)
			(xy 442.990548 2.160575) (xy 443.113699 2.228636) (xy 443.240472 2.289685) (xy 443.370469 2.343529)
			(xy 443.503281 2.39) (xy 443.638489 2.42895) (xy 443.775669 2.460258) (xy 443.914388 2.483825) (xy 444.054211 2.499576)
			(xy 444.194697 2.507463) (xy 444.26505 2.507996) (xy 465.600034 2.507996) (xy 465.65584 2.508519)
			(xy 465.767141 2.516862) (xy 465.877506 2.533499) (xy 465.98632 2.558338) (xy 466.092974 2.591238)
			(xy 466.19687 2.632016) (xy 466.297429 2.680445) (xy 466.394088 2.736252) (xy 466.486306 2.799127)
			(xy 466.573567 2.868717) (xy 466.655384 2.944634) (xy 466.7313 3.026452) (xy 466.800888 3.113715)
			(xy 466.863762 3.205934) (xy 466.919568 3.302594) (xy 466.967994 3.403154) (xy 467.008771 3.507051)
			(xy 467.041669 3.613705) (xy 467.066505 3.722519) (xy 467.083141 3.832885) (xy 467.091482 3.944186)
			(xy 467.09203 3.999992) (xy 467.09203 24.157686) (xy 467.091509 24.213494) (xy 467.083169 24.324797)
			(xy 467.066535 24.435167) (xy 467.041699 24.543984) (xy 467.008801 24.650641) (xy 466.968025 24.754542)
			(xy 466.919598 24.855105) (xy 466.863791 24.951768) (xy 466.800917 25.04399) (xy 466.731327 25.131255)
			(xy 466.655411 25.213077) (xy 466.573592 25.288996) (xy 466.486328 25.358589) (xy 466.394108 25.421466)
			(xy 466.297447 25.477275) (xy 466.196886 25.525705) (xy 466.092987 25.566485) (xy 465.986331 25.599387)
			(xy 465.877514 25.624226) (xy 465.767145 25.640863) (xy 465.655842 25.649207) (xy 465.600034 25.649682)
			(xy 160.11398 25.649682) (xy 160.058174 25.64916) (xy 159.946873 25.640817) (xy 159.836507 25.624181)
			(xy 159.727693 25.599343) (xy 159.62104 25.566443) (xy 159.517143 25.525665) (xy 159.416584 25.477237)
			(xy 159.319925 25.42143) (xy 159.227707 25.358555) (xy 159.140445 25.288965) (xy 159.058628 25.213048)
			(xy 158.982713 25.131229) (xy 158.913125 25.043966) (xy 158.850252 24.951746) (xy 158.794447 24.855086)
			(xy 158.746021 24.754526) (xy 158.705245 24.650628) (xy 158.672348 24.543974) (xy 158.647513 24.435159)
			(xy 158.630879 24.324793) (xy 158.622539 24.213492) (xy 158.621984 24.157686) (xy 158.621984 21.802649)
			(xy 269.304757 21.802649) (xy 269.304757 21.888399) (xy 269.312669 21.973782) (xy 269.328425 22.058072)
			(xy 269.351892 22.140548) (xy 269.382868 22.220507) (xy 269.42109 22.297267) (xy 269.466231 22.370173)
			(xy 269.517907 22.438602) (xy 269.575676 22.501972) (xy 269.639046 22.559741) (xy 269.707475 22.611417)
			(xy 269.780381 22.656558) (xy 269.857141 22.69478) (xy 269.9371 22.725756) (xy 270.019576 22.749223)
			(xy 270.103866 22.764979) (xy 270.189249 22.772891) (xy 270.274999 22.772891) (xy 270.360382 22.764979)
			(xy 270.444672 22.749223) (xy 270.527148 22.725756) (xy 270.607107 22.69478) (xy 270.683867 22.656558)
			(xy 270.756773 22.611417) (xy 270.825202 22.559741) (xy 270.888572 22.501972) (xy 270.946341 22.438602)
			(xy 270.998017 22.370173) (xy 271.043158 22.297267) (xy 271.08138 22.220507) (xy 271.112356 22.140548)
			(xy 271.135823 22.058072) (xy 271.151579 21.973782) (xy 271.159491 21.888399) (xy 271.159986 21.845524)
			(xy 271.159491 21.802649) (xy 275.654757 21.802649) (xy 275.654757 21.888399) (xy 275.662669 21.973782)
			(xy 275.678425 22.058072) (xy 275.701892 22.140548) (xy 275.732868 22.220507) (xy 275.77109 22.297267)
			(xy 275.816231 22.370173) (xy 275.867907 22.438602) (xy 275.925676 22.501972) (xy 275.989046 22.559741)
			(xy 276.057475 22.611417) (xy 276.130381 22.656558) (xy 276.207141 22.69478) (xy 276.2871 22.725756)
			(xy 276.369576 22.749223) (xy 276.453866 22.764979) (xy 276.539249 22.772891) (xy 276.624999 22.772891)
			(xy 276.710382 22.764979) (xy 276.794672 22.749223) (xy 276.877148 22.725756) (xy 276.957107 22.69478)
			(xy 277.033867 22.656558) (xy 277.106773 22.611417) (xy 277.175202 22.559741) (xy 277.238572 22.501972)
			(xy 277.296341 22.438602) (xy 277.348017 22.370173) (xy 277.393158 22.297267) (xy 277.43138 22.220507)
			(xy 277.462356 22.140548) (xy 277.485823 22.058072) (xy 277.501579 21.973782) (xy 277.509491 21.888399)
			(xy 277.509986 21.845524) (xy 277.509491 21.802649) (xy 277.508832 21.795537) (xy 308.364877 21.795537)
			(xy 308.364877 21.881287) (xy 308.372789 21.96667) (xy 308.388545 22.05096) (xy 308.412012 22.133436)
			(xy 308.442988 22.213395) (xy 308.48121 22.290155) (xy 308.526351 22.363061) (xy 308.578027 22.43149)
			(xy 308.635796 22.49486) (xy 308.699166 22.552629) (xy 308.767595 22.604305) (xy 308.840501 22.649446)
			(xy 308.917261 22.687668) (xy 308.99722 22.718644) (xy 309.079696 22.742111) (xy 309.163986 22.757867)
			(xy 309.249369 22.765779) (xy 309.335119 22.765779) (xy 309.420502 22.757867) (xy 309.504792 22.742111)
			(xy 309.587268 22.718644) (xy 309.667227 22.687668) (xy 309.743987 22.649446) (xy 309.816893 22.604305)
			(xy 309.885322 22.552629) (xy 309.948692 22.49486) (xy 310.006461 22.43149) (xy 310.058137 22.363061)
			(xy 310.103278 22.290155) (xy 310.1415 22.213395) (xy 310.172476 22.133436) (xy 310.195943 22.05096)
			(xy 310.211699 21.96667) (xy 310.219611 21.881287) (xy 310.220106 21.838412) (xy 310.219611 21.795537)
			(xy 314.714877 21.795537) (xy 314.714877 21.881287) (xy 314.722789 21.96667) (xy 314.738545 22.05096)
			(xy 314.762012 22.133436) (xy 314.792988 22.213395) (xy 314.83121 22.290155) (xy 314.876351 22.363061)
			(xy 314.928027 22.43149) (xy 314.985796 22.49486) (xy 315.049166 22.552629) (xy 315.117595 22.604305)
			(xy 315.190501 22.649446) (xy 315.267261 22.687668) (xy 315.34722 22.718644) (xy 315.429696 22.742111)
			(xy 315.513986 22.757867) (xy 315.599369 22.765779) (xy 315.685119 22.765779) (xy 315.770502 22.757867)
			(xy 315.854792 22.742111) (xy 315.937268 22.718644) (xy 316.017227 22.687668) (xy 316.093987 22.649446)
			(xy 316.166893 22.604305) (xy 316.235322 22.552629) (xy 316.298692 22.49486) (xy 316.356461 22.43149)
			(xy 316.408137 22.363061) (xy 316.453278 22.290155) (xy 316.4915 22.213395) (xy 316.522476 22.133436)
			(xy 316.545943 22.05096) (xy 316.561699 21.96667) (xy 316.569611 21.881287) (xy 316.570106 21.838412)
			(xy 316.569693 21.802649) (xy 334.455757 21.802649) (xy 334.455757 21.888399) (xy 334.463669 21.973782)
			(xy 334.479425 22.058072) (xy 334.502892 22.140548) (xy 334.533868 22.220507) (xy 334.57209 22.297267)
			(xy 334.617231 22.370173) (xy 334.668907 22.438602) (xy 334.726676 22.501972) (xy 334.790046 22.559741)
			(xy 334.858475 22.611417) (xy 334.931381 22.656558) (xy 335.008141 22.69478) (xy 335.0881 22.725756)
			(xy 335.170576 22.749223) (xy 335.254866 22.764979) (xy 335.340249 22.772891) (xy 335.425999 22.772891)
			(xy 335.511382 22.764979) (xy 335.595672 22.749223) (xy 335.678148 22.725756) (xy 335.758107 22.69478)
			(xy 335.834867 22.656558) (xy 335.907773 22.611417) (xy 335.976202 22.559741) (xy 336.039572 22.501972)
			(xy 336.097341 22.438602) (xy 336.149017 22.370173) (xy 336.194158 22.297267) (xy 336.23238 22.220507)
			(xy 336.263356 22.140548) (xy 336.286823 22.058072) (xy 336.302579 21.973782) (xy 336.310491 21.888399)
			(xy 336.310986 21.845524) (xy 336.310491 21.802649) (xy 340.805757 21.802649) (xy 340.805757 21.888399)
			(xy 340.813669 21.973782) (xy 340.829425 22.058072) (xy 340.852892 22.140548) (xy 340.883868 22.220507)
			(xy 340.92209 22.297267) (xy 340.967231 22.370173) (xy 341.018907 22.438602) (xy 341.076676 22.501972)
			(xy 341.140046 22.559741) (xy 341.208475 22.611417) (xy 341.281381 22.656558) (xy 341.358141 22.69478)
			(xy 341.4381 22.725756) (xy 341.520576 22.749223) (xy 341.604866 22.764979) (xy 341.690249 22.772891)
			(xy 341.775999 22.772891) (xy 341.861382 22.764979) (xy 341.945672 22.749223) (xy 342.028148 22.725756)
			(xy 342.108107 22.69478) (xy 342.184867 22.656558) (xy 342.257773 22.611417) (xy 342.326202 22.559741)
			(xy 342.389572 22.501972) (xy 342.447341 22.438602) (xy 342.499017 22.370173) (xy 342.544158 22.297267)
			(xy 342.58238 22.220507) (xy 342.613356 22.140548) (xy 342.636823 22.058072) (xy 342.652579 21.973782)
			(xy 342.660491 21.888399) (xy 342.660986 21.845524) (xy 342.660491 21.802649) (xy 342.659832 21.795537)
			(xy 373.515877 21.795537) (xy 373.515877 21.881287) (xy 373.523789 21.96667) (xy 373.539545 22.05096)
			(xy 373.563012 22.133436) (xy 373.593988 22.213395) (xy 373.63221 22.290155) (xy 373.677351 22.363061)
			(xy 373.729027 22.43149) (xy 373.786796 22.49486) (xy 373.850166 22.552629) (xy 373.918595 22.604305)
			(xy 373.991501 22.649446) (xy 374.068261 22.687668) (xy 374.14822 22.718644) (xy 374.230696 22.742111)
			(xy 374.314986 22.757867) (xy 374.400369 22.765779) (xy 374.486119 22.765779) (xy 374.571502 22.757867)
			(xy 374.655792 22.742111) (xy 374.738268 22.718644) (xy 374.818227 22.687668) (xy 374.894987 22.649446)
			(xy 374.967893 22.604305) (xy 375.036322 22.552629) (xy 375.099692 22.49486) (xy 375.157461 22.43149)
			(xy 375.209137 22.363061) (xy 375.254278 22.290155) (xy 375.2925 22.213395) (xy 375.323476 22.133436)
			(xy 375.346943 22.05096) (xy 375.362699 21.96667) (xy 375.370611 21.881287) (xy 375.371106 21.838412)
			(xy 375.370611 21.795537) (xy 379.865877 21.795537) (xy 379.865877 21.881287) (xy 379.873789 21.96667)
			(xy 379.889545 22.05096) (xy 379.913012 22.133436) (xy 379.943988 22.213395) (xy 379.98221 22.290155)
			(xy 380.027351 22.363061) (xy 380.079027 22.43149) (xy 380.136796 22.49486) (xy 380.200166 22.552629)
			(xy 380.268595 22.604305) (xy 380.341501 22.649446) (xy 380.418261 22.687668) (xy 380.49822 22.718644)
			(xy 380.580696 22.742111) (xy 380.664986 22.757867) (xy 380.750369 22.765779) (xy 380.836119 22.765779)
			(xy 380.921502 22.757867) (xy 381.005792 22.742111) (xy 381.088268 22.718644) (xy 381.168227 22.687668)
			(xy 381.244987 22.649446) (xy 381.317893 22.604305) (xy 381.386322 22.552629) (xy 381.449692 22.49486)
			(xy 381.507461 22.43149) (xy 381.559137 22.363061) (xy 381.604278 22.290155) (xy 381.6425 22.213395)
			(xy 381.673476 22.133436) (xy 381.696943 22.05096) (xy 381.712699 21.96667) (xy 381.720611 21.881287)
			(xy 381.721106 21.838412) (xy 381.720693 21.802649) (xy 399.098757 21.802649) (xy 399.098757 21.888399)
			(xy 399.106669 21.973782) (xy 399.122425 22.058072) (xy 399.145892 22.140548) (xy 399.176868 22.220507)
			(xy 399.21509 22.297267) (xy 399.260231 22.370173) (xy 399.311907 22.438602) (xy 399.369676 22.501972)
			(xy 399.433046 22.559741) (xy 399.501475 22.611417) (xy 399.574381 22.656558) (xy 399.651141 22.69478)
			(xy 399.7311 22.725756) (xy 399.813576 22.749223) (xy 399.897866 22.764979) (xy 399.983249 22.772891)
			(xy 400.068999 22.772891) (xy 400.154382 22.764979) (xy 400.238672 22.749223) (xy 400.321148 22.725756)
			(xy 400.401107 22.69478) (xy 400.477867 22.656558) (xy 400.550773 22.611417) (xy 400.619202 22.559741)
			(xy 400.682572 22.501972) (xy 400.740341 22.438602) (xy 400.792017 22.370173) (xy 400.837158 22.297267)
			(xy 400.87538 22.220507) (xy 400.906356 22.140548) (xy 400.929823 22.058072) (xy 400.945579 21.973782)
			(xy 400.953491 21.888399) (xy 400.953986 21.845524) (xy 400.953491 21.802649) (xy 405.448757 21.802649)
			(xy 405.448757 21.888399) (xy 405.456669 21.973782) (xy 405.472425 22.058072) (xy 405.495892 22.140548)
			(xy 405.526868 22.220507) (xy 405.56509 22.297267) (xy 405.610231 22.370173) (xy 405.661907 22.438602)
			(xy 405.719676 22.501972) (xy 405.783046 22.559741) (xy 405.851475 22.611417) (xy 405.924381 22.656558)
			(xy 406.001141 22.69478) (xy 406.0811 22.725756) (xy 406.163576 22.749223) (xy 406.247866 22.764979)
			(xy 406.333249 22.772891) (xy 406.418999 22.772891) (xy 406.504382 22.764979) (xy 406.588672 22.749223)
			(xy 406.671148 22.725756) (xy 406.751107 22.69478) (xy 406.827867 22.656558) (xy 406.900773 22.611417)
			(xy 406.969202 22.559741) (xy 407.032572 22.501972) (xy 407.090341 22.438602) (xy 407.142017 22.370173)
			(xy 407.187158 22.297267) (xy 407.22538 22.220507) (xy 407.256356 22.140548) (xy 407.279823 22.058072)
			(xy 407.295579 21.973782) (xy 407.303491 21.888399) (xy 407.303986 21.845524) (xy 407.303491 21.802649)
			(xy 407.302832 21.795537) (xy 438.158877 21.795537) (xy 438.158877 21.881287) (xy 438.166789 21.96667)
			(xy 438.182545 22.05096) (xy 438.206012 22.133436) (xy 438.236988 22.213395) (xy 438.27521 22.290155)
			(xy 438.320351 22.363061) (xy 438.372027 22.43149) (xy 438.429796 22.49486) (xy 438.493166 22.552629)
			(xy 438.561595 22.604305) (xy 438.634501 22.649446) (xy 438.711261 22.687668) (xy 438.79122 22.718644)
			(xy 438.873696 22.742111) (xy 438.957986 22.757867) (xy 439.043369 22.765779) (xy 439.129119 22.765779)
			(xy 439.214502 22.757867) (xy 439.298792 22.742111) (xy 439.381268 22.718644) (xy 439.461227 22.687668)
			(xy 439.537987 22.649446) (xy 439.610893 22.604305) (xy 439.679322 22.552629) (xy 439.742692 22.49486)
			(xy 439.800461 22.43149) (xy 439.852137 22.363061) (xy 439.897278 22.290155) (xy 439.9355 22.213395)
			(xy 439.966476 22.133436) (xy 439.989943 22.05096) (xy 440.005699 21.96667) (xy 440.013611 21.881287)
			(xy 440.014106 21.838412) (xy 440.013611 21.795537) (xy 444.508877 21.795537) (xy 444.508877 21.881287)
			(xy 444.516789 21.96667) (xy 444.532545 22.05096) (xy 444.556012 22.133436) (xy 444.586988 22.213395)
			(xy 444.62521 22.290155) (xy 444.670351 22.363061) (xy 444.722027 22.43149) (xy 444.779796 22.49486)
			(xy 444.843166 22.552629) (xy 444.911595 22.604305) (xy 444.984501 22.649446) (xy 445.061261 22.687668)
			(xy 445.14122 22.718644) (xy 445.223696 22.742111) (xy 445.307986 22.757867) (xy 445.393369 22.765779)
			(xy 445.479119 22.765779) (xy 445.564502 22.757867) (xy 445.648792 22.742111) (xy 445.731268 22.718644)
			(xy 445.811227 22.687668) (xy 445.887987 22.649446) (xy 445.960893 22.604305) (xy 446.029322 22.552629)
			(xy 446.092692 22.49486) (xy 446.150461 22.43149) (xy 446.202137 22.363061) (xy 446.247278 22.290155)
			(xy 446.2855 22.213395) (xy 446.316476 22.133436) (xy 446.339943 22.05096) (xy 446.355699 21.96667)
			(xy 446.363611 21.881287) (xy 446.364106 21.838412) (xy 446.363611 21.795537) (xy 446.355699 21.710154)
			(xy 446.339943 21.625864) (xy 446.316476 21.543388) (xy 446.2855 21.463429) (xy 446.247278 21.386669)
			(xy 446.202137 21.313763) (xy 446.150461 21.245334) (xy 446.092692 21.181964) (xy 446.029322 21.124195)
			(xy 445.988175 21.093122) (xy 460.504275 21.093122) (xy 460.504275 21.222262) (xy 460.512225 21.351157)
			(xy 460.528095 21.479317) (xy 460.551824 21.606258) (xy 460.583323 21.731497) (xy 460.622472 21.85456)
			(xy 460.669123 21.974979) (xy 460.723098 22.092298) (xy 460.784193 22.206072) (xy 460.852176 22.315869)
			(xy 460.92679 22.421272) (xy 461.007751 22.521882) (xy 461.094751 22.617317) (xy 461.187462 22.707216)
			(xy 461.285532 22.791237) (xy 461.388587 22.869061) (xy 461.496238 22.940393) (xy 461.608077 23.004963)
			(xy 461.723678 23.062525) (xy 461.842603 23.112862) (xy 461.964402 23.155782) (xy 462.088612 23.191123)
			(xy 462.214761 23.21875) (xy 462.342373 23.238559) (xy 462.470962 23.250475) (xy 462.60004 23.254452)
			(xy 462.729118 23.250475) (xy 462.857707 23.238559) (xy 462.985319 23.21875) (xy 463.111468 23.191123)
			(xy 463.235678 23.155782) (xy 463.357477 23.112862) (xy 463.476402 23.062525) (xy 463.592003 23.004963)
			(xy 463.703842 22.940393) (xy 463.811493 22.869061) (xy 463.914548 22.791237) (xy 464.012618 22.707216)
			(xy 464.105329 22.617317) (xy 464.192329 22.521882) (xy 464.27329 22.421272) (xy 464.347904 22.315869)
			(xy 464.415887 22.206072) (xy 464.476982 22.092298) (xy 464.530957 21.974979) (xy 464.577608 21.85456)
			(xy 464.616757 21.731497) (xy 464.648256 21.606258) (xy 464.671985 21.479317) (xy 464.687855 21.351157)
			(xy 464.695805 21.222262) (xy 464.696302 21.157692) (xy 464.695805 21.093122) (xy 464.687855 20.964227)
			(xy 464.671985 20.836067) (xy 464.648256 20.709126) (xy 464.616757 20.583887) (xy 464.577608 20.460824)
			(xy 464.530957 20.340405) (xy 464.476982 20.223086) (xy 464.415887 20.109312) (xy 464.347904 19.999515)
			(xy 464.27329 19.894112) (xy 464.192329 19.793502) (xy 464.105329 19.698067) (xy 464.012618 19.608168)
			(xy 463.914548 19.524147) (xy 463.811493 19.446323) (xy 463.703842 19.374991) (xy 463.592003 19.310421)
			(xy 463.476402 19.252859) (xy 463.357477 19.202522) (xy 463.235678 19.159602) (xy 463.111468 19.124261)
			(xy 462.985319 19.096634) (xy 462.857707 19.076825) (xy 462.729118 19.064909) (xy 462.60004 19.060933)
			(xy 462.470962 19.064909) (xy 462.342373 19.076825) (xy 462.214761 19.096634) (xy 462.088612 19.124261)
			(xy 461.964402 19.159602) (xy 461.842603 19.202522) (xy 461.723678 19.252859) (xy 461.608077 19.310421)
			(xy 461.496238 19.374991) (xy 461.388587 19.446323) (xy 461.285532 19.524147) (xy 461.187462 19.608168)
			(xy 461.094751 19.698067) (xy 461.007751 19.793502) (xy 460.92679 19.894112) (xy 460.852176 19.999515)
			(xy 460.784193 20.109312) (xy 460.723098 20.223086) (xy 460.669123 20.340405) (xy 460.622472 20.460824)
			(xy 460.583323 20.583887) (xy 460.551824 20.709126) (xy 460.528095 20.836067) (xy 460.512225 20.964227)
			(xy 460.504275 21.093122) (xy 445.988175 21.093122) (xy 445.960893 21.072519) (xy 445.887987 21.027378)
			(xy 445.811227 20.989156) (xy 445.731268 20.95818) (xy 445.648792 20.934713) (xy 445.564502 20.918957)
			(xy 445.479119 20.911045) (xy 445.393369 20.911045) (xy 445.307986 20.918957) (xy 445.223696 20.934713)
			(xy 445.14122 20.95818) (xy 445.061261 20.989156) (xy 444.984501 21.027378) (xy 444.911595 21.072519)
			(xy 444.843166 21.124195) (xy 444.779796 21.181964) (xy 444.722027 21.245334) (xy 444.670351 21.313763)
			(xy 444.62521 21.386669) (xy 444.586988 21.463429) (xy 444.556012 21.543388) (xy 444.532545 21.625864)
			(xy 444.516789 21.710154) (xy 444.508877 21.795537) (xy 440.013611 21.795537) (xy 440.005699 21.710154)
			(xy 439.989943 21.625864) (xy 439.966476 21.543388) (xy 439.9355 21.463429) (xy 439.897278 21.386669)
			(xy 439.852137 21.313763) (xy 439.800461 21.245334) (xy 439.742692 21.181964) (xy 439.679322 21.124195)
			(xy 439.610893 21.072519) (xy 439.537987 21.027378) (xy 439.461227 20.989156) (xy 439.381268 20.95818)
			(xy 439.298792 20.934713) (xy 439.214502 20.918957) (xy 439.129119 20.911045) (xy 439.043369 20.911045)
			(xy 438.957986 20.918957) (xy 438.873696 20.934713) (xy 438.79122 20.95818) (xy 438.711261 20.989156)
			(xy 438.634501 21.027378) (xy 438.561595 21.072519) (xy 438.493166 21.124195) (xy 438.429796 21.181964)
			(xy 438.372027 21.245334) (xy 438.320351 21.313763) (xy 438.27521 21.386669) (xy 438.236988 21.463429)
			(xy 438.206012 21.543388) (xy 438.182545 21.625864) (xy 438.166789 21.710154) (xy 438.158877 21.795537)
			(xy 407.302832 21.795537) (xy 407.295579 21.717266) (xy 407.279823 21.632976) (xy 407.256356 21.5505)
			(xy 407.22538 21.470541) (xy 407.187158 21.393781) (xy 407.142017 21.320875) (xy 407.090341 21.252446)
			(xy 407.032572 21.189076) (xy 406.969202 21.131307) (xy 406.900773 21.079631) (xy 406.827867 21.03449)
			(xy 406.751107 20.996268) (xy 406.671148 20.965292) (xy 406.588672 20.941825) (xy 406.504382 20.926069)
			(xy 406.418999 20.918157) (xy 406.333249 20.918157) (xy 406.247866 20.926069) (xy 406.163576 20.941825)
			(xy 406.0811 20.965292) (xy 406.001141 20.996268) (xy 405.924381 21.03449) (xy 405.851475 21.079631)
			(xy 405.783046 21.131307) (xy 405.719676 21.189076) (xy 405.661907 21.252446) (xy 405.610231 21.320875)
			(xy 405.56509 21.393781) (xy 405.526868 21.470541) (xy 405.495892 21.5505) (xy 405.472425 21.632976)
			(xy 405.456669 21.717266) (xy 405.448757 21.802649) (xy 400.953491 21.802649) (xy 400.945579 21.717266)
			(xy 400.929823 21.632976) (xy 400.906356 21.5505) (xy 400.87538 21.470541) (xy 400.837158 21.393781)
			(xy 400.792017 21.320875) (xy 400.740341 21.252446) (xy 400.682572 21.189076) (xy 400.619202 21.131307)
			(xy 400.550773 21.079631) (xy 400.477867 21.03449) (xy 400.401107 20.996268) (xy 400.321148 20.965292)
			(xy 400.238672 20.941825) (xy 400.154382 20.926069) (xy 400.068999 20.918157) (xy 399.983249 20.918157)
			(xy 399.897866 20.926069) (xy 399.813576 20.941825) (xy 399.7311 20.965292) (xy 399.651141 20.996268)
			(xy 399.574381 21.03449) (xy 399.501475 21.079631) (xy 399.433046 21.131307) (xy 399.369676 21.189076)
			(xy 399.311907 21.252446) (xy 399.260231 21.320875) (xy 399.21509 21.393781) (xy 399.176868 21.470541)
			(xy 399.145892 21.5505) (xy 399.122425 21.632976) (xy 399.106669 21.717266) (xy 399.098757 21.802649)
			(xy 381.720693 21.802649) (xy 381.720611 21.795537) (xy 381.712699 21.710154) (xy 381.696943 21.625864)
			(xy 381.673476 21.543388) (xy 381.6425 21.463429) (xy 381.604278 21.386669) (xy 381.559137 21.313763)
			(xy 381.507461 21.245334) (xy 381.449692 21.181964) (xy 381.386322 21.124195) (xy 381.317893 21.072519)
			(xy 381.244987 21.027378) (xy 381.168227 20.989156) (xy 381.088268 20.95818) (xy 381.005792 20.934713)
			(xy 380.921502 20.918957) (xy 380.836119 20.911045) (xy 380.750369 20.911045) (xy 380.664986 20.918957)
			(xy 380.580696 20.934713) (xy 380.49822 20.95818) (xy 380.418261 20.989156) (xy 380.341501 21.027378)
			(xy 380.268595 21.072519) (xy 380.200166 21.124195) (xy 380.136796 21.181964) (xy 380.079027 21.245334)
			(xy 380.027351 21.313763) (xy 379.98221 21.386669) (xy 379.943988 21.463429) (xy 379.913012 21.543388)
			(xy 379.889545 21.625864) (xy 379.873789 21.710154) (xy 379.865877 21.795537) (xy 375.370611 21.795537)
			(xy 375.362699 21.710154) (xy 375.346943 21.625864) (xy 375.323476 21.543388) (xy 375.2925 21.463429)
			(xy 375.254278 21.386669) (xy 375.209137 21.313763) (xy 375.157461 21.245334) (xy 375.099692 21.181964)
			(xy 375.036322 21.124195) (xy 374.967893 21.072519) (xy 374.894987 21.027378) (xy 374.818227 20.989156)
			(xy 374.738268 20.95818) (xy 374.655792 20.934713) (xy 374.571502 20.918957) (xy 374.486119 20.911045)
			(xy 374.400369 20.911045) (xy 374.314986 20.918957) (xy 374.230696 20.934713) (xy 374.14822 20.95818)
			(xy 374.068261 20.989156) (xy 373.991501 21.027378) (xy 373.918595 21.072519) (xy 373.850166 21.124195)
			(xy 373.786796 21.181964) (xy 373.729027 21.245334) (xy 373.677351 21.313763) (xy 373.63221 21.386669)
			(xy 373.593988 21.463429) (xy 373.563012 21.543388) (xy 373.539545 21.625864) (xy 373.523789 21.710154)
			(xy 373.515877 21.795537) (xy 342.659832 21.795537) (xy 342.652579 21.717266) (xy 342.636823 21.632976)
			(xy 342.613356 21.5505) (xy 342.58238 21.470541) (xy 342.544158 21.393781) (xy 342.499017 21.320875)
			(xy 342.447341 21.252446) (xy 342.389572 21.189076) (xy 342.326202 21.131307) (xy 342.257773 21.079631)
			(xy 342.184867 21.03449) (xy 342.108107 20.996268) (xy 342.028148 20.965292) (xy 341.945672 20.941825)
			(xy 341.861382 20.926069) (xy 341.775999 20.918157) (xy 341.690249 20.918157) (xy 341.604866 20.926069)
			(xy 341.520576 20.941825) (xy 341.4381 20.965292) (xy 341.358141 20.996268) (xy 341.281381 21.03449)
			(xy 341.208475 21.079631) (xy 341.140046 21.131307) (xy 341.076676 21.189076) (xy 341.018907 21.252446)
			(xy 340.967231 21.320875) (xy 340.92209 21.393781) (xy 340.883868 21.470541) (xy 340.852892 21.5505)
			(xy 340.829425 21.632976) (xy 340.813669 21.717266) (xy 340.805757 21.802649) (xy 336.310491 21.802649)
			(xy 336.302579 21.717266) (xy 336.286823 21.632976) (xy 336.263356 21.5505) (xy 336.23238 21.470541)
			(xy 336.194158 21.393781) (xy 336.149017 21.320875) (xy 336.097341 21.252446) (xy 336.039572 21.189076)
			(xy 335.976202 21.131307) (xy 335.907773 21.079631) (xy 335.834867 21.03449) (xy 335.758107 20.996268)
			(xy 335.678148 20.965292) (xy 335.595672 20.941825) (xy 335.511382 20.926069) (xy 335.425999 20.918157)
			(xy 335.340249 20.918157) (xy 335.254866 20.926069) (xy 335.170576 20.941825) (xy 335.0881 20.965292)
			(xy 335.008141 20.996268) (xy 334.931381 21.03449) (xy 334.858475 21.079631) (xy 334.790046 21.131307)
			(xy 334.726676 21.189076) (xy 334.668907 21.252446) (xy 334.617231 21.320875) (xy 334.57209 21.393781)
			(xy 334.533868 21.470541) (xy 334.502892 21.5505) (xy 334.479425 21.632976) (xy 334.463669 21.717266)
			(xy 334.455757 21.802649) (xy 316.569693 21.802649) (xy 316.569611 21.795537) (xy 316.561699 21.710154)
			(xy 316.545943 21.625864) (xy 316.522476 21.543388) (xy 316.4915 21.463429) (xy 316.453278 21.386669)
			(xy 316.408137 21.313763) (xy 316.356461 21.245334) (xy 316.298692 21.181964) (xy 316.235322 21.124195)
			(xy 316.166893 21.072519) (xy 316.093987 21.027378) (xy 316.017227 20.989156) (xy 315.937268 20.95818)
			(xy 315.854792 20.934713) (xy 315.770502 20.918957) (xy 315.685119 20.911045) (xy 315.599369 20.911045)
			(xy 315.513986 20.918957) (xy 315.429696 20.934713) (xy 315.34722 20.95818) (xy 315.267261 20.989156)
			(xy 315.190501 21.027378) (xy 315.117595 21.072519) (xy 315.049166 21.124195) (xy 314.985796 21.181964)
			(xy 314.928027 21.245334) (xy 314.876351 21.313763) (xy 314.83121 21.386669) (xy 314.792988 21.463429)
			(xy 314.762012 21.543388) (xy 314.738545 21.625864) (xy 314.722789 21.710154) (xy 314.714877 21.795537)
			(xy 310.219611 21.795537) (xy 310.211699 21.710154) (xy 310.195943 21.625864) (xy 310.172476 21.543388)
			(xy 310.1415 21.463429) (xy 310.103278 21.386669) (xy 310.058137 21.313763) (xy 310.006461 21.245334)
			(xy 309.948692 21.181964) (xy 309.885322 21.124195) (xy 309.816893 21.072519) (xy 309.743987 21.027378)
			(xy 309.667227 20.989156) (xy 309.587268 20.95818) (xy 309.504792 20.934713) (xy 309.420502 20.918957)
			(xy 309.335119 20.911045) (xy 309.249369 20.911045) (xy 309.163986 20.918957) (xy 309.079696 20.934713)
			(xy 308.99722 20.95818) (xy 308.917261 20.989156) (xy 308.840501 21.027378) (xy 308.767595 21.072519)
			(xy 308.699166 21.124195) (xy 308.635796 21.181964) (xy 308.578027 21.245334) (xy 308.526351 21.313763)
			(xy 308.48121 21.386669) (xy 308.442988 21.463429) (xy 308.412012 21.543388) (xy 308.388545 21.625864)
			(xy 308.372789 21.710154) (xy 308.364877 21.795537) (xy 277.508832 21.795537) (xy 277.501579 21.717266)
			(xy 277.485823 21.632976) (xy 277.462356 21.5505) (xy 277.43138 21.470541) (xy 277.393158 21.393781)
			(xy 277.348017 21.320875) (xy 277.296341 21.252446) (xy 277.238572 21.189076) (xy 277.175202 21.131307)
			(xy 277.106773 21.079631) (xy 277.033867 21.03449) (xy 276.957107 20.996268) (xy 276.877148 20.965292)
			(xy 276.794672 20.941825) (xy 276.710382 20.926069) (xy 276.624999 20.918157) (xy 276.539249 20.918157)
			(xy 276.453866 20.926069) (xy 276.369576 20.941825) (xy 276.2871 20.965292) (xy 276.207141 20.996268)
			(xy 276.130381 21.03449) (xy 276.057475 21.079631) (xy 275.989046 21.131307) (xy 275.925676 21.189076)
			(xy 275.867907 21.252446) (xy 275.816231 21.320875) (xy 275.77109 21.393781) (xy 275.732868 21.470541)
			(xy 275.701892 21.5505) (xy 275.678425 21.632976) (xy 275.662669 21.717266) (xy 275.654757 21.802649)
			(xy 271.159491 21.802649) (xy 271.151579 21.717266) (xy 271.135823 21.632976) (xy 271.112356 21.5505)
			(xy 271.08138 21.470541) (xy 271.043158 21.393781) (xy 270.998017 21.320875) (xy 270.946341 21.252446)
			(xy 270.888572 21.189076) (xy 270.825202 21.131307) (xy 270.756773 21.079631) (xy 270.683867 21.03449)
			(xy 270.607107 20.996268) (xy 270.527148 20.965292) (xy 270.444672 20.941825) (xy 270.360382 20.926069)
			(xy 270.274999 20.918157) (xy 270.189249 20.918157) (xy 270.103866 20.926069) (xy 270.019576 20.941825)
			(xy 269.9371 20.965292) (xy 269.857141 20.996268) (xy 269.780381 21.03449) (xy 269.707475 21.079631)
			(xy 269.639046 21.131307) (xy 269.575676 21.189076) (xy 269.517907 21.252446) (xy 269.466231 21.320875)
			(xy 269.42109 21.393781) (xy 269.382868 21.470541) (xy 269.351892 21.5505) (xy 269.328425 21.632976)
			(xy 269.312669 21.717266) (xy 269.304757 21.802649) (xy 158.621984 21.802649) (xy 158.621984 19.262649)
			(xy 209.995757 19.262649) (xy 209.995757 19.348399) (xy 210.003669 19.433782) (xy 210.019425 19.518072)
			(xy 210.042892 19.600548) (xy 210.073868 19.680507) (xy 210.11209 19.757267) (xy 210.157231 19.830173)
			(xy 210.208907 19.898602) (xy 210.266676 19.961972) (xy 210.330046 20.019741) (xy 210.398475 20.071417)
			(xy 210.471381 20.116558) (xy 210.548141 20.15478) (xy 210.6281 20.185756) (xy 210.710576 20.209223)
			(xy 210.794866 20.224979) (xy 210.880249 20.232891) (xy 210.965999 20.232891) (xy 211.051382 20.224979)
			(xy 211.135672 20.209223) (xy 211.218148 20.185756) (xy 211.298107 20.15478) (xy 211.374867 20.116558)
			(xy 211.447773 20.071417) (xy 211.516202 20.019741) (xy 211.579572 19.961972) (xy 211.637341 19.898602)
			(xy 211.689017 19.830173) (xy 211.734158 19.757267) (xy 211.77238 19.680507) (xy 211.803356 19.600548)
			(xy 211.826823 19.518072) (xy 211.842579 19.433782) (xy 211.850491 19.348399) (xy 211.850986 19.305524)
			(xy 211.850491 19.262649) (xy 216.345757 19.262649) (xy 216.345757 19.348399) (xy 216.353669 19.433782)
			(xy 216.369425 19.518072) (xy 216.392892 19.600548) (xy 216.423868 19.680507) (xy 216.46209 19.757267)
			(xy 216.507231 19.830173) (xy 216.558907 19.898602) (xy 216.616676 19.961972) (xy 216.680046 20.019741)
			(xy 216.748475 20.071417) (xy 216.821381 20.116558) (xy 216.898141 20.15478) (xy 216.9781 20.185756)
			(xy 217.060576 20.209223) (xy 217.144866 20.224979) (xy 217.230249 20.232891) (xy 217.315999 20.232891)
			(xy 217.401382 20.224979) (xy 217.485672 20.209223) (xy 217.568148 20.185756) (xy 217.648107 20.15478)
			(xy 217.724867 20.116558) (xy 217.797773 20.071417) (xy 217.866202 20.019741) (xy 217.929572 19.961972)
			(xy 217.987341 19.898602) (xy 218.039017 19.830173) (xy 218.084158 19.757267) (xy 218.12238 19.680507)
			(xy 218.153356 19.600548) (xy 218.176823 19.518072) (xy 218.192579 19.433782) (xy 218.200491 19.348399)
			(xy 218.200986 19.305524) (xy 218.200491 19.262649) (xy 218.199832 19.255537) (xy 244.026677 19.255537)
			(xy 244.026677 19.341287) (xy 244.034589 19.42667) (xy 244.050345 19.51096) (xy 244.073812 19.593436)
			(xy 244.104788 19.673395) (xy 244.14301 19.750155) (xy 244.188151 19.823061) (xy 244.239827 19.89149)
			(xy 244.297596 19.95486) (xy 244.360966 20.012629) (xy 244.429395 20.064305) (xy 244.502301 20.109446)
			(xy 244.579061 20.147668) (xy 244.65902 20.178644) (xy 244.741496 20.202111) (xy 244.825786 20.217867)
			(xy 244.911169 20.225779) (xy 244.996919 20.225779) (xy 245.082302 20.217867) (xy 245.166592 20.202111)
			(xy 245.249068 20.178644) (xy 245.329027 20.147668) (xy 245.405787 20.109446) (xy 245.478693 20.064305)
			(xy 245.547122 20.012629) (xy 245.610492 19.95486) (xy 245.668261 19.89149) (xy 245.719937 19.823061)
			(xy 245.765078 19.750155) (xy 245.8033 19.673395) (xy 245.834276 19.593436) (xy 245.857743 19.51096)
			(xy 245.873499 19.42667) (xy 245.881411 19.341287) (xy 245.881906 19.298412) (xy 245.881411 19.255537)
			(xy 250.376677 19.255537) (xy 250.376677 19.341287) (xy 250.384589 19.42667) (xy 250.400345 19.51096)
			(xy 250.423812 19.593436) (xy 250.454788 19.673395) (xy 250.49301 19.750155) (xy 250.538151 19.823061)
			(xy 250.589827 19.89149) (xy 250.647596 19.95486) (xy 250.710966 20.012629) (xy 250.779395 20.064305)
			(xy 250.852301 20.109446) (xy 250.929061 20.147668) (xy 251.00902 20.178644) (xy 251.091496 20.202111)
			(xy 251.175786 20.217867) (xy 251.261169 20.225779) (xy 251.346919 20.225779) (xy 251.432302 20.217867)
			(xy 251.516592 20.202111) (xy 251.599068 20.178644) (xy 251.679027 20.147668) (xy 251.755787 20.109446)
			(xy 251.828693 20.064305) (xy 251.897122 20.012629) (xy 251.960492 19.95486) (xy 252.018261 19.89149)
			(xy 252.069937 19.823061) (xy 252.115078 19.750155) (xy 252.1533 19.673395) (xy 252.184276 19.593436)
			(xy 252.207743 19.51096) (xy 252.223499 19.42667) (xy 252.231411 19.341287) (xy 252.231906 19.298412)
			(xy 252.231493 19.262649) (xy 269.304757 19.262649) (xy 269.304757 19.348399) (xy 269.312669 19.433782)
			(xy 269.328425 19.518072) (xy 269.351892 19.600548) (xy 269.382868 19.680507) (xy 269.42109 19.757267)
			(xy 269.466231 19.830173) (xy 269.517907 19.898602) (xy 269.575676 19.961972) (xy 269.639046 20.019741)
			(xy 269.707475 20.071417) (xy 269.780381 20.116558) (xy 269.857141 20.15478) (xy 269.9371 20.185756)
			(xy 270.019576 20.209223) (xy 270.103866 20.224979) (xy 270.189249 20.232891) (xy 270.274999 20.232891)
			(xy 270.360382 20.224979) (xy 270.444672 20.209223) (xy 270.527148 20.185756) (xy 270.607107 20.15478)
			(xy 270.62931 20.143724) (xy 274.239736 20.143724) (xy 274.239736 21.007324) (xy 274.240222 21.034593)
			(xy 274.247984 21.088577) (xy 274.263349 21.140907) (xy 274.286006 21.190517) (xy 274.315492 21.236398)
			(xy 274.351207 21.277615) (xy 274.392424 21.31333) (xy 274.438305 21.342816) (xy 274.487915 21.365473)
			(xy 274.540245 21.380838) (xy 274.594229 21.3886) (xy 274.648767 21.3886) (xy 274.702751 21.380838)
			(xy 274.755081 21.365473) (xy 274.804691 21.342816) (xy 274.850572 21.31333) (xy 274.891789 21.277615)
			(xy 274.927504 21.236398) (xy 274.95699 21.190517) (xy 274.979647 21.140907) (xy 274.995012 21.088577)
			(xy 275.002774 21.034593) (xy 275.00326 21.007324) (xy 275.00326 20.143724) (xy 275.002774 20.116455)
			(xy 274.995012 20.062471) (xy 274.979647 20.010141) (xy 274.95699 19.960531) (xy 274.927504 19.91465)
			(xy 274.891789 19.873433) (xy 274.850572 19.837718) (xy 274.804691 19.808232) (xy 274.755081 19.785575)
			(xy 274.702751 19.77021) (xy 274.648767 19.762448) (xy 274.594229 19.762448) (xy 274.540245 19.77021)
			(xy 274.487915 19.785575) (xy 274.438305 19.808232) (xy 274.392424 19.837718) (xy 274.351207 19.873433)
			(xy 274.315492 19.91465) (xy 274.286006 19.960531) (xy 274.263349 20.010141) (xy 274.247984 20.062471)
			(xy 274.240222 20.116455) (xy 274.239736 20.143724) (xy 270.62931 20.143724) (xy 270.683867 20.116558)
			(xy 270.756773 20.071417) (xy 270.825202 20.019741) (xy 270.888572 19.961972) (xy 270.946341 19.898602)
			(xy 270.998017 19.830173) (xy 271.043158 19.757267) (xy 271.08138 19.680507) (xy 271.112356 19.600548)
			(xy 271.135823 19.518072) (xy 271.151579 19.433782) (xy 271.159491 19.348399) (xy 271.159986 19.305524)
			(xy 271.159491 19.262649) (xy 275.654757 19.262649) (xy 275.654757 19.348399) (xy 275.662669 19.433782)
			(xy 275.678425 19.518072) (xy 275.701892 19.600548) (xy 275.732868 19.680507) (xy 275.77109 19.757267)
			(xy 275.816231 19.830173) (xy 275.867907 19.898602) (xy 275.925676 19.961972) (xy 275.989046 20.019741)
			(xy 276.057475 20.071417) (xy 276.130381 20.116558) (xy 276.207141 20.15478) (xy 276.2871 20.185756)
			(xy 276.369576 20.209223) (xy 276.453866 20.224979) (xy 276.539249 20.232891) (xy 276.624999 20.232891)
			(xy 276.710382 20.224979) (xy 276.794672 20.209223) (xy 276.877148 20.185756) (xy 276.957107 20.15478)
			(xy 277.033867 20.116558) (xy 277.106773 20.071417) (xy 277.175202 20.019741) (xy 277.238572 19.961972)
			(xy 277.296341 19.898602) (xy 277.348017 19.830173) (xy 277.393158 19.757267) (xy 277.43138 19.680507)
			(xy 277.462356 19.600548) (xy 277.485823 19.518072) (xy 277.501579 19.433782) (xy 277.509491 19.348399)
			(xy 277.509986 19.305524) (xy 277.509491 19.262649) (xy 277.508832 19.255537) (xy 308.364877 19.255537)
			(xy 308.364877 19.341287) (xy 308.372789 19.42667) (xy 308.388545 19.51096) (xy 308.412012 19.593436)
			(xy 308.442988 19.673395) (xy 308.48121 19.750155) (xy 308.526351 19.823061) (xy 308.578027 19.89149)
			(xy 308.635796 19.95486) (xy 308.699166 20.012629) (xy 308.767595 20.064305) (xy 308.840501 20.109446)
			(xy 308.917261 20.147668) (xy 308.99722 20.178644) (xy 309.079696 20.202111) (xy 309.163986 20.217867)
			(xy 309.249369 20.225779) (xy 309.335119 20.225779) (xy 309.420502 20.217867) (xy 309.504792 20.202111)
			(xy 309.587268 20.178644) (xy 309.667227 20.147668) (xy 309.68943 20.136612) (xy 310.871108 20.136612)
			(xy 310.871108 21.000212) (xy 310.871594 21.027481) (xy 310.879356 21.081465) (xy 310.894721 21.133795)
			(xy 310.917378 21.183405) (xy 310.946864 21.229286) (xy 310.982579 21.270503) (xy 311.023796 21.306218)
			(xy 311.069677 21.335704) (xy 311.119287 21.358361) (xy 311.171617 21.373726) (xy 311.225601 21.381488)
			(xy 311.280139 21.381488) (xy 311.334123 21.373726) (xy 311.386453 21.358361) (xy 311.436063 21.335704)
			(xy 311.481944 21.306218) (xy 311.523161 21.270503) (xy 311.558876 21.229286) (xy 311.588362 21.183405)
			(xy 311.611019 21.133795) (xy 311.626384 21.081465) (xy 311.634146 21.027481) (xy 311.634632 21.000212)
			(xy 311.634632 20.136612) (xy 311.634146 20.109343) (xy 311.626384 20.055359) (xy 311.611019 20.003029)
			(xy 311.588362 19.953419) (xy 311.558876 19.907538) (xy 311.523161 19.866321) (xy 311.481944 19.830606)
			(xy 311.436063 19.80112) (xy 311.386453 19.778463) (xy 311.334123 19.763098) (xy 311.280139 19.755336)
			(xy 311.225601 19.755336) (xy 311.171617 19.763098) (xy 311.119287 19.778463) (xy 311.069677 19.80112)
			(xy 311.023796 19.830606) (xy 310.982579 19.866321) (xy 310.946864 19.907538) (xy 310.917378 19.953419)
			(xy 310.894721 20.003029) (xy 310.879356 20.055359) (xy 310.871594 20.109343) (xy 310.871108 20.136612)
			(xy 309.68943 20.136612) (xy 309.743987 20.109446) (xy 309.816893 20.064305) (xy 309.885322 20.012629)
			(xy 309.948692 19.95486) (xy 310.006461 19.89149) (xy 310.058137 19.823061) (xy 310.103278 19.750155)
			(xy 310.1415 19.673395) (xy 310.172476 19.593436) (xy 310.195943 19.51096) (xy 310.211699 19.42667)
			(xy 310.219611 19.341287) (xy 310.220106 19.298412) (xy 310.219611 19.255537) (xy 314.714877 19.255537)
			(xy 314.714877 19.341287) (xy 314.722789 19.42667) (xy 314.738545 19.51096) (xy 314.762012 19.593436)
			(xy 314.792988 19.673395) (xy 314.83121 19.750155) (xy 314.876351 19.823061) (xy 314.928027 19.89149)
			(xy 314.985796 19.95486) (xy 315.049166 20.012629) (xy 315.117595 20.064305) (xy 315.190501 20.109446)
			(xy 315.267261 20.147668) (xy 315.34722 20.178644) (xy 315.429696 20.202111) (xy 315.513986 20.217867)
			(xy 315.599369 20.225779) (xy 315.685119 20.225779) (xy 315.770502 20.217867) (xy 315.854792 20.202111)
			(xy 315.937268 20.178644) (xy 316.017227 20.147668) (xy 316.093987 20.109446) (xy 316.166893 20.064305)
			(xy 316.235322 20.012629) (xy 316.298692 19.95486) (xy 316.356461 19.89149) (xy 316.408137 19.823061)
			(xy 316.453278 19.750155) (xy 316.4915 19.673395) (xy 316.522476 19.593436) (xy 316.545943 19.51096)
			(xy 316.561699 19.42667) (xy 316.569611 19.341287) (xy 316.570106 19.298412) (xy 316.569693 19.262649)
			(xy 334.455757 19.262649) (xy 334.455757 19.348399) (xy 334.463669 19.433782) (xy 334.479425 19.518072)
			(xy 334.502892 19.600548) (xy 334.533868 19.680507) (xy 334.57209 19.757267) (xy 334.617231 19.830173)
			(xy 334.668907 19.898602) (xy 334.726676 19.961972) (xy 334.790046 20.019741) (xy 334.858475 20.071417)
			(xy 334.931381 20.116558) (xy 335.008141 20.15478) (xy 335.0881 20.185756) (xy 335.170576 20.209223)
			(xy 335.254866 20.224979) (xy 335.340249 20.232891) (xy 335.425999 20.232891) (xy 335.511382 20.224979)
			(xy 335.595672 20.209223) (xy 335.678148 20.185756) (xy 335.758107 20.15478) (xy 335.78031 20.143724)
			(xy 339.390736 20.143724) (xy 339.390736 21.007324) (xy 339.391222 21.034593) (xy 339.398984 21.088577)
			(xy 339.414349 21.140907) (xy 339.437006 21.190517) (xy 339.466492 21.236398) (xy 339.502207 21.277615)
			(xy 339.543424 21.31333) (xy 339.589305 21.342816) (xy 339.638915 21.365473) (xy 339.691245 21.380838)
			(xy 339.745229 21.3886) (xy 339.799767 21.3886) (xy 339.853751 21.380838) (xy 339.906081 21.365473)
			(xy 339.955691 21.342816) (xy 340.001572 21.31333) (xy 340.042789 21.277615) (xy 340.078504 21.236398)
			(xy 340.10799 21.190517) (xy 340.130647 21.140907) (xy 340.146012 21.088577) (xy 340.153774 21.034593)
			(xy 340.15426 21.007324) (xy 340.15426 20.143724) (xy 340.153774 20.116455) (xy 340.146012 20.062471)
			(xy 340.130647 20.010141) (xy 340.10799 19.960531) (xy 340.078504 19.91465) (xy 340.042789 19.873433)
			(xy 340.001572 19.837718) (xy 339.955691 19.808232) (xy 339.906081 19.785575) (xy 339.853751 19.77021)
			(xy 339.799767 19.762448) (xy 339.745229 19.762448) (xy 339.691245 19.77021) (xy 339.638915 19.785575)
			(xy 339.589305 19.808232) (xy 339.543424 19.837718) (xy 339.502207 19.873433) (xy 339.466492 19.91465)
			(xy 339.437006 19.960531) (xy 339.414349 20.010141) (xy 339.398984 20.062471) (xy 339.391222 20.116455)
			(xy 339.390736 20.143724) (xy 335.78031 20.143724) (xy 335.834867 20.116558) (xy 335.907773 20.071417)
			(xy 335.976202 20.019741) (xy 336.039572 19.961972) (xy 336.097341 19.898602) (xy 336.149017 19.830173)
			(xy 336.194158 19.757267) (xy 336.23238 19.680507) (xy 336.263356 19.600548) (xy 336.286823 19.518072)
			(xy 336.302579 19.433782) (xy 336.310491 19.348399) (xy 336.310986 19.305524) (xy 336.310491 19.262649)
			(xy 340.805757 19.262649) (xy 340.805757 19.348399) (xy 340.813669 19.433782) (xy 340.829425 19.518072)
			(xy 340.852892 19.600548) (xy 340.883868 19.680507) (xy 340.92209 19.757267) (xy 340.967231 19.830173)
			(xy 341.018907 19.898602) (xy 341.076676 19.961972) (xy 341.140046 20.019741) (xy 341.208475 20.071417)
			(xy 341.281381 20.116558) (xy 341.358141 20.15478) (xy 341.4381 20.185756) (xy 341.520576 20.209223)
			(xy 341.604866 20.224979) (xy 341.690249 20.232891) (xy 341.775999 20.232891) (xy 341.861382 20.224979)
			(xy 341.945672 20.209223) (xy 342.028148 20.185756) (xy 342.108107 20.15478) (xy 342.184867 20.116558)
			(xy 342.257773 20.071417) (xy 342.326202 20.019741) (xy 342.389572 19.961972) (xy 342.447341 19.898602)
			(xy 342.499017 19.830173) (xy 342.544158 19.757267) (xy 342.58238 19.680507) (xy 342.613356 19.600548)
			(xy 342.636823 19.518072) (xy 342.652579 19.433782) (xy 342.660491 19.348399) (xy 342.660986 19.305524)
			(xy 342.660491 19.262649) (xy 342.659832 19.255537) (xy 373.515877 19.255537) (xy 373.515877 19.341287)
			(xy 373.523789 19.42667) (xy 373.539545 19.51096) (xy 373.563012 19.593436) (xy 373.593988 19.673395)
			(xy 373.63221 19.750155) (xy 373.677351 19.823061) (xy 373.729027 19.89149) (xy 373.786796 19.95486)
			(xy 373.850166 20.012629) (xy 373.918595 20.064305) (xy 373.991501 20.109446) (xy 374.068261 20.147668)
			(xy 374.14822 20.178644) (xy 374.230696 20.202111) (xy 374.314986 20.217867) (xy 374.400369 20.225779)
			(xy 374.486119 20.225779) (xy 374.571502 20.217867) (xy 374.655792 20.202111) (xy 374.738268 20.178644)
			(xy 374.818227 20.147668) (xy 374.84043 20.136612) (xy 376.022108 20.136612) (xy 376.022108 21.000212)
			(xy 376.022594 21.027481) (xy 376.030356 21.081465) (xy 376.045721 21.133795) (xy 376.068378 21.183405)
			(xy 376.097864 21.229286) (xy 376.133579 21.270503) (xy 376.174796 21.306218) (xy 376.220677 21.335704)
			(xy 376.270287 21.358361) (xy 376.322617 21.373726) (xy 376.376601 21.381488) (xy 376.431139 21.381488)
			(xy 376.485123 21.373726) (xy 376.537453 21.358361) (xy 376.587063 21.335704) (xy 376.632944 21.306218)
			(xy 376.674161 21.270503) (xy 376.709876 21.229286) (xy 376.739362 21.183405) (xy 376.762019 21.133795)
			(xy 376.777384 21.081465) (xy 376.785146 21.027481) (xy 376.785632 21.000212) (xy 376.785632 20.136612)
			(xy 376.785146 20.109343) (xy 376.777384 20.055359) (xy 376.762019 20.003029) (xy 376.739362 19.953419)
			(xy 376.709876 19.907538) (xy 376.674161 19.866321) (xy 376.632944 19.830606) (xy 376.587063 19.80112)
			(xy 376.537453 19.778463) (xy 376.485123 19.763098) (xy 376.431139 19.755336) (xy 376.376601 19.755336)
			(xy 376.322617 19.763098) (xy 376.270287 19.778463) (xy 376.220677 19.80112) (xy 376.174796 19.830606)
			(xy 376.133579 19.866321) (xy 376.097864 19.907538) (xy 376.068378 19.953419) (xy 376.045721 20.003029)
			(xy 376.030356 20.055359) (xy 376.022594 20.109343) (xy 376.022108 20.136612) (xy 374.84043 20.136612)
			(xy 374.894987 20.109446) (xy 374.967893 20.064305) (xy 375.036322 20.012629) (xy 375.099692 19.95486)
			(xy 375.157461 19.89149) (xy 375.209137 19.823061) (xy 375.254278 19.750155) (xy 375.2925 19.673395)
			(xy 375.323476 19.593436) (xy 375.346943 19.51096) (xy 375.362699 19.42667) (xy 375.370611 19.341287)
			(xy 375.371106 19.298412) (xy 375.370611 19.255537) (xy 379.865877 19.255537) (xy 379.865877 19.341287)
			(xy 379.873789 19.42667) (xy 379.889545 19.51096) (xy 379.913012 19.593436) (xy 379.943988 19.673395)
			(xy 379.98221 19.750155) (xy 380.027351 19.823061) (xy 380.079027 19.89149) (xy 380.136796 19.95486)
			(xy 380.200166 20.012629) (xy 380.268595 20.064305) (xy 380.341501 20.109446) (xy 380.418261 20.147668)
			(xy 380.49822 20.178644) (xy 380.580696 20.202111) (xy 380.664986 20.217867) (xy 380.750369 20.225779)
			(xy 380.836119 20.225779) (xy 380.921502 20.217867) (xy 381.005792 20.202111) (xy 381.088268 20.178644)
			(xy 381.168227 20.147668) (xy 381.244987 20.109446) (xy 381.317893 20.064305) (xy 381.386322 20.012629)
			(xy 381.449692 19.95486) (xy 381.507461 19.89149) (xy 381.559137 19.823061) (xy 381.604278 19.750155)
			(xy 381.6425 19.673395) (xy 381.673476 19.593436) (xy 381.696943 19.51096) (xy 381.712699 19.42667)
			(xy 381.720611 19.341287) (xy 381.721106 19.298412) (xy 381.720693 19.262649) (xy 399.098757 19.262649)
			(xy 399.098757 19.348399) (xy 399.106669 19.433782) (xy 399.122425 19.518072) (xy 399.145892 19.600548)
			(xy 399.176868 19.680507) (xy 399.21509 19.757267) (xy 399.260231 19.830173) (xy 399.311907 19.898602)
			(xy 399.369676 19.961972) (xy 399.433046 20.019741) (xy 399.501475 20.071417) (xy 399.574381 20.116558)
			(xy 399.651141 20.15478) (xy 399.7311 20.185756) (xy 399.813576 20.209223) (xy 399.897866 20.224979)
			(xy 399.983249 20.232891) (xy 400.068999 20.232891) (xy 400.154382 20.224979) (xy 400.238672 20.209223)
			(xy 400.321148 20.185756) (xy 400.401107 20.15478) (xy 400.42331 20.143724) (xy 404.033736 20.143724)
			(xy 404.033736 21.007324) (xy 404.034222 21.034593) (xy 404.041984 21.088577) (xy 404.057349 21.140907)
			(xy 404.080006 21.190517) (xy 404.109492 21.236398) (xy 404.145207 21.277615) (xy 404.186424 21.31333)
			(xy 404.232305 21.342816) (xy 404.281915 21.365473) (xy 404.334245 21.380838) (xy 404.388229 21.3886)
			(xy 404.442767 21.3886) (xy 404.496751 21.380838) (xy 404.549081 21.365473) (xy 404.598691 21.342816)
			(xy 404.644572 21.31333) (xy 404.685789 21.277615) (xy 404.721504 21.236398) (xy 404.75099 21.190517)
			(xy 404.773647 21.140907) (xy 404.789012 21.088577) (xy 404.796774 21.034593) (xy 404.79726 21.007324)
			(xy 404.79726 20.143724) (xy 404.796774 20.116455) (xy 404.789012 20.062471) (xy 404.773647 20.010141)
			(xy 404.75099 19.960531) (xy 404.721504 19.91465) (xy 404.685789 19.873433) (xy 404.644572 19.837718)
			(xy 404.598691 19.808232) (xy 404.549081 19.785575) (xy 404.496751 19.77021) (xy 404.442767 19.762448)
			(xy 404.388229 19.762448) (xy 404.334245 19.77021) (xy 404.281915 19.785575) (xy 404.232305 19.808232)
			(xy 404.186424 19.837718) (xy 404.145207 19.873433) (xy 404.109492 19.91465) (xy 404.080006 19.960531)
			(xy 404.057349 20.010141) (xy 404.041984 20.062471) (xy 404.034222 20.116455) (xy 404.033736 20.143724)
			(xy 400.42331 20.143724) (xy 400.477867 20.116558) (xy 400.550773 20.071417) (xy 400.619202 20.019741)
			(xy 400.682572 19.961972) (xy 400.740341 19.898602) (xy 400.792017 19.830173) (xy 400.837158 19.757267)
			(xy 400.87538 19.680507) (xy 400.906356 19.600548) (xy 400.929823 19.518072) (xy 400.945579 19.433782)
			(xy 400.953491 19.348399) (xy 400.953986 19.305524) (xy 400.953491 19.262649) (xy 405.448757 19.262649)
			(xy 405.448757 19.348399) (xy 405.456669 19.433782) (xy 405.472425 19.518072) (xy 405.495892 19.600548)
			(xy 405.526868 19.680507) (xy 405.56509 19.757267) (xy 405.610231 19.830173) (xy 405.661907 19.898602)
			(xy 405.719676 19.961972) (xy 405.783046 20.019741) (xy 405.851475 20.071417) (xy 405.924381 20.116558)
			(xy 406.001141 20.15478) (xy 406.0811 20.185756) (xy 406.163576 20.209223) (xy 406.247866 20.224979)
			(xy 406.333249 20.232891) (xy 406.418999 20.232891) (xy 406.504382 20.224979) (xy 406.588672 20.209223)
			(xy 406.671148 20.185756) (xy 406.751107 20.15478) (xy 406.827867 20.116558) (xy 406.900773 20.071417)
			(xy 406.969202 20.019741) (xy 407.032572 19.961972) (xy 407.090341 19.898602) (xy 407.142017 19.830173)
			(xy 407.187158 19.757267) (xy 407.22538 19.680507) (xy 407.256356 19.600548) (xy 407.279823 19.518072)
			(xy 407.295579 19.433782) (xy 407.303491 19.348399) (xy 407.303986 19.305524) (xy 407.303491 19.262649)
			(xy 407.302832 19.255537) (xy 438.158877 19.255537) (xy 438.158877 19.341287) (xy 438.166789 19.42667)
			(xy 438.182545 19.51096) (xy 438.206012 19.593436) (xy 438.236988 19.673395) (xy 438.27521 19.750155)
			(xy 438.320351 19.823061) (xy 438.372027 19.89149) (xy 438.429796 19.95486) (xy 438.493166 20.012629)
			(xy 438.561595 20.064305) (xy 438.634501 20.109446) (xy 438.711261 20.147668) (xy 438.79122 20.178644)
			(xy 438.873696 20.202111) (xy 438.957986 20.217867) (xy 439.043369 20.225779) (xy 439.129119 20.225779)
			(xy 439.214502 20.217867) (xy 439.298792 20.202111) (xy 439.381268 20.178644) (xy 439.461227 20.147668)
			(xy 439.48343 20.136612) (xy 440.665108 20.136612) (xy 440.665108 21.000212) (xy 440.665594 21.027481)
			(xy 440.673356 21.081465) (xy 440.688721 21.133795) (xy 440.711378 21.183405) (xy 440.740864 21.229286)
			(xy 440.776579 21.270503) (xy 440.817796 21.306218) (xy 440.863677 21.335704) (xy 440.913287 21.358361)
			(xy 440.965617 21.373726) (xy 441.019601 21.381488) (xy 441.074139 21.381488) (xy 441.128123 21.373726)
			(xy 441.180453 21.358361) (xy 441.230063 21.335704) (xy 441.275944 21.306218) (xy 441.317161 21.270503)
			(xy 441.352876 21.229286) (xy 441.382362 21.183405) (xy 441.405019 21.133795) (xy 441.420384 21.081465)
			(xy 441.428146 21.027481) (xy 441.428632 21.000212) (xy 441.428632 20.136612) (xy 441.428146 20.109343)
			(xy 441.420384 20.055359) (xy 441.405019 20.003029) (xy 441.382362 19.953419) (xy 441.352876 19.907538)
			(xy 441.317161 19.866321) (xy 441.275944 19.830606) (xy 441.230063 19.80112) (xy 441.180453 19.778463)
			(xy 441.128123 19.763098) (xy 441.074139 19.755336) (xy 441.019601 19.755336) (xy 440.965617 19.763098)
			(xy 440.913287 19.778463) (xy 440.863677 19.80112) (xy 440.817796 19.830606) (xy 440.776579 19.866321)
			(xy 440.740864 19.907538) (xy 440.711378 19.953419) (xy 440.688721 20.003029) (xy 440.673356 20.055359)
			(xy 440.665594 20.109343) (xy 440.665108 20.136612) (xy 439.48343 20.136612) (xy 439.537987 20.109446)
			(xy 439.610893 20.064305) (xy 439.679322 20.012629) (xy 439.742692 19.95486) (xy 439.800461 19.89149)
			(xy 439.852137 19.823061) (xy 439.897278 19.750155) (xy 439.9355 19.673395) (xy 439.966476 19.593436)
			(xy 439.989943 19.51096) (xy 440.005699 19.42667) (xy 440.013611 19.341287) (xy 440.014106 19.298412)
			(xy 440.013611 19.255537) (xy 444.508877 19.255537) (xy 444.508877 19.341287) (xy 444.516789 19.42667)
			(xy 444.532545 19.51096) (xy 444.556012 19.593436) (xy 444.586988 19.673395) (xy 444.62521 19.750155)
			(xy 444.670351 19.823061) (xy 444.722027 19.89149) (xy 444.779796 19.95486) (xy 444.843166 20.012629)
			(xy 444.911595 20.064305) (xy 444.984501 20.109446) (xy 445.061261 20.147668) (xy 445.14122 20.178644)
			(xy 445.223696 20.202111) (xy 445.307986 20.217867) (xy 445.393369 20.225779) (xy 445.479119 20.225779)
			(xy 445.564502 20.217867) (xy 445.648792 20.202111) (xy 445.731268 20.178644) (xy 445.811227 20.147668)
			(xy 445.887987 20.109446) (xy 445.960893 20.064305) (xy 446.029322 20.012629) (xy 446.092692 19.95486)
			(xy 446.150461 19.89149) (xy 446.202137 19.823061) (xy 446.247278 19.750155) (xy 446.2855 19.673395)
			(xy 446.316476 19.593436) (xy 446.339943 19.51096) (xy 446.355699 19.42667) (xy 446.363611 19.341287)
			(xy 446.364106 19.298412) (xy 446.363611 19.255537) (xy 446.355699 19.170154) (xy 446.339943 19.085864)
			(xy 446.316476 19.003388) (xy 446.2855 18.923429) (xy 446.247278 18.846669) (xy 446.202137 18.773763)
			(xy 446.150461 18.705334) (xy 446.092692 18.641964) (xy 446.029322 18.584195) (xy 445.960893 18.532519)
			(xy 445.887987 18.487378) (xy 445.811227 18.449156) (xy 445.731268 18.41818) (xy 445.648792 18.394713)
			(xy 445.564502 18.378957) (xy 445.479119 18.371045) (xy 445.393369 18.371045) (xy 445.307986 18.378957)
			(xy 445.223696 18.394713) (xy 445.14122 18.41818) (xy 445.061261 18.449156) (xy 444.984501 18.487378)
			(xy 444.911595 18.532519) (xy 444.843166 18.584195) (xy 444.779796 18.641964) (xy 444.722027 18.705334)
			(xy 444.670351 18.773763) (xy 444.62521 18.846669) (xy 444.586988 18.923429) (xy 444.556012 19.003388)
			(xy 444.532545 19.085864) (xy 444.516789 19.170154) (xy 444.508877 19.255537) (xy 440.013611 19.255537)
			(xy 440.005699 19.170154) (xy 439.989943 19.085864) (xy 439.966476 19.003388) (xy 439.9355 18.923429)
			(xy 439.897278 18.846669) (xy 439.852137 18.773763) (xy 439.800461 18.705334) (xy 439.742692 18.641964)
			(xy 439.679322 18.584195) (xy 439.610893 18.532519) (xy 439.537987 18.487378) (xy 439.461227 18.449156)
			(xy 439.381268 18.41818) (xy 439.298792 18.394713) (xy 439.214502 18.378957) (xy 439.129119 18.371045)
			(xy 439.043369 18.371045) (xy 438.957986 18.378957) (xy 438.873696 18.394713) (xy 438.79122 18.41818)
			(xy 438.711261 18.449156) (xy 438.634501 18.487378) (xy 438.561595 18.532519) (xy 438.493166 18.584195)
			(xy 438.429796 18.641964) (xy 438.372027 18.705334) (xy 438.320351 18.773763) (xy 438.27521 18.846669)
			(xy 438.236988 18.923429) (xy 438.206012 19.003388) (xy 438.182545 19.085864) (xy 438.166789 19.170154)
			(xy 438.158877 19.255537) (xy 407.302832 19.255537) (xy 407.295579 19.177266) (xy 407.279823 19.092976)
			(xy 407.256356 19.0105) (xy 407.22538 18.930541) (xy 407.187158 18.853781) (xy 407.142017 18.780875)
			(xy 407.090341 18.712446) (xy 407.032572 18.649076) (xy 406.969202 18.591307) (xy 406.900773 18.539631)
			(xy 406.827867 18.49449) (xy 406.751107 18.456268) (xy 406.671148 18.425292) (xy 406.588672 18.401825)
			(xy 406.504382 18.386069) (xy 406.418999 18.378157) (xy 406.333249 18.378157) (xy 406.247866 18.386069)
			(xy 406.163576 18.401825) (xy 406.0811 18.425292) (xy 406.001141 18.456268) (xy 405.924381 18.49449)
			(xy 405.851475 18.539631) (xy 405.783046 18.591307) (xy 405.719676 18.649076) (xy 405.661907 18.712446)
			(xy 405.610231 18.780875) (xy 405.56509 18.853781) (xy 405.526868 18.930541) (xy 405.495892 19.0105)
			(xy 405.472425 19.092976) (xy 405.456669 19.177266) (xy 405.448757 19.262649) (xy 400.953491 19.262649)
			(xy 400.945579 19.177266) (xy 400.929823 19.092976) (xy 400.906356 19.0105) (xy 400.87538 18.930541)
			(xy 400.837158 18.853781) (xy 400.792017 18.780875) (xy 400.740341 18.712446) (xy 400.682572 18.649076)
			(xy 400.619202 18.591307) (xy 400.550773 18.539631) (xy 400.477867 18.49449) (xy 400.401107 18.456268)
			(xy 400.321148 18.425292) (xy 400.238672 18.401825) (xy 400.154382 18.386069) (xy 400.068999 18.378157)
			(xy 399.983249 18.378157) (xy 399.897866 18.386069) (xy 399.813576 18.401825) (xy 399.7311 18.425292)
			(xy 399.651141 18.456268) (xy 399.574381 18.49449) (xy 399.501475 18.539631) (xy 399.433046 18.591307)
			(xy 399.369676 18.649076) (xy 399.311907 18.712446) (xy 399.260231 18.780875) (xy 399.21509 18.853781)
			(xy 399.176868 18.930541) (xy 399.145892 19.0105) (xy 399.122425 19.092976) (xy 399.106669 19.177266)
			(xy 399.098757 19.262649) (xy 381.720693 19.262649) (xy 381.720611 19.255537) (xy 381.712699 19.170154)
			(xy 381.696943 19.085864) (xy 381.673476 19.003388) (xy 381.6425 18.923429) (xy 381.604278 18.846669)
			(xy 381.559137 18.773763) (xy 381.507461 18.705334) (xy 381.449692 18.641964) (xy 381.386322 18.584195)
			(xy 381.317893 18.532519) (xy 381.244987 18.487378) (xy 381.168227 18.449156) (xy 381.088268 18.41818)
			(xy 381.005792 18.394713) (xy 380.921502 18.378957) (xy 380.836119 18.371045) (xy 380.750369 18.371045)
			(xy 380.664986 18.378957) (xy 380.580696 18.394713) (xy 380.49822 18.41818) (xy 380.418261 18.449156)
			(xy 380.341501 18.487378) (xy 380.268595 18.532519) (xy 380.200166 18.584195) (xy 380.136796 18.641964)
			(xy 380.079027 18.705334) (xy 380.027351 18.773763) (xy 379.98221 18.846669) (xy 379.943988 18.923429)
			(xy 379.913012 19.003388) (xy 379.889545 19.085864) (xy 379.873789 19.170154) (xy 379.865877 19.255537)
			(xy 375.370611 19.255537) (xy 375.362699 19.170154) (xy 375.346943 19.085864) (xy 375.323476 19.003388)
			(xy 375.2925 18.923429) (xy 375.254278 18.846669) (xy 375.209137 18.773763) (xy 375.157461 18.705334)
			(xy 375.099692 18.641964) (xy 375.036322 18.584195) (xy 374.967893 18.532519) (xy 374.894987 18.487378)
			(xy 374.818227 18.449156) (xy 374.738268 18.41818) (xy 374.655792 18.394713) (xy 374.571502 18.378957)
			(xy 374.486119 18.371045) (xy 374.400369 18.371045) (xy 374.314986 18.378957) (xy 374.230696 18.394713)
			(xy 374.14822 18.41818) (xy 374.068261 18.449156) (xy 373.991501 18.487378) (xy 373.918595 18.532519)
			(xy 373.850166 18.584195) (xy 373.786796 18.641964) (xy 373.729027 18.705334) (xy 373.677351 18.773763)
			(xy 373.63221 18.846669) (xy 373.593988 18.923429) (xy 373.563012 19.003388) (xy 373.539545 19.085864)
			(xy 373.523789 19.170154) (xy 373.515877 19.255537) (xy 342.659832 19.255537) (xy 342.652579 19.177266)
			(xy 342.636823 19.092976) (xy 342.613356 19.0105) (xy 342.58238 18.930541) (xy 342.544158 18.853781)
			(xy 342.499017 18.780875) (xy 342.447341 18.712446) (xy 342.389572 18.649076) (xy 342.326202 18.591307)
			(xy 342.257773 18.539631) (xy 342.184867 18.49449) (xy 342.108107 18.456268) (xy 342.028148 18.425292)
			(xy 341.945672 18.401825) (xy 341.861382 18.386069) (xy 341.775999 18.378157) (xy 341.690249 18.378157)
			(xy 341.604866 18.386069) (xy 341.520576 18.401825) (xy 341.4381 18.425292) (xy 341.358141 18.456268)
			(xy 341.281381 18.49449) (xy 341.208475 18.539631) (xy 341.140046 18.591307) (xy 341.076676 18.649076)
			(xy 341.018907 18.712446) (xy 340.967231 18.780875) (xy 340.92209 18.853781) (xy 340.883868 18.930541)
			(xy 340.852892 19.0105) (xy 340.829425 19.092976) (xy 340.813669 19.177266) (xy 340.805757 19.262649)
			(xy 336.310491 19.262649) (xy 336.302579 19.177266) (xy 336.286823 19.092976) (xy 336.263356 19.0105)
			(xy 336.23238 18.930541) (xy 336.194158 18.853781) (xy 336.149017 18.780875) (xy 336.097341 18.712446)
			(xy 336.039572 18.649076) (xy 335.976202 18.591307) (xy 335.907773 18.539631) (xy 335.834867 18.49449)
			(xy 335.758107 18.456268) (xy 335.678148 18.425292) (xy 335.595672 18.401825) (xy 335.511382 18.386069)
			(xy 335.425999 18.378157) (xy 335.340249 18.378157) (xy 335.254866 18.386069) (xy 335.170576 18.401825)
			(xy 335.0881 18.425292) (xy 335.008141 18.456268) (xy 334.931381 18.49449) (xy 334.858475 18.539631)
			(xy 334.790046 18.591307) (xy 334.726676 18.649076) (xy 334.668907 18.712446) (xy 334.617231 18.780875)
			(xy 334.57209 18.853781) (xy 334.533868 18.930541) (xy 334.502892 19.0105) (xy 334.479425 19.092976)
			(xy 334.463669 19.177266) (xy 334.455757 19.262649) (xy 316.569693 19.262649) (xy 316.569611 19.255537)
			(xy 316.561699 19.170154) (xy 316.545943 19.085864) (xy 316.522476 19.003388) (xy 316.4915 18.923429)
			(xy 316.453278 18.846669) (xy 316.408137 18.773763) (xy 316.356461 18.705334) (xy 316.298692 18.641964)
			(xy 316.235322 18.584195) (xy 316.166893 18.532519) (xy 316.093987 18.487378) (xy 316.017227 18.449156)
			(xy 315.937268 18.41818) (xy 315.854792 18.394713) (xy 315.770502 18.378957) (xy 315.685119 18.371045)
			(xy 315.599369 18.371045) (xy 315.513986 18.378957) (xy 315.429696 18.394713) (xy 315.34722 18.41818)
			(xy 315.267261 18.449156) (xy 315.190501 18.487378) (xy 315.117595 18.532519) (xy 315.049166 18.584195)
			(xy 314.985796 18.641964) (xy 314.928027 18.705334) (xy 314.876351 18.773763) (xy 314.83121 18.846669)
			(xy 314.792988 18.923429) (xy 314.762012 19.003388) (xy 314.738545 19.085864) (xy 314.722789 19.170154)
			(xy 314.714877 19.255537) (xy 310.219611 19.255537) (xy 310.211699 19.170154) (xy 310.195943 19.085864)
			(xy 310.172476 19.003388) (xy 310.1415 18.923429) (xy 310.103278 18.846669) (xy 310.058137 18.773763)
			(xy 310.006461 18.705334) (xy 309.948692 18.641964) (xy 309.885322 18.584195) (xy 309.816893 18.532519)
			(xy 309.743987 18.487378) (xy 309.667227 18.449156) (xy 309.587268 18.41818) (xy 309.504792 18.394713)
			(xy 309.420502 18.378957) (xy 309.335119 18.371045) (xy 309.249369 18.371045) (xy 309.163986 18.378957)
			(xy 309.079696 18.394713) (xy 308.99722 18.41818) (xy 308.917261 18.449156) (xy 308.840501 18.487378)
			(xy 308.767595 18.532519) (xy 308.699166 18.584195) (xy 308.635796 18.641964) (xy 308.578027 18.705334)
			(xy 308.526351 18.773763) (xy 308.48121 18.846669) (xy 308.442988 18.923429) (xy 308.412012 19.003388)
			(xy 308.388545 19.085864) (xy 308.372789 19.170154) (xy 308.364877 19.255537) (xy 277.508832 19.255537)
			(xy 277.501579 19.177266) (xy 277.485823 19.092976) (xy 277.462356 19.0105) (xy 277.43138 18.930541)
			(xy 277.393158 18.853781) (xy 277.348017 18.780875) (xy 277.296341 18.712446) (xy 277.238572 18.649076)
			(xy 277.175202 18.591307) (xy 277.106773 18.539631) (xy 277.033867 18.49449) (xy 276.957107 18.456268)
			(xy 276.877148 18.425292) (xy 276.794672 18.401825) (xy 276.710382 18.386069) (xy 276.624999 18.378157)
			(xy 276.539249 18.378157) (xy 276.453866 18.386069) (xy 276.369576 18.401825) (xy 276.2871 18.425292)
			(xy 276.207141 18.456268) (xy 276.130381 18.49449) (xy 276.057475 18.539631) (xy 275.989046 18.591307)
			(xy 275.925676 18.649076) (xy 275.867907 18.712446) (xy 275.816231 18.780875) (xy 275.77109 18.853781)
			(xy 275.732868 18.930541) (xy 275.701892 19.0105) (xy 275.678425 19.092976) (xy 275.662669 19.177266)
			(xy 275.654757 19.262649) (xy 271.159491 19.262649) (xy 271.151579 19.177266) (xy 271.135823 19.092976)
			(xy 271.112356 19.0105) (xy 271.08138 18.930541) (xy 271.043158 18.853781) (xy 270.998017 18.780875)
			(xy 270.946341 18.712446) (xy 270.888572 18.649076) (xy 270.825202 18.591307) (xy 270.756773 18.539631)
			(xy 270.683867 18.49449) (xy 270.607107 18.456268) (xy 270.527148 18.425292) (xy 270.444672 18.401825)
			(xy 270.360382 18.386069) (xy 270.274999 18.378157) (xy 270.189249 18.378157) (xy 270.103866 18.386069)
			(xy 270.019576 18.401825) (xy 269.9371 18.425292) (xy 269.857141 18.456268) (xy 269.780381 18.49449)
			(xy 269.707475 18.539631) (xy 269.639046 18.591307) (xy 269.575676 18.649076) (xy 269.517907 18.712446)
			(xy 269.466231 18.780875) (xy 269.42109 18.853781) (xy 269.382868 18.930541) (xy 269.351892 19.0105)
			(xy 269.328425 19.092976) (xy 269.312669 19.177266) (xy 269.304757 19.262649) (xy 252.231493 19.262649)
			(xy 252.231411 19.255537) (xy 252.223499 19.170154) (xy 252.207743 19.085864) (xy 252.184276 19.003388)
			(xy 252.1533 18.923429) (xy 252.115078 18.846669) (xy 252.069937 18.773763) (xy 252.018261 18.705334)
			(xy 251.960492 18.641964) (xy 251.897122 18.584195) (xy 251.828693 18.532519) (xy 251.755787 18.487378)
			(xy 251.679027 18.449156) (xy 251.599068 18.41818) (xy 251.516592 18.394713) (xy 251.432302 18.378957)
			(xy 251.346919 18.371045) (xy 251.261169 18.371045) (xy 251.175786 18.378957) (xy 251.091496 18.394713)
			(xy 251.00902 18.41818) (xy 250.929061 18.449156) (xy 250.852301 18.487378) (xy 250.779395 18.532519)
			(xy 250.710966 18.584195) (xy 250.647596 18.641964) (xy 250.589827 18.705334) (xy 250.538151 18.773763)
			(xy 250.49301 18.846669) (xy 250.454788 18.923429) (xy 250.423812 19.003388) (xy 250.400345 19.085864)
			(xy 250.384589 19.170154) (xy 250.376677 19.255537) (xy 245.881411 19.255537) (xy 245.873499 19.170154)
			(xy 245.857743 19.085864) (xy 245.834276 19.003388) (xy 245.8033 18.923429) (xy 245.765078 18.846669)
			(xy 245.719937 18.773763) (xy 245.668261 18.705334) (xy 245.610492 18.641964) (xy 245.547122 18.584195)
			(xy 245.478693 18.532519) (xy 245.405787 18.487378) (xy 245.329027 18.449156) (xy 245.249068 18.41818)
			(xy 245.166592 18.394713) (xy 245.082302 18.378957) (xy 244.996919 18.371045) (xy 244.911169 18.371045)
			(xy 244.825786 18.378957) (xy 244.741496 18.394713) (xy 244.65902 18.41818) (xy 244.579061 18.449156)
			(xy 244.502301 18.487378) (xy 244.429395 18.532519) (xy 244.360966 18.584195) (xy 244.297596 18.641964)
			(xy 244.239827 18.705334) (xy 244.188151 18.773763) (xy 244.14301 18.846669) (xy 244.104788 18.923429)
			(xy 244.073812 19.003388) (xy 244.050345 19.085864) (xy 244.034589 19.170154) (xy 244.026677 19.255537)
			(xy 218.199832 19.255537) (xy 218.192579 19.177266) (xy 218.176823 19.092976) (xy 218.153356 19.0105)
			(xy 218.12238 18.930541) (xy 218.084158 18.853781) (xy 218.039017 18.780875) (xy 217.987341 18.712446)
			(xy 217.929572 18.649076) (xy 217.866202 18.591307) (xy 217.797773 18.539631) (xy 217.724867 18.49449)
			(xy 217.648107 18.456268) (xy 217.568148 18.425292) (xy 217.485672 18.401825) (xy 217.401382 18.386069)
			(xy 217.315999 18.378157) (xy 217.230249 18.378157) (xy 217.144866 18.386069) (xy 217.060576 18.401825)
			(xy 216.9781 18.425292) (xy 216.898141 18.456268) (xy 216.821381 18.49449) (xy 216.748475 18.539631)
			(xy 216.680046 18.591307) (xy 216.616676 18.649076) (xy 216.558907 18.712446) (xy 216.507231 18.780875)
			(xy 216.46209 18.853781) (xy 216.423868 18.930541) (xy 216.392892 19.0105) (xy 216.369425 19.092976)
			(xy 216.353669 19.177266) (xy 216.345757 19.262649) (xy 211.850491 19.262649) (xy 211.842579 19.177266)
			(xy 211.826823 19.092976) (xy 211.803356 19.0105) (xy 211.77238 18.930541) (xy 211.734158 18.853781)
			(xy 211.689017 18.780875) (xy 211.637341 18.712446) (xy 211.579572 18.649076) (xy 211.516202 18.591307)
			(xy 211.447773 18.539631) (xy 211.374867 18.49449) (xy 211.298107 18.456268) (xy 211.218148 18.425292)
			(xy 211.135672 18.401825) (xy 211.051382 18.386069) (xy 210.965999 18.378157) (xy 210.880249 18.378157)
			(xy 210.794866 18.386069) (xy 210.710576 18.401825) (xy 210.6281 18.425292) (xy 210.548141 18.456268)
			(xy 210.471381 18.49449) (xy 210.398475 18.539631) (xy 210.330046 18.591307) (xy 210.266676 18.649076)
			(xy 210.208907 18.712446) (xy 210.157231 18.780875) (xy 210.11209 18.853781) (xy 210.073868 18.930541)
			(xy 210.042892 19.0105) (xy 210.019425 19.092976) (xy 210.003669 19.177266) (xy 209.995757 19.262649)
			(xy 158.621984 19.262649) (xy 158.621984 16.722649) (xy 209.995757 16.722649) (xy 209.995757 16.808399)
			(xy 210.003669 16.893782) (xy 210.019425 16.978072) (xy 210.042892 17.060548) (xy 210.073868 17.140507)
			(xy 210.11209 17.217267) (xy 210.157231 17.290173) (xy 210.208907 17.358602) (xy 210.266676 17.421972)
			(xy 210.330046 17.479741) (xy 210.398475 17.531417) (xy 210.471381 17.576558) (xy 210.548141 17.61478)
			(xy 210.6281 17.645756) (xy 210.710576 17.669223) (xy 210.794866 17.684979) (xy 210.880249 17.692891)
			(xy 210.965999 17.692891) (xy 211.051382 17.684979) (xy 211.135672 17.669223) (xy 211.218148 17.645756)
			(xy 211.298107 17.61478) (xy 211.374867 17.576558) (xy 211.447773 17.531417) (xy 211.516202 17.479741)
			(xy 211.579572 17.421972) (xy 211.637341 17.358602) (xy 211.689017 17.290173) (xy 211.734158 17.217267)
			(xy 211.77238 17.140507) (xy 211.803356 17.060548) (xy 211.826823 16.978072) (xy 211.842579 16.893782)
			(xy 211.850491 16.808399) (xy 211.850986 16.765524) (xy 211.850491 16.722649) (xy 216.345757 16.722649)
			(xy 216.345757 16.808399) (xy 216.353669 16.893782) (xy 216.369425 16.978072) (xy 216.392892 17.060548)
			(xy 216.423868 17.140507) (xy 216.46209 17.217267) (xy 216.507231 17.290173) (xy 216.558907 17.358602)
			(xy 216.616676 17.421972) (xy 216.680046 17.479741) (xy 216.748475 17.531417) (xy 216.821381 17.576558)
			(xy 216.898141 17.61478) (xy 216.9781 17.645756) (xy 217.060576 17.669223) (xy 217.144866 17.684979)
			(xy 217.230249 17.692891) (xy 217.315999 17.692891) (xy 217.401382 17.684979) (xy 217.485672 17.669223)
			(xy 217.568148 17.645756) (xy 217.648107 17.61478) (xy 217.724867 17.576558) (xy 217.797773 17.531417)
			(xy 217.866202 17.479741) (xy 217.929572 17.421972) (xy 217.987341 17.358602) (xy 218.039017 17.290173)
			(xy 218.084158 17.217267) (xy 218.12238 17.140507) (xy 218.153356 17.060548) (xy 218.176823 16.978072)
			(xy 218.192579 16.893782) (xy 218.200491 16.808399) (xy 218.200986 16.765524) (xy 218.200491 16.722649)
			(xy 218.199832 16.715537) (xy 244.026677 16.715537) (xy 244.026677 16.801287) (xy 244.034589 16.88667)
			(xy 244.050345 16.97096) (xy 244.073812 17.053436) (xy 244.104788 17.133395) (xy 244.14301 17.210155)
			(xy 244.188151 17.283061) (xy 244.239827 17.35149) (xy 244.297596 17.41486) (xy 244.360966 17.472629)
			(xy 244.429395 17.524305) (xy 244.502301 17.569446) (xy 244.579061 17.607668) (xy 244.65902 17.638644)
			(xy 244.741496 17.662111) (xy 244.825786 17.677867) (xy 244.911169 17.685779) (xy 244.996919 17.685779)
			(xy 245.082302 17.677867) (xy 245.166592 17.662111) (xy 245.249068 17.638644) (xy 245.329027 17.607668)
			(xy 245.405787 17.569446) (xy 245.478693 17.524305) (xy 245.547122 17.472629) (xy 245.610492 17.41486)
			(xy 245.668261 17.35149) (xy 245.719937 17.283061) (xy 245.765078 17.210155) (xy 245.8033 17.133395)
			(xy 245.834276 17.053436) (xy 245.857743 16.97096) (xy 245.873499 16.88667) (xy 245.881411 16.801287)
			(xy 245.881906 16.758412) (xy 245.881411 16.715537) (xy 250.376677 16.715537) (xy 250.376677 16.801287)
			(xy 250.384589 16.88667) (xy 250.400345 16.97096) (xy 250.423812 17.053436) (xy 250.454788 17.133395)
			(xy 250.49301 17.210155) (xy 250.538151 17.283061) (xy 250.589827 17.35149) (xy 250.647596 17.41486)
			(xy 250.710966 17.472629) (xy 250.779395 17.524305) (xy 250.852301 17.569446) (xy 250.929061 17.607668)
			(xy 251.00902 17.638644) (xy 251.091496 17.662111) (xy 251.175786 17.677867) (xy 251.261169 17.685779)
			(xy 251.346919 17.685779) (xy 251.432302 17.677867) (xy 251.516592 17.662111) (xy 251.599068 17.638644)
			(xy 251.679027 17.607668) (xy 251.755787 17.569446) (xy 251.828693 17.524305) (xy 251.897122 17.472629)
			(xy 251.960492 17.41486) (xy 252.018261 17.35149) (xy 252.069937 17.283061) (xy 252.115078 17.210155)
			(xy 252.1533 17.133395) (xy 252.184276 17.053436) (xy 252.207743 16.97096) (xy 252.223499 16.88667)
			(xy 252.231411 16.801287) (xy 252.231906 16.758412) (xy 252.231493 16.722649) (xy 269.304757 16.722649)
			(xy 269.304757 16.808399) (xy 269.312669 16.893782) (xy 269.328425 16.978072) (xy 269.351892 17.060548)
			(xy 269.382868 17.140507) (xy 269.42109 17.217267) (xy 269.466231 17.290173) (xy 269.517907 17.358602)
			(xy 269.575676 17.421972) (xy 269.639046 17.479741) (xy 269.707475 17.531417) (xy 269.780381 17.576558)
			(xy 269.857141 17.61478) (xy 269.9371 17.645756) (xy 270.019576 17.669223) (xy 270.103866 17.684979)
			(xy 270.189249 17.692891) (xy 270.274999 17.692891) (xy 270.360382 17.684979) (xy 270.444672 17.669223)
			(xy 270.527148 17.645756) (xy 270.607107 17.61478) (xy 270.62931 17.603724) (xy 274.239736 17.603724)
			(xy 274.239736 18.467324) (xy 274.240222 18.494593) (xy 274.247984 18.548577) (xy 274.263349 18.600907)
			(xy 274.286006 18.650517) (xy 274.315492 18.696398) (xy 274.351207 18.737615) (xy 274.392424 18.77333)
			(xy 274.438305 18.802816) (xy 274.487915 18.825473) (xy 274.540245 18.840838) (xy 274.594229 18.8486)
			(xy 274.648767 18.8486) (xy 274.702751 18.840838) (xy 274.755081 18.825473) (xy 274.804691 18.802816)
			(xy 274.850572 18.77333) (xy 274.891789 18.737615) (xy 274.927504 18.696398) (xy 274.95699 18.650517)
			(xy 274.979647 18.600907) (xy 274.995012 18.548577) (xy 275.002774 18.494593) (xy 275.00326 18.467324)
			(xy 275.00326 17.603724) (xy 275.002774 17.576455) (xy 274.995012 17.522471) (xy 274.979647 17.470141)
			(xy 274.95699 17.420531) (xy 274.927504 17.37465) (xy 274.891789 17.333433) (xy 274.850572 17.297718)
			(xy 274.804691 17.268232) (xy 274.755081 17.245575) (xy 274.702751 17.23021) (xy 274.648767 17.222448)
			(xy 274.594229 17.222448) (xy 274.540245 17.23021) (xy 274.487915 17.245575) (xy 274.438305 17.268232)
			(xy 274.392424 17.297718) (xy 274.351207 17.333433) (xy 274.315492 17.37465) (xy 274.286006 17.420531)
			(xy 274.263349 17.470141) (xy 274.247984 17.522471) (xy 274.240222 17.576455) (xy 274.239736 17.603724)
			(xy 270.62931 17.603724) (xy 270.683867 17.576558) (xy 270.756773 17.531417) (xy 270.825202 17.479741)
			(xy 270.888572 17.421972) (xy 270.946341 17.358602) (xy 270.998017 17.290173) (xy 271.043158 17.217267)
			(xy 271.08138 17.140507) (xy 271.112356 17.060548) (xy 271.135823 16.978072) (xy 271.151579 16.893782)
			(xy 271.159491 16.808399) (xy 271.159986 16.765524) (xy 271.159491 16.722649) (xy 275.654757 16.722649)
			(xy 275.654757 16.808399) (xy 275.662669 16.893782) (xy 275.678425 16.978072) (xy 275.701892 17.060548)
			(xy 275.732868 17.140507) (xy 275.77109 17.217267) (xy 275.816231 17.290173) (xy 275.867907 17.358602)
			(xy 275.925676 17.421972) (xy 275.989046 17.479741) (xy 276.057475 17.531417) (xy 276.130381 17.576558)
			(xy 276.207141 17.61478) (xy 276.2871 17.645756) (xy 276.369576 17.669223) (xy 276.453866 17.684979)
			(xy 276.539249 17.692891) (xy 276.624999 17.692891) (xy 276.710382 17.684979) (xy 276.794672 17.669223)
			(xy 276.877148 17.645756) (xy 276.957107 17.61478) (xy 277.033867 17.576558) (xy 277.106773 17.531417)
			(xy 277.175202 17.479741) (xy 277.238572 17.421972) (xy 277.296341 17.358602) (xy 277.348017 17.290173)
			(xy 277.393158 17.217267) (xy 277.43138 17.140507) (xy 277.462356 17.060548) (xy 277.485823 16.978072)
			(xy 277.501579 16.893782) (xy 277.509491 16.808399) (xy 277.509986 16.765524) (xy 277.509491 16.722649)
			(xy 277.508832 16.715537) (xy 308.364877 16.715537) (xy 308.364877 16.801287) (xy 308.372789 16.88667)
			(xy 308.388545 16.97096) (xy 308.412012 17.053436) (xy 308.442988 17.133395) (xy 308.48121 17.210155)
			(xy 308.526351 17.283061) (xy 308.578027 17.35149) (xy 308.635796 17.41486) (xy 308.699166 17.472629)
			(xy 308.767595 17.524305) (xy 308.840501 17.569446) (xy 308.917261 17.607668) (xy 308.99722 17.638644)
			(xy 309.079696 17.662111) (xy 309.163986 17.677867) (xy 309.249369 17.685779) (xy 309.335119 17.685779)
			(xy 309.420502 17.677867) (xy 309.504792 17.662111) (xy 309.587268 17.638644) (xy 309.667227 17.607668)
			(xy 309.68943 17.596612) (xy 310.871108 17.596612) (xy 310.871108 18.460212) (xy 310.871594 18.487481)
			(xy 310.879356 18.541465) (xy 310.894721 18.593795) (xy 310.917378 18.643405) (xy 310.946864 18.689286)
			(xy 310.982579 18.730503) (xy 311.023796 18.766218) (xy 311.069677 18.795704) (xy 311.119287 18.818361)
			(xy 311.171617 18.833726) (xy 311.225601 18.841488) (xy 311.280139 18.841488) (xy 311.334123 18.833726)
			(xy 311.386453 18.818361) (xy 311.436063 18.795704) (xy 311.481944 18.766218) (xy 311.523161 18.730503)
			(xy 311.558876 18.689286) (xy 311.588362 18.643405) (xy 311.611019 18.593795) (xy 311.626384 18.541465)
			(xy 311.634146 18.487481) (xy 311.634632 18.460212) (xy 311.634632 17.596612) (xy 311.634146 17.569343)
			(xy 311.626384 17.515359) (xy 311.611019 17.463029) (xy 311.588362 17.413419) (xy 311.558876 17.367538)
			(xy 311.523161 17.326321) (xy 311.481944 17.290606) (xy 311.436063 17.26112) (xy 311.386453 17.238463)
			(xy 311.334123 17.223098) (xy 311.280139 17.215336) (xy 311.225601 17.215336) (xy 311.171617 17.223098)
			(xy 311.119287 17.238463) (xy 311.069677 17.26112) (xy 311.023796 17.290606) (xy 310.982579 17.326321)
			(xy 310.946864 17.367538) (xy 310.917378 17.413419) (xy 310.894721 17.463029) (xy 310.879356 17.515359)
			(xy 310.871594 17.569343) (xy 310.871108 17.596612) (xy 309.68943 17.596612) (xy 309.743987 17.569446)
			(xy 309.816893 17.524305) (xy 309.885322 17.472629) (xy 309.948692 17.41486) (xy 310.006461 17.35149)
			(xy 310.058137 17.283061) (xy 310.103278 17.210155) (xy 310.1415 17.133395) (xy 310.172476 17.053436)
			(xy 310.195943 16.97096) (xy 310.211699 16.88667) (xy 310.219611 16.801287) (xy 310.220106 16.758412)
			(xy 310.219611 16.715537) (xy 314.714877 16.715537) (xy 314.714877 16.801287) (xy 314.722789 16.88667)
			(xy 314.738545 16.97096) (xy 314.762012 17.053436) (xy 314.792988 17.133395) (xy 314.83121 17.210155)
			(xy 314.876351 17.283061) (xy 314.928027 17.35149) (xy 314.985796 17.41486) (xy 315.049166 17.472629)
			(xy 315.117595 17.524305) (xy 315.190501 17.569446) (xy 315.267261 17.607668) (xy 315.34722 17.638644)
			(xy 315.429696 17.662111) (xy 315.513986 17.677867) (xy 315.599369 17.685779) (xy 315.685119 17.685779)
			(xy 315.770502 17.677867) (xy 315.854792 17.662111) (xy 315.937268 17.638644) (xy 316.017227 17.607668)
			(xy 316.093987 17.569446) (xy 316.166893 17.524305) (xy 316.235322 17.472629) (xy 316.298692 17.41486)
			(xy 316.356461 17.35149) (xy 316.408137 17.283061) (xy 316.453278 17.210155) (xy 316.4915 17.133395)
			(xy 316.522476 17.053436) (xy 316.545943 16.97096) (xy 316.561699 16.88667) (xy 316.569611 16.801287)
			(xy 316.570106 16.758412) (xy 316.569693 16.722649) (xy 334.455757 16.722649) (xy 334.455757 16.808399)
			(xy 334.463669 16.893782) (xy 334.479425 16.978072) (xy 334.502892 17.060548) (xy 334.533868 17.140507)
			(xy 334.57209 17.217267) (xy 334.617231 17.290173) (xy 334.668907 17.358602) (xy 334.726676 17.421972)
			(xy 334.790046 17.479741) (xy 334.858475 17.531417) (xy 334.931381 17.576558) (xy 335.008141 17.61478)
			(xy 335.0881 17.645756) (xy 335.170576 17.669223) (xy 335.254866 17.684979) (xy 335.340249 17.692891)
			(xy 335.425999 17.692891) (xy 335.511382 17.684979) (xy 335.595672 17.669223) (xy 335.678148 17.645756)
			(xy 335.758107 17.61478) (xy 335.78031 17.603724) (xy 339.390736 17.603724) (xy 339.390736 18.467324)
			(xy 339.391222 18.494593) (xy 339.398984 18.548577) (xy 339.414349 18.600907) (xy 339.437006 18.650517)
			(xy 339.466492 18.696398) (xy 339.502207 18.737615) (xy 339.543424 18.77333) (xy 339.589305 18.802816)
			(xy 339.638915 18.825473) (xy 339.691245 18.840838) (xy 339.745229 18.8486) (xy 339.799767 18.8486)
			(xy 339.853751 18.840838) (xy 339.906081 18.825473) (xy 339.955691 18.802816) (xy 340.001572 18.77333)
			(xy 340.042789 18.737615) (xy 340.078504 18.696398) (xy 340.10799 18.650517) (xy 340.130647 18.600907)
			(xy 340.146012 18.548577) (xy 340.153774 18.494593) (xy 340.15426 18.467324) (xy 340.15426 17.603724)
			(xy 340.153774 17.576455) (xy 340.146012 17.522471) (xy 340.130647 17.470141) (xy 340.10799 17.420531)
			(xy 340.078504 17.37465) (xy 340.042789 17.333433) (xy 340.001572 17.297718) (xy 339.955691 17.268232)
			(xy 339.906081 17.245575) (xy 339.853751 17.23021) (xy 339.799767 17.222448) (xy 339.745229 17.222448)
			(xy 339.691245 17.23021) (xy 339.638915 17.245575) (xy 339.589305 17.268232) (xy 339.543424 17.297718)
			(xy 339.502207 17.333433) (xy 339.466492 17.37465) (xy 339.437006 17.420531) (xy 339.414349 17.470141)
			(xy 339.398984 17.522471) (xy 339.391222 17.576455) (xy 339.390736 17.603724) (xy 335.78031 17.603724)
			(xy 335.834867 17.576558) (xy 335.907773 17.531417) (xy 335.976202 17.479741) (xy 336.039572 17.421972)
			(xy 336.097341 17.358602) (xy 336.149017 17.290173) (xy 336.194158 17.217267) (xy 336.23238 17.140507)
			(xy 336.263356 17.060548) (xy 336.286823 16.978072) (xy 336.302579 16.893782) (xy 336.310491 16.808399)
			(xy 336.310986 16.765524) (xy 336.310491 16.722649) (xy 340.805757 16.722649) (xy 340.805757 16.808399)
			(xy 340.813669 16.893782) (xy 340.829425 16.978072) (xy 340.852892 17.060548) (xy 340.883868 17.140507)
			(xy 340.92209 17.217267) (xy 340.967231 17.290173) (xy 341.018907 17.358602) (xy 341.076676 17.421972)
			(xy 341.140046 17.479741) (xy 341.208475 17.531417) (xy 341.281381 17.576558) (xy 341.358141 17.61478)
			(xy 341.4381 17.645756) (xy 341.520576 17.669223) (xy 341.604866 17.684979) (xy 341.690249 17.692891)
			(xy 341.775999 17.692891) (xy 341.861382 17.684979) (xy 341.945672 17.669223) (xy 342.028148 17.645756)
			(xy 342.108107 17.61478) (xy 342.184867 17.576558) (xy 342.257773 17.531417) (xy 342.326202 17.479741)
			(xy 342.389572 17.421972) (xy 342.447341 17.358602) (xy 342.499017 17.290173) (xy 342.544158 17.217267)
			(xy 342.58238 17.140507) (xy 342.613356 17.060548) (xy 342.636823 16.978072) (xy 342.652579 16.893782)
			(xy 342.660491 16.808399) (xy 342.660986 16.765524) (xy 342.660491 16.722649) (xy 342.659832 16.715537)
			(xy 373.515877 16.715537) (xy 373.515877 16.801287) (xy 373.523789 16.88667) (xy 373.539545 16.97096)
			(xy 373.563012 17.053436) (xy 373.593988 17.133395) (xy 373.63221 17.210155) (xy 373.677351 17.283061)
			(xy 373.729027 17.35149) (xy 373.786796 17.41486) (xy 373.850166 17.472629) (xy 373.918595 17.524305)
			(xy 373.991501 17.569446) (xy 374.068261 17.607668) (xy 374.14822 17.638644) (xy 374.230696 17.662111)
			(xy 374.314986 17.677867) (xy 374.400369 17.685779) (xy 374.486119 17.685779) (xy 374.571502 17.677867)
			(xy 374.655792 17.662111) (xy 374.738268 17.638644) (xy 374.818227 17.607668) (xy 374.84043 17.596612)
			(xy 376.022108 17.596612) (xy 376.022108 18.460212) (xy 376.022594 18.487481) (xy 376.030356 18.541465)
			(xy 376.045721 18.593795) (xy 376.068378 18.643405) (xy 376.097864 18.689286) (xy 376.133579 18.730503)
			(xy 376.174796 18.766218) (xy 376.220677 18.795704) (xy 376.270287 18.818361) (xy 376.322617 18.833726)
			(xy 376.376601 18.841488) (xy 376.431139 18.841488) (xy 376.485123 18.833726) (xy 376.537453 18.818361)
			(xy 376.587063 18.795704) (xy 376.632944 18.766218) (xy 376.674161 18.730503) (xy 376.709876 18.689286)
			(xy 376.739362 18.643405) (xy 376.762019 18.593795) (xy 376.777384 18.541465) (xy 376.785146 18.487481)
			(xy 376.785632 18.460212) (xy 376.785632 17.596612) (xy 376.785146 17.569343) (xy 376.777384 17.515359)
			(xy 376.762019 17.463029) (xy 376.739362 17.413419) (xy 376.709876 17.367538) (xy 376.674161 17.326321)
			(xy 376.632944 17.290606) (xy 376.587063 17.26112) (xy 376.537453 17.238463) (xy 376.485123 17.223098)
			(xy 376.431139 17.215336) (xy 376.376601 17.215336) (xy 376.322617 17.223098) (xy 376.270287 17.238463)
			(xy 376.220677 17.26112) (xy 376.174796 17.290606) (xy 376.133579 17.326321) (xy 376.097864 17.367538)
			(xy 376.068378 17.413419) (xy 376.045721 17.463029) (xy 376.030356 17.515359) (xy 376.022594 17.569343)
			(xy 376.022108 17.596612) (xy 374.84043 17.596612) (xy 374.894987 17.569446) (xy 374.967893 17.524305)
			(xy 375.036322 17.472629) (xy 375.099692 17.41486) (xy 375.157461 17.35149) (xy 375.209137 17.283061)
			(xy 375.254278 17.210155) (xy 375.2925 17.133395) (xy 375.323476 17.053436) (xy 375.346943 16.97096)
			(xy 375.362699 16.88667) (xy 375.370611 16.801287) (xy 375.371106 16.758412) (xy 375.370611 16.715537)
			(xy 379.865877 16.715537) (xy 379.865877 16.801287) (xy 379.873789 16.88667) (xy 379.889545 16.97096)
			(xy 379.913012 17.053436) (xy 379.943988 17.133395) (xy 379.98221 17.210155) (xy 380.027351 17.283061)
			(xy 380.079027 17.35149) (xy 380.136796 17.41486) (xy 380.200166 17.472629) (xy 380.268595 17.524305)
			(xy 380.341501 17.569446) (xy 380.418261 17.607668) (xy 380.49822 17.638644) (xy 380.580696 17.662111)
			(xy 380.664986 17.677867) (xy 380.750369 17.685779) (xy 380.836119 17.685779) (xy 380.921502 17.677867)
			(xy 381.005792 17.662111) (xy 381.088268 17.638644) (xy 381.168227 17.607668) (xy 381.244987 17.569446)
			(xy 381.317893 17.524305) (xy 381.386322 17.472629) (xy 381.449692 17.41486) (xy 381.507461 17.35149)
			(xy 381.559137 17.283061) (xy 381.604278 17.210155) (xy 381.6425 17.133395) (xy 381.673476 17.053436)
			(xy 381.696943 16.97096) (xy 381.712699 16.88667) (xy 381.720611 16.801287) (xy 381.721106 16.758412)
			(xy 381.720693 16.722649) (xy 399.098757 16.722649) (xy 399.098757 16.808399) (xy 399.106669 16.893782)
			(xy 399.122425 16.978072) (xy 399.145892 17.060548) (xy 399.176868 17.140507) (xy 399.21509 17.217267)
			(xy 399.260231 17.290173) (xy 399.311907 17.358602) (xy 399.369676 17.421972) (xy 399.433046 17.479741)
			(xy 399.501475 17.531417) (xy 399.574381 17.576558) (xy 399.651141 17.61478) (xy 399.7311 17.645756)
			(xy 399.813576 17.669223) (xy 399.897866 17.684979) (xy 399.983249 17.692891) (xy 400.068999 17.692891)
			(xy 400.154382 17.684979) (xy 400.238672 17.669223) (xy 400.321148 17.645756) (xy 400.401107 17.61478)
			(xy 400.42331 17.603724) (xy 404.033736 17.603724) (xy 404.033736 18.467324) (xy 404.034222 18.494593)
			(xy 404.041984 18.548577) (xy 404.057349 18.600907) (xy 404.080006 18.650517) (xy 404.109492 18.696398)
			(xy 404.145207 18.737615) (xy 404.186424 18.77333) (xy 404.232305 18.802816) (xy 404.281915 18.825473)
			(xy 404.334245 18.840838) (xy 404.388229 18.8486) (xy 404.442767 18.8486) (xy 404.496751 18.840838)
			(xy 404.549081 18.825473) (xy 404.598691 18.802816) (xy 404.644572 18.77333) (xy 404.685789 18.737615)
			(xy 404.721504 18.696398) (xy 404.75099 18.650517) (xy 404.773647 18.600907) (xy 404.789012 18.548577)
			(xy 404.796774 18.494593) (xy 404.79726 18.467324) (xy 404.79726 17.603724) (xy 404.796774 17.576455)
			(xy 404.789012 17.522471) (xy 404.773647 17.470141) (xy 404.75099 17.420531) (xy 404.721504 17.37465)
			(xy 404.685789 17.333433) (xy 404.644572 17.297718) (xy 404.598691 17.268232) (xy 404.549081 17.245575)
			(xy 404.496751 17.23021) (xy 404.442767 17.222448) (xy 404.388229 17.222448) (xy 404.334245 17.23021)
			(xy 404.281915 17.245575) (xy 404.232305 17.268232) (xy 404.186424 17.297718) (xy 404.145207 17.333433)
			(xy 404.109492 17.37465) (xy 404.080006 17.420531) (xy 404.057349 17.470141) (xy 404.041984 17.522471)
			(xy 404.034222 17.576455) (xy 404.033736 17.603724) (xy 400.42331 17.603724) (xy 400.477867 17.576558)
			(xy 400.550773 17.531417) (xy 400.619202 17.479741) (xy 400.682572 17.421972) (xy 400.740341 17.358602)
			(xy 400.792017 17.290173) (xy 400.837158 17.217267) (xy 400.87538 17.140507) (xy 400.906356 17.060548)
			(xy 400.929823 16.978072) (xy 400.945579 16.893782) (xy 400.953491 16.808399) (xy 400.953986 16.765524)
			(xy 400.953491 16.722649) (xy 405.448757 16.722649) (xy 405.448757 16.808399) (xy 405.456669 16.893782)
			(xy 405.472425 16.978072) (xy 405.495892 17.060548) (xy 405.526868 17.140507) (xy 405.56509 17.217267)
			(xy 405.610231 17.290173) (xy 405.661907 17.358602) (xy 405.719676 17.421972) (xy 405.783046 17.479741)
			(xy 405.851475 17.531417) (xy 405.924381 17.576558) (xy 406.001141 17.61478) (xy 406.0811 17.645756)
			(xy 406.163576 17.669223) (xy 406.247866 17.684979) (xy 406.333249 17.692891) (xy 406.418999 17.692891)
			(xy 406.504382 17.684979) (xy 406.588672 17.669223) (xy 406.671148 17.645756) (xy 406.751107 17.61478)
			(xy 406.827867 17.576558) (xy 406.900773 17.531417) (xy 406.969202 17.479741) (xy 407.032572 17.421972)
			(xy 407.090341 17.358602) (xy 407.142017 17.290173) (xy 407.187158 17.217267) (xy 407.22538 17.140507)
			(xy 407.256356 17.060548) (xy 407.279823 16.978072) (xy 407.295579 16.893782) (xy 407.303491 16.808399)
			(xy 407.303986 16.765524) (xy 407.303491 16.722649) (xy 407.302832 16.715537) (xy 438.158877 16.715537)
			(xy 438.158877 16.801287) (xy 438.166789 16.88667) (xy 438.182545 16.97096) (xy 438.206012 17.053436)
			(xy 438.236988 17.133395) (xy 438.27521 17.210155) (xy 438.320351 17.283061) (xy 438.372027 17.35149)
			(xy 438.429796 17.41486) (xy 438.493166 17.472629) (xy 438.561595 17.524305) (xy 438.634501 17.569446)
			(xy 438.711261 17.607668) (xy 438.79122 17.638644) (xy 438.873696 17.662111) (xy 438.957986 17.677867)
			(xy 439.043369 17.685779) (xy 439.129119 17.685779) (xy 439.214502 17.677867) (xy 439.298792 17.662111)
			(xy 439.381268 17.638644) (xy 439.461227 17.607668) (xy 439.48343 17.596612) (xy 440.665108 17.596612)
			(xy 440.665108 18.460212) (xy 440.665594 18.487481) (xy 440.673356 18.541465) (xy 440.688721 18.593795)
			(xy 440.711378 18.643405) (xy 440.740864 18.689286) (xy 440.776579 18.730503) (xy 440.817796 18.766218)
			(xy 440.863677 18.795704) (xy 440.913287 18.818361) (xy 440.965617 18.833726) (xy 441.019601 18.841488)
			(xy 441.074139 18.841488) (xy 441.128123 18.833726) (xy 441.180453 18.818361) (xy 441.230063 18.795704)
			(xy 441.275944 18.766218) (xy 441.317161 18.730503) (xy 441.352876 18.689286) (xy 441.382362 18.643405)
			(xy 441.405019 18.593795) (xy 441.420384 18.541465) (xy 441.428146 18.487481) (xy 441.428632 18.460212)
			(xy 441.428632 17.596612) (xy 441.428146 17.569343) (xy 441.420384 17.515359) (xy 441.405019 17.463029)
			(xy 441.382362 17.413419) (xy 441.352876 17.367538) (xy 441.317161 17.326321) (xy 441.275944 17.290606)
			(xy 441.230063 17.26112) (xy 441.180453 17.238463) (xy 441.128123 17.223098) (xy 441.074139 17.215336)
			(xy 441.019601 17.215336) (xy 440.965617 17.223098) (xy 440.913287 17.238463) (xy 440.863677 17.26112)
			(xy 440.817796 17.290606) (xy 440.776579 17.326321) (xy 440.740864 17.367538) (xy 440.711378 17.413419)
			(xy 440.688721 17.463029) (xy 440.673356 17.515359) (xy 440.665594 17.569343) (xy 440.665108 17.596612)
			(xy 439.48343 17.596612) (xy 439.537987 17.569446) (xy 439.610893 17.524305) (xy 439.679322 17.472629)
			(xy 439.742692 17.41486) (xy 439.800461 17.35149) (xy 439.852137 17.283061) (xy 439.897278 17.210155)
			(xy 439.9355 17.133395) (xy 439.966476 17.053436) (xy 439.989943 16.97096) (xy 440.005699 16.88667)
			(xy 440.013611 16.801287) (xy 440.014106 16.758412) (xy 440.013611 16.715537) (xy 444.508877 16.715537)
			(xy 444.508877 16.801287) (xy 444.516789 16.88667) (xy 444.532545 16.97096) (xy 444.556012 17.053436)
			(xy 444.586988 17.133395) (xy 444.62521 17.210155) (xy 444.670351 17.283061) (xy 444.722027 17.35149)
			(xy 444.779796 17.41486) (xy 444.843166 17.472629) (xy 444.911595 17.524305) (xy 444.984501 17.569446)
			(xy 445.061261 17.607668) (xy 445.14122 17.638644) (xy 445.223696 17.662111) (xy 445.307986 17.677867)
			(xy 445.393369 17.685779) (xy 445.479119 17.685779) (xy 445.564502 17.677867) (xy 445.648792 17.662111)
			(xy 445.731268 17.638644) (xy 445.811227 17.607668) (xy 445.887987 17.569446) (xy 445.960893 17.524305)
			(xy 446.029322 17.472629) (xy 446.092692 17.41486) (xy 446.150461 17.35149) (xy 446.202137 17.283061)
			(xy 446.247278 17.210155) (xy 446.2855 17.133395) (xy 446.316476 17.053436) (xy 446.339943 16.97096)
			(xy 446.355699 16.88667) (xy 446.363611 16.801287) (xy 446.364106 16.758412) (xy 446.363611 16.715537)
			(xy 446.355699 16.630154) (xy 446.339943 16.545864) (xy 446.316476 16.463388) (xy 446.2855 16.383429)
			(xy 446.247278 16.306669) (xy 446.202137 16.233763) (xy 446.150461 16.165334) (xy 446.092692 16.101964)
			(xy 446.029322 16.044195) (xy 445.960893 15.992519) (xy 445.887987 15.947378) (xy 445.811227 15.909156)
			(xy 445.731268 15.87818) (xy 445.648792 15.854713) (xy 445.564502 15.838957) (xy 445.479119 15.831045)
			(xy 445.393369 15.831045) (xy 445.307986 15.838957) (xy 445.223696 15.854713) (xy 445.14122 15.87818)
			(xy 445.061261 15.909156) (xy 444.984501 15.947378) (xy 444.911595 15.992519) (xy 444.843166 16.044195)
			(xy 444.779796 16.101964) (xy 444.722027 16.165334) (xy 444.670351 16.233763) (xy 444.62521 16.306669)
			(xy 444.586988 16.383429) (xy 444.556012 16.463388) (xy 444.532545 16.545864) (xy 444.516789 16.630154)
			(xy 444.508877 16.715537) (xy 440.013611 16.715537) (xy 440.005699 16.630154) (xy 439.989943 16.545864)
			(xy 439.966476 16.463388) (xy 439.9355 16.383429) (xy 439.897278 16.306669) (xy 439.852137 16.233763)
			(xy 439.800461 16.165334) (xy 439.742692 16.101964) (xy 439.679322 16.044195) (xy 439.610893 15.992519)
			(xy 439.537987 15.947378) (xy 439.461227 15.909156) (xy 439.381268 15.87818) (xy 439.298792 15.854713)
			(xy 439.214502 15.838957) (xy 439.129119 15.831045) (xy 439.043369 15.831045) (xy 438.957986 15.838957)
			(xy 438.873696 15.854713) (xy 438.79122 15.87818) (xy 438.711261 15.909156) (xy 438.634501 15.947378)
			(xy 438.561595 15.992519) (xy 438.493166 16.044195) (xy 438.429796 16.101964) (xy 438.372027 16.165334)
			(xy 438.320351 16.233763) (xy 438.27521 16.306669) (xy 438.236988 16.383429) (xy 438.206012 16.463388)
			(xy 438.182545 16.545864) (xy 438.166789 16.630154) (xy 438.158877 16.715537) (xy 407.302832 16.715537)
			(xy 407.295579 16.637266) (xy 407.279823 16.552976) (xy 407.256356 16.4705) (xy 407.22538 16.390541)
			(xy 407.187158 16.313781) (xy 407.142017 16.240875) (xy 407.090341 16.172446) (xy 407.032572 16.109076)
			(xy 406.969202 16.051307) (xy 406.900773 15.999631) (xy 406.827867 15.95449) (xy 406.751107 15.916268)
			(xy 406.671148 15.885292) (xy 406.588672 15.861825) (xy 406.504382 15.846069) (xy 406.418999 15.838157)
			(xy 406.333249 15.838157) (xy 406.247866 15.846069) (xy 406.163576 15.861825) (xy 406.0811 15.885292)
			(xy 406.001141 15.916268) (xy 405.924381 15.95449) (xy 405.851475 15.999631) (xy 405.783046 16.051307)
			(xy 405.719676 16.109076) (xy 405.661907 16.172446) (xy 405.610231 16.240875) (xy 405.56509 16.313781)
			(xy 405.526868 16.390541) (xy 405.495892 16.4705) (xy 405.472425 16.552976) (xy 405.456669 16.637266)
			(xy 405.448757 16.722649) (xy 400.953491 16.722649) (xy 400.945579 16.637266) (xy 400.929823 16.552976)
			(xy 400.906356 16.4705) (xy 400.87538 16.390541) (xy 400.837158 16.313781) (xy 400.792017 16.240875)
			(xy 400.740341 16.172446) (xy 400.682572 16.109076) (xy 400.619202 16.051307) (xy 400.550773 15.999631)
			(xy 400.477867 15.95449) (xy 400.401107 15.916268) (xy 400.321148 15.885292) (xy 400.238672 15.861825)
			(xy 400.154382 15.846069) (xy 400.068999 15.838157) (xy 399.983249 15.838157) (xy 399.897866 15.846069)
			(xy 399.813576 15.861825) (xy 399.7311 15.885292) (xy 399.651141 15.916268) (xy 399.574381 15.95449)
			(xy 399.501475 15.999631) (xy 399.433046 16.051307) (xy 399.369676 16.109076) (xy 399.311907 16.172446)
			(xy 399.260231 16.240875) (xy 399.21509 16.313781) (xy 399.176868 16.390541) (xy 399.145892 16.4705)
			(xy 399.122425 16.552976) (xy 399.106669 16.637266) (xy 399.098757 16.722649) (xy 381.720693 16.722649)
			(xy 381.720611 16.715537) (xy 381.712699 16.630154) (xy 381.696943 16.545864) (xy 381.673476 16.463388)
			(xy 381.6425 16.383429) (xy 381.604278 16.306669) (xy 381.559137 16.233763) (xy 381.507461 16.165334)
			(xy 381.449692 16.101964) (xy 381.386322 16.044195) (xy 381.317893 15.992519) (xy 381.244987 15.947378)
			(xy 381.168227 15.909156) (xy 381.088268 15.87818) (xy 381.005792 15.854713) (xy 380.921502 15.838957)
			(xy 380.836119 15.831045) (xy 380.750369 15.831045) (xy 380.664986 15.838957) (xy 380.580696 15.854713)
			(xy 380.49822 15.87818) (xy 380.418261 15.909156) (xy 380.341501 15.947378) (xy 380.268595 15.992519)
			(xy 380.200166 16.044195) (xy 380.136796 16.101964) (xy 380.079027 16.165334) (xy 380.027351 16.233763)
			(xy 379.98221 16.306669) (xy 379.943988 16.383429) (xy 379.913012 16.463388) (xy 379.889545 16.545864)
			(xy 379.873789 16.630154) (xy 379.865877 16.715537) (xy 375.370611 16.715537) (xy 375.362699 16.630154)
			(xy 375.346943 16.545864) (xy 375.323476 16.463388) (xy 375.2925 16.383429) (xy 375.254278 16.306669)
			(xy 375.209137 16.233763) (xy 375.157461 16.165334) (xy 375.099692 16.101964) (xy 375.036322 16.044195)
			(xy 374.967893 15.992519) (xy 374.894987 15.947378) (xy 374.818227 15.909156) (xy 374.738268 15.87818)
			(xy 374.655792 15.854713) (xy 374.571502 15.838957) (xy 374.486119 15.831045) (xy 374.400369 15.831045)
			(xy 374.314986 15.838957) (xy 374.230696 15.854713) (xy 374.14822 15.87818) (xy 374.068261 15.909156)
			(xy 373.991501 15.947378) (xy 373.918595 15.992519) (xy 373.850166 16.044195) (xy 373.786796 16.101964)
			(xy 373.729027 16.165334) (xy 373.677351 16.233763) (xy 373.63221 16.306669) (xy 373.593988 16.383429)
			(xy 373.563012 16.463388) (xy 373.539545 16.545864) (xy 373.523789 16.630154) (xy 373.515877 16.715537)
			(xy 342.659832 16.715537) (xy 342.652579 16.637266) (xy 342.636823 16.552976) (xy 342.613356 16.4705)
			(xy 342.58238 16.390541) (xy 342.544158 16.313781) (xy 342.499017 16.240875) (xy 342.447341 16.172446)
			(xy 342.389572 16.109076) (xy 342.326202 16.051307) (xy 342.257773 15.999631) (xy 342.184867 15.95449)
			(xy 342.108107 15.916268) (xy 342.028148 15.885292) (xy 341.945672 15.861825) (xy 341.861382 15.846069)
			(xy 341.775999 15.838157) (xy 341.690249 15.838157) (xy 341.604866 15.846069) (xy 341.520576 15.861825)
			(xy 341.4381 15.885292) (xy 341.358141 15.916268) (xy 341.281381 15.95449) (xy 341.208475 15.999631)
			(xy 341.140046 16.051307) (xy 341.076676 16.109076) (xy 341.018907 16.172446) (xy 340.967231 16.240875)
			(xy 340.92209 16.313781) (xy 340.883868 16.390541) (xy 340.852892 16.4705) (xy 340.829425 16.552976)
			(xy 340.813669 16.637266) (xy 340.805757 16.722649) (xy 336.310491 16.722649) (xy 336.302579 16.637266)
			(xy 336.286823 16.552976) (xy 336.263356 16.4705) (xy 336.23238 16.390541) (xy 336.194158 16.313781)
			(xy 336.149017 16.240875) (xy 336.097341 16.172446) (xy 336.039572 16.109076) (xy 335.976202 16.051307)
			(xy 335.907773 15.999631) (xy 335.834867 15.95449) (xy 335.758107 15.916268) (xy 335.678148 15.885292)
			(xy 335.595672 15.861825) (xy 335.511382 15.846069) (xy 335.425999 15.838157) (xy 335.340249 15.838157)
			(xy 335.254866 15.846069) (xy 335.170576 15.861825) (xy 335.0881 15.885292) (xy 335.008141 15.916268)
			(xy 334.931381 15.95449) (xy 334.858475 15.999631) (xy 334.790046 16.051307) (xy 334.726676 16.109076)
			(xy 334.668907 16.172446) (xy 334.617231 16.240875) (xy 334.57209 16.313781) (xy 334.533868 16.390541)
			(xy 334.502892 16.4705) (xy 334.479425 16.552976) (xy 334.463669 16.637266) (xy 334.455757 16.722649)
			(xy 316.569693 16.722649) (xy 316.569611 16.715537) (xy 316.561699 16.630154) (xy 316.545943 16.545864)
			(xy 316.522476 16.463388) (xy 316.4915 16.383429) (xy 316.453278 16.306669) (xy 316.408137 16.233763)
			(xy 316.356461 16.165334) (xy 316.298692 16.101964) (xy 316.235322 16.044195) (xy 316.166893 15.992519)
			(xy 316.093987 15.947378) (xy 316.017227 15.909156) (xy 315.937268 15.87818) (xy 315.854792 15.854713)
			(xy 315.770502 15.838957) (xy 315.685119 15.831045) (xy 315.599369 15.831045) (xy 315.513986 15.838957)
			(xy 315.429696 15.854713) (xy 315.34722 15.87818) (xy 315.267261 15.909156) (xy 315.190501 15.947378)
			(xy 315.117595 15.992519) (xy 315.049166 16.044195) (xy 314.985796 16.101964) (xy 314.928027 16.165334)
			(xy 314.876351 16.233763) (xy 314.83121 16.306669) (xy 314.792988 16.383429) (xy 314.762012 16.463388)
			(xy 314.738545 16.545864) (xy 314.722789 16.630154) (xy 314.714877 16.715537) (xy 310.219611 16.715537)
			(xy 310.211699 16.630154) (xy 310.195943 16.545864) (xy 310.172476 16.463388) (xy 310.1415 16.383429)
			(xy 310.103278 16.306669) (xy 310.058137 16.233763) (xy 310.006461 16.165334) (xy 309.948692 16.101964)
			(xy 309.885322 16.044195) (xy 309.816893 15.992519) (xy 309.743987 15.947378) (xy 309.667227 15.909156)
			(xy 309.587268 15.87818) (xy 309.504792 15.854713) (xy 309.420502 15.838957) (xy 309.335119 15.831045)
			(xy 309.249369 15.831045) (xy 309.163986 15.838957) (xy 309.079696 15.854713) (xy 308.99722 15.87818)
			(xy 308.917261 15.909156) (xy 308.840501 15.947378) (xy 308.767595 15.992519) (xy 308.699166 16.044195)
			(xy 308.635796 16.101964) (xy 308.578027 16.165334) (xy 308.526351 16.233763) (xy 308.48121 16.306669)
			(xy 308.442988 16.383429) (xy 308.412012 16.463388) (xy 308.388545 16.545864) (xy 308.372789 16.630154)
			(xy 308.364877 16.715537) (xy 277.508832 16.715537) (xy 277.501579 16.637266) (xy 277.485823 16.552976)
			(xy 277.462356 16.4705) (xy 277.43138 16.390541) (xy 277.393158 16.313781) (xy 277.348017 16.240875)
			(xy 277.296341 16.172446) (xy 277.238572 16.109076) (xy 277.175202 16.051307) (xy 277.106773 15.999631)
			(xy 277.033867 15.95449) (xy 276.957107 15.916268) (xy 276.877148 15.885292) (xy 276.794672 15.861825)
			(xy 276.710382 15.846069) (xy 276.624999 15.838157) (xy 276.539249 15.838157) (xy 276.453866 15.846069)
			(xy 276.369576 15.861825) (xy 276.2871 15.885292) (xy 276.207141 15.916268) (xy 276.130381 15.95449)
			(xy 276.057475 15.999631) (xy 275.989046 16.051307) (xy 275.925676 16.109076) (xy 275.867907 16.172446)
			(xy 275.816231 16.240875) (xy 275.77109 16.313781) (xy 275.732868 16.390541) (xy 275.701892 16.4705)
			(xy 275.678425 16.552976) (xy 275.662669 16.637266) (xy 275.654757 16.722649) (xy 271.159491 16.722649)
			(xy 271.151579 16.637266) (xy 271.135823 16.552976) (xy 271.112356 16.4705) (xy 271.08138 16.390541)
			(xy 271.043158 16.313781) (xy 270.998017 16.240875) (xy 270.946341 16.172446) (xy 270.888572 16.109076)
			(xy 270.825202 16.051307) (xy 270.756773 15.999631) (xy 270.683867 15.95449) (xy 270.607107 15.916268)
			(xy 270.527148 15.885292) (xy 270.444672 15.861825) (xy 270.360382 15.846069) (xy 270.274999 15.838157)
			(xy 270.189249 15.838157) (xy 270.103866 15.846069) (xy 270.019576 15.861825) (xy 269.9371 15.885292)
			(xy 269.857141 15.916268) (xy 269.780381 15.95449) (xy 269.707475 15.999631) (xy 269.639046 16.051307)
			(xy 269.575676 16.109076) (xy 269.517907 16.172446) (xy 269.466231 16.240875) (xy 269.42109 16.313781)
			(xy 269.382868 16.390541) (xy 269.351892 16.4705) (xy 269.328425 16.552976) (xy 269.312669 16.637266)
			(xy 269.304757 16.722649) (xy 252.231493 16.722649) (xy 252.231411 16.715537) (xy 252.223499 16.630154)
			(xy 252.207743 16.545864) (xy 252.184276 16.463388) (xy 252.1533 16.383429) (xy 252.115078 16.306669)
			(xy 252.069937 16.233763) (xy 252.018261 16.165334) (xy 251.960492 16.101964) (xy 251.897122 16.044195)
			(xy 251.828693 15.992519) (xy 251.755787 15.947378) (xy 251.679027 15.909156) (xy 251.599068 15.87818)
			(xy 251.516592 15.854713) (xy 251.432302 15.838957) (xy 251.346919 15.831045) (xy 251.261169 15.831045)
			(xy 251.175786 15.838957) (xy 251.091496 15.854713) (xy 251.00902 15.87818) (xy 250.929061 15.909156)
			(xy 250.852301 15.947378) (xy 250.779395 15.992519) (xy 250.710966 16.044195) (xy 250.647596 16.101964)
			(xy 250.589827 16.165334) (xy 250.538151 16.233763) (xy 250.49301 16.306669) (xy 250.454788 16.383429)
			(xy 250.423812 16.463388) (xy 250.400345 16.545864) (xy 250.384589 16.630154) (xy 250.376677 16.715537)
			(xy 245.881411 16.715537) (xy 245.873499 16.630154) (xy 245.857743 16.545864) (xy 245.834276 16.463388)
			(xy 245.8033 16.383429) (xy 245.765078 16.306669) (xy 245.719937 16.233763) (xy 245.668261 16.165334)
			(xy 245.610492 16.101964) (xy 245.547122 16.044195) (xy 245.478693 15.992519) (xy 245.405787 15.947378)
			(xy 245.329027 15.909156) (xy 245.249068 15.87818) (xy 245.166592 15.854713) (xy 245.082302 15.838957)
			(xy 244.996919 15.831045) (xy 244.911169 15.831045) (xy 244.825786 15.838957) (xy 244.741496 15.854713)
			(xy 244.65902 15.87818) (xy 244.579061 15.909156) (xy 244.502301 15.947378) (xy 244.429395 15.992519)
			(xy 244.360966 16.044195) (xy 244.297596 16.101964) (xy 244.239827 16.165334) (xy 244.188151 16.233763)
			(xy 244.14301 16.306669) (xy 244.104788 16.383429) (xy 244.073812 16.463388) (xy 244.050345 16.545864)
			(xy 244.034589 16.630154) (xy 244.026677 16.715537) (xy 218.199832 16.715537) (xy 218.192579 16.637266)
			(xy 218.176823 16.552976) (xy 218.153356 16.4705) (xy 218.12238 16.390541) (xy 218.084158 16.313781)
			(xy 218.039017 16.240875) (xy 217.987341 16.172446) (xy 217.929572 16.109076) (xy 217.866202 16.051307)
			(xy 217.797773 15.999631) (xy 217.724867 15.95449) (xy 217.648107 15.916268) (xy 217.568148 15.885292)
			(xy 217.485672 15.861825) (xy 217.401382 15.846069) (xy 217.315999 15.838157) (xy 217.230249 15.838157)
			(xy 217.144866 15.846069) (xy 217.060576 15.861825) (xy 216.9781 15.885292) (xy 216.898141 15.916268)
			(xy 216.821381 15.95449) (xy 216.748475 15.999631) (xy 216.680046 16.051307) (xy 216.616676 16.109076)
			(xy 216.558907 16.172446) (xy 216.507231 16.240875) (xy 216.46209 16.313781) (xy 216.423868 16.390541)
			(xy 216.392892 16.4705) (xy 216.369425 16.552976) (xy 216.353669 16.637266) (xy 216.345757 16.722649)
			(xy 211.850491 16.722649) (xy 211.842579 16.637266) (xy 211.826823 16.552976) (xy 211.803356 16.4705)
			(xy 211.77238 16.390541) (xy 211.734158 16.313781) (xy 211.689017 16.240875) (xy 211.637341 16.172446)
			(xy 211.579572 16.109076) (xy 211.516202 16.051307) (xy 211.447773 15.999631) (xy 211.374867 15.95449)
			(xy 211.298107 15.916268) (xy 211.218148 15.885292) (xy 211.135672 15.861825) (xy 211.051382 15.846069)
			(xy 210.965999 15.838157) (xy 210.880249 15.838157) (xy 210.794866 15.846069) (xy 210.710576 15.861825)
			(xy 210.6281 15.885292) (xy 210.548141 15.916268) (xy 210.471381 15.95449) (xy 210.398475 15.999631)
			(xy 210.330046 16.051307) (xy 210.266676 16.109076) (xy 210.208907 16.172446) (xy 210.157231 16.240875)
			(xy 210.11209 16.313781) (xy 210.073868 16.390541) (xy 210.042892 16.4705) (xy 210.019425 16.552976)
			(xy 210.003669 16.637266) (xy 209.995757 16.722649) (xy 158.621984 16.722649) (xy 158.621984 11.850929)
			(xy 251.524757 11.850929) (xy 251.524757 11.936679) (xy 251.532669 12.022062) (xy 251.548425 12.106352)
			(xy 251.571892 12.188828) (xy 251.602868 12.268787) (xy 251.64109 12.345547) (xy 251.686231 12.418453)
			(xy 251.737907 12.486882) (xy 251.795676 12.550252) (xy 251.859046 12.608021) (xy 251.927475 12.659697)
			(xy 252.000381 12.704838) (xy 252.077141 12.74306) (xy 252.1571 12.774036) (xy 252.239576 12.797503)
			(xy 252.323866 12.813259) (xy 252.409249 12.821171) (xy 252.494999 12.821171) (xy 252.580382 12.813259)
			(xy 252.664672 12.797503) (xy 252.747148 12.774036) (xy 252.827107 12.74306) (xy 252.903867 12.704838)
			(xy 252.976773 12.659697) (xy 253.045202 12.608021) (xy 253.108572 12.550252) (xy 253.166341 12.486882)
			(xy 253.218017 12.418453) (xy 253.263158 12.345547) (xy 253.30138 12.268787) (xy 253.332356 12.188828)
			(xy 253.355823 12.106352) (xy 253.371579 12.022062) (xy 253.379491 11.936679) (xy 253.379986 11.893804)
			(xy 253.379491 11.850929) (xy 257.874757 11.850929) (xy 257.874757 11.936679) (xy 257.882669 12.022062)
			(xy 257.898425 12.106352) (xy 257.921892 12.188828) (xy 257.952868 12.268787) (xy 257.99109 12.345547)
			(xy 258.036231 12.418453) (xy 258.087907 12.486882) (xy 258.145676 12.550252) (xy 258.209046 12.608021)
			(xy 258.277475 12.659697) (xy 258.350381 12.704838) (xy 258.427141 12.74306) (xy 258.5071 12.774036)
			(xy 258.589576 12.797503) (xy 258.673866 12.813259) (xy 258.759249 12.821171) (xy 258.844999 12.821171)
			(xy 258.930382 12.813259) (xy 259.014672 12.797503) (xy 259.097148 12.774036) (xy 259.177107 12.74306)
			(xy 259.253867 12.704838) (xy 259.326773 12.659697) (xy 259.395202 12.608021) (xy 259.458572 12.550252)
			(xy 259.516341 12.486882) (xy 259.568017 12.418453) (xy 259.613158 12.345547) (xy 259.65138 12.268787)
			(xy 259.682356 12.188828) (xy 259.705823 12.106352) (xy 259.721579 12.022062) (xy 259.729491 11.936679)
			(xy 259.729986 11.893804) (xy 259.72979 11.876837) (xy 309.725301 11.876837) (xy 309.725301 11.962587)
			(xy 309.733213 12.04797) (xy 309.748969 12.13226) (xy 309.772436 12.214736) (xy 309.803412 12.294695)
			(xy 309.841634 12.371455) (xy 309.886775 12.444361) (xy 309.938451 12.51279) (xy 309.99622 12.57616)
			(xy 310.05959 12.633929) (xy 310.128019 12.685605) (xy 310.200925 12.730746) (xy 310.277685 12.768968)
			(xy 310.357644 12.799944) (xy 310.44012 12.823411) (xy 310.52441 12.839167) (xy 310.609793 12.847079)
			(xy 310.695543 12.847079) (xy 310.780926 12.839167) (xy 310.865216 12.823411) (xy 310.947692 12.799944)
			(xy 311.027651 12.768968) (xy 311.104411 12.730746) (xy 311.177317 12.685605) (xy 311.245746 12.633929)
			(xy 311.309116 12.57616) (xy 311.366885 12.51279) (xy 311.418561 12.444361) (xy 311.463702 12.371455)
			(xy 311.501924 12.294695) (xy 311.5329 12.214736) (xy 311.556367 12.13226) (xy 311.572123 12.04797)
			(xy 311.580035 11.962587) (xy 311.58053 11.919712) (xy 311.580035 11.876837) (xy 316.075301 11.876837)
			(xy 316.075301 11.962587) (xy 316.083213 12.04797) (xy 316.098969 12.13226) (xy 316.122436 12.214736)
			(xy 316.153412 12.294695) (xy 316.191634 12.371455) (xy 316.236775 12.444361) (xy 316.288451 12.51279)
			(xy 316.34622 12.57616) (xy 316.40959 12.633929) (xy 316.478019 12.685605) (xy 316.550925 12.730746)
			(xy 316.627685 12.768968) (xy 316.707644 12.799944) (xy 316.79012 12.823411) (xy 316.87441 12.839167)
			(xy 316.959793 12.847079) (xy 317.045543 12.847079) (xy 317.130926 12.839167) (xy 317.215216 12.823411)
			(xy 317.297692 12.799944) (xy 317.377651 12.768968) (xy 317.454411 12.730746) (xy 317.527317 12.685605)
			(xy 317.595746 12.633929) (xy 317.659116 12.57616) (xy 317.716885 12.51279) (xy 317.768561 12.444361)
			(xy 317.813702 12.371455) (xy 317.851924 12.294695) (xy 317.8829 12.214736) (xy 317.906367 12.13226)
			(xy 317.922123 12.04797) (xy 317.930035 11.962587) (xy 317.93053 11.919712) (xy 317.930117 11.883949)
			(xy 324.295757 11.883949) (xy 324.295757 11.969699) (xy 324.303669 12.055082) (xy 324.319425 12.139372)
			(xy 324.342892 12.221848) (xy 324.373868 12.301807) (xy 324.41209 12.378567) (xy 324.457231 12.451473)
			(xy 324.508907 12.519902) (xy 324.566676 12.583272) (xy 324.630046 12.641041) (xy 324.698475 12.692717)
			(xy 324.771381 12.737858) (xy 324.848141 12.77608) (xy 324.9281 12.807056) (xy 325.010576 12.830523)
			(xy 325.094866 12.846279) (xy 325.180249 12.854191) (xy 325.265999 12.854191) (xy 325.351382 12.846279)
			(xy 325.435672 12.830523) (xy 325.518148 12.807056) (xy 325.598107 12.77608) (xy 325.674867 12.737858)
			(xy 325.747773 12.692717) (xy 325.816202 12.641041) (xy 325.879572 12.583272) (xy 325.937341 12.519902)
			(xy 325.989017 12.451473) (xy 326.034158 12.378567) (xy 326.07238 12.301807) (xy 326.103356 12.221848)
			(xy 326.126823 12.139372) (xy 326.142579 12.055082) (xy 326.150491 11.969699) (xy 326.150986 11.926824)
			(xy 326.150491 11.883949) (xy 330.645757 11.883949) (xy 330.645757 11.969699) (xy 330.653669 12.055082)
			(xy 330.669425 12.139372) (xy 330.692892 12.221848) (xy 330.723868 12.301807) (xy 330.76209 12.378567)
			(xy 330.807231 12.451473) (xy 330.858907 12.519902) (xy 330.916676 12.583272) (xy 330.980046 12.641041)
			(xy 331.048475 12.692717) (xy 331.121381 12.737858) (xy 331.198141 12.77608) (xy 331.2781 12.807056)
			(xy 331.360576 12.830523) (xy 331.444866 12.846279) (xy 331.530249 12.854191) (xy 331.615999 12.854191)
			(xy 331.701382 12.846279) (xy 331.785672 12.830523) (xy 331.868148 12.807056) (xy 331.948107 12.77608)
			(xy 332.024867 12.737858) (xy 332.097773 12.692717) (xy 332.166202 12.641041) (xy 332.229572 12.583272)
			(xy 332.287341 12.519902) (xy 332.339017 12.451473) (xy 332.384158 12.378567) (xy 332.42238 12.301807)
			(xy 332.453356 12.221848) (xy 332.476823 12.139372) (xy 332.492579 12.055082) (xy 332.500491 11.969699)
			(xy 332.500986 11.926824) (xy 332.50079 11.909857) (xy 382.496301 11.909857) (xy 382.496301 11.995607)
			(xy 382.504213 12.08099) (xy 382.519969 12.16528) (xy 382.543436 12.247756) (xy 382.574412 12.327715)
			(xy 382.612634 12.404475) (xy 382.657775 12.477381) (xy 382.709451 12.54581) (xy 382.76722 12.60918)
			(xy 382.83059 12.666949) (xy 382.899019 12.718625) (xy 382.971925 12.763766) (xy 383.048685 12.801988)
			(xy 383.128644 12.832964) (xy 383.21112 12.856431) (xy 383.29541 12.872187) (xy 383.380793 12.880099)
			(xy 383.466543 12.880099) (xy 383.551926 12.872187) (xy 383.636216 12.856431) (xy 383.718692 12.832964)
			(xy 383.798651 12.801988) (xy 383.875411 12.763766) (xy 383.948317 12.718625) (xy 384.016746 12.666949)
			(xy 384.080116 12.60918) (xy 384.137885 12.54581) (xy 384.189561 12.477381) (xy 384.234702 12.404475)
			(xy 384.272924 12.327715) (xy 384.3039 12.247756) (xy 384.327367 12.16528) (xy 384.343123 12.08099)
			(xy 384.351035 11.995607) (xy 384.35153 11.952732) (xy 384.351035 11.909857) (xy 388.846301 11.909857)
			(xy 388.846301 11.995607) (xy 388.854213 12.08099) (xy 388.869969 12.16528) (xy 388.893436 12.247756)
			(xy 388.924412 12.327715) (xy 388.962634 12.404475) (xy 389.007775 12.477381) (xy 389.059451 12.54581)
			(xy 389.11722 12.60918) (xy 389.18059 12.666949) (xy 389.249019 12.718625) (xy 389.321925 12.763766)
			(xy 389.398685 12.801988) (xy 389.478644 12.832964) (xy 389.56112 12.856431) (xy 389.64541 12.872187)
			(xy 389.730793 12.880099) (xy 389.816543 12.880099) (xy 389.901926 12.872187) (xy 389.986216 12.856431)
			(xy 390.068692 12.832964) (xy 390.148651 12.801988) (xy 390.225411 12.763766) (xy 390.298317 12.718625)
			(xy 390.366746 12.666949) (xy 390.430116 12.60918) (xy 390.487885 12.54581) (xy 390.539561 12.477381)
			(xy 390.584702 12.404475) (xy 390.622924 12.327715) (xy 390.6539 12.247756) (xy 390.677367 12.16528)
			(xy 390.693123 12.08099) (xy 390.701035 11.995607) (xy 390.70153 11.952732) (xy 390.701117 11.916969)
			(xy 396.558757 11.916969) (xy 396.558757 12.002719) (xy 396.566669 12.088102) (xy 396.582425 12.172392)
			(xy 396.605892 12.254868) (xy 396.636868 12.334827) (xy 396.67509 12.411587) (xy 396.720231 12.484493)
			(xy 396.771907 12.552922) (xy 396.829676 12.616292) (xy 396.893046 12.674061) (xy 396.961475 12.725737)
			(xy 397.034381 12.770878) (xy 397.111141 12.8091) (xy 397.1911 12.840076) (xy 397.273576 12.863543)
			(xy 397.357866 12.879299) (xy 397.443249 12.887211) (xy 397.528999 12.887211) (xy 397.614382 12.879299)
			(xy 397.698672 12.863543) (xy 397.781148 12.840076) (xy 397.861107 12.8091) (xy 397.937867 12.770878)
			(xy 398.010773 12.725737) (xy 398.079202 12.674061) (xy 398.142572 12.616292) (xy 398.200341 12.552922)
			(xy 398.252017 12.484493) (xy 398.297158 12.411587) (xy 398.33538 12.334827) (xy 398.366356 12.254868)
			(xy 398.389823 12.172392) (xy 398.405579 12.088102) (xy 398.413491 12.002719) (xy 398.413986 11.959844)
			(xy 398.413491 11.916969) (xy 402.908757 11.916969) (xy 402.908757 12.002719) (xy 402.916669 12.088102)
			(xy 402.932425 12.172392) (xy 402.955892 12.254868) (xy 402.986868 12.334827) (xy 403.02509 12.411587)
			(xy 403.070231 12.484493) (xy 403.121907 12.552922) (xy 403.179676 12.616292) (xy 403.243046 12.674061)
			(xy 403.311475 12.725737) (xy 403.384381 12.770878) (xy 403.461141 12.8091) (xy 403.5411 12.840076)
			(xy 403.623576 12.863543) (xy 403.707866 12.879299) (xy 403.793249 12.887211) (xy 403.878999 12.887211)
			(xy 403.964382 12.879299) (xy 404.048672 12.863543) (xy 404.131148 12.840076) (xy 404.211107 12.8091)
			(xy 404.287867 12.770878) (xy 404.360773 12.725737) (xy 404.429202 12.674061) (xy 404.492572 12.616292)
			(xy 404.550341 12.552922) (xy 404.602017 12.484493) (xy 404.647158 12.411587) (xy 404.68538 12.334827)
			(xy 404.716356 12.254868) (xy 404.739823 12.172392) (xy 404.755579 12.088102) (xy 404.763491 12.002719)
			(xy 404.763986 11.959844) (xy 404.76379 11.942877) (xy 454.759301 11.942877) (xy 454.759301 12.028627)
			(xy 454.767213 12.11401) (xy 454.782969 12.1983) (xy 454.806436 12.280776) (xy 454.837412 12.360735)
			(xy 454.875634 12.437495) (xy 454.920775 12.510401) (xy 454.972451 12.57883) (xy 455.03022 12.6422)
			(xy 455.09359 12.699969) (xy 455.162019 12.751645) (xy 455.234925 12.796786) (xy 455.311685 12.835008)
			(xy 455.391644 12.865984) (xy 455.47412 12.889451) (xy 455.55841 12.905207) (xy 455.643793 12.913119)
			(xy 455.729543 12.913119) (xy 455.814926 12.905207) (xy 455.899216 12.889451) (xy 455.981692 12.865984)
			(xy 456.061651 12.835008) (xy 456.138411 12.796786) (xy 456.211317 12.751645) (xy 456.279746 12.699969)
			(xy 456.343116 12.6422) (xy 456.400885 12.57883) (xy 456.452561 12.510401) (xy 456.497702 12.437495)
			(xy 456.535924 12.360735) (xy 456.5669 12.280776) (xy 456.590367 12.1983) (xy 456.606123 12.11401)
			(xy 456.614035 12.028627) (xy 456.61453 11.985752) (xy 456.614035 11.942877) (xy 461.109301 11.942877)
			(xy 461.109301 12.028627) (xy 461.117213 12.11401) (xy 461.132969 12.1983) (xy 461.156436 12.280776)
			(xy 461.187412 12.360735) (xy 461.225634 12.437495) (xy 461.270775 12.510401) (xy 461.322451 12.57883)
			(xy 461.38022 12.6422) (xy 461.44359 12.699969) (xy 461.512019 12.751645) (xy 461.584925 12.796786)
			(xy 461.661685 12.835008) (xy 461.741644 12.865984) (xy 461.82412 12.889451) (xy 461.90841 12.905207)
			(xy 461.993793 12.913119) (xy 462.079543 12.913119) (xy 462.164926 12.905207) (xy 462.249216 12.889451)
			(xy 462.331692 12.865984) (xy 462.411651 12.835008) (xy 462.488411 12.796786) (xy 462.561317 12.751645)
			(xy 462.629746 12.699969) (xy 462.693116 12.6422) (xy 462.750885 12.57883) (xy 462.802561 12.510401)
			(xy 462.847702 12.437495) (xy 462.885924 12.360735) (xy 462.9169 12.280776) (xy 462.940367 12.1983)
			(xy 462.956123 12.11401) (xy 462.964035 12.028627) (xy 462.96453 11.985752) (xy 462.964035 11.942877)
			(xy 462.956123 11.857494) (xy 462.940367 11.773204) (xy 462.9169 11.690728) (xy 462.885924 11.610769)
			(xy 462.847702 11.534009) (xy 462.802561 11.461103) (xy 462.750885 11.392674) (xy 462.693116 11.329304)
			(xy 462.629746 11.271535) (xy 462.561317 11.219859) (xy 462.488411 11.174718) (xy 462.411651 11.136496)
			(xy 462.331692 11.10552) (xy 462.249216 11.082053) (xy 462.164926 11.066297) (xy 462.079543 11.058385)
			(xy 461.993793 11.058385) (xy 461.90841 11.066297) (xy 461.82412 11.082053) (xy 461.741644 11.10552)
			(xy 461.661685 11.136496) (xy 461.584925 11.174718) (xy 461.512019 11.219859) (xy 461.44359 11.271535)
			(xy 461.38022 11.329304) (xy 461.322451 11.392674) (xy 461.270775 11.461103) (xy 461.225634 11.534009)
			(xy 461.187412 11.610769) (xy 461.156436 11.690728) (xy 461.132969 11.773204) (xy 461.117213 11.857494)
			(xy 461.109301 11.942877) (xy 456.614035 11.942877) (xy 456.606123 11.857494) (xy 456.590367 11.773204)
			(xy 456.5669 11.690728) (xy 456.535924 11.610769) (xy 456.497702 11.534009) (xy 456.452561 11.461103)
			(xy 456.400885 11.392674) (xy 456.343116 11.329304) (xy 456.279746 11.271535) (xy 456.211317 11.219859)
			(xy 456.138411 11.174718) (xy 456.061651 11.136496) (xy 455.981692 11.10552) (xy 455.899216 11.082053)
			(xy 455.814926 11.066297) (xy 455.729543 11.058385) (xy 455.643793 11.058385) (xy 455.55841 11.066297)
			(xy 455.47412 11.082053) (xy 455.391644 11.10552) (xy 455.311685 11.136496) (xy 455.234925 11.174718)
			(xy 455.162019 11.219859) (xy 455.09359 11.271535) (xy 455.03022 11.329304) (xy 454.972451 11.392674)
			(xy 454.920775 11.461103) (xy 454.875634 11.534009) (xy 454.837412 11.610769) (xy 454.806436 11.690728)
			(xy 454.782969 11.773204) (xy 454.767213 11.857494) (xy 454.759301 11.942877) (xy 404.76379 11.942877)
			(xy 404.763491 11.916969) (xy 404.755579 11.831586) (xy 404.739823 11.747296) (xy 404.716356 11.66482)
			(xy 404.68538 11.584861) (xy 404.647158 11.508101) (xy 404.602017 11.435195) (xy 404.550341 11.366766)
			(xy 404.492572 11.303396) (xy 404.429202 11.245627) (xy 404.360773 11.193951) (xy 404.287867 11.14881)
			(xy 404.211107 11.110588) (xy 404.131148 11.079612) (xy 404.048672 11.056145) (xy 403.964382 11.040389)
			(xy 403.878999 11.032477) (xy 403.793249 11.032477) (xy 403.707866 11.040389) (xy 403.623576 11.056145)
			(xy 403.5411 11.079612) (xy 403.461141 11.110588) (xy 403.384381 11.14881) (xy 403.311475 11.193951)
			(xy 403.243046 11.245627) (xy 403.179676 11.303396) (xy 403.121907 11.366766) (xy 403.070231 11.435195)
			(xy 403.02509 11.508101) (xy 402.986868 11.584861) (xy 402.955892 11.66482) (xy 402.932425 11.747296)
			(xy 402.916669 11.831586) (xy 402.908757 11.916969) (xy 398.413491 11.916969) (xy 398.405579 11.831586)
			(xy 398.389823 11.747296) (xy 398.366356 11.66482) (xy 398.33538 11.584861) (xy 398.297158 11.508101)
			(xy 398.252017 11.435195) (xy 398.200341 11.366766) (xy 398.142572 11.303396) (xy 398.079202 11.245627)
			(xy 398.010773 11.193951) (xy 397.937867 11.14881) (xy 397.861107 11.110588) (xy 397.781148 11.079612)
			(xy 397.698672 11.056145) (xy 397.614382 11.040389) (xy 397.528999 11.032477) (xy 397.443249 11.032477)
			(xy 397.357866 11.040389) (xy 397.273576 11.056145) (xy 397.1911 11.079612) (xy 397.111141 11.110588)
			(xy 397.034381 11.14881) (xy 396.961475 11.193951) (xy 396.893046 11.245627) (xy 396.829676 11.303396)
			(xy 396.771907 11.366766) (xy 396.720231 11.435195) (xy 396.67509 11.508101) (xy 396.636868 11.584861)
			(xy 396.605892 11.66482) (xy 396.582425 11.747296) (xy 396.566669 11.831586) (xy 396.558757 11.916969)
			(xy 390.701117 11.916969) (xy 390.701035 11.909857) (xy 390.693123 11.824474) (xy 390.677367 11.740184)
			(xy 390.6539 11.657708) (xy 390.622924 11.577749) (xy 390.584702 11.500989) (xy 390.539561 11.428083)
			(xy 390.487885 11.359654) (xy 390.430116 11.296284) (xy 390.366746 11.238515) (xy 390.298317 11.186839)
			(xy 390.225411 11.141698) (xy 390.148651 11.103476) (xy 390.068692 11.0725) (xy 389.986216 11.049033)
			(xy 389.901926 11.033277) (xy 389.816543 11.025365) (xy 389.730793 11.025365) (xy 389.64541 11.033277)
			(xy 389.56112 11.049033) (xy 389.478644 11.0725) (xy 389.398685 11.103476) (xy 389.321925 11.141698)
			(xy 389.249019 11.186839) (xy 389.18059 11.238515) (xy 389.11722 11.296284) (xy 389.059451 11.359654)
			(xy 389.007775 11.428083) (xy 388.962634 11.500989) (xy 388.924412 11.577749) (xy 388.893436 11.657708)
			(xy 388.869969 11.740184) (xy 388.854213 11.824474) (xy 388.846301 11.909857) (xy 384.351035 11.909857)
			(xy 384.343123 11.824474) (xy 384.327367 11.740184) (xy 384.3039 11.657708) (xy 384.272924 11.577749)
			(xy 384.234702 11.500989) (xy 384.189561 11.428083) (xy 384.137885 11.359654) (xy 384.080116 11.296284)
			(xy 384.016746 11.238515) (xy 383.948317 11.186839) (xy 383.875411 11.141698) (xy 383.798651 11.103476)
			(xy 383.718692 11.0725) (xy 383.636216 11.049033) (xy 383.551926 11.033277) (xy 383.466543 11.025365)
			(xy 383.380793 11.025365) (xy 383.29541 11.033277) (xy 383.21112 11.049033) (xy 383.128644 11.0725)
			(xy 383.048685 11.103476) (xy 382.971925 11.141698) (xy 382.899019 11.186839) (xy 382.83059 11.238515)
			(xy 382.76722 11.296284) (xy 382.709451 11.359654) (xy 382.657775 11.428083) (xy 382.612634 11.500989)
			(xy 382.574412 11.577749) (xy 382.543436 11.657708) (xy 382.519969 11.740184) (xy 382.504213 11.824474)
			(xy 382.496301 11.909857) (xy 332.50079 11.909857) (xy 332.500491 11.883949) (xy 332.492579 11.798566)
			(xy 332.476823 11.714276) (xy 332.453356 11.6318) (xy 332.42238 11.551841) (xy 332.384158 11.475081)
			(xy 332.339017 11.402175) (xy 332.287341 11.333746) (xy 332.229572 11.270376) (xy 332.166202 11.212607)
			(xy 332.097773 11.160931) (xy 332.024867 11.11579) (xy 331.948107 11.077568) (xy 331.868148 11.046592)
			(xy 331.785672 11.023125) (xy 331.701382 11.007369) (xy 331.615999 10.999457) (xy 331.530249 10.999457)
			(xy 331.444866 11.007369) (xy 331.360576 11.023125) (xy 331.2781 11.046592) (xy 331.198141 11.077568)
			(xy 331.121381 11.11579) (xy 331.048475 11.160931) (xy 330.980046 11.212607) (xy 330.916676 11.270376)
			(xy 330.858907 11.333746) (xy 330.807231 11.402175) (xy 330.76209 11.475081) (xy 330.723868 11.551841)
			(xy 330.692892 11.6318) (xy 330.669425 11.714276) (xy 330.653669 11.798566) (xy 330.645757 11.883949)
			(xy 326.150491 11.883949) (xy 326.142579 11.798566) (xy 326.126823 11.714276) (xy 326.103356 11.6318)
			(xy 326.07238 11.551841) (xy 326.034158 11.475081) (xy 325.989017 11.402175) (xy 325.937341 11.333746)
			(xy 325.879572 11.270376) (xy 325.816202 11.212607) (xy 325.747773 11.160931) (xy 325.674867 11.11579)
			(xy 325.598107 11.077568) (xy 325.518148 11.046592) (xy 325.435672 11.023125) (xy 325.351382 11.007369)
			(xy 325.265999 10.999457) (xy 325.180249 10.999457) (xy 325.094866 11.007369) (xy 325.010576 11.023125)
			(xy 324.9281 11.046592) (xy 324.848141 11.077568) (xy 324.771381 11.11579) (xy 324.698475 11.160931)
			(xy 324.630046 11.212607) (xy 324.566676 11.270376) (xy 324.508907 11.333746) (xy 324.457231 11.402175)
			(xy 324.41209 11.475081) (xy 324.373868 11.551841) (xy 324.342892 11.6318) (xy 324.319425 11.714276)
			(xy 324.303669 11.798566) (xy 324.295757 11.883949) (xy 317.930117 11.883949) (xy 317.930035 11.876837)
			(xy 317.922123 11.791454) (xy 317.906367 11.707164) (xy 317.8829 11.624688) (xy 317.851924 11.544729)
			(xy 317.813702 11.467969) (xy 317.768561 11.395063) (xy 317.716885 11.326634) (xy 317.659116 11.263264)
			(xy 317.595746 11.205495) (xy 317.527317 11.153819) (xy 317.454411 11.108678) (xy 317.377651 11.070456)
			(xy 317.297692 11.03948) (xy 317.215216 11.016013) (xy 317.130926 11.000257) (xy 317.045543 10.992345)
			(xy 316.959793 10.992345) (xy 316.87441 11.000257) (xy 316.79012 11.016013) (xy 316.707644 11.03948)
			(xy 316.627685 11.070456) (xy 316.550925 11.108678) (xy 316.478019 11.153819) (xy 316.40959 11.205495)
			(xy 316.34622 11.263264) (xy 316.288451 11.326634) (xy 316.236775 11.395063) (xy 316.191634 11.467969)
			(xy 316.153412 11.544729) (xy 316.122436 11.624688) (xy 316.098969 11.707164) (xy 316.083213 11.791454)
			(xy 316.075301 11.876837) (xy 311.580035 11.876837) (xy 311.572123 11.791454) (xy 311.556367 11.707164)
			(xy 311.5329 11.624688) (xy 311.501924 11.544729) (xy 311.463702 11.467969) (xy 311.418561 11.395063)
			(xy 311.366885 11.326634) (xy 311.309116 11.263264) (xy 311.245746 11.205495) (xy 311.177317 11.153819)
			(xy 311.104411 11.108678) (xy 311.027651 11.070456) (xy 310.947692 11.03948) (xy 310.865216 11.016013)
			(xy 310.780926 11.000257) (xy 310.695543 10.992345) (xy 310.609793 10.992345) (xy 310.52441 11.000257)
			(xy 310.44012 11.016013) (xy 310.357644 11.03948) (xy 310.277685 11.070456) (xy 310.200925 11.108678)
			(xy 310.128019 11.153819) (xy 310.05959 11.205495) (xy 309.99622 11.263264) (xy 309.938451 11.326634)
			(xy 309.886775 11.395063) (xy 309.841634 11.467969) (xy 309.803412 11.544729) (xy 309.772436 11.624688)
			(xy 309.748969 11.707164) (xy 309.733213 11.791454) (xy 309.725301 11.876837) (xy 259.72979 11.876837)
			(xy 259.729491 11.850929) (xy 259.721579 11.765546) (xy 259.705823 11.681256) (xy 259.682356 11.59878)
			(xy 259.65138 11.518821) (xy 259.613158 11.442061) (xy 259.568017 11.369155) (xy 259.516341 11.300726)
			(xy 259.458572 11.237356) (xy 259.395202 11.179587) (xy 259.326773 11.127911) (xy 259.253867 11.08277)
			(xy 259.177107 11.044548) (xy 259.097148 11.013572) (xy 259.014672 10.990105) (xy 258.930382 10.974349)
			(xy 258.844999 10.966437) (xy 258.759249 10.966437) (xy 258.673866 10.974349) (xy 258.589576 10.990105)
			(xy 258.5071 11.013572) (xy 258.427141 11.044548) (xy 258.350381 11.08277) (xy 258.277475 11.127911)
			(xy 258.209046 11.179587) (xy 258.145676 11.237356) (xy 258.087907 11.300726) (xy 258.036231 11.369155)
			(xy 257.99109 11.442061) (xy 257.952868 11.518821) (xy 257.921892 11.59878) (xy 257.898425 11.681256)
			(xy 257.882669 11.765546) (xy 257.874757 11.850929) (xy 253.379491 11.850929) (xy 253.371579 11.765546)
			(xy 253.355823 11.681256) (xy 253.332356 11.59878) (xy 253.30138 11.518821) (xy 253.263158 11.442061)
			(xy 253.218017 11.369155) (xy 253.166341 11.300726) (xy 253.108572 11.237356) (xy 253.045202 11.179587)
			(xy 252.976773 11.127911) (xy 252.903867 11.08277) (xy 252.827107 11.044548) (xy 252.747148 11.013572)
			(xy 252.664672 10.990105) (xy 252.580382 10.974349) (xy 252.494999 10.966437) (xy 252.409249 10.966437)
			(xy 252.323866 10.974349) (xy 252.239576 10.990105) (xy 252.1571 11.013572) (xy 252.077141 11.044548)
			(xy 252.000381 11.08277) (xy 251.927475 11.127911) (xy 251.859046 11.179587) (xy 251.795676 11.237356)
			(xy 251.737907 11.300726) (xy 251.686231 11.369155) (xy 251.64109 11.442061) (xy 251.602868 11.518821)
			(xy 251.571892 11.59878) (xy 251.548425 11.681256) (xy 251.532669 11.765546) (xy 251.524757 11.850929)
			(xy 158.621984 11.850929) (xy 158.621984 9.310929) (xy 179.515757 9.310929) (xy 179.515757 9.396679)
			(xy 179.523669 9.482062) (xy 179.539425 9.566352) (xy 179.562892 9.648828) (xy 179.593868 9.728787)
			(xy 179.63209 9.805547) (xy 179.677231 9.878453) (xy 179.728907 9.946882) (xy 179.786676 10.010252)
			(xy 179.850046 10.068021) (xy 179.918475 10.119697) (xy 179.991381 10.164838) (xy 180.068141 10.20306)
			(xy 180.1481 10.234036) (xy 180.230576 10.257503) (xy 180.314866 10.273259) (xy 180.400249 10.281171)
			(xy 180.485999 10.281171) (xy 180.571382 10.273259) (xy 180.655672 10.257503) (xy 180.738148 10.234036)
			(xy 180.818107 10.20306) (xy 180.894867 10.164838) (xy 180.967773 10.119697) (xy 181.036202 10.068021)
			(xy 181.099572 10.010252) (xy 181.157341 9.946882) (xy 181.209017 9.878453) (xy 181.254158 9.805547)
			(xy 181.29238 9.728787) (xy 181.323356 9.648828) (xy 181.346823 9.566352) (xy 181.362579 9.482062)
			(xy 181.370491 9.396679) (xy 181.370986 9.353804) (xy 181.370491 9.310929) (xy 185.865757 9.310929)
			(xy 185.865757 9.396679) (xy 185.873669 9.482062) (xy 185.889425 9.566352) (xy 185.912892 9.648828)
			(xy 185.943868 9.728787) (xy 185.98209 9.805547) (xy 186.027231 9.878453) (xy 186.078907 9.946882)
			(xy 186.136676 10.010252) (xy 186.200046 10.068021) (xy 186.268475 10.119697) (xy 186.341381 10.164838)
			(xy 186.418141 10.20306) (xy 186.4981 10.234036) (xy 186.580576 10.257503) (xy 186.664866 10.273259)
			(xy 186.750249 10.281171) (xy 186.835999 10.281171) (xy 186.921382 10.273259) (xy 187.005672 10.257503)
			(xy 187.088148 10.234036) (xy 187.168107 10.20306) (xy 187.244867 10.164838) (xy 187.317773 10.119697)
			(xy 187.386202 10.068021) (xy 187.449572 10.010252) (xy 187.507341 9.946882) (xy 187.559017 9.878453)
			(xy 187.604158 9.805547) (xy 187.64238 9.728787) (xy 187.673356 9.648828) (xy 187.696823 9.566352)
			(xy 187.712579 9.482062) (xy 187.720491 9.396679) (xy 187.720986 9.353804) (xy 187.720491 9.310929)
			(xy 187.719832 9.303817) (xy 237.716301 9.303817) (xy 237.716301 9.389567) (xy 237.724213 9.47495)
			(xy 237.739969 9.55924) (xy 237.763436 9.641716) (xy 237.794412 9.721675) (xy 237.832634 9.798435)
			(xy 237.877775 9.871341) (xy 237.929451 9.93977) (xy 237.98722 10.00314) (xy 238.05059 10.060909)
			(xy 238.119019 10.112585) (xy 238.191925 10.157726) (xy 238.268685 10.195948) (xy 238.348644 10.226924)
			(xy 238.43112 10.250391) (xy 238.51541 10.266147) (xy 238.600793 10.274059) (xy 238.686543 10.274059)
			(xy 238.771926 10.266147) (xy 238.856216 10.250391) (xy 238.938692 10.226924) (xy 239.018651 10.195948)
			(xy 239.095411 10.157726) (xy 239.168317 10.112585) (xy 239.236746 10.060909) (xy 239.300116 10.00314)
			(xy 239.357885 9.93977) (xy 239.409561 9.871341) (xy 239.454702 9.798435) (xy 239.492924 9.721675)
			(xy 239.5239 9.641716) (xy 239.547367 9.55924) (xy 239.563123 9.47495) (xy 239.571035 9.389567) (xy 239.57153 9.346692)
			(xy 239.571035 9.303817) (xy 244.066301 9.303817) (xy 244.066301 9.389567) (xy 244.074213 9.47495)
			(xy 244.089969 9.55924) (xy 244.113436 9.641716) (xy 244.144412 9.721675) (xy 244.182634 9.798435)
			(xy 244.227775 9.871341) (xy 244.279451 9.93977) (xy 244.33722 10.00314) (xy 244.40059 10.060909)
			(xy 244.469019 10.112585) (xy 244.541925 10.157726) (xy 244.618685 10.195948) (xy 244.698644 10.226924)
			(xy 244.78112 10.250391) (xy 244.86541 10.266147) (xy 244.950793 10.274059) (xy 245.036543 10.274059)
			(xy 245.121926 10.266147) (xy 245.206216 10.250391) (xy 245.288692 10.226924) (xy 245.368651 10.195948)
			(xy 245.445411 10.157726) (xy 245.518317 10.112585) (xy 245.586746 10.060909) (xy 245.650116 10.00314)
			(xy 245.707885 9.93977) (xy 245.759561 9.871341) (xy 245.804702 9.798435) (xy 245.842924 9.721675)
			(xy 245.8739 9.641716) (xy 245.897367 9.55924) (xy 245.913123 9.47495) (xy 245.921035 9.389567) (xy 245.92153 9.346692)
			(xy 245.921117 9.310929) (xy 251.524757 9.310929) (xy 251.524757 9.396679) (xy 251.532669 9.482062)
			(xy 251.548425 9.566352) (xy 251.571892 9.648828) (xy 251.602868 9.728787) (xy 251.64109 9.805547)
			(xy 251.686231 9.878453) (xy 251.737907 9.946882) (xy 251.795676 10.010252) (xy 251.859046 10.068021)
			(xy 251.927475 10.119697) (xy 252.000381 10.164838) (xy 252.077141 10.20306) (xy 252.1571 10.234036)
			(xy 252.239576 10.257503) (xy 252.323866 10.273259) (xy 252.409249 10.281171) (xy 252.494999 10.281171)
			(xy 252.580382 10.273259) (xy 252.664672 10.257503) (xy 252.747148 10.234036) (xy 252.827107 10.20306)
			(xy 252.84931 10.192004) (xy 256.459736 10.192004) (xy 256.459736 11.055604) (xy 256.460222 11.082873)
			(xy 256.467984 11.136857) (xy 256.483349 11.189187) (xy 256.506006 11.238797) (xy 256.535492 11.284678)
			(xy 256.571207 11.325895) (xy 256.612424 11.36161) (xy 256.658305 11.391096) (xy 256.707915 11.413753)
			(xy 256.760245 11.429118) (xy 256.814229 11.43688) (xy 256.868767 11.43688) (xy 256.922751 11.429118)
			(xy 256.975081 11.413753) (xy 257.024691 11.391096) (xy 257.070572 11.36161) (xy 257.111789 11.325895)
			(xy 257.147504 11.284678) (xy 257.17699 11.238797) (xy 257.199647 11.189187) (xy 257.215012 11.136857)
			(xy 257.222774 11.082873) (xy 257.22326 11.055604) (xy 257.22326 10.192004) (xy 257.222774 10.164735)
			(xy 257.215012 10.110751) (xy 257.199647 10.058421) (xy 257.17699 10.008811) (xy 257.147504 9.96293)
			(xy 257.111789 9.921713) (xy 257.070572 9.885998) (xy 257.024691 9.856512) (xy 256.975081 9.833855)
			(xy 256.922751 9.81849) (xy 256.868767 9.810728) (xy 256.814229 9.810728) (xy 256.760245 9.81849)
			(xy 256.707915 9.833855) (xy 256.658305 9.856512) (xy 256.612424 9.885998) (xy 256.571207 9.921713)
			(xy 256.535492 9.96293) (xy 256.506006 10.008811) (xy 256.483349 10.058421) (xy 256.467984 10.110751)
			(xy 256.460222 10.164735) (xy 256.459736 10.192004) (xy 252.84931 10.192004) (xy 252.903867 10.164838)
			(xy 252.976773 10.119697) (xy 253.045202 10.068021) (xy 253.108572 10.010252) (xy 253.166341 9.946882)
			(xy 253.218017 9.878453) (xy 253.263158 9.805547) (xy 253.30138 9.728787) (xy 253.332356 9.648828)
			(xy 253.355823 9.566352) (xy 253.371579 9.482062) (xy 253.379491 9.396679) (xy 253.379986 9.353804)
			(xy 253.379491 9.310929) (xy 257.874757 9.310929) (xy 257.874757 9.396679) (xy 257.882669 9.482062)
			(xy 257.898425 9.566352) (xy 257.921892 9.648828) (xy 257.952868 9.728787) (xy 257.99109 9.805547)
			(xy 258.036231 9.878453) (xy 258.087907 9.946882) (xy 258.145676 10.010252) (xy 258.209046 10.068021)
			(xy 258.277475 10.119697) (xy 258.350381 10.164838) (xy 258.427141 10.20306) (xy 258.5071 10.234036)
			(xy 258.589576 10.257503) (xy 258.673866 10.273259) (xy 258.759249 10.281171) (xy 258.844999 10.281171)
			(xy 258.930382 10.273259) (xy 259.014672 10.257503) (xy 259.097148 10.234036) (xy 259.177107 10.20306)
			(xy 259.253867 10.164838) (xy 259.326773 10.119697) (xy 259.395202 10.068021) (xy 259.458572 10.010252)
			(xy 259.516341 9.946882) (xy 259.568017 9.878453) (xy 259.613158 9.805547) (xy 259.65138 9.728787)
			(xy 259.682356 9.648828) (xy 259.705823 9.566352) (xy 259.721579 9.482062) (xy 259.729491 9.396679)
			(xy 259.729986 9.353804) (xy 259.72979 9.336837) (xy 309.725301 9.336837) (xy 309.725301 9.422587)
			(xy 309.733213 9.50797) (xy 309.748969 9.59226) (xy 309.772436 9.674736) (xy 309.803412 9.754695)
			(xy 309.841634 9.831455) (xy 309.886775 9.904361) (xy 309.938451 9.97279) (xy 309.99622 10.03616)
			(xy 310.05959 10.093929) (xy 310.128019 10.145605) (xy 310.200925 10.190746) (xy 310.277685 10.228968)
			(xy 310.357644 10.259944) (xy 310.44012 10.283411) (xy 310.52441 10.299167) (xy 310.609793 10.307079)
			(xy 310.695543 10.307079) (xy 310.780926 10.299167) (xy 310.865216 10.283411) (xy 310.947692 10.259944)
			(xy 311.027651 10.228968) (xy 311.049854 10.217912) (xy 312.231532 10.217912) (xy 312.231532 11.081512)
			(xy 312.232018 11.108781) (xy 312.23978 11.162765) (xy 312.255145 11.215095) (xy 312.277802 11.264705)
			(xy 312.307288 11.310586) (xy 312.343003 11.351803) (xy 312.38422 11.387518) (xy 312.430101 11.417004)
			(xy 312.479711 11.439661) (xy 312.532041 11.455026) (xy 312.586025 11.462788) (xy 312.640563 11.462788)
			(xy 312.694547 11.455026) (xy 312.746877 11.439661) (xy 312.796487 11.417004) (xy 312.842368 11.387518)
			(xy 312.883585 11.351803) (xy 312.9193 11.310586) (xy 312.948786 11.264705) (xy 312.971443 11.215095)
			(xy 312.986808 11.162765) (xy 312.99457 11.108781) (xy 312.995056 11.081512) (xy 312.995056 10.217912)
			(xy 312.99457 10.190643) (xy 312.986808 10.136659) (xy 312.971443 10.084329) (xy 312.948786 10.034719)
			(xy 312.9193 9.988838) (xy 312.883585 9.947621) (xy 312.842368 9.911906) (xy 312.796487 9.88242)
			(xy 312.746877 9.859763) (xy 312.694547 9.844398) (xy 312.640563 9.836636) (xy 312.586025 9.836636)
			(xy 312.532041 9.844398) (xy 312.479711 9.859763) (xy 312.430101 9.88242) (xy 312.38422 9.911906)
			(xy 312.343003 9.947621) (xy 312.307288 9.988838) (xy 312.277802 10.034719) (xy 312.255145 10.084329)
			(xy 312.23978 10.136659) (xy 312.232018 10.190643) (xy 312.231532 10.217912) (xy 311.049854 10.217912)
			(xy 311.104411 10.190746) (xy 311.177317 10.145605) (xy 311.245746 10.093929) (xy 311.309116 10.03616)
			(xy 311.366885 9.97279) (xy 311.418561 9.904361) (xy 311.463702 9.831455) (xy 311.501924 9.754695)
			(xy 311.5329 9.674736) (xy 311.556367 9.59226) (xy 311.572123 9.50797) (xy 311.580035 9.422587) (xy 311.58053 9.379712)
			(xy 311.580035 9.336837) (xy 316.075301 9.336837) (xy 316.075301 9.422587) (xy 316.083213 9.50797)
			(xy 316.098969 9.59226) (xy 316.122436 9.674736) (xy 316.153412 9.754695) (xy 316.191634 9.831455)
			(xy 316.236775 9.904361) (xy 316.288451 9.97279) (xy 316.34622 10.03616) (xy 316.40959 10.093929)
			(xy 316.478019 10.145605) (xy 316.550925 10.190746) (xy 316.627685 10.228968) (xy 316.707644 10.259944)
			(xy 316.79012 10.283411) (xy 316.87441 10.299167) (xy 316.959793 10.307079) (xy 317.045543 10.307079)
			(xy 317.130926 10.299167) (xy 317.215216 10.283411) (xy 317.297692 10.259944) (xy 317.377651 10.228968)
			(xy 317.454411 10.190746) (xy 317.527317 10.145605) (xy 317.595746 10.093929) (xy 317.659116 10.03616)
			(xy 317.716885 9.97279) (xy 317.768561 9.904361) (xy 317.813702 9.831455) (xy 317.851924 9.754695)
			(xy 317.8829 9.674736) (xy 317.906367 9.59226) (xy 317.922123 9.50797) (xy 317.930035 9.422587) (xy 317.93053 9.379712)
			(xy 317.930117 9.343949) (xy 324.295757 9.343949) (xy 324.295757 9.429699) (xy 324.303669 9.515082)
			(xy 324.319425 9.599372) (xy 324.342892 9.681848) (xy 324.373868 9.761807) (xy 324.41209 9.838567)
			(xy 324.457231 9.911473) (xy 324.508907 9.979902) (xy 324.566676 10.043272) (xy 324.630046 10.101041)
			(xy 324.698475 10.152717) (xy 324.771381 10.197858) (xy 324.848141 10.23608) (xy 324.9281 10.267056)
			(xy 325.010576 10.290523) (xy 325.094866 10.306279) (xy 325.180249 10.314191) (xy 325.265999 10.314191)
			(xy 325.351382 10.306279) (xy 325.435672 10.290523) (xy 325.518148 10.267056) (xy 325.598107 10.23608)
			(xy 325.62031 10.225024) (xy 329.230736 10.225024) (xy 329.230736 11.088624) (xy 329.231222 11.115893)
			(xy 329.238984 11.169877) (xy 329.254349 11.222207) (xy 329.277006 11.271817) (xy 329.306492 11.317698)
			(xy 329.342207 11.358915) (xy 329.383424 11.39463) (xy 329.429305 11.424116) (xy 329.478915 11.446773)
			(xy 329.531245 11.462138) (xy 329.585229 11.4699) (xy 329.639767 11.4699) (xy 329.693751 11.462138)
			(xy 329.746081 11.446773) (xy 329.795691 11.424116) (xy 329.841572 11.39463) (xy 329.882789 11.358915)
			(xy 329.918504 11.317698) (xy 329.94799 11.271817) (xy 329.970647 11.222207) (xy 329.986012 11.169877)
			(xy 329.993774 11.115893) (xy 329.99426 11.088624) (xy 329.99426 10.225024) (xy 329.993774 10.197755)
			(xy 329.986012 10.143771) (xy 329.970647 10.091441) (xy 329.94799 10.041831) (xy 329.918504 9.99595)
			(xy 329.882789 9.954733) (xy 329.841572 9.919018) (xy 329.795691 9.889532) (xy 329.746081 9.866875)
			(xy 329.693751 9.85151) (xy 329.639767 9.843748) (xy 329.585229 9.843748) (xy 329.531245 9.85151)
			(xy 329.478915 9.866875) (xy 329.429305 9.889532) (xy 329.383424 9.919018) (xy 329.342207 9.954733)
			(xy 329.306492 9.99595) (xy 329.277006 10.041831) (xy 329.254349 10.091441) (xy 329.238984 10.143771)
			(xy 329.231222 10.197755) (xy 329.230736 10.225024) (xy 325.62031 10.225024) (xy 325.674867 10.197858)
			(xy 325.747773 10.152717) (xy 325.816202 10.101041) (xy 325.879572 10.043272) (xy 325.937341 9.979902)
			(xy 325.989017 9.911473) (xy 326.034158 9.838567) (xy 326.07238 9.761807) (xy 326.103356 9.681848)
			(xy 326.126823 9.599372) (xy 326.142579 9.515082) (xy 326.150491 9.429699) (xy 326.150986 9.386824)
			(xy 326.150491 9.343949) (xy 330.645757 9.343949) (xy 330.645757 9.429699) (xy 330.653669 9.515082)
			(xy 330.669425 9.599372) (xy 330.692892 9.681848) (xy 330.723868 9.761807) (xy 330.76209 9.838567)
			(xy 330.807231 9.911473) (xy 330.858907 9.979902) (xy 330.916676 10.043272) (xy 330.980046 10.101041)
			(xy 331.048475 10.152717) (xy 331.121381 10.197858) (xy 331.198141 10.23608) (xy 331.2781 10.267056)
			(xy 331.360576 10.290523) (xy 331.444866 10.306279) (xy 331.530249 10.314191) (xy 331.615999 10.314191)
			(xy 331.701382 10.306279) (xy 331.785672 10.290523) (xy 331.868148 10.267056) (xy 331.948107 10.23608)
			(xy 332.024867 10.197858) (xy 332.097773 10.152717) (xy 332.166202 10.101041) (xy 332.229572 10.043272)
			(xy 332.287341 9.979902) (xy 332.339017 9.911473) (xy 332.384158 9.838567) (xy 332.42238 9.761807)
			(xy 332.453356 9.681848) (xy 332.476823 9.599372) (xy 332.492579 9.515082) (xy 332.500491 9.429699)
			(xy 332.500986 9.386824) (xy 332.50079 9.369857) (xy 382.496301 9.369857) (xy 382.496301 9.455607)
			(xy 382.504213 9.54099) (xy 382.519969 9.62528) (xy 382.543436 9.707756) (xy 382.574412 9.787715)
			(xy 382.612634 9.864475) (xy 382.657775 9.937381) (xy 382.709451 10.00581) (xy 382.76722 10.06918)
			(xy 382.83059 10.126949) (xy 382.899019 10.178625) (xy 382.971925 10.223766) (xy 383.048685 10.261988)
			(xy 383.128644 10.292964) (xy 383.21112 10.316431) (xy 383.29541 10.332187) (xy 383.380793 10.340099)
			(xy 383.466543 10.340099) (xy 383.551926 10.332187) (xy 383.636216 10.316431) (xy 383.718692 10.292964)
			(xy 383.798651 10.261988) (xy 383.820854 10.250932) (xy 385.002532 10.250932) (xy 385.002532 11.114532)
			(xy 385.003018 11.141801) (xy 385.01078 11.195785) (xy 385.026145 11.248115) (xy 385.048802 11.297725)
			(xy 385.078288 11.343606) (xy 385.114003 11.384823) (xy 385.15522 11.420538) (xy 385.201101 11.450024)
			(xy 385.250711 11.472681) (xy 385.303041 11.488046) (xy 385.357025 11.495808) (xy 385.411563 11.495808)
			(xy 385.465547 11.488046) (xy 385.517877 11.472681) (xy 385.567487 11.450024) (xy 385.613368 11.420538)
			(xy 385.654585 11.384823) (xy 385.6903 11.343606) (xy 385.719786 11.297725) (xy 385.742443 11.248115)
			(xy 385.757808 11.195785) (xy 385.76557 11.141801) (xy 385.766056 11.114532) (xy 385.766056 10.250932)
			(xy 385.76557 10.223663) (xy 385.757808 10.169679) (xy 385.742443 10.117349) (xy 385.719786 10.067739)
			(xy 385.6903 10.021858) (xy 385.654585 9.980641) (xy 385.613368 9.944926) (xy 385.567487 9.91544)
			(xy 385.517877 9.892783) (xy 385.465547 9.877418) (xy 385.411563 9.869656) (xy 385.357025 9.869656)
			(xy 385.303041 9.877418) (xy 385.250711 9.892783) (xy 385.201101 9.91544) (xy 385.15522 9.944926)
			(xy 385.114003 9.980641) (xy 385.078288 10.021858) (xy 385.048802 10.067739) (xy 385.026145 10.117349)
			(xy 385.01078 10.169679) (xy 385.003018 10.223663) (xy 385.002532 10.250932) (xy 383.820854 10.250932)
			(xy 383.875411 10.223766) (xy 383.948317 10.178625) (xy 384.016746 10.126949) (xy 384.080116 10.06918)
			(xy 384.137885 10.00581) (xy 384.189561 9.937381) (xy 384.234702 9.864475) (xy 384.272924 9.787715)
			(xy 384.3039 9.707756) (xy 384.327367 9.62528) (xy 384.343123 9.54099) (xy 384.351035 9.455607) (xy 384.35153 9.412732)
			(xy 384.351035 9.369857) (xy 388.846301 9.369857) (xy 388.846301 9.455607) (xy 388.854213 9.54099)
			(xy 388.869969 9.62528) (xy 388.893436 9.707756) (xy 388.924412 9.787715) (xy 388.962634 9.864475)
			(xy 389.007775 9.937381) (xy 389.059451 10.00581) (xy 389.11722 10.06918) (xy 389.18059 10.126949)
			(xy 389.249019 10.178625) (xy 389.321925 10.223766) (xy 389.398685 10.261988) (xy 389.478644 10.292964)
			(xy 389.56112 10.316431) (xy 389.64541 10.332187) (xy 389.730793 10.340099) (xy 389.816543 10.340099)
			(xy 389.901926 10.332187) (xy 389.986216 10.316431) (xy 390.068692 10.292964) (xy 390.148651 10.261988)
			(xy 390.225411 10.223766) (xy 390.298317 10.178625) (xy 390.366746 10.126949) (xy 390.430116 10.06918)
			(xy 390.487885 10.00581) (xy 390.539561 9.937381) (xy 390.584702 9.864475) (xy 390.622924 9.787715)
			(xy 390.6539 9.707756) (xy 390.677367 9.62528) (xy 390.693123 9.54099) (xy 390.701035 9.455607) (xy 390.70153 9.412732)
			(xy 390.701117 9.376969) (xy 396.558757 9.376969) (xy 396.558757 9.462719) (xy 396.566669 9.548102)
			(xy 396.582425 9.632392) (xy 396.605892 9.714868) (xy 396.636868 9.794827) (xy 396.67509 9.871587)
			(xy 396.720231 9.944493) (xy 396.771907 10.012922) (xy 396.829676 10.076292) (xy 396.893046 10.134061)
			(xy 396.961475 10.185737) (xy 397.034381 10.230878) (xy 397.111141 10.2691) (xy 397.1911 10.300076)
			(xy 397.273576 10.323543) (xy 397.357866 10.339299) (xy 397.443249 10.347211) (xy 397.528999 10.347211)
			(xy 397.614382 10.339299) (xy 397.698672 10.323543) (xy 397.781148 10.300076) (xy 397.861107 10.2691)
			(xy 397.88331 10.258044) (xy 401.493736 10.258044) (xy 401.493736 11.121644) (xy 401.494222 11.148913)
			(xy 401.501984 11.202897) (xy 401.517349 11.255227) (xy 401.540006 11.304837) (xy 401.569492 11.350718)
			(xy 401.605207 11.391935) (xy 401.646424 11.42765) (xy 401.692305 11.457136) (xy 401.741915 11.479793)
			(xy 401.794245 11.495158) (xy 401.848229 11.50292) (xy 401.902767 11.50292) (xy 401.956751 11.495158)
			(xy 402.009081 11.479793) (xy 402.058691 11.457136) (xy 402.104572 11.42765) (xy 402.145789 11.391935)
			(xy 402.181504 11.350718) (xy 402.21099 11.304837) (xy 402.233647 11.255227) (xy 402.249012 11.202897)
			(xy 402.256774 11.148913) (xy 402.25726 11.121644) (xy 402.25726 10.258044) (xy 402.256774 10.230775)
			(xy 402.249012 10.176791) (xy 402.233647 10.124461) (xy 402.21099 10.074851) (xy 402.181504 10.02897)
			(xy 402.145789 9.987753) (xy 402.104572 9.952038) (xy 402.058691 9.922552) (xy 402.009081 9.899895)
			(xy 401.956751 9.88453) (xy 401.902767 9.876768) (xy 401.848229 9.876768) (xy 401.794245 9.88453)
			(xy 401.741915 9.899895) (xy 401.692305 9.922552) (xy 401.646424 9.952038) (xy 401.605207 9.987753)
			(xy 401.569492 10.02897) (xy 401.540006 10.074851) (xy 401.517349 10.124461) (xy 401.501984 10.176791)
			(xy 401.494222 10.230775) (xy 401.493736 10.258044) (xy 397.88331 10.258044) (xy 397.937867 10.230878)
			(xy 398.010773 10.185737) (xy 398.079202 10.134061) (xy 398.142572 10.076292) (xy 398.200341 10.012922)
			(xy 398.252017 9.944493) (xy 398.297158 9.871587) (xy 398.33538 9.794827) (xy 398.366356 9.714868)
			(xy 398.389823 9.632392) (xy 398.405579 9.548102) (xy 398.413491 9.462719) (xy 398.413986 9.419844)
			(xy 398.413491 9.376969) (xy 402.908757 9.376969) (xy 402.908757 9.462719) (xy 402.916669 9.548102)
			(xy 402.932425 9.632392) (xy 402.955892 9.714868) (xy 402.986868 9.794827) (xy 403.02509 9.871587)
			(xy 403.070231 9.944493) (xy 403.121907 10.012922) (xy 403.179676 10.076292) (xy 403.243046 10.134061)
			(xy 403.311475 10.185737) (xy 403.384381 10.230878) (xy 403.461141 10.2691) (xy 403.5411 10.300076)
			(xy 403.623576 10.323543) (xy 403.707866 10.339299) (xy 403.793249 10.347211) (xy 403.878999 10.347211)
			(xy 403.964382 10.339299) (xy 404.048672 10.323543) (xy 404.131148 10.300076) (xy 404.211107 10.2691)
			(xy 404.287867 10.230878) (xy 404.360773 10.185737) (xy 404.429202 10.134061) (xy 404.492572 10.076292)
			(xy 404.550341 10.012922) (xy 404.602017 9.944493) (xy 404.647158 9.871587) (xy 404.68538 9.794827)
			(xy 404.716356 9.714868) (xy 404.739823 9.632392) (xy 404.755579 9.548102) (xy 404.763491 9.462719)
			(xy 404.763986 9.419844) (xy 404.76379 9.402877) (xy 454.759301 9.402877) (xy 454.759301 9.488627)
			(xy 454.767213 9.57401) (xy 454.782969 9.6583) (xy 454.806436 9.740776) (xy 454.837412 9.820735)
			(xy 454.875634 9.897495) (xy 454.920775 9.970401) (xy 454.972451 10.03883) (xy 455.03022 10.1022)
			(xy 455.09359 10.159969) (xy 455.162019 10.211645) (xy 455.234925 10.256786) (xy 455.311685 10.295008)
			(xy 455.391644 10.325984) (xy 455.47412 10.349451) (xy 455.55841 10.365207) (xy 455.643793 10.373119)
			(xy 455.729543 10.373119) (xy 455.814926 10.365207) (xy 455.899216 10.349451) (xy 455.981692 10.325984)
			(xy 456.061651 10.295008) (xy 456.083854 10.283952) (xy 457.265532 10.283952) (xy 457.265532 11.147552)
			(xy 457.266018 11.174821) (xy 457.27378 11.228805) (xy 457.289145 11.281135) (xy 457.311802 11.330745)
			(xy 457.341288 11.376626) (xy 457.377003 11.417843) (xy 457.41822 11.453558) (xy 457.464101 11.483044)
			(xy 457.513711 11.505701) (xy 457.566041 11.521066) (xy 457.620025 11.528828) (xy 457.674563 11.528828)
			(xy 457.728547 11.521066) (xy 457.780877 11.505701) (xy 457.830487 11.483044) (xy 457.876368 11.453558)
			(xy 457.917585 11.417843) (xy 457.9533 11.376626) (xy 457.982786 11.330745) (xy 458.005443 11.281135)
			(xy 458.020808 11.228805) (xy 458.02857 11.174821) (xy 458.029056 11.147552) (xy 458.029056 10.283952)
			(xy 458.02857 10.256683) (xy 458.020808 10.202699) (xy 458.005443 10.150369) (xy 457.982786 10.100759)
			(xy 457.9533 10.054878) (xy 457.917585 10.013661) (xy 457.876368 9.977946) (xy 457.830487 9.94846)
			(xy 457.780877 9.925803) (xy 457.728547 9.910438) (xy 457.674563 9.902676) (xy 457.620025 9.902676)
			(xy 457.566041 9.910438) (xy 457.513711 9.925803) (xy 457.464101 9.94846) (xy 457.41822 9.977946)
			(xy 457.377003 10.013661) (xy 457.341288 10.054878) (xy 457.311802 10.100759) (xy 457.289145 10.150369)
			(xy 457.27378 10.202699) (xy 457.266018 10.256683) (xy 457.265532 10.283952) (xy 456.083854 10.283952)
			(xy 456.138411 10.256786) (xy 456.211317 10.211645) (xy 456.279746 10.159969) (xy 456.343116 10.1022)
			(xy 456.400885 10.03883) (xy 456.452561 9.970401) (xy 456.497702 9.897495) (xy 456.535924 9.820735)
			(xy 456.5669 9.740776) (xy 456.590367 9.6583) (xy 456.606123 9.57401) (xy 456.614035 9.488627) (xy 456.61453 9.445752)
			(xy 456.614035 9.402877) (xy 461.109301 9.402877) (xy 461.109301 9.488627) (xy 461.117213 9.57401)
			(xy 461.132969 9.6583) (xy 461.156436 9.740776) (xy 461.187412 9.820735) (xy 461.225634 9.897495)
			(xy 461.270775 9.970401) (xy 461.322451 10.03883) (xy 461.38022 10.1022) (xy 461.44359 10.159969)
			(xy 461.512019 10.211645) (xy 461.584925 10.256786) (xy 461.661685 10.295008) (xy 461.741644 10.325984)
			(xy 461.82412 10.349451) (xy 461.90841 10.365207) (xy 461.993793 10.373119) (xy 462.079543 10.373119)
			(xy 462.164926 10.365207) (xy 462.249216 10.349451) (xy 462.331692 10.325984) (xy 462.411651 10.295008)
			(xy 462.488411 10.256786) (xy 462.561317 10.211645) (xy 462.629746 10.159969) (xy 462.693116 10.1022)
			(xy 462.750885 10.03883) (xy 462.802561 9.970401) (xy 462.847702 9.897495) (xy 462.885924 9.820735)
			(xy 462.9169 9.740776) (xy 462.940367 9.6583) (xy 462.956123 9.57401) (xy 462.964035 9.488627) (xy 462.96453 9.445752)
			(xy 462.964035 9.402877) (xy 462.956123 9.317494) (xy 462.940367 9.233204) (xy 462.9169 9.150728)
			(xy 462.885924 9.070769) (xy 462.847702 8.994009) (xy 462.802561 8.921103) (xy 462.750885 8.852674)
			(xy 462.693116 8.789304) (xy 462.629746 8.731535) (xy 462.561317 8.679859) (xy 462.488411 8.634718)
			(xy 462.411651 8.596496) (xy 462.331692 8.56552) (xy 462.249216 8.542053) (xy 462.164926 8.526297)
			(xy 462.079543 8.518385) (xy 461.993793 8.518385) (xy 461.90841 8.526297) (xy 461.82412 8.542053)
			(xy 461.741644 8.56552) (xy 461.661685 8.596496) (xy 461.584925 8.634718) (xy 461.512019 8.679859)
			(xy 461.44359 8.731535) (xy 461.38022 8.789304) (xy 461.322451 8.852674) (xy 461.270775 8.921103)
			(xy 461.225634 8.994009) (xy 461.187412 9.070769) (xy 461.156436 9.150728) (xy 461.132969 9.233204)
			(xy 461.117213 9.317494) (xy 461.109301 9.402877) (xy 456.614035 9.402877) (xy 456.606123 9.317494)
			(xy 456.590367 9.233204) (xy 456.5669 9.150728) (xy 456.535924 9.070769) (xy 456.497702 8.994009)
			(xy 456.452561 8.921103) (xy 456.400885 8.852674) (xy 456.343116 8.789304) (xy 456.279746 8.731535)
			(xy 456.211317 8.679859) (xy 456.138411 8.634718) (xy 456.061651 8.596496) (xy 455.981692 8.56552)
			(xy 455.899216 8.542053) (xy 455.814926 8.526297) (xy 455.729543 8.518385) (xy 455.643793 8.518385)
			(xy 455.55841 8.526297) (xy 455.47412 8.542053) (xy 455.391644 8.56552) (xy 455.311685 8.596496)
			(xy 455.234925 8.634718) (xy 455.162019 8.679859) (xy 455.09359 8.731535) (xy 455.03022 8.789304)
			(xy 454.972451 8.852674) (xy 454.920775 8.921103) (xy 454.875634 8.994009) (xy 454.837412 9.070769)
			(xy 454.806436 9.150728) (xy 454.782969 9.233204) (xy 454.767213 9.317494) (xy 454.759301 9.402877)
			(xy 404.76379 9.402877) (xy 404.763491 9.376969) (xy 404.755579 9.291586) (xy 404.739823 9.207296)
			(xy 404.716356 9.12482) (xy 404.68538 9.044861) (xy 404.647158 8.968101) (xy 404.602017 8.895195)
			(xy 404.550341 8.826766) (xy 404.492572 8.763396) (xy 404.429202 8.705627) (xy 404.360773 8.653951)
			(xy 404.287867 8.60881) (xy 404.211107 8.570588) (xy 404.131148 8.539612) (xy 404.048672 8.516145)
			(xy 403.964382 8.500389) (xy 403.878999 8.492477) (xy 403.793249 8.492477) (xy 403.707866 8.500389)
			(xy 403.623576 8.516145) (xy 403.5411 8.539612) (xy 403.461141 8.570588) (xy 403.384381 8.60881)
			(xy 403.311475 8.653951) (xy 403.243046 8.705627) (xy 403.179676 8.763396) (xy 403.121907 8.826766)
			(xy 403.070231 8.895195) (xy 403.02509 8.968101) (xy 402.986868 9.044861) (xy 402.955892 9.12482)
			(xy 402.932425 9.207296) (xy 402.916669 9.291586) (xy 402.908757 9.376969) (xy 398.413491 9.376969)
			(xy 398.405579 9.291586) (xy 398.389823 9.207296) (xy 398.366356 9.12482) (xy 398.33538 9.044861)
			(xy 398.297158 8.968101) (xy 398.252017 8.895195) (xy 398.200341 8.826766) (xy 398.142572 8.763396)
			(xy 398.079202 8.705627) (xy 398.010773 8.653951) (xy 397.937867 8.60881) (xy 397.861107 8.570588)
			(xy 397.781148 8.539612) (xy 397.698672 8.516145) (xy 397.614382 8.500389) (xy 397.528999 8.492477)
			(xy 397.443249 8.492477) (xy 397.357866 8.500389) (xy 397.273576 8.516145) (xy 397.1911 8.539612)
			(xy 397.111141 8.570588) (xy 397.034381 8.60881) (xy 396.961475 8.653951) (xy 396.893046 8.705627)
			(xy 396.829676 8.763396) (xy 396.771907 8.826766) (xy 396.720231 8.895195) (xy 396.67509 8.968101)
			(xy 396.636868 9.044861) (xy 396.605892 9.12482) (xy 396.582425 9.207296) (xy 396.566669 9.291586)
			(xy 396.558757 9.376969) (xy 390.701117 9.376969) (xy 390.701035 9.369857) (xy 390.693123 9.284474)
			(xy 390.677367 9.200184) (xy 390.6539 9.117708) (xy 390.622924 9.037749) (xy 390.584702 8.960989)
			(xy 390.539561 8.888083) (xy 390.487885 8.819654) (xy 390.430116 8.756284) (xy 390.366746 8.698515)
			(xy 390.298317 8.646839) (xy 390.225411 8.601698) (xy 390.148651 8.563476) (xy 390.068692 8.5325)
			(xy 389.986216 8.509033) (xy 389.901926 8.493277) (xy 389.816543 8.485365) (xy 389.730793 8.485365)
			(xy 389.64541 8.493277) (xy 389.56112 8.509033) (xy 389.478644 8.5325) (xy 389.398685 8.563476) (xy 389.321925 8.601698)
			(xy 389.249019 8.646839) (xy 389.18059 8.698515) (xy 389.11722 8.756284) (xy 389.059451 8.819654)
			(xy 389.007775 8.888083) (xy 388.962634 8.960989) (xy 388.924412 9.037749) (xy 388.893436 9.117708)
			(xy 388.869969 9.200184) (xy 388.854213 9.284474) (xy 388.846301 9.369857) (xy 384.351035 9.369857)
			(xy 384.343123 9.284474) (xy 384.327367 9.200184) (xy 384.3039 9.117708) (xy 384.272924 9.037749)
			(xy 384.234702 8.960989) (xy 384.189561 8.888083) (xy 384.137885 8.819654) (xy 384.080116 8.756284)
			(xy 384.016746 8.698515) (xy 383.948317 8.646839) (xy 383.875411 8.601698) (xy 383.798651 8.563476)
			(xy 383.718692 8.5325) (xy 383.636216 8.509033) (xy 383.551926 8.493277) (xy 383.466543 8.485365)
			(xy 383.380793 8.485365) (xy 383.29541 8.493277) (xy 383.21112 8.509033) (xy 383.128644 8.5325) (xy 383.048685 8.563476)
			(xy 382.971925 8.601698) (xy 382.899019 8.646839) (xy 382.83059 8.698515) (xy 382.76722 8.756284)
			(xy 382.709451 8.819654) (xy 382.657775 8.888083) (xy 382.612634 8.960989) (xy 382.574412 9.037749)
			(xy 382.543436 9.117708) (xy 382.519969 9.200184) (xy 382.504213 9.284474) (xy 382.496301 9.369857)
			(xy 332.50079 9.369857) (xy 332.500491 9.343949) (xy 332.492579 9.258566) (xy 332.476823 9.174276)
			(xy 332.453356 9.0918) (xy 332.42238 9.011841) (xy 332.384158 8.935081) (xy 332.339017 8.862175)
			(xy 332.287341 8.793746) (xy 332.229572 8.730376) (xy 332.166202 8.672607) (xy 332.097773 8.620931)
			(xy 332.024867 8.57579) (xy 331.948107 8.537568) (xy 331.868148 8.506592) (xy 331.785672 8.483125)
			(xy 331.701382 8.467369) (xy 331.615999 8.459457) (xy 331.530249 8.459457) (xy 331.444866 8.467369)
			(xy 331.360576 8.483125) (xy 331.2781 8.506592) (xy 331.198141 8.537568) (xy 331.121381 8.57579)
			(xy 331.048475 8.620931) (xy 330.980046 8.672607) (xy 330.916676 8.730376) (xy 330.858907 8.793746)
			(xy 330.807231 8.862175) (xy 330.76209 8.935081) (xy 330.723868 9.011841) (xy 330.692892 9.0918)
			(xy 330.669425 9.174276) (xy 330.653669 9.258566) (xy 330.645757 9.343949) (xy 326.150491 9.343949)
			(xy 326.142579 9.258566) (xy 326.126823 9.174276) (xy 326.103356 9.0918) (xy 326.07238 9.011841)
			(xy 326.034158 8.935081) (xy 325.989017 8.862175) (xy 325.937341 8.793746) (xy 325.879572 8.730376)
			(xy 325.816202 8.672607) (xy 325.747773 8.620931) (xy 325.674867 8.57579) (xy 325.598107 8.537568)
			(xy 325.518148 8.506592) (xy 325.435672 8.483125) (xy 325.351382 8.467369) (xy 325.265999 8.459457)
			(xy 325.180249 8.459457) (xy 325.094866 8.467369) (xy 325.010576 8.483125) (xy 324.9281 8.506592)
			(xy 324.848141 8.537568) (xy 324.771381 8.57579) (xy 324.698475 8.620931) (xy 324.630046 8.672607)
			(xy 324.566676 8.730376) (xy 324.508907 8.793746) (xy 324.457231 8.862175) (xy 324.41209 8.935081)
			(xy 324.373868 9.011841) (xy 324.342892 9.0918) (xy 324.319425 9.174276) (xy 324.303669 9.258566)
			(xy 324.295757 9.343949) (xy 317.930117 9.343949) (xy 317.930035 9.336837) (xy 317.922123 9.251454)
			(xy 317.906367 9.167164) (xy 317.8829 9.084688) (xy 317.851924 9.004729) (xy 317.813702 8.927969)
			(xy 317.768561 8.855063) (xy 317.716885 8.786634) (xy 317.659116 8.723264) (xy 317.595746 8.665495)
			(xy 317.527317 8.613819) (xy 317.454411 8.568678) (xy 317.377651 8.530456) (xy 317.297692 8.49948)
			(xy 317.215216 8.476013) (xy 317.130926 8.460257) (xy 317.045543 8.452345) (xy 316.959793 8.452345)
			(xy 316.87441 8.460257) (xy 316.79012 8.476013) (xy 316.707644 8.49948) (xy 316.627685 8.530456)
			(xy 316.550925 8.568678) (xy 316.478019 8.613819) (xy 316.40959 8.665495) (xy 316.34622 8.723264)
			(xy 316.288451 8.786634) (xy 316.236775 8.855063) (xy 316.191634 8.927969) (xy 316.153412 9.004729)
			(xy 316.122436 9.084688) (xy 316.098969 9.167164) (xy 316.083213 9.251454) (xy 316.075301 9.336837)
			(xy 311.580035 9.336837) (xy 311.572123 9.251454) (xy 311.556367 9.167164) (xy 311.5329 9.084688)
			(xy 311.501924 9.004729) (xy 311.463702 8.927969) (xy 311.418561 8.855063) (xy 311.366885 8.786634)
			(xy 311.309116 8.723264) (xy 311.245746 8.665495) (xy 311.177317 8.613819) (xy 311.104411 8.568678)
			(xy 311.027651 8.530456) (xy 310.947692 8.49948) (xy 310.865216 8.476013) (xy 310.780926 8.460257)
			(xy 310.695543 8.452345) (xy 310.609793 8.452345) (xy 310.52441 8.460257) (xy 310.44012 8.476013)
			(xy 310.357644 8.49948) (xy 310.277685 8.530456) (xy 310.200925 8.568678) (xy 310.128019 8.613819)
			(xy 310.05959 8.665495) (xy 309.99622 8.723264) (xy 309.938451 8.786634) (xy 309.886775 8.855063)
			(xy 309.841634 8.927969) (xy 309.803412 9.004729) (xy 309.772436 9.084688) (xy 309.748969 9.167164)
			(xy 309.733213 9.251454) (xy 309.725301 9.336837) (xy 259.72979 9.336837) (xy 259.729491 9.310929)
			(xy 259.721579 9.225546) (xy 259.705823 9.141256) (xy 259.682356 9.05878) (xy 259.65138 8.978821)
			(xy 259.613158 8.902061) (xy 259.568017 8.829155) (xy 259.516341 8.760726) (xy 259.458572 8.697356)
			(xy 259.395202 8.639587) (xy 259.326773 8.587911) (xy 259.253867 8.54277) (xy 259.177107 8.504548)
			(xy 259.097148 8.473572) (xy 259.014672 8.450105) (xy 258.930382 8.434349) (xy 258.844999 8.426437)
			(xy 258.759249 8.426437) (xy 258.673866 8.434349) (xy 258.589576 8.450105) (xy 258.5071 8.473572)
			(xy 258.427141 8.504548) (xy 258.350381 8.54277) (xy 258.277475 8.587911) (xy 258.209046 8.639587)
			(xy 258.145676 8.697356) (xy 258.087907 8.760726) (xy 258.036231 8.829155) (xy 257.99109 8.902061)
			(xy 257.952868 8.978821) (xy 257.921892 9.05878) (xy 257.898425 9.141256) (xy 257.882669 9.225546)
			(xy 257.874757 9.310929) (xy 253.379491 9.310929) (xy 253.371579 9.225546) (xy 253.355823 9.141256)
			(xy 253.332356 9.05878) (xy 253.30138 8.978821) (xy 253.263158 8.902061) (xy 253.218017 8.829155)
			(xy 253.166341 8.760726) (xy 253.108572 8.697356) (xy 253.045202 8.639587) (xy 252.976773 8.587911)
			(xy 252.903867 8.54277) (xy 252.827107 8.504548) (xy 252.747148 8.473572) (xy 252.664672 8.450105)
			(xy 252.580382 8.434349) (xy 252.494999 8.426437) (xy 252.409249 8.426437) (xy 252.323866 8.434349)
			(xy 252.239576 8.450105) (xy 252.1571 8.473572) (xy 252.077141 8.504548) (xy 252.000381 8.54277)
			(xy 251.927475 8.587911) (xy 251.859046 8.639587) (xy 251.795676 8.697356) (xy 251.737907 8.760726)
			(xy 251.686231 8.829155) (xy 251.64109 8.902061) (xy 251.602868 8.978821) (xy 251.571892 9.05878)
			(xy 251.548425 9.141256) (xy 251.532669 9.225546) (xy 251.524757 9.310929) (xy 245.921117 9.310929)
			(xy 245.921035 9.303817) (xy 245.913123 9.218434) (xy 245.897367 9.134144) (xy 245.8739 9.051668)
			(xy 245.842924 8.971709) (xy 245.804702 8.894949) (xy 245.759561 8.822043) (xy 245.707885 8.753614)
			(xy 245.650116 8.690244) (xy 245.586746 8.632475) (xy 245.518317 8.580799) (xy 245.445411 8.535658)
			(xy 245.368651 8.497436) (xy 245.288692 8.46646) (xy 245.206216 8.442993) (xy 245.121926 8.427237)
			(xy 245.036543 8.419325) (xy 244.950793 8.419325) (xy 244.86541 8.427237) (xy 244.78112 8.442993)
			(xy 244.698644 8.46646) (xy 244.618685 8.497436) (xy 244.541925 8.535658) (xy 244.469019 8.580799)
			(xy 244.40059 8.632475) (xy 244.33722 8.690244) (xy 244.279451 8.753614) (xy 244.227775 8.822043)
			(xy 244.182634 8.894949) (xy 244.144412 8.971709) (xy 244.113436 9.051668) (xy 244.089969 9.134144)
			(xy 244.074213 9.218434) (xy 244.066301 9.303817) (xy 239.571035 9.303817) (xy 239.563123 9.218434)
			(xy 239.547367 9.134144) (xy 239.5239 9.051668) (xy 239.492924 8.971709) (xy 239.454702 8.894949)
			(xy 239.409561 8.822043) (xy 239.357885 8.753614) (xy 239.300116 8.690244) (xy 239.236746 8.632475)
			(xy 239.168317 8.580799) (xy 239.095411 8.535658) (xy 239.018651 8.497436) (xy 238.938692 8.46646)
			(xy 238.856216 8.442993) (xy 238.771926 8.427237) (xy 238.686543 8.419325) (xy 238.600793 8.419325)
			(xy 238.51541 8.427237) (xy 238.43112 8.442993) (xy 238.348644 8.46646) (xy 238.268685 8.497436)
			(xy 238.191925 8.535658) (xy 238.119019 8.580799) (xy 238.05059 8.632475) (xy 237.98722 8.690244)
			(xy 237.929451 8.753614) (xy 237.877775 8.822043) (xy 237.832634 8.894949) (xy 237.794412 8.971709)
			(xy 237.763436 9.051668) (xy 237.739969 9.134144) (xy 237.724213 9.218434) (xy 237.716301 9.303817)
			(xy 187.719832 9.303817) (xy 187.712579 9.225546) (xy 187.696823 9.141256) (xy 187.673356 9.05878)
			(xy 187.64238 8.978821) (xy 187.604158 8.902061) (xy 187.559017 8.829155) (xy 187.507341 8.760726)
			(xy 187.449572 8.697356) (xy 187.386202 8.639587) (xy 187.317773 8.587911) (xy 187.244867 8.54277)
			(xy 187.168107 8.504548) (xy 187.088148 8.473572) (xy 187.005672 8.450105) (xy 186.921382 8.434349)
			(xy 186.835999 8.426437) (xy 186.750249 8.426437) (xy 186.664866 8.434349) (xy 186.580576 8.450105)
			(xy 186.4981 8.473572) (xy 186.418141 8.504548) (xy 186.341381 8.54277) (xy 186.268475 8.587911)
			(xy 186.200046 8.639587) (xy 186.136676 8.697356) (xy 186.078907 8.760726) (xy 186.027231 8.829155)
			(xy 185.98209 8.902061) (xy 185.943868 8.978821) (xy 185.912892 9.05878) (xy 185.889425 9.141256)
			(xy 185.873669 9.225546) (xy 185.865757 9.310929) (xy 181.370491 9.310929) (xy 181.362579 9.225546)
			(xy 181.346823 9.141256) (xy 181.323356 9.05878) (xy 181.29238 8.978821) (xy 181.254158 8.902061)
			(xy 181.209017 8.829155) (xy 181.157341 8.760726) (xy 181.099572 8.697356) (xy 181.036202 8.639587)
			(xy 180.967773 8.587911) (xy 180.894867 8.54277) (xy 180.818107 8.504548) (xy 180.738148 8.473572)
			(xy 180.655672 8.450105) (xy 180.571382 8.434349) (xy 180.485999 8.426437) (xy 180.400249 8.426437)
			(xy 180.314866 8.434349) (xy 180.230576 8.450105) (xy 180.1481 8.473572) (xy 180.068141 8.504548)
			(xy 179.991381 8.54277) (xy 179.918475 8.587911) (xy 179.850046 8.639587) (xy 179.786676 8.697356)
			(xy 179.728907 8.760726) (xy 179.677231 8.829155) (xy 179.63209 8.902061) (xy 179.593868 8.978821)
			(xy 179.562892 9.05878) (xy 179.539425 9.141256) (xy 179.523669 9.225546) (xy 179.515757 9.310929)
			(xy 158.621984 9.310929) (xy 158.621984 8.377682) (xy 158.62149 8.307329) (xy 158.6136 8.166844)
			(xy 158.597845 8.027022) (xy 158.574274 7.888303) (xy 158.542963 7.751125) (xy 158.50401 7.615918)
			(xy 158.457537 7.483107) (xy 158.40369 7.353112) (xy 158.342638 7.22634) (xy 158.274575 7.103191)
			(xy 158.199714 6.984051) (xy 158.11829 6.869297) (xy 158.039844 6.770929) (xy 179.515757 6.770929)
			(xy 179.515757 6.856679) (xy 179.523669 6.942062) (xy 179.539425 7.026352) (xy 179.562892 7.108828)
			(xy 179.593868 7.188787) (xy 179.63209 7.265547) (xy 179.677231 7.338453) (xy 179.728907 7.406882)
			(xy 179.786676 7.470252) (xy 179.850046 7.528021) (xy 179.918475 7.579697) (xy 179.991381 7.624838)
			(xy 180.068141 7.66306) (xy 180.1481 7.694036) (xy 180.230576 7.717503) (xy 180.314866 7.733259)
			(xy 180.400249 7.741171) (xy 180.485999 7.741171) (xy 180.571382 7.733259) (xy 180.655672 7.717503)
			(xy 180.738148 7.694036) (xy 180.818107 7.66306) (xy 180.894867 7.624838) (xy 180.967773 7.579697)
			(xy 181.036202 7.528021) (xy 181.099572 7.470252) (xy 181.157341 7.406882) (xy 181.209017 7.338453)
			(xy 181.254158 7.265547) (xy 181.29238 7.188787) (xy 181.323356 7.108828) (xy 181.346823 7.026352)
			(xy 181.362579 6.942062) (xy 181.370491 6.856679) (xy 181.370986 6.813804) (xy 181.370491 6.770929)
			(xy 185.865757 6.770929) (xy 185.865757 6.856679) (xy 185.873669 6.942062) (xy 185.889425 7.026352)
			(xy 185.912892 7.108828) (xy 185.943868 7.188787) (xy 185.98209 7.265547) (xy 186.027231 7.338453)
			(xy 186.078907 7.406882) (xy 186.136676 7.470252) (xy 186.200046 7.528021) (xy 186.268475 7.579697)
			(xy 186.341381 7.624838) (xy 186.418141 7.66306) (xy 186.4981 7.694036) (xy 186.580576 7.717503)
			(xy 186.664866 7.733259) (xy 186.750249 7.741171) (xy 186.835999 7.741171) (xy 186.921382 7.733259)
			(xy 187.005672 7.717503) (xy 187.088148 7.694036) (xy 187.168107 7.66306) (xy 187.244867 7.624838)
			(xy 187.317773 7.579697) (xy 187.386202 7.528021) (xy 187.449572 7.470252) (xy 187.507341 7.406882)
			(xy 187.559017 7.338453) (xy 187.604158 7.265547) (xy 187.64238 7.188787) (xy 187.673356 7.108828)
			(xy 187.696823 7.026352) (xy 187.712579 6.942062) (xy 187.720491 6.856679) (xy 187.720986 6.813804)
			(xy 187.720491 6.770929) (xy 187.719832 6.763817) (xy 237.716301 6.763817) (xy 237.716301 6.849567)
			(xy 237.724213 6.93495) (xy 237.739969 7.01924) (xy 237.763436 7.101716) (xy 237.794412 7.181675)
			(xy 237.832634 7.258435) (xy 237.877775 7.331341) (xy 237.929451 7.39977) (xy 237.98722 7.46314)
			(xy 238.05059 7.520909) (xy 238.119019 7.572585) (xy 238.191925 7.617726) (xy 238.268685 7.655948)
			(xy 238.348644 7.686924) (xy 238.43112 7.710391) (xy 238.51541 7.726147) (xy 238.600793 7.734059)
			(xy 238.686543 7.734059) (xy 238.771926 7.726147) (xy 238.856216 7.710391) (xy 238.938692 7.686924)
			(xy 239.018651 7.655948) (xy 239.095411 7.617726) (xy 239.168317 7.572585) (xy 239.236746 7.520909)
			(xy 239.300116 7.46314) (xy 239.357885 7.39977) (xy 239.409561 7.331341) (xy 239.454702 7.258435)
			(xy 239.492924 7.181675) (xy 239.5239 7.101716) (xy 239.547367 7.01924) (xy 239.563123 6.93495) (xy 239.571035 6.849567)
			(xy 239.57153 6.806692) (xy 239.571035 6.763817) (xy 244.066301 6.763817) (xy 244.066301 6.849567)
			(xy 244.074213 6.93495) (xy 244.089969 7.01924) (xy 244.113436 7.101716) (xy 244.144412 7.181675)
			(xy 244.182634 7.258435) (xy 244.227775 7.331341) (xy 244.279451 7.39977) (xy 244.33722 7.46314)
			(xy 244.40059 7.520909) (xy 244.469019 7.572585) (xy 244.541925 7.617726) (xy 244.618685 7.655948)
			(xy 244.698644 7.686924) (xy 244.78112 7.710391) (xy 244.86541 7.726147) (xy 244.950793 7.734059)
			(xy 245.036543 7.734059) (xy 245.121926 7.726147) (xy 245.206216 7.710391) (xy 245.288692 7.686924)
			(xy 245.368651 7.655948) (xy 245.445411 7.617726) (xy 245.518317 7.572585) (xy 245.586746 7.520909)
			(xy 245.650116 7.46314) (xy 245.707885 7.39977) (xy 245.759561 7.331341) (xy 245.804702 7.258435)
			(xy 245.842924 7.181675) (xy 245.8739 7.101716) (xy 245.897367 7.01924) (xy 245.913123 6.93495) (xy 245.921035 6.849567)
			(xy 245.92153 6.806692) (xy 245.921117 6.770929) (xy 251.524757 6.770929) (xy 251.524757 6.856679)
			(xy 251.532669 6.942062) (xy 251.548425 7.026352) (xy 251.571892 7.108828) (xy 251.602868 7.188787)
			(xy 251.64109 7.265547) (xy 251.686231 7.338453) (xy 251.737907 7.406882) (xy 251.795676 7.470252)
			(xy 251.859046 7.528021) (xy 251.927475 7.579697) (xy 252.000381 7.624838) (xy 252.077141 7.66306)
			(xy 252.1571 7.694036) (xy 252.239576 7.717503) (xy 252.323866 7.733259) (xy 252.409249 7.741171)
			(xy 252.494999 7.741171) (xy 252.580382 7.733259) (xy 252.664672 7.717503) (xy 252.747148 7.694036)
			(xy 252.827107 7.66306) (xy 252.84931 7.652004) (xy 256.459736 7.652004) (xy 256.459736 8.515604)
			(xy 256.460222 8.542873) (xy 256.467984 8.596857) (xy 256.483349 8.649187) (xy 256.506006 8.698797)
			(xy 256.535492 8.744678) (xy 256.571207 8.785895) (xy 256.612424 8.82161) (xy 256.658305 8.851096)
			(xy 256.707915 8.873753) (xy 256.760245 8.889118) (xy 256.814229 8.89688) (xy 256.868767 8.89688)
			(xy 256.922751 8.889118) (xy 256.975081 8.873753) (xy 257.024691 8.851096) (xy 257.070572 8.82161)
			(xy 257.111789 8.785895) (xy 257.147504 8.744678) (xy 257.17699 8.698797) (xy 257.199647 8.649187)
			(xy 257.215012 8.596857) (xy 257.222774 8.542873) (xy 257.22326 8.515604) (xy 257.22326 7.652004)
			(xy 257.222774 7.624735) (xy 257.215012 7.570751) (xy 257.199647 7.518421) (xy 257.17699 7.468811)
			(xy 257.147504 7.42293) (xy 257.111789 7.381713) (xy 257.070572 7.345998) (xy 257.024691 7.316512)
			(xy 256.975081 7.293855) (xy 256.922751 7.27849) (xy 256.868767 7.270728) (xy 256.814229 7.270728)
			(xy 256.760245 7.27849) (xy 256.707915 7.293855) (xy 256.658305 7.316512) (xy 256.612424 7.345998)
			(xy 256.571207 7.381713) (xy 256.535492 7.42293) (xy 256.506006 7.468811) (xy 256.483349 7.518421)
			(xy 256.467984 7.570751) (xy 256.460222 7.624735) (xy 256.459736 7.652004) (xy 252.84931 7.652004)
			(xy 252.903867 7.624838) (xy 252.976773 7.579697) (xy 253.045202 7.528021) (xy 253.108572 7.470252)
			(xy 253.166341 7.406882) (xy 253.218017 7.338453) (xy 253.263158 7.265547) (xy 253.30138 7.188787)
			(xy 253.332356 7.108828) (xy 253.355823 7.026352) (xy 253.371579 6.942062) (xy 253.379491 6.856679)
			(xy 253.379986 6.813804) (xy 253.379491 6.770929) (xy 257.874757 6.770929) (xy 257.874757 6.856679)
			(xy 257.882669 6.942062) (xy 257.898425 7.026352) (xy 257.921892 7.108828) (xy 257.952868 7.188787)
			(xy 257.99109 7.265547) (xy 258.036231 7.338453) (xy 258.087907 7.406882) (xy 258.145676 7.470252)
			(xy 258.209046 7.528021) (xy 258.277475 7.579697) (xy 258.350381 7.624838) (xy 258.427141 7.66306)
			(xy 258.5071 7.694036) (xy 258.589576 7.717503) (xy 258.673866 7.733259) (xy 258.759249 7.741171)
			(xy 258.844999 7.741171) (xy 258.930382 7.733259) (xy 259.014672 7.717503) (xy 259.097148 7.694036)
			(xy 259.177107 7.66306) (xy 259.253867 7.624838) (xy 259.326773 7.579697) (xy 259.395202 7.528021)
			(xy 259.458572 7.470252) (xy 259.516341 7.406882) (xy 259.568017 7.338453) (xy 259.613158 7.265547)
			(xy 259.65138 7.188787) (xy 259.682356 7.108828) (xy 259.705823 7.026352) (xy 259.721579 6.942062)
			(xy 259.729491 6.856679) (xy 259.729986 6.813804) (xy 259.72979 6.796837) (xy 309.725301 6.796837)
			(xy 309.725301 6.882587) (xy 309.733213 6.96797) (xy 309.748969 7.05226) (xy 309.772436 7.134736)
			(xy 309.803412 7.214695) (xy 309.841634 7.291455) (xy 309.886775 7.364361) (xy 309.938451 7.43279)
			(xy 309.99622 7.49616) (xy 310.05959 7.553929) (xy 310.128019 7.605605) (xy 310.200925 7.650746)
			(xy 310.277685 7.688968) (xy 310.357644 7.719944) (xy 310.44012 7.743411) (xy 310.52441 7.759167)
			(xy 310.609793 7.767079) (xy 310.695543 7.767079) (xy 310.780926 7.759167) (xy 310.865216 7.743411)
			(xy 310.947692 7.719944) (xy 311.027651 7.688968) (xy 311.049854 7.677912) (xy 312.231532 7.677912)
			(xy 312.231532 8.541512) (xy 312.232018 8.568781) (xy 312.23978 8.622765) (xy 312.255145 8.675095)
			(xy 312.277802 8.724705) (xy 312.307288 8.770586) (xy 312.343003 8.811803) (xy 312.38422 8.847518)
			(xy 312.430101 8.877004) (xy 312.479711 8.899661) (xy 312.532041 8.915026) (xy 312.586025 8.922788)
			(xy 312.640563 8.922788) (xy 312.694547 8.915026) (xy 312.746877 8.899661) (xy 312.796487 8.877004)
			(xy 312.842368 8.847518) (xy 312.883585 8.811803) (xy 312.9193 8.770586) (xy 312.948786 8.724705)
			(xy 312.971443 8.675095) (xy 312.986808 8.622765) (xy 312.99457 8.568781) (xy 312.995056 8.541512)
			(xy 312.995056 7.677912) (xy 312.99457 7.650643) (xy 312.986808 7.596659) (xy 312.971443 7.544329)
			(xy 312.948786 7.494719) (xy 312.9193 7.448838) (xy 312.883585 7.407621) (xy 312.842368 7.371906)
			(xy 312.796487 7.34242) (xy 312.746877 7.319763) (xy 312.694547 7.304398) (xy 312.640563 7.296636)
			(xy 312.586025 7.296636) (xy 312.532041 7.304398) (xy 312.479711 7.319763) (xy 312.430101 7.34242)
			(xy 312.38422 7.371906) (xy 312.343003 7.407621) (xy 312.307288 7.448838) (xy 312.277802 7.494719)
			(xy 312.255145 7.544329) (xy 312.23978 7.596659) (xy 312.232018 7.650643) (xy 312.231532 7.677912)
			(xy 311.049854 7.677912) (xy 311.104411 7.650746) (xy 311.177317 7.605605) (xy 311.245746 7.553929)
			(xy 311.309116 7.49616) (xy 311.366885 7.43279) (xy 311.418561 7.364361) (xy 311.463702 7.291455)
			(xy 311.501924 7.214695) (xy 311.5329 7.134736) (xy 311.556367 7.05226) (xy 311.572123 6.96797) (xy 311.580035 6.882587)
			(xy 311.58053 6.839712) (xy 311.580035 6.796837) (xy 316.075301 6.796837) (xy 316.075301 6.882587)
			(xy 316.083213 6.96797) (xy 316.098969 7.05226) (xy 316.122436 7.134736) (xy 316.153412 7.214695)
			(xy 316.191634 7.291455) (xy 316.236775 7.364361) (xy 316.288451 7.43279) (xy 316.34622 7.49616)
			(xy 316.40959 7.553929) (xy 316.478019 7.605605) (xy 316.550925 7.650746) (xy 316.627685 7.688968)
			(xy 316.707644 7.719944) (xy 316.79012 7.743411) (xy 316.87441 7.759167) (xy 316.959793 7.767079)
			(xy 317.045543 7.767079) (xy 317.130926 7.759167) (xy 317.215216 7.743411) (xy 317.297692 7.719944)
			(xy 317.377651 7.688968) (xy 317.454411 7.650746) (xy 317.527317 7.605605) (xy 317.595746 7.553929)
			(xy 317.659116 7.49616) (xy 317.716885 7.43279) (xy 317.768561 7.364361) (xy 317.813702 7.291455)
			(xy 317.851924 7.214695) (xy 317.8829 7.134736) (xy 317.906367 7.05226) (xy 317.922123 6.96797) (xy 317.930035 6.882587)
			(xy 317.93053 6.839712) (xy 317.930117 6.803949) (xy 324.295757 6.803949) (xy 324.295757 6.889699)
			(xy 324.303669 6.975082) (xy 324.319425 7.059372) (xy 324.342892 7.141848) (xy 324.373868 7.221807)
			(xy 324.41209 7.298567) (xy 324.457231 7.371473) (xy 324.508907 7.439902) (xy 324.566676 7.503272)
			(xy 324.630046 7.561041) (xy 324.698475 7.612717) (xy 324.771381 7.657858) (xy 324.848141 7.69608)
			(xy 324.9281 7.727056) (xy 325.010576 7.750523) (xy 325.094866 7.766279) (xy 325.180249 7.774191)
			(xy 325.265999 7.774191) (xy 325.351382 7.766279) (xy 325.435672 7.750523) (xy 325.518148 7.727056)
			(xy 325.598107 7.69608) (xy 325.62031 7.685024) (xy 329.230736 7.685024) (xy 329.230736 8.548624)
			(xy 329.231222 8.575893) (xy 329.238984 8.629877) (xy 329.254349 8.682207) (xy 329.277006 8.731817)
			(xy 329.306492 8.777698) (xy 329.342207 8.818915) (xy 329.383424 8.85463) (xy 329.429305 8.884116)
			(xy 329.478915 8.906773) (xy 329.531245 8.922138) (xy 329.585229 8.9299) (xy 329.639767 8.9299) (xy 329.693751 8.922138)
			(xy 329.746081 8.906773) (xy 329.795691 8.884116) (xy 329.841572 8.85463) (xy 329.882789 8.818915)
			(xy 329.918504 8.777698) (xy 329.94799 8.731817) (xy 329.970647 8.682207) (xy 329.986012 8.629877)
			(xy 329.993774 8.575893) (xy 329.99426 8.548624) (xy 329.99426 7.685024) (xy 329.993774 7.657755)
			(xy 329.986012 7.603771) (xy 329.970647 7.551441) (xy 329.94799 7.501831) (xy 329.918504 7.45595)
			(xy 329.882789 7.414733) (xy 329.841572 7.379018) (xy 329.795691 7.349532) (xy 329.746081 7.326875)
			(xy 329.693751 7.31151) (xy 329.639767 7.303748) (xy 329.585229 7.303748) (xy 329.531245 7.31151)
			(xy 329.478915 7.326875) (xy 329.429305 7.349532) (xy 329.383424 7.379018) (xy 329.342207 7.414733)
			(xy 329.306492 7.45595) (xy 329.277006 7.501831) (xy 329.254349 7.551441) (xy 329.238984 7.603771)
			(xy 329.231222 7.657755) (xy 329.230736 7.685024) (xy 325.62031 7.685024) (xy 325.674867 7.657858)
			(xy 325.747773 7.612717) (xy 325.816202 7.561041) (xy 325.879572 7.503272) (xy 325.937341 7.439902)
			(xy 325.989017 7.371473) (xy 326.034158 7.298567) (xy 326.07238 7.221807) (xy 326.103356 7.141848)
			(xy 326.126823 7.059372) (xy 326.142579 6.975082) (xy 326.150491 6.889699) (xy 326.150986 6.846824)
			(xy 326.150491 6.803949) (xy 330.645757 6.803949) (xy 330.645757 6.889699) (xy 330.653669 6.975082)
			(xy 330.669425 7.059372) (xy 330.692892 7.141848) (xy 330.723868 7.221807) (xy 330.76209 7.298567)
			(xy 330.807231 7.371473) (xy 330.858907 7.439902) (xy 330.916676 7.503272) (xy 330.980046 7.561041)
			(xy 331.048475 7.612717) (xy 331.121381 7.657858) (xy 331.198141 7.69608) (xy 331.2781 7.727056)
			(xy 331.360576 7.750523) (xy 331.444866 7.766279) (xy 331.530249 7.774191) (xy 331.615999 7.774191)
			(xy 331.701382 7.766279) (xy 331.785672 7.750523) (xy 331.868148 7.727056) (xy 331.948107 7.69608)
			(xy 332.024867 7.657858) (xy 332.097773 7.612717) (xy 332.166202 7.561041) (xy 332.229572 7.503272)
			(xy 332.287341 7.439902) (xy 332.339017 7.371473) (xy 332.384158 7.298567) (xy 332.42238 7.221807)
			(xy 332.453356 7.141848) (xy 332.476823 7.059372) (xy 332.492579 6.975082) (xy 332.500491 6.889699)
			(xy 332.500986 6.846824) (xy 332.50079 6.829857) (xy 382.496301 6.829857) (xy 382.496301 6.915607)
			(xy 382.504213 7.00099) (xy 382.519969 7.08528) (xy 382.543436 7.167756) (xy 382.574412 7.247715)
			(xy 382.612634 7.324475) (xy 382.657775 7.397381) (xy 382.709451 7.46581) (xy 382.76722 7.52918)
			(xy 382.83059 7.586949) (xy 382.899019 7.638625) (xy 382.971925 7.683766) (xy 383.048685 7.721988)
			(xy 383.128644 7.752964) (xy 383.21112 7.776431) (xy 383.29541 7.792187) (xy 383.380793 7.800099)
			(xy 383.466543 7.800099) (xy 383.551926 7.792187) (xy 383.636216 7.776431) (xy 383.718692 7.752964)
			(xy 383.798651 7.721988) (xy 383.820854 7.710932) (xy 385.002532 7.710932) (xy 385.002532 8.574532)
			(xy 385.003018 8.601801) (xy 385.01078 8.655785) (xy 385.026145 8.708115) (xy 385.048802 8.757725)
			(xy 385.078288 8.803606) (xy 385.114003 8.844823) (xy 385.15522 8.880538) (xy 385.201101 8.910024)
			(xy 385.250711 8.932681) (xy 385.303041 8.948046) (xy 385.357025 8.955808) (xy 385.411563 8.955808)
			(xy 385.465547 8.948046) (xy 385.517877 8.932681) (xy 385.567487 8.910024) (xy 385.613368 8.880538)
			(xy 385.654585 8.844823) (xy 385.6903 8.803606) (xy 385.719786 8.757725) (xy 385.742443 8.708115)
			(xy 385.757808 8.655785) (xy 385.76557 8.601801) (xy 385.766056 8.574532) (xy 385.766056 7.710932)
			(xy 385.76557 7.683663) (xy 385.757808 7.629679) (xy 385.742443 7.577349) (xy 385.719786 7.527739)
			(xy 385.6903 7.481858) (xy 385.654585 7.440641) (xy 385.613368 7.404926) (xy 385.567487 7.37544)
			(xy 385.517877 7.352783) (xy 385.465547 7.337418) (xy 385.411563 7.329656) (xy 385.357025 7.329656)
			(xy 385.303041 7.337418) (xy 385.250711 7.352783) (xy 385.201101 7.37544) (xy 385.15522 7.404926)
			(xy 385.114003 7.440641) (xy 385.078288 7.481858) (xy 385.048802 7.527739) (xy 385.026145 7.577349)
			(xy 385.01078 7.629679) (xy 385.003018 7.683663) (xy 385.002532 7.710932) (xy 383.820854 7.710932)
			(xy 383.875411 7.683766) (xy 383.948317 7.638625) (xy 384.016746 7.586949) (xy 384.080116 7.52918)
			(xy 384.137885 7.46581) (xy 384.189561 7.397381) (xy 384.234702 7.324475) (xy 384.272924 7.247715)
			(xy 384.3039 7.167756) (xy 384.327367 7.08528) (xy 384.343123 7.00099) (xy 384.351035 6.915607) (xy 384.35153 6.872732)
			(xy 384.351035 6.829857) (xy 388.846301 6.829857) (xy 388.846301 6.915607) (xy 388.854213 7.00099)
			(xy 388.869969 7.08528) (xy 388.893436 7.167756) (xy 388.924412 7.247715) (xy 388.962634 7.324475)
			(xy 389.007775 7.397381) (xy 389.059451 7.46581) (xy 389.11722 7.52918) (xy 389.18059 7.586949) (xy 389.249019 7.638625)
			(xy 389.321925 7.683766) (xy 389.398685 7.721988) (xy 389.478644 7.752964) (xy 389.56112 7.776431)
			(xy 389.64541 7.792187) (xy 389.730793 7.800099) (xy 389.816543 7.800099) (xy 389.901926 7.792187)
			(xy 389.986216 7.776431) (xy 390.068692 7.752964) (xy 390.148651 7.721988) (xy 390.225411 7.683766)
			(xy 390.298317 7.638625) (xy 390.366746 7.586949) (xy 390.430116 7.52918) (xy 390.487885 7.46581)
			(xy 390.539561 7.397381) (xy 390.584702 7.324475) (xy 390.622924 7.247715) (xy 390.6539 7.167756)
			(xy 390.677367 7.08528) (xy 390.693123 7.00099) (xy 390.701035 6.915607) (xy 390.70153 6.872732)
			(xy 390.701117 6.836969) (xy 396.558757 6.836969) (xy 396.558757 6.922719) (xy 396.566669 7.008102)
			(xy 396.582425 7.092392) (xy 396.605892 7.174868) (xy 396.636868 7.254827) (xy 396.67509 7.331587)
			(xy 396.720231 7.404493) (xy 396.771907 7.472922) (xy 396.829676 7.536292) (xy 396.893046 7.594061)
			(xy 396.961475 7.645737) (xy 397.034381 7.690878) (xy 397.111141 7.7291) (xy 397.1911 7.760076) (xy 397.273576 7.783543)
			(xy 397.357866 7.799299) (xy 397.443249 7.807211) (xy 397.528999 7.807211) (xy 397.614382 7.799299)
			(xy 397.698672 7.783543) (xy 397.781148 7.760076) (xy 397.861107 7.7291) (xy 397.88331 7.718044)
			(xy 401.493736 7.718044) (xy 401.493736 8.581644) (xy 401.494222 8.608913) (xy 401.501984 8.662897)
			(xy 401.517349 8.715227) (xy 401.540006 8.764837) (xy 401.569492 8.810718) (xy 401.605207 8.851935)
			(xy 401.646424 8.88765) (xy 401.692305 8.917136) (xy 401.741915 8.939793) (xy 401.794245 8.955158)
			(xy 401.848229 8.96292) (xy 401.902767 8.96292) (xy 401.956751 8.955158) (xy 402.009081 8.939793)
			(xy 402.058691 8.917136) (xy 402.104572 8.88765) (xy 402.145789 8.851935) (xy 402.181504 8.810718)
			(xy 402.21099 8.764837) (xy 402.233647 8.715227) (xy 402.249012 8.662897) (xy 402.256774 8.608913)
			(xy 402.25726 8.581644) (xy 402.25726 7.718044) (xy 402.256774 7.690775) (xy 402.249012 7.636791)
			(xy 402.233647 7.584461) (xy 402.21099 7.534851) (xy 402.181504 7.48897) (xy 402.145789 7.447753)
			(xy 402.104572 7.412038) (xy 402.058691 7.382552) (xy 402.009081 7.359895) (xy 401.956751 7.34453)
			(xy 401.902767 7.336768) (xy 401.848229 7.336768) (xy 401.794245 7.34453) (xy 401.741915 7.359895)
			(xy 401.692305 7.382552) (xy 401.646424 7.412038) (xy 401.605207 7.447753) (xy 401.569492 7.48897)
			(xy 401.540006 7.534851) (xy 401.517349 7.584461) (xy 401.501984 7.636791) (xy 401.494222 7.690775)
			(xy 401.493736 7.718044) (xy 397.88331 7.718044) (xy 397.937867 7.690878) (xy 398.010773 7.645737)
			(xy 398.079202 7.594061) (xy 398.142572 7.536292) (xy 398.200341 7.472922) (xy 398.252017 7.404493)
			(xy 398.297158 7.331587) (xy 398.33538 7.254827) (xy 398.366356 7.174868) (xy 398.389823 7.092392)
			(xy 398.405579 7.008102) (xy 398.413491 6.922719) (xy 398.413986 6.879844) (xy 398.413491 6.836969)
			(xy 402.908757 6.836969) (xy 402.908757 6.922719) (xy 402.916669 7.008102) (xy 402.932425 7.092392)
			(xy 402.955892 7.174868) (xy 402.986868 7.254827) (xy 403.02509 7.331587) (xy 403.070231 7.404493)
			(xy 403.121907 7.472922) (xy 403.179676 7.536292) (xy 403.243046 7.594061) (xy 403.311475 7.645737)
			(xy 403.384381 7.690878) (xy 403.461141 7.7291) (xy 403.5411 7.760076) (xy 403.623576 7.783543) (xy 403.707866 7.799299)
			(xy 403.793249 7.807211) (xy 403.878999 7.807211) (xy 403.964382 7.799299) (xy 404.048672 7.783543)
			(xy 404.131148 7.760076) (xy 404.211107 7.7291) (xy 404.287867 7.690878) (xy 404.360773 7.645737)
			(xy 404.429202 7.594061) (xy 404.492572 7.536292) (xy 404.550341 7.472922) (xy 404.602017 7.404493)
			(xy 404.647158 7.331587) (xy 404.68538 7.254827) (xy 404.716356 7.174868) (xy 404.739823 7.092392)
			(xy 404.755579 7.008102) (xy 404.763491 6.922719) (xy 404.763986 6.879844) (xy 404.76379 6.862877)
			(xy 454.759301 6.862877) (xy 454.759301 6.948627) (xy 454.767213 7.03401) (xy 454.782969 7.1183)
			(xy 454.806436 7.200776) (xy 454.837412 7.280735) (xy 454.875634 7.357495) (xy 454.920775 7.430401)
			(xy 454.972451 7.49883) (xy 455.03022 7.5622) (xy 455.09359 7.619969) (xy 455.162019 7.671645) (xy 455.234925 7.716786)
			(xy 455.311685 7.755008) (xy 455.391644 7.785984) (xy 455.47412 7.809451) (xy 455.55841 7.825207)
			(xy 455.643793 7.833119) (xy 455.729543 7.833119) (xy 455.814926 7.825207) (xy 455.899216 7.809451)
			(xy 455.981692 7.785984) (xy 456.061651 7.755008) (xy 456.083854 7.743952) (xy 457.265532 7.743952)
			(xy 457.265532 8.607552) (xy 457.266018 8.634821) (xy 457.27378 8.688805) (xy 457.289145 8.741135)
			(xy 457.311802 8.790745) (xy 457.341288 8.836626) (xy 457.377003 8.877843) (xy 457.41822 8.913558)
			(xy 457.464101 8.943044) (xy 457.513711 8.965701) (xy 457.566041 8.981066) (xy 457.620025 8.988828)
			(xy 457.674563 8.988828) (xy 457.728547 8.981066) (xy 457.780877 8.965701) (xy 457.830487 8.943044)
			(xy 457.876368 8.913558) (xy 457.917585 8.877843) (xy 457.9533 8.836626) (xy 457.982786 8.790745)
			(xy 458.005443 8.741135) (xy 458.020808 8.688805) (xy 458.02857 8.634821) (xy 458.029056 8.607552)
			(xy 458.029056 7.743952) (xy 458.02857 7.716683) (xy 458.020808 7.662699) (xy 458.005443 7.610369)
			(xy 457.982786 7.560759) (xy 457.9533 7.514878) (xy 457.917585 7.473661) (xy 457.876368 7.437946)
			(xy 457.830487 7.40846) (xy 457.780877 7.385803) (xy 457.728547 7.370438) (xy 457.674563 7.362676)
			(xy 457.620025 7.362676) (xy 457.566041 7.370438) (xy 457.513711 7.385803) (xy 457.464101 7.40846)
			(xy 457.41822 7.437946) (xy 457.377003 7.473661) (xy 457.341288 7.514878) (xy 457.311802 7.560759)
			(xy 457.289145 7.610369) (xy 457.27378 7.662699) (xy 457.266018 7.716683) (xy 457.265532 7.743952)
			(xy 456.083854 7.743952) (xy 456.138411 7.716786) (xy 456.211317 7.671645) (xy 456.279746 7.619969)
			(xy 456.343116 7.5622) (xy 456.400885 7.49883) (xy 456.452561 7.430401) (xy 456.497702 7.357495)
			(xy 456.535924 7.280735) (xy 456.5669 7.200776) (xy 456.590367 7.1183) (xy 456.606123 7.03401) (xy 456.614035 6.948627)
			(xy 456.61453 6.905752) (xy 456.614035 6.862877) (xy 461.109301 6.862877) (xy 461.109301 6.948627)
			(xy 461.117213 7.03401) (xy 461.132969 7.1183) (xy 461.156436 7.200776) (xy 461.187412 7.280735)
			(xy 461.225634 7.357495) (xy 461.270775 7.430401) (xy 461.322451 7.49883) (xy 461.38022 7.5622) (xy 461.44359 7.619969)
			(xy 461.512019 7.671645) (xy 461.584925 7.716786) (xy 461.661685 7.755008) (xy 461.741644 7.785984)
			(xy 461.82412 7.809451) (xy 461.90841 7.825207) (xy 461.993793 7.833119) (xy 462.079543 7.833119)
			(xy 462.164926 7.825207) (xy 462.249216 7.809451) (xy 462.331692 7.785984) (xy 462.411651 7.755008)
			(xy 462.488411 7.716786) (xy 462.561317 7.671645) (xy 462.629746 7.619969) (xy 462.693116 7.5622)
			(xy 462.750885 7.49883) (xy 462.802561 7.430401) (xy 462.847702 7.357495) (xy 462.885924 7.280735)
			(xy 462.9169 7.200776) (xy 462.940367 7.1183) (xy 462.956123 7.03401) (xy 462.964035 6.948627) (xy 462.96453 6.905752)
			(xy 462.964035 6.862877) (xy 462.956123 6.777494) (xy 462.940367 6.693204) (xy 462.9169 6.610728)
			(xy 462.885924 6.530769) (xy 462.847702 6.454009) (xy 462.802561 6.381103) (xy 462.750885 6.312674)
			(xy 462.693116 6.249304) (xy 462.629746 6.191535) (xy 462.561317 6.139859) (xy 462.488411 6.094718)
			(xy 462.411651 6.056496) (xy 462.331692 6.02552) (xy 462.249216 6.002053) (xy 462.164926 5.986297)
			(xy 462.079543 5.978385) (xy 461.993793 5.978385) (xy 461.90841 5.986297) (xy 461.82412 6.002053)
			(xy 461.741644 6.02552) (xy 461.661685 6.056496) (xy 461.584925 6.094718) (xy 461.512019 6.139859)
			(xy 461.44359 6.191535) (xy 461.38022 6.249304) (xy 461.322451 6.312674) (xy 461.270775 6.381103)
			(xy 461.225634 6.454009) (xy 461.187412 6.530769) (xy 461.156436 6.610728) (xy 461.132969 6.693204)
			(xy 461.117213 6.777494) (xy 461.109301 6.862877) (xy 456.614035 6.862877) (xy 456.606123 6.777494)
			(xy 456.590367 6.693204) (xy 456.5669 6.610728) (xy 456.535924 6.530769) (xy 456.497702 6.454009)
			(xy 456.452561 6.381103) (xy 456.400885 6.312674) (xy 456.343116 6.249304) (xy 456.279746 6.191535)
			(xy 456.211317 6.139859) (xy 456.138411 6.094718) (xy 456.061651 6.056496) (xy 455.981692 6.02552)
			(xy 455.899216 6.002053) (xy 455.814926 5.986297) (xy 455.729543 5.978385) (xy 455.643793 5.978385)
			(xy 455.55841 5.986297) (xy 455.47412 6.002053) (xy 455.391644 6.02552) (xy 455.311685 6.056496)
			(xy 455.234925 6.094718) (xy 455.162019 6.139859) (xy 455.09359 6.191535) (xy 455.03022 6.249304)
			(xy 454.972451 6.312674) (xy 454.920775 6.381103) (xy 454.875634 6.454009) (xy 454.837412 6.530769)
			(xy 454.806436 6.610728) (xy 454.782969 6.693204) (xy 454.767213 6.777494) (xy 454.759301 6.862877)
			(xy 404.76379 6.862877) (xy 404.763491 6.836969) (xy 404.755579 6.751586) (xy 404.739823 6.667296)
			(xy 404.716356 6.58482) (xy 404.68538 6.504861) (xy 404.647158 6.428101) (xy 404.602017 6.355195)
			(xy 404.550341 6.286766) (xy 404.492572 6.223396) (xy 404.429202 6.165627) (xy 404.360773 6.113951)
			(xy 404.287867 6.06881) (xy 404.211107 6.030588) (xy 404.131148 5.999612) (xy 404.048672 5.976145)
			(xy 403.964382 5.960389) (xy 403.878999 5.952477) (xy 403.793249 5.952477) (xy 403.707866 5.960389)
			(xy 403.623576 5.976145) (xy 403.5411 5.999612) (xy 403.461141 6.030588) (xy 403.384381 6.06881)
			(xy 403.311475 6.113951) (xy 403.243046 6.165627) (xy 403.179676 6.223396) (xy 403.121907 6.286766)
			(xy 403.070231 6.355195) (xy 403.02509 6.428101) (xy 402.986868 6.504861) (xy 402.955892 6.58482)
			(xy 402.932425 6.667296) (xy 402.916669 6.751586) (xy 402.908757 6.836969) (xy 398.413491 6.836969)
			(xy 398.405579 6.751586) (xy 398.389823 6.667296) (xy 398.366356 6.58482) (xy 398.33538 6.504861)
			(xy 398.297158 6.428101) (xy 398.252017 6.355195) (xy 398.200341 6.286766) (xy 398.142572 6.223396)
			(xy 398.079202 6.165627) (xy 398.010773 6.113951) (xy 397.937867 6.06881) (xy 397.861107 6.030588)
			(xy 397.781148 5.999612) (xy 397.698672 5.976145) (xy 397.614382 5.960389) (xy 397.528999 5.952477)
			(xy 397.443249 5.952477) (xy 397.357866 5.960389) (xy 397.273576 5.976145) (xy 397.1911 5.999612)
			(xy 397.111141 6.030588) (xy 397.034381 6.06881) (xy 396.961475 6.113951) (xy 396.893046 6.165627)
			(xy 396.829676 6.223396) (xy 396.771907 6.286766) (xy 396.720231 6.355195) (xy 396.67509 6.428101)
			(xy 396.636868 6.504861) (xy 396.605892 6.58482) (xy 396.582425 6.667296) (xy 396.566669 6.751586)
			(xy 396.558757 6.836969) (xy 390.701117 6.836969) (xy 390.701035 6.829857) (xy 390.693123 6.744474)
			(xy 390.677367 6.660184) (xy 390.6539 6.577708) (xy 390.622924 6.497749) (xy 390.584702 6.420989)
			(xy 390.539561 6.348083) (xy 390.487885 6.279654) (xy 390.430116 6.216284) (xy 390.366746 6.158515)
			(xy 390.298317 6.106839) (xy 390.225411 6.061698) (xy 390.148651 6.023476) (xy 390.068692 5.9925)
			(xy 389.986216 5.969033) (xy 389.901926 5.953277) (xy 389.816543 5.945365) (xy 389.730793 5.945365)
			(xy 389.64541 5.953277) (xy 389.56112 5.969033) (xy 389.478644 5.9925) (xy 389.398685 6.023476) (xy 389.321925 6.061698)
			(xy 389.249019 6.106839) (xy 389.18059 6.158515) (xy 389.11722 6.216284) (xy 389.059451 6.279654)
			(xy 389.007775 6.348083) (xy 388.962634 6.420989) (xy 388.924412 6.497749) (xy 388.893436 6.577708)
			(xy 388.869969 6.660184) (xy 388.854213 6.744474) (xy 388.846301 6.829857) (xy 384.351035 6.829857)
			(xy 384.343123 6.744474) (xy 384.327367 6.660184) (xy 384.3039 6.577708) (xy 384.272924 6.497749)
			(xy 384.234702 6.420989) (xy 384.189561 6.348083) (xy 384.137885 6.279654) (xy 384.080116 6.216284)
			(xy 384.016746 6.158515) (xy 383.948317 6.106839) (xy 383.875411 6.061698) (xy 383.798651 6.023476)
			(xy 383.718692 5.9925) (xy 383.636216 5.969033) (xy 383.551926 5.953277) (xy 383.466543 5.945365)
			(xy 383.380793 5.945365) (xy 383.29541 5.953277) (xy 383.21112 5.969033) (xy 383.128644 5.9925) (xy 383.048685 6.023476)
			(xy 382.971925 6.061698) (xy 382.899019 6.106839) (xy 382.83059 6.158515) (xy 382.76722 6.216284)
			(xy 382.709451 6.279654) (xy 382.657775 6.348083) (xy 382.612634 6.420989) (xy 382.574412 6.497749)
			(xy 382.543436 6.577708) (xy 382.519969 6.660184) (xy 382.504213 6.744474) (xy 382.496301 6.829857)
			(xy 332.50079 6.829857) (xy 332.500491 6.803949) (xy 332.492579 6.718566) (xy 332.476823 6.634276)
			(xy 332.453356 6.5518) (xy 332.42238 6.471841) (xy 332.384158 6.395081) (xy 332.339017 6.322175)
			(xy 332.287341 6.253746) (xy 332.229572 6.190376) (xy 332.166202 6.132607) (xy 332.097773 6.080931)
			(xy 332.024867 6.03579) (xy 331.948107 5.997568) (xy 331.868148 5.966592) (xy 331.785672 5.943125)
			(xy 331.701382 5.927369) (xy 331.615999 5.919457) (xy 331.530249 5.919457) (xy 331.444866 5.927369)
			(xy 331.360576 5.943125) (xy 331.2781 5.966592) (xy 331.198141 5.997568) (xy 331.121381 6.03579)
			(xy 331.048475 6.080931) (xy 330.980046 6.132607) (xy 330.916676 6.190376) (xy 330.858907 6.253746)
			(xy 330.807231 6.322175) (xy 330.76209 6.395081) (xy 330.723868 6.471841) (xy 330.692892 6.5518)
			(xy 330.669425 6.634276) (xy 330.653669 6.718566) (xy 330.645757 6.803949) (xy 326.150491 6.803949)
			(xy 326.142579 6.718566) (xy 326.126823 6.634276) (xy 326.103356 6.5518) (xy 326.07238 6.471841)
			(xy 326.034158 6.395081) (xy 325.989017 6.322175) (xy 325.937341 6.253746) (xy 325.879572 6.190376)
			(xy 325.816202 6.132607) (xy 325.747773 6.080931) (xy 325.674867 6.03579) (xy 325.598107 5.997568)
			(xy 325.518148 5.966592) (xy 325.435672 5.943125) (xy 325.351382 5.927369) (xy 325.265999 5.919457)
			(xy 325.180249 5.919457) (xy 325.094866 5.927369) (xy 325.010576 5.943125) (xy 324.9281 5.966592)
			(xy 324.848141 5.997568) (xy 324.771381 6.03579) (xy 324.698475 6.080931) (xy 324.630046 6.132607)
			(xy 324.566676 6.190376) (xy 324.508907 6.253746) (xy 324.457231 6.322175) (xy 324.41209 6.395081)
			(xy 324.373868 6.471841) (xy 324.342892 6.5518) (xy 324.319425 6.634276) (xy 324.303669 6.718566)
			(xy 324.295757 6.803949) (xy 317.930117 6.803949) (xy 317.930035 6.796837) (xy 317.922123 6.711454)
			(xy 317.906367 6.627164) (xy 317.8829 6.544688) (xy 317.851924 6.464729) (xy 317.813702 6.387969)
			(xy 317.768561 6.315063) (xy 317.716885 6.246634) (xy 317.659116 6.183264) (xy 317.595746 6.125495)
			(xy 317.527317 6.073819) (xy 317.454411 6.028678) (xy 317.377651 5.990456) (xy 317.297692 5.95948)
			(xy 317.215216 5.936013) (xy 317.130926 5.920257) (xy 317.045543 5.912345) (xy 316.959793 5.912345)
			(xy 316.87441 5.920257) (xy 316.79012 5.936013) (xy 316.707644 5.95948) (xy 316.627685 5.990456)
			(xy 316.550925 6.028678) (xy 316.478019 6.073819) (xy 316.40959 6.125495) (xy 316.34622 6.183264)
			(xy 316.288451 6.246634) (xy 316.236775 6.315063) (xy 316.191634 6.387969) (xy 316.153412 6.464729)
			(xy 316.122436 6.544688) (xy 316.098969 6.627164) (xy 316.083213 6.711454) (xy 316.075301 6.796837)
			(xy 311.580035 6.796837) (xy 311.572123 6.711454) (xy 311.556367 6.627164) (xy 311.5329 6.544688)
			(xy 311.501924 6.464729) (xy 311.463702 6.387969) (xy 311.418561 6.315063) (xy 311.366885 6.246634)
			(xy 311.309116 6.183264) (xy 311.245746 6.125495) (xy 311.177317 6.073819) (xy 311.104411 6.028678)
			(xy 311.027651 5.990456) (xy 310.947692 5.95948) (xy 310.865216 5.936013) (xy 310.780926 5.920257)
			(xy 310.695543 5.912345) (xy 310.609793 5.912345) (xy 310.52441 5.920257) (xy 310.44012 5.936013)
			(xy 310.357644 5.95948) (xy 310.277685 5.990456) (xy 310.200925 6.028678) (xy 310.128019 6.073819)
			(xy 310.05959 6.125495) (xy 309.99622 6.183264) (xy 309.938451 6.246634) (xy 309.886775 6.315063)
			(xy 309.841634 6.387969) (xy 309.803412 6.464729) (xy 309.772436 6.544688) (xy 309.748969 6.627164)
			(xy 309.733213 6.711454) (xy 309.725301 6.796837) (xy 259.72979 6.796837) (xy 259.729491 6.770929)
			(xy 259.721579 6.685546) (xy 259.705823 6.601256) (xy 259.682356 6.51878) (xy 259.65138 6.438821)
			(xy 259.613158 6.362061) (xy 259.568017 6.289155) (xy 259.516341 6.220726) (xy 259.458572 6.157356)
			(xy 259.395202 6.099587) (xy 259.326773 6.047911) (xy 259.253867 6.00277) (xy 259.177107 5.964548)
			(xy 259.097148 5.933572) (xy 259.014672 5.910105) (xy 258.930382 5.894349) (xy 258.844999 5.886437)
			(xy 258.759249 5.886437) (xy 258.673866 5.894349) (xy 258.589576 5.910105) (xy 258.5071 5.933572)
			(xy 258.427141 5.964548) (xy 258.350381 6.00277) (xy 258.277475 6.047911) (xy 258.209046 6.099587)
			(xy 258.145676 6.157356) (xy 258.087907 6.220726) (xy 258.036231 6.289155) (xy 257.99109 6.362061)
			(xy 257.952868 6.438821) (xy 257.921892 6.51878) (xy 257.898425 6.601256) (xy 257.882669 6.685546)
			(xy 257.874757 6.770929) (xy 253.379491 6.770929) (xy 253.371579 6.685546) (xy 253.355823 6.601256)
			(xy 253.332356 6.51878) (xy 253.30138 6.438821) (xy 253.263158 6.362061) (xy 253.218017 6.289155)
			(xy 253.166341 6.220726) (xy 253.108572 6.157356) (xy 253.045202 6.099587) (xy 252.976773 6.047911)
			(xy 252.903867 6.00277) (xy 252.827107 5.964548) (xy 252.747148 5.933572) (xy 252.664672 5.910105)
			(xy 252.580382 5.894349) (xy 252.494999 5.886437) (xy 252.409249 5.886437) (xy 252.323866 5.894349)
			(xy 252.239576 5.910105) (xy 252.1571 5.933572) (xy 252.077141 5.964548) (xy 252.000381 6.00277)
			(xy 251.927475 6.047911) (xy 251.859046 6.099587) (xy 251.795676 6.157356) (xy 251.737907 6.220726)
			(xy 251.686231 6.289155) (xy 251.64109 6.362061) (xy 251.602868 6.438821) (xy 251.571892 6.51878)
			(xy 251.548425 6.601256) (xy 251.532669 6.685546) (xy 251.524757 6.770929) (xy 245.921117 6.770929)
			(xy 245.921035 6.763817) (xy 245.913123 6.678434) (xy 245.897367 6.594144) (xy 245.8739 6.511668)
			(xy 245.842924 6.431709) (xy 245.804702 6.354949) (xy 245.759561 6.282043) (xy 245.707885 6.213614)
			(xy 245.650116 6.150244) (xy 245.586746 6.092475) (xy 245.518317 6.040799) (xy 245.445411 5.995658)
			(xy 245.368651 5.957436) (xy 245.288692 5.92646) (xy 245.206216 5.902993) (xy 245.121926 5.887237)
			(xy 245.036543 5.879325) (xy 244.950793 5.879325) (xy 244.86541 5.887237) (xy 244.78112 5.902993)
			(xy 244.698644 5.92646) (xy 244.618685 5.957436) (xy 244.541925 5.995658) (xy 244.469019 6.040799)
			(xy 244.40059 6.092475) (xy 244.33722 6.150244) (xy 244.279451 6.213614) (xy 244.227775 6.282043)
			(xy 244.182634 6.354949) (xy 244.144412 6.431709) (xy 244.113436 6.511668) (xy 244.089969 6.594144)
			(xy 244.074213 6.678434) (xy 244.066301 6.763817) (xy 239.571035 6.763817) (xy 239.563123 6.678434)
			(xy 239.547367 6.594144) (xy 239.5239 6.511668) (xy 239.492924 6.431709) (xy 239.454702 6.354949)
			(xy 239.409561 6.282043) (xy 239.357885 6.213614) (xy 239.300116 6.150244) (xy 239.236746 6.092475)
			(xy 239.168317 6.040799) (xy 239.095411 5.995658) (xy 239.018651 5.957436) (xy 238.938692 5.92646)
			(xy 238.856216 5.902993) (xy 238.771926 5.887237) (xy 238.686543 5.879325) (xy 238.600793 5.879325)
			(xy 238.51541 5.887237) (xy 238.43112 5.902993) (xy 238.348644 5.92646) (xy 238.268685 5.957436)
			(xy 238.191925 5.995658) (xy 238.119019 6.040799) (xy 238.05059 6.092475) (xy 237.98722 6.150244)
			(xy 237.929451 6.213614) (xy 237.877775 6.282043) (xy 237.832634 6.354949) (xy 237.794412 6.431709)
			(xy 237.763436 6.511668) (xy 237.739969 6.594144) (xy 237.724213 6.678434) (xy 237.716301 6.763817)
			(xy 187.719832 6.763817) (xy 187.712579 6.685546) (xy 187.696823 6.601256) (xy 187.673356 6.51878)
			(xy 187.64238 6.438821) (xy 187.604158 6.362061) (xy 187.559017 6.289155) (xy 187.507341 6.220726)
			(xy 187.449572 6.157356) (xy 187.386202 6.099587) (xy 187.317773 6.047911) (xy 187.244867 6.00277)
			(xy 187.168107 5.964548) (xy 187.088148 5.933572) (xy 187.005672 5.910105) (xy 186.921382 5.894349)
			(xy 186.835999 5.886437) (xy 186.750249 5.886437) (xy 186.664866 5.894349) (xy 186.580576 5.910105)
			(xy 186.4981 5.933572) (xy 186.418141 5.964548) (xy 186.341381 6.00277) (xy 186.268475 6.047911)
			(xy 186.200046 6.099587) (xy 186.136676 6.157356) (xy 186.078907 6.220726) (xy 186.027231 6.289155)
			(xy 185.98209 6.362061) (xy 185.943868 6.438821) (xy 185.912892 6.51878) (xy 185.889425 6.601256)
			(xy 185.873669 6.685546) (xy 185.865757 6.770929) (xy 181.370491 6.770929) (xy 181.362579 6.685546)
			(xy 181.346823 6.601256) (xy 181.323356 6.51878) (xy 181.29238 6.438821) (xy 181.254158 6.362061)
			(xy 181.209017 6.289155) (xy 181.157341 6.220726) (xy 181.099572 6.157356) (xy 181.036202 6.099587)
			(xy 180.967773 6.047911) (xy 180.894867 6.00277) (xy 180.818107 5.964548) (xy 180.738148 5.933572)
			(xy 180.655672 5.910105) (xy 180.571382 5.894349) (xy 180.485999 5.886437) (xy 180.400249 5.886437)
			(xy 180.314866 5.894349) (xy 180.230576 5.910105) (xy 180.1481 5.933572) (xy 180.068141 5.964548)
			(xy 179.991381 6.00277) (xy 179.918475 6.047911) (xy 179.850046 6.099587) (xy 179.786676 6.157356)
			(xy 179.728907 6.220726) (xy 179.677231 6.289155) (xy 179.63209 6.362061) (xy 179.593868 6.438821)
			(xy 179.562892 6.51878) (xy 179.539425 6.601256) (xy 179.523669 6.685546) (xy 179.515757 6.770929)
			(xy 158.039844 6.770929) (xy 158.030561 6.759289) (xy 157.936801 6.654373) (xy 157.837306 6.554879)
			(xy 157.732388 6.46112) (xy 157.622379 6.373391) (xy 157.507624 6.291969) (xy 157.388483 6.21711)
			(xy 157.265333 6.149048) (xy 157.138561 6.087998) (xy 157.008565 6.034153) (xy 156.875754 5.987681)
			(xy 156.740546 5.948729) (xy 156.603367 5.91742) (xy 156.464649 5.893851) (xy 156.324827 5.878098)
			(xy 156.184341 5.870209) (xy 156.113988 5.869686) (xy 17.493996 5.869686) (xy 17.423642 5.870179)
			(xy 17.283156 5.878069) (xy 17.143333 5.893824) (xy 17.004613 5.917393) (xy 16.867433 5.948703) (xy 16.732225 5.987656)
			(xy 16.599413 6.034129) (xy 16.469416 6.087976) (xy 16.342643 6.149026) (xy 16.219492 6.217089) (xy 16.100351 6.29195)
			(xy 15.985596 6.373373) (xy 15.875586 6.461103) (xy 15.770668 6.554863) (xy 15.671172 6.654358) (xy 15.577412 6.759275)
			(xy 15.489682 6.869284) (xy 15.408258 6.98404) (xy 15.333396 7.10318) (xy 15.265333 7.22633) (xy 15.204281 7.353103)
			(xy 15.150434 7.4831) (xy 15.103961 7.615912) (xy 15.065007 7.75112) (xy 15.033696 7.8883) (xy 15.010125 8.027019)
			(xy 14.99437 8.166842) (xy 14.98648 8.307328) (xy 14.986 8.377682) (xy 14.986 24.157686) (xy 14.985478 24.213493)
			(xy 14.977137 24.324795) (xy 14.960501 24.435162) (xy 14.935664 24.543977) (xy 14.902765 24.650632)
			(xy 14.861988 24.754531) (xy 14.81356 24.855091) (xy 14.757753 24.951752) (xy 14.694879 25.043971)
			(xy 14.625289 25.131234) (xy 14.549372 25.213053) (xy 14.467553 25.28897) (xy 14.38029 25.35856)
			(xy 14.28807 25.421434) (xy 14.19141 25.477241) (xy 14.090849 25.525669) (xy 13.986951 25.566446)
			(xy 13.880295 25.599345) (xy 13.77148 25.624182) (xy 13.661113 25.640817) (xy 13.549811 25.649158)
			(xy 13.494004 25.649682) (xy 1.999996 25.649682) (xy 1.944189 25.64916) (xy 1.832887 25.640819) (xy 1.72252 25.624184)
			(xy 1.613704 25.599347) (xy 1.507049 25.566448) (xy 1.40315 25.525671) (xy 1.30259 25.477243) (xy 1.205929 25.421436)
			(xy 1.113709 25.358562) (xy 1.026446 25.288971) (xy 0.944627 25.213055) (xy 0.86871 25.131236) (xy 0.79912 25.043972)
			(xy 0.736245 24.951753) (xy 0.680438 24.855092) (xy 0.63201 24.754532) (xy 0.591233 24.650633) (xy 0.558334 24.543978)
			(xy 0.533497 24.435162) (xy 0.516861 24.324795) (xy 0.50852 24.213493) (xy 0.508 24.157686) (xy 0.508 21.093122)
			(xy 2.904225 21.093122) (xy 2.904225 21.222262) (xy 2.912175 21.351157) (xy 2.928045 21.479317) (xy 2.951774 21.606258)
			(xy 2.983273 21.731497) (xy 3.022422 21.85456) (xy 3.069073 21.974979) (xy 3.123048 22.092298) (xy 3.184143 22.206072)
			(xy 3.252126 22.315869) (xy 3.32674 22.421272) (xy 3.407701 22.521882) (xy 3.494701 22.617317) (xy 3.587412 22.707216)
			(xy 3.685482 22.791237) (xy 3.788537 22.869061) (xy 3.896188 22.940393) (xy 4.008027 23.004963) (xy 4.123628 23.062525)
			(xy 4.242553 23.112862) (xy 4.364352 23.155782) (xy 4.488562 23.191123) (xy 4.614711 23.21875) (xy 4.742323 23.238559)
			(xy 4.870912 23.250475) (xy 4.99999 23.254452) (xy 5.129068 23.250475) (xy 5.257657 23.238559) (xy 5.385269 23.21875)
			(xy 5.511418 23.191123) (xy 5.635628 23.155782) (xy 5.757427 23.112862) (xy 5.876352 23.062525) (xy 5.991953 23.004963)
			(xy 6.103792 22.940393) (xy 6.211443 22.869061) (xy 6.314498 22.791237) (xy 6.412568 22.707216) (xy 6.505279 22.617317)
			(xy 6.592279 22.521882) (xy 6.67324 22.421272) (xy 6.747854 22.315869) (xy 6.815837 22.206072) (xy 6.876932 22.092298)
			(xy 6.930907 21.974979) (xy 6.977558 21.85456) (xy 7.016707 21.731497) (xy 7.048206 21.606258) (xy 7.071935 21.479317)
			(xy 7.087805 21.351157) (xy 7.095755 21.222262) (xy 7.096252 21.157692) (xy 7.095755 21.093122) (xy 7.087805 20.964227)
			(xy 7.071935 20.836067) (xy 7.048206 20.709126) (xy 7.016707 20.583887) (xy 6.977558 20.460824) (xy 6.930907 20.340405)
			(xy 6.876932 20.223086) (xy 6.815837 20.109312) (xy 6.747854 19.999515) (xy 6.67324 19.894112) (xy 6.592279 19.793502)
			(xy 6.505279 19.698067) (xy 6.412568 19.608168) (xy 6.314498 19.524147) (xy 6.211443 19.446323) (xy 6.103792 19.374991)
			(xy 5.991953 19.310421) (xy 5.876352 19.252859) (xy 5.757427 19.202522) (xy 5.635628 19.159602) (xy 5.511418 19.124261)
			(xy 5.385269 19.096634) (xy 5.257657 19.076825) (xy 5.129068 19.064909) (xy 4.99999 19.060933) (xy 4.870912 19.064909)
			(xy 4.742323 19.076825) (xy 4.614711 19.096634) (xy 4.488562 19.124261) (xy 4.364352 19.159602) (xy 4.242553 19.202522)
			(xy 4.123628 19.252859) (xy 4.008027 19.310421) (xy 3.896188 19.374991) (xy 3.788537 19.446323) (xy 3.685482 19.524147)
			(xy 3.587412 19.608168) (xy 3.494701 19.698067) (xy 3.407701 19.793502) (xy 3.32674 19.894112) (xy 3.252126 19.999515)
			(xy 3.184143 20.109312) (xy 3.123048 20.223086) (xy 3.069073 20.340405) (xy 3.022422 20.460824) (xy 2.983273 20.583887)
			(xy 2.951774 20.709126) (xy 2.928045 20.836067) (xy 2.912175 20.964227) (xy 2.904225 21.093122) (xy 0.508 21.093122)
			(xy 0.508 3.999992) (xy 0.508522 3.944185) (xy 0.516863 3.832883) (xy 0.533498 3.722516) (xy 0.558335 3.6137)
			(xy 0.591234 3.507045) (xy 0.632011 3.403146) (xy 0.680438 3.302586) (xy 0.736246 3.205925) (xy 0.79912 3.113705)
			(xy 0.86871 3.026442) (xy 0.944627 2.944623) (xy 1.026446 2.868706) (xy 1.113709 2.799116) (xy 1.205929 2.736242)
			(xy 1.30259 2.680434) (xy 1.40315 2.632007) (xy 1.507049 2.59123) (xy 1.613704 2.558331) (xy 1.72252 2.533494)
			(xy 1.832887 2.516859) (xy 1.944189 2.508518) (xy 1.999996 2.507996) (xy 7.964932 2.507996) (xy 8.035286 2.507503)
			(xy 8.175772 2.499613) (xy 8.315594 2.483859) (xy 8.454314 2.460289) (xy 8.591493 2.428979) (xy 8.726701 2.390026)
			(xy 8.859513 2.343553) (xy 8.989509 2.289707) (xy 9.116282 2.228656) (xy 9.239433 2.160593) (xy 9.358573 2.085732)
			(xy 9.473329 2.004309) (xy 9.583338 1.916579) (xy 9.688255 1.822819) (xy 9.78775 1.723324) (xy 9.88151 1.618406)
			(xy 9.96924 1.508397) (xy 10.050663 1.393641) (xy 10.125524 1.274501) (xy 10.193587 1.151351) (xy 10.254637 1.024578)
			(xy 10.308484 0.894581) (xy 10.354957 0.76177) (xy 10.393909 0.626561) (xy 10.42522 0.489382) (xy 10.448789 0.350662)
			(xy 10.464543 0.21084) (xy 10.472433 0.070354) (xy 10.472928 0) (xy 10.472928 -8.850122) (xy 10.47345 -8.905929)
			(xy 10.481791 -9.017231) (xy 10.498426 -9.127599) (xy 10.523263 -9.236414) (xy 10.556162 -9.34307)
			(xy 10.596939 -9.446968) (xy 10.645366 -9.547529) (xy 10.701173 -9.64419) (xy 10.764048 -9.73641)
			(xy 10.833638 -9.823673) (xy 10.909555 -9.905492) (xy 10.991374 -9.981409) (xy 11.078637 -10.051)
			(xy 11.170857 -10.113875) (xy 11.267517 -10.169682) (xy 11.368078 -10.21811) (xy 11.471977 -10.258887)
			(xy 11.578632 -10.291786) (xy 11.687448 -10.316623) (xy 11.797815 -10.333259) (xy 11.909117 -10.3416)
			(xy 11.964924 -10.342118)
		)
		(stroke
			(width 0)
			(type solid)
		)
		(fill yes)
		(layer "In8.Cu")
		(net "COUPON_GND2")
	)
	(gr_poly
		(pts
			(xy 200.481692 -418.081968) (xy 200.538276 -418.081432) (xy 200.651116 -418.072836) (xy 200.76298 -418.055715)
			(xy 200.873227 -418.030169) (xy 200.98122 -417.996343) (xy 201.086341 -417.954433) (xy 201.187984 -417.904678)
			(xy 201.285565 -417.847366) (xy 201.378524 -417.782825) (xy 201.466326 -417.711427) (xy 201.548466 -417.633582)
			(xy 201.586846 -417.592002) (xy 201.634058 -417.54062) (xy 201.733379 -417.442584) (xy 201.837997 -417.350223)
			(xy 201.947589 -417.26382) (xy 202.061814 -417.183644) (xy 202.18032 -417.109943) (xy 202.302741 -417.042944)
			(xy 202.428697 -416.982855) (xy 202.557798 -416.929861) (xy 202.689647 -416.884127) (xy 202.823834 -416.845794)
			(xy 202.959945 -416.81498) (xy 203.097558 -416.791782) (xy 203.236248 -416.77627) (xy 203.375587 -416.768492)
			(xy 203.445364 -416.768026) (xy 271.794732 -416.768026) (xy 271.864502 -416.768512) (xy 272.003824 -416.776289)
			(xy 272.142499 -416.791801) (xy 272.280097 -416.814999) (xy 272.416192 -416.845812) (xy 272.550363 -416.884144)
			(xy 272.682195 -416.929877) (xy 272.811281 -416.982869) (xy 272.937221 -417.042957) (xy 273.059624 -417.109954)
			(xy 273.178113 -417.183654) (xy 273.292321 -417.263827) (xy 273.401895 -417.350227) (xy 273.434939 -417.379404)
			(xy 313.073796 -417.379404) (xy 313.073796 -394.27912) (xy 326.479662 -394.27912) (xy 326.525636 -394.325094)
			(xy 326.525636 -397.823826) (xy 330.929171 -397.823826) (xy 330.929175 -397.756517) (xy 330.937223 -397.689692)
			(xy 330.953201 -397.624307) (xy 330.976879 -397.561301) (xy 331.007918 -397.501576) (xy 331.045873 -397.44599)
			(xy 331.067664 -397.420338) (xy 331.073477 -397.413205) (xy 331.07998 -397.396005) (xy 331.080364 -397.38681)
			(xy 331.080364 -396.893542) (xy 331.079919 -396.884359) (xy 331.073428 -396.867175) (xy 331.067664 -396.860014)
			(xy 331.045866 -396.83437) (xy 331.007916 -396.778783) (xy 330.976881 -396.719059) (xy 330.953208 -396.656053)
			(xy 330.937235 -396.59067) (xy 330.929191 -396.523846) (xy 330.929192 -396.456539) (xy 330.937238 -396.389716)
			(xy 330.953213 -396.324333) (xy 330.976888 -396.261328) (xy 331.007923 -396.201604) (xy 331.045875 -396.146018)
			(xy 331.067664 -396.120366) (xy 331.073465 -396.113225) (xy 331.079975 -396.096031) (xy 331.080364 -396.086838)
			(xy 331.080364 -395.92885) (xy 331.080805 -395.918678) (xy 331.088579 -395.89988) (xy 331.10296 -395.885492)
			(xy 331.121755 -395.87771) (xy 331.131926 -395.877288) (xy 331.848206 -395.877288) (xy 331.858384 -395.87766)
			(xy 331.877189 -395.885456) (xy 331.891575 -395.899859) (xy 331.899351 -395.918671) (xy 331.899768 -395.92885)
			(xy 331.899768 -396.086838) (xy 331.900167 -396.096026) (xy 331.906689 -396.11321) (xy 331.912468 -396.120366)
			(xy 331.934246 -396.146026) (xy 331.972195 -396.201612) (xy 332.003228 -396.261334) (xy 332.026901 -396.324338)
			(xy 332.042874 -396.389719) (xy 332.050919 -396.45654) (xy 332.05092 -396.523845) (xy 332.042877 -396.590666)
			(xy 332.026905 -396.656048) (xy 332.003234 -396.719052) (xy 331.972202 -396.778775) (xy 331.934255 -396.834362)
			(xy 331.912468 -396.860014) (xy 331.906679 -396.867164) (xy 331.90016 -396.884351) (xy 331.899768 -396.893542)
			(xy 331.899768 -397.38681) (xy 331.90018 -397.395997) (xy 331.906693 -397.413181) (xy 331.912468 -397.420338)
			(xy 331.934218 -397.446021) (xy 331.972167 -397.501603) (xy 332.00059 -397.556296) (xy 333.128836 -397.556296)
			(xy 333.136911 -397.489358) (xy 333.152946 -397.423869) (xy 333.17671 -397.360773) (xy 333.20786 -397.300977)
			(xy 333.245948 -397.245343) (xy 333.267812 -397.219678) (xy 333.273602 -397.212528) (xy 333.28012 -397.195341)
			(xy 333.280512 -397.18615) (xy 333.280512 -397.028924) (xy 333.280936 -397.018802) (xy 333.288678 -397.000096)
			(xy 333.302993 -396.985781) (xy 333.321698 -396.978037) (xy 333.33182 -396.977616) (xy 334.0481 -396.977616)
			(xy 334.058224 -396.978016) (xy 334.076931 -396.985768) (xy 334.091246 -397.000089) (xy 334.098988 -397.018799)
			(xy 334.099408 -397.028924) (xy 334.099408 -397.18615) (xy 334.09984 -397.195335) (xy 334.106338 -397.21252)
			(xy 334.112108 -397.219678) (xy 334.133982 -397.245335) (xy 334.172069 -397.300971) (xy 334.203219 -397.360769)
			(xy 334.226982 -397.423866) (xy 334.243017 -397.489356) (xy 334.251092 -397.556295) (xy 334.251091 -397.62372)
			(xy 334.243014 -397.690658) (xy 334.226978 -397.756148) (xy 334.203213 -397.819245) (xy 334.200796 -397.823884)
			(xy 335.328964 -397.823884) (xy 335.328968 -397.756459) (xy 335.337047 -397.689518) (xy 335.353085 -397.624028)
			(xy 335.376852 -397.560929) (xy 335.408005 -397.501132) (xy 335.446095 -397.445496) (xy 335.46796 -397.41983)
			(xy 335.473776 -397.412699) (xy 335.480277 -397.395497) (xy 335.48066 -397.386302) (xy 335.48066 -396.89405)
			(xy 335.480213 -396.884867) (xy 335.473723 -396.867683) (xy 335.46796 -396.860522) (xy 335.446088 -396.834864)
			(xy 335.408002 -396.779228) (xy 335.376854 -396.71943) (xy 335.353092 -396.656332) (xy 335.337058 -396.590843)
			(xy 335.328984 -396.523904) (xy 335.328985 -396.456481) (xy 335.337061 -396.389542) (xy 335.353096 -396.324053)
			(xy 335.37686 -396.260956) (xy 335.40801 -396.201159) (xy 335.446097 -396.145524) (xy 335.46796 -396.119858)
			(xy 335.473764 -396.112719) (xy 335.480273 -396.095523) (xy 335.48066 -396.08633) (xy 335.48066 -395.92885)
			(xy 335.481168 -395.918724) (xy 335.488883 -395.9) (xy 335.503164 -395.885642) (xy 335.521845 -395.877824)
			(xy 335.531968 -395.877288) (xy 336.248248 -395.877288) (xy 336.258404 -395.877682) (xy 336.277155 -395.885491)
			(xy 336.291476 -395.899896) (xy 336.299176 -395.918692) (xy 336.299556 -395.92885) (xy 336.299556 -396.08633)
			(xy 336.299962 -396.095517) (xy 336.30648 -396.112701) (xy 336.312256 -396.119858) (xy 336.334112 -396.145531)
			(xy 336.372204 -396.201163) (xy 336.403357 -396.260958) (xy 336.427124 -396.324054) (xy 336.443161 -396.389542)
			(xy 336.451239 -396.456481) (xy 336.45124 -396.523904) (xy 336.443164 -396.590843) (xy 336.427128 -396.656332)
			(xy 336.403363 -396.719428) (xy 336.372211 -396.779224) (xy 336.334121 -396.834858) (xy 336.312256 -396.860522)
			(xy 336.306462 -396.867669) (xy 336.299947 -396.884858) (xy 336.299556 -396.89405) (xy 336.299556 -397.386302)
			(xy 336.299975 -397.395488) (xy 336.306484 -397.412672) (xy 336.312256 -397.41983) (xy 336.334084 -397.445525)
			(xy 336.372177 -397.501154) (xy 336.40094 -397.556356) (xy 337.529156 -397.556356) (xy 337.537198 -397.489535)
			(xy 337.553169 -397.424153) (xy 337.576839 -397.361149) (xy 337.607869 -397.301426) (xy 337.645814 -397.245839)
			(xy 337.6676 -397.220186) (xy 337.673385 -397.213033) (xy 337.679907 -397.195848) (xy 337.6803 -397.186658)
			(xy 337.6803 -397.028924) (xy 337.680741 -397.018771) (xy 337.688529 -397.000019) (xy 337.70292 -396.985695)
			(xy 337.721708 -396.977995) (xy 337.731862 -396.977616) (xy 338.448142 -396.977616) (xy 338.458268 -396.978091)
			(xy 338.476986 -396.985829) (xy 338.49134 -397.000118) (xy 338.499162 -397.0188) (xy 338.499704 -397.028924)
			(xy 338.499704 -397.186658) (xy 338.500133 -397.195843) (xy 338.506634 -397.213028) (xy 338.512404 -397.220186)
			(xy 338.5342 -397.245831) (xy 338.572146 -397.301419) (xy 338.603176 -397.361144) (xy 338.626847 -397.42415)
			(xy 338.642818 -397.489532) (xy 338.65086 -397.556355) (xy 338.650859 -397.62366) (xy 338.642815 -397.690483)
			(xy 338.626842 -397.755865) (xy 338.60317 -397.81887) (xy 338.600595 -397.823826) (xy 339.729259 -397.823826)
			(xy 339.729263 -397.756517) (xy 339.737311 -397.689692) (xy 339.753288 -397.624308) (xy 339.776965 -397.561301)
			(xy 339.808004 -397.501577) (xy 339.845958 -397.44599) (xy 339.867748 -397.420338) (xy 339.873559 -397.413204)
			(xy 339.880064 -397.396005) (xy 339.880448 -397.38681) (xy 339.880448 -396.893542) (xy 339.880007 -396.884358)
			(xy 339.873513 -396.867174) (xy 339.867748 -396.860014) (xy 339.84595 -396.83437) (xy 339.808001 -396.778783)
			(xy 339.776968 -396.719058) (xy 339.753295 -396.656052) (xy 339.737322 -396.590669) (xy 339.729279 -396.523845)
			(xy 339.72928 -396.456539) (xy 339.737325 -396.389716) (xy 339.753299 -396.324333) (xy 339.776974 -396.261328)
			(xy 339.808009 -396.201604) (xy 339.845959 -396.146018) (xy 339.867748 -396.120366) (xy 339.873547 -396.113223)
			(xy 339.880059 -396.096031) (xy 339.880448 -396.086838) (xy 339.880448 -395.92885) (xy 339.880905 -395.91868)
			(xy 339.888675 -395.899885) (xy 339.903051 -395.885498) (xy 339.921841 -395.877713) (xy 339.93201 -395.877288)
			(xy 340.64829 -395.877288) (xy 340.658467 -395.877673) (xy 340.677271 -395.885464) (xy 340.691658 -395.899862)
			(xy 340.699435 -395.918672) (xy 340.699852 -395.92885) (xy 340.699852 -396.086838) (xy 340.700255 -396.096026)
			(xy 340.706775 -396.113209) (xy 340.712552 -396.120366) (xy 340.73433 -396.146026) (xy 340.77228 -396.201611)
			(xy 340.803314 -396.261334) (xy 340.826988 -396.324337) (xy 340.842962 -396.389718) (xy 340.851007 -396.45654)
			(xy 340.851007 -396.523845) (xy 340.842964 -396.590667) (xy 340.826992 -396.656048) (xy 340.80332 -396.719053)
			(xy 340.772287 -396.778776) (xy 340.734339 -396.834362) (xy 340.712552 -396.860014) (xy 340.706761 -396.867163)
			(xy 340.700244 -396.884351) (xy 340.699852 -396.893542) (xy 340.699852 -397.38681) (xy 340.700268 -397.395996)
			(xy 340.706779 -397.41318) (xy 340.712552 -397.420338) (xy 340.734302 -397.446021) (xy 340.772253 -397.501603)
			(xy 340.800676 -397.556296) (xy 341.928924 -397.556296) (xy 341.936999 -397.489359) (xy 341.953033 -397.42387)
			(xy 341.976796 -397.360774) (xy 342.007946 -397.300978) (xy 342.046033 -397.245343) (xy 342.067896 -397.219678)
			(xy 342.073684 -397.212527) (xy 342.080204 -397.195341) (xy 342.080596 -397.18615) (xy 342.080596 -397.028924)
			(xy 342.081035 -397.018804) (xy 342.088775 -397.000101) (xy 342.103084 -396.985786) (xy 342.121784 -396.978039)
			(xy 342.131904 -396.977616) (xy 342.848184 -396.977616) (xy 342.858307 -396.978029) (xy 342.877014 -396.985775)
			(xy 342.891329 -397.000093) (xy 342.899072 -397.0188) (xy 342.899492 -397.028924) (xy 342.899492 -397.18615)
			(xy 342.899928 -397.195334) (xy 342.906424 -397.212519) (xy 342.912192 -397.219678) (xy 342.934066 -397.245335)
			(xy 342.972155 -397.300971) (xy 343.003306 -397.360768) (xy 343.02707 -397.423866) (xy 343.043105 -397.489356)
			(xy 343.05118 -397.556295) (xy 343.051179 -397.62372) (xy 343.043102 -397.690659) (xy 343.027065 -397.756149)
			(xy 343.0033 -397.819246) (xy 343.000914 -397.823825) (xy 344.12905 -397.823825) (xy 344.129054 -397.756517)
			(xy 344.137101 -397.689692) (xy 344.153078 -397.624308) (xy 344.176755 -397.561302) (xy 344.207793 -397.501577)
			(xy 344.245746 -397.44599) (xy 344.267536 -397.420338) (xy 344.273346 -397.413202) (xy 344.279852 -397.396004)
			(xy 344.280236 -397.38681) (xy 344.280236 -396.893542) (xy 344.279797 -396.884358) (xy 344.273303 -396.867174)
			(xy 344.267536 -396.860014) (xy 344.245738 -396.83437) (xy 344.20779 -396.778782) (xy 344.176757 -396.719058)
			(xy 344.153085 -396.656052) (xy 344.137113 -396.590669) (xy 344.12907 -396.523845) (xy 344.129071 -396.45654)
			(xy 344.137116 -396.389716) (xy 344.15309 -396.324334) (xy 344.176764 -396.261329) (xy 344.207798 -396.201605)
			(xy 344.245748 -396.146018) (xy 344.267536 -396.120366) (xy 344.273334 -396.113222) (xy 344.279847 -396.09603)
			(xy 344.280236 -396.086838) (xy 344.280236 -395.92885) (xy 344.280705 -395.918682) (xy 344.288473 -395.899889)
			(xy 344.302845 -395.885502) (xy 344.32163 -395.877715) (xy 344.331798 -395.877288) (xy 345.048078 -395.877288)
			(xy 345.058254 -395.877683) (xy 345.077058 -395.88547) (xy 345.091445 -395.899866) (xy 345.099222 -395.918673)
			(xy 345.09964 -395.92885) (xy 345.09964 -396.086838) (xy 345.100045 -396.096025) (xy 345.106564 -396.113209)
			(xy 345.11234 -396.120366) (xy 345.134118 -396.146026) (xy 345.172069 -396.201611) (xy 345.203104 -396.261333)
			(xy 345.226778 -396.324337) (xy 345.242752 -396.389718) (xy 345.250798 -396.45654) (xy 345.250798 -396.523845)
			(xy 345.242755 -396.590667) (xy 345.226782 -396.656049) (xy 345.20311 -396.719053) (xy 345.172077 -396.778776)
			(xy 345.134128 -396.834362) (xy 345.11234 -396.860014) (xy 345.106548 -396.867162) (xy 345.100032 -396.884351)
			(xy 345.09964 -396.893542) (xy 345.09964 -397.38681) (xy 345.100059 -397.395996) (xy 345.106568 -397.41318)
			(xy 345.11234 -397.420338) (xy 345.134091 -397.446021) (xy 345.172042 -397.501602) (xy 345.200497 -397.556355)
			(xy 346.32922 -397.556355) (xy 346.337264 -397.489532) (xy 346.353237 -397.42415) (xy 346.37691 -397.361146)
			(xy 346.407945 -397.301423) (xy 346.445896 -397.245838) (xy 346.467684 -397.220186) (xy 346.473467 -397.213031)
			(xy 346.47999 -397.195848) (xy 346.480384 -397.186658) (xy 346.480384 -397.028924) (xy 346.480841 -397.018773)
			(xy 346.488625 -397.000025) (xy 346.503011 -396.985701) (xy 346.521794 -396.977997) (xy 346.531946 -396.977616)
			(xy 347.248226 -396.977616) (xy 347.258351 -396.978104) (xy 347.277069 -396.985836) (xy 347.291423 -397.000121)
			(xy 347.299246 -397.018801) (xy 347.299788 -397.028924) (xy 347.299788 -397.186658) (xy 347.300221 -397.195843)
			(xy 347.306719 -397.213027) (xy 347.312488 -397.220186) (xy 347.334285 -397.24583) (xy 347.372232 -397.301419)
			(xy 347.403263 -397.361143) (xy 347.426934 -397.424149) (xy 347.442905 -397.489532) (xy 347.450948 -397.556355)
			(xy 347.450947 -397.62366) (xy 347.442903 -397.690483) (xy 347.426929 -397.755865) (xy 347.403257 -397.81887)
			(xy 347.400682 -397.823826) (xy 374.92908 -397.823826) (xy 374.929084 -397.756517) (xy 374.937132 -397.689691)
			(xy 374.95311 -397.624306) (xy 374.976789 -397.5613) (xy 375.007829 -397.501576) (xy 375.045785 -397.445989)
			(xy 375.067576 -397.420338) (xy 375.073379 -397.413197) (xy 375.07989 -397.396003) (xy 375.080276 -397.38681)
			(xy 375.080276 -396.893542) (xy 375.079851 -396.884356) (xy 375.073348 -396.867171) (xy 375.067576 -396.860014)
			(xy 375.045777 -396.83437) (xy 375.007826 -396.778784) (xy 374.976792 -396.719059) (xy 374.953118 -396.656053)
			(xy 374.937144 -396.59067) (xy 374.9291 -396.523846) (xy 374.929101 -396.456539) (xy 374.937147 -396.389715)
			(xy 374.953122 -396.324332) (xy 374.976798 -396.261327) (xy 375.007834 -396.201604) (xy 375.045787 -396.146018)
			(xy 375.067576 -396.120366) (xy 375.073367 -396.113216) (xy 375.079886 -396.096029) (xy 375.080276 -396.086838)
			(xy 375.080276 -395.92885) (xy 375.080706 -395.918677) (xy 375.088481 -395.899876) (xy 375.102866 -395.885488)
			(xy 375.121665 -395.877708) (xy 375.131838 -395.877288) (xy 375.848118 -395.877288) (xy 375.858297 -395.87765)
			(xy 375.877102 -395.885451) (xy 375.891487 -395.899856) (xy 375.899263 -395.91867) (xy 375.89968 -395.92885)
			(xy 375.89968 -396.086838) (xy 375.900076 -396.096027) (xy 375.9066 -396.113211) (xy 375.91238 -396.120366)
			(xy 375.934157 -396.146026) (xy 375.972105 -396.201612) (xy 376.003138 -396.261335) (xy 376.02681 -396.324338)
			(xy 376.042784 -396.389719) (xy 376.050828 -396.456541) (xy 376.050829 -396.523844) (xy 376.042786 -396.590666)
			(xy 376.026815 -396.656047) (xy 376.003144 -396.719051) (xy 375.972113 -396.778775) (xy 375.934167 -396.834362)
			(xy 375.91238 -396.860014) (xy 375.906593 -396.867166) (xy 375.900073 -396.884351) (xy 375.89968 -396.893542)
			(xy 375.89968 -397.38681) (xy 375.90009 -397.395997) (xy 375.906604 -397.413181) (xy 375.91238 -397.420338)
			(xy 375.93413 -397.446021) (xy 375.972078 -397.501604) (xy 376.0005 -397.556296) (xy 377.128745 -397.556296)
			(xy 377.136821 -397.489358) (xy 377.152856 -397.423869) (xy 377.17662 -397.360772) (xy 377.207771 -397.300977)
			(xy 377.24586 -397.245343) (xy 377.267724 -397.219678) (xy 377.273515 -397.212529) (xy 377.280032 -397.195341)
			(xy 377.280424 -397.18615) (xy 377.280424 -397.028924) (xy 377.280836 -397.0188) (xy 377.288581 -397.000092)
			(xy 377.302899 -396.985776) (xy 377.321608 -396.978034) (xy 377.331732 -396.977616) (xy 378.048012 -396.977616)
			(xy 378.058137 -396.978006) (xy 378.076844 -396.985761) (xy 378.091159 -397.000086) (xy 378.098901 -397.018798)
			(xy 378.09932 -397.028924) (xy 378.09932 -397.18615) (xy 378.09975 -397.195335) (xy 378.10625 -397.21252)
			(xy 378.11202 -397.219678) (xy 378.133893 -397.245335) (xy 378.17198 -397.300972) (xy 378.203129 -397.360769)
			(xy 378.226892 -397.423867) (xy 378.242926 -397.489357) (xy 378.251001 -397.556295) (xy 378.251 -397.62372)
			(xy 378.242924 -397.690658) (xy 378.226888 -397.756147) (xy 378.203123 -397.819245) (xy 378.200706 -397.823885)
			(xy 379.328873 -397.823885) (xy 379.328877 -397.756458) (xy 379.336956 -397.689518) (xy 379.352995 -397.624027)
			(xy 379.376762 -397.560929) (xy 379.407915 -397.501131) (xy 379.446007 -397.445496) (xy 379.467872 -397.41983)
			(xy 379.47369 -397.4127) (xy 379.48019 -397.395498) (xy 379.480572 -397.386302) (xy 379.480572 -396.89405)
			(xy 379.480144 -396.884865) (xy 379.473643 -396.86768) (xy 379.467872 -396.860522) (xy 379.445999 -396.834864)
			(xy 379.407913 -396.779228) (xy 379.376764 -396.719431) (xy 379.353002 -396.656333) (xy 379.336968 -396.590843)
			(xy 379.328893 -396.523904) (xy 379.328894 -396.456481) (xy 379.33697 -396.389542) (xy 379.353006 -396.324053)
			(xy 379.37677 -396.260956) (xy 379.40792 -396.201159) (xy 379.446008 -396.145524) (xy 379.467872 -396.119858)
			(xy 379.473678 -396.11272) (xy 379.480185 -396.095524) (xy 379.480572 -396.08633) (xy 379.480572 -395.92885)
			(xy 379.481069 -395.918723) (xy 379.488786 -395.899996) (xy 379.50307 -395.885637) (xy 379.521755 -395.877822)
			(xy 379.53188 -395.877288) (xy 380.24816 -395.877288) (xy 380.258278 -395.877749) (xy 380.276979 -395.885481)
			(xy 380.291294 -395.899784) (xy 380.299043 -395.918478) (xy 380.299468 -395.928596) (xy 380.299468 -396.08633)
			(xy 380.299871 -396.095518) (xy 380.30639 -396.112702) (xy 380.312168 -396.119858) (xy 380.334023 -396.145531)
			(xy 380.372114 -396.201163) (xy 380.403267 -396.260958) (xy 380.427033 -396.324054) (xy 380.443071 -396.389543)
			(xy 380.451148 -396.456481) (xy 380.451149 -396.523904) (xy 380.443073 -396.590842) (xy 380.427038 -396.656331)
			(xy 380.403273 -396.719428) (xy 380.372122 -396.779224) (xy 380.334032 -396.834857) (xy 380.312168 -396.860522)
			(xy 380.306375 -396.86767) (xy 380.299859 -396.884858) (xy 380.299468 -396.89405) (xy 380.299468 -397.386302)
			(xy 380.299884 -397.395488) (xy 380.306394 -397.412672) (xy 380.312168 -397.41983) (xy 380.333996 -397.445525)
			(xy 380.372088 -397.501155) (xy 380.40085 -397.556356) (xy 381.529065 -397.556356) (xy 381.537108 -397.489534)
			(xy 381.553079 -397.424153) (xy 381.576749 -397.361149) (xy 381.60778 -397.301425) (xy 381.645726 -397.245838)
			(xy 381.667512 -397.220186) (xy 381.673298 -397.213034) (xy 381.679819 -397.195849) (xy 381.680212 -397.186658)
			(xy 381.680212 -397.028924) (xy 381.680636 -397.018802) (xy 381.688378 -397.000096) (xy 381.702693 -396.985781)
			(xy 381.721398 -396.978037) (xy 381.73152 -396.977616) (xy 382.448054 -396.977616) (xy 382.458175 -396.978164)
			(xy 382.47689 -396.985872) (xy 382.491247 -397.000139) (xy 382.499072 -397.018806) (xy 382.499616 -397.028924)
			(xy 382.499616 -397.186658) (xy 382.500043 -397.195844) (xy 382.506544 -397.213028) (xy 382.512316 -397.220186)
			(xy 382.534115 -397.245829) (xy 382.572066 -397.301416) (xy 382.603102 -397.36114) (xy 382.626776 -397.424146)
			(xy 382.642749 -397.48953) (xy 382.650793 -397.556354) (xy 382.650793 -397.623661) (xy 382.642747 -397.690485)
			(xy 382.626771 -397.755868) (xy 382.603096 -397.818873) (xy 382.600522 -397.823826) (xy 383.729168 -397.823826)
			(xy 383.729172 -397.756517) (xy 383.73722 -397.689692) (xy 383.753198 -397.624307) (xy 383.776876 -397.561301)
			(xy 383.807914 -397.501576) (xy 383.845869 -397.44599) (xy 383.86766 -397.420338) (xy 383.873473 -397.413205)
			(xy 383.879976 -397.396005) (xy 383.88036 -397.38681) (xy 383.88036 -396.893542) (xy 383.879916 -396.884359)
			(xy 383.873425 -396.867175) (xy 383.86766 -396.860014) (xy 383.845862 -396.83437) (xy 383.807912 -396.778783)
			(xy 383.776878 -396.719058) (xy 383.753205 -396.656053) (xy 383.737232 -396.590669) (xy 383.729188 -396.523846)
			(xy 383.729189 -396.456539) (xy 383.737235 -396.389716) (xy 383.753209 -396.324333) (xy 383.776884 -396.261328)
			(xy 383.80792 -396.201604) (xy 383.845871 -396.146018) (xy 383.86766 -396.120366) (xy 383.873461 -396.113224)
			(xy 383.879971 -396.096031) (xy 383.88036 -396.086838) (xy 383.88036 -395.92885) (xy 383.880805 -395.918679)
			(xy 383.888578 -395.899881) (xy 383.902958 -395.885494) (xy 383.921751 -395.877711) (xy 383.931922 -395.877288)
			(xy 384.648202 -395.877288) (xy 384.65838 -395.877663) (xy 384.677184 -395.885458) (xy 384.691571 -395.899859)
			(xy 384.699347 -395.918672) (xy 384.699764 -395.92885) (xy 384.699764 -396.086838) (xy 384.700164 -396.096026)
			(xy 384.706686 -396.11321) (xy 384.712464 -396.120366) (xy 384.734242 -396.146026) (xy 384.772191 -396.201612)
			(xy 384.803224 -396.261334) (xy 384.826898 -396.324337) (xy 384.842871 -396.389719) (xy 384.850916 -396.45654)
			(xy 384.850917 -396.523845) (xy 384.842874 -396.590666) (xy 384.826902 -396.656048) (xy 384.803231 -396.719052)
			(xy 384.772199 -396.778776) (xy 384.734251 -396.834362) (xy 384.712464 -396.860014) (xy 384.706674 -396.867164)
			(xy 384.700156 -396.884351) (xy 384.699764 -396.893542) (xy 384.699764 -397.38681) (xy 384.700177 -397.395997)
			(xy 384.70669 -397.413181) (xy 384.712464 -397.420338) (xy 384.734214 -397.446021) (xy 384.772164 -397.501603)
			(xy 384.800587 -397.556296) (xy 385.928833 -397.556296) (xy 385.936908 -397.489358) (xy 385.952943 -397.42387)
			(xy 385.976706 -397.360773) (xy 386.007856 -397.300977) (xy 386.045944 -397.245343) (xy 386.067808 -397.219678)
			(xy 386.073597 -397.212528) (xy 386.080116 -397.195341) (xy 386.080508 -397.18615) (xy 386.080508 -397.028924)
			(xy 386.080936 -397.018802) (xy 386.088677 -397.000097) (xy 386.102991 -396.985782) (xy 386.121694 -396.978037)
			(xy 386.131816 -396.977616) (xy 386.848096 -396.977616) (xy 386.85822 -396.97802) (xy 386.876927 -396.985769)
			(xy 386.891242 -397.00009) (xy 386.898984 -397.0188) (xy 386.899404 -397.028924) (xy 386.899404 -397.18615)
			(xy 386.899837 -397.195335) (xy 386.906335 -397.212519) (xy 386.912104 -397.219678) (xy 386.933978 -397.245335)
			(xy 386.972066 -397.300971) (xy 387.003216 -397.360768) (xy 387.026979 -397.423866) (xy 387.043014 -397.489356)
			(xy 387.051089 -397.556295) (xy 387.051088 -397.62372) (xy 387.043011 -397.690659) (xy 387.026975 -397.756148)
			(xy 387.00321 -397.819245) (xy 387.000823 -397.823826) (xy 388.128959 -397.823826) (xy 388.128963 -397.756517)
			(xy 388.137011 -397.689692) (xy 388.152988 -397.624308) (xy 388.176665 -397.561301) (xy 388.207704 -397.501577)
			(xy 388.245658 -397.44599) (xy 388.267448 -397.420338) (xy 388.273259 -397.413204) (xy 388.279764 -397.396005)
			(xy 388.280148 -397.38681) (xy 388.280148 -396.893542) (xy 388.279707 -396.884358) (xy 388.273213 -396.867174)
			(xy 388.267448 -396.860014) (xy 388.24565 -396.83437) (xy 388.207701 -396.778783) (xy 388.176668 -396.719058)
			(xy 388.152995 -396.656052) (xy 388.137022 -396.590669) (xy 388.128979 -396.523845) (xy 388.12898 -396.456539)
			(xy 388.137025 -396.389716) (xy 388.152999 -396.324333) (xy 388.176674 -396.261328) (xy 388.207709 -396.201604)
			(xy 388.245659 -396.146018) (xy 388.267448 -396.120366) (xy 388.273247 -396.113223) (xy 388.279759 -396.096031)
			(xy 388.280148 -396.086838) (xy 388.280148 -395.92885) (xy 388.280605 -395.91868) (xy 388.288375 -395.899885)
			(xy 388.302751 -395.885498) (xy 388.321541 -395.877713) (xy 388.33171 -395.877288) (xy 389.04799 -395.877288)
			(xy 389.058167 -395.877673) (xy 389.076971 -395.885464) (xy 389.091358 -395.899862) (xy 389.099135 -395.918672)
			(xy 389.099552 -395.92885) (xy 389.099552 -396.086838) (xy 389.099955 -396.096026) (xy 389.106475 -396.113209)
			(xy 389.112252 -396.120366) (xy 389.13403 -396.146026) (xy 389.17198 -396.201611) (xy 389.203014 -396.261334)
			(xy 389.226688 -396.324337) (xy 389.242662 -396.389718) (xy 389.250707 -396.45654) (xy 389.250707 -396.523845)
			(xy 389.242664 -396.590667) (xy 389.226692 -396.656048) (xy 389.20302 -396.719053) (xy 389.171987 -396.778776)
			(xy 389.134039 -396.834362) (xy 389.112252 -396.860014) (xy 389.106461 -396.867163) (xy 389.099944 -396.884351)
			(xy 389.099552 -396.893542) (xy 389.099552 -397.38681) (xy 389.099968 -397.395996) (xy 389.106479 -397.41318)
			(xy 389.112252 -397.420338) (xy 389.134002 -397.446021) (xy 389.171953 -397.501603) (xy 389.200407 -397.556356)
			(xy 390.329153 -397.556356) (xy 390.337195 -397.489535) (xy 390.353166 -397.424153) (xy 390.376836 -397.36115)
			(xy 390.407865 -397.301426) (xy 390.44581 -397.245839) (xy 390.467596 -397.220186) (xy 390.473381 -397.213032)
			(xy 390.479903 -397.195848) (xy 390.480296 -397.186658) (xy 390.480296 -397.028924) (xy 390.480735 -397.018804)
			(xy 390.488475 -397.000101) (xy 390.502784 -396.985786) (xy 390.521484 -396.978039) (xy 390.531604 -396.977616)
			(xy 391.248138 -396.977616) (xy 391.258264 -396.978095) (xy 391.276982 -396.985831) (xy 391.291336 -397.000119)
			(xy 391.299158 -397.0188) (xy 391.2997 -397.028924) (xy 391.2997 -397.186658) (xy 391.30013 -397.195843)
			(xy 391.30663 -397.213028) (xy 391.3124 -397.220186) (xy 391.334196 -397.245831) (xy 391.372142 -397.301419)
			(xy 391.403173 -397.361144) (xy 391.426844 -397.424149) (xy 391.442815 -397.489532) (xy 391.450857 -397.556355)
			(xy 391.450856 -397.62366) (xy 391.442812 -397.690483) (xy 391.426839 -397.755865) (xy 391.403167 -397.81887)
			(xy 391.372135 -397.878594) (xy 391.334187 -397.934181) (xy 391.3124 -397.959834) (xy 391.306606 -397.966981)
			(xy 391.30009 -397.98417) (xy 391.2997 -397.993362) (xy 391.2997 -398.486884) (xy 391.300118 -398.49607)
			(xy 391.306626 -398.513255) (xy 391.3124 -398.520412) (xy 391.334222 -398.546036) (xy 391.372167 -398.601627)
			(xy 391.403197 -398.661355) (xy 391.426866 -398.724363) (xy 391.442835 -398.789748) (xy 391.450876 -398.856574)
			(xy 391.450872 -398.923881) (xy 391.442825 -398.990705) (xy 391.42685 -399.056089) (xy 391.403175 -399.119095)
			(xy 391.372139 -399.178819) (xy 391.334189 -399.234407) (xy 391.3124 -399.26006) (xy 391.306595 -399.2672)
			(xy 391.300086 -399.284394) (xy 391.2997 -399.293588) (xy 391.2997 -399.451576) (xy 391.299265 -399.461697)
			(xy 391.291524 -399.4804) (xy 391.277214 -399.494715) (xy 391.258513 -399.502461) (xy 391.248392 -399.502884)
			(xy 390.531858 -399.502884) (xy 390.521732 -399.502409) (xy 390.503014 -399.494671) (xy 390.48866 -399.480382)
			(xy 390.480838 -399.4617) (xy 390.480296 -399.451576) (xy 390.480296 -399.293588) (xy 390.479892 -399.2844)
			(xy 390.473374 -399.267216) (xy 390.467596 -399.26006) (xy 390.445845 -399.234378) (xy 390.407898 -399.178795)
			(xy 390.376865 -399.119075) (xy 390.353192 -399.056075) (xy 390.337218 -398.990696) (xy 390.329172 -398.923878)
			(xy 390.329169 -398.856576) (xy 390.337209 -398.789757) (xy 390.353176 -398.724377) (xy 390.376843 -398.661374)
			(xy 390.40787 -398.601652) (xy 390.445812 -398.546065) (xy 390.467596 -398.520412) (xy 390.473412 -398.51328)
			(xy 390.479915 -398.49608) (xy 390.480296 -398.486884) (xy 390.480296 -397.993362) (xy 390.479905 -397.984173)
			(xy 390.473378 -397.966988) (xy 390.467596 -397.959834) (xy 390.445819 -397.934173) (xy 390.407873 -397.878587)
			(xy 390.376842 -397.818864) (xy 390.35317 -397.755861) (xy 390.337198 -397.69048) (xy 390.329154 -397.623659)
			(xy 390.329153 -397.556356) (xy 389.200407 -397.556356) (xy 389.202988 -397.561322) (xy 389.226664 -397.624322)
			(xy 389.24264 -397.689701) (xy 389.250687 -397.75652) (xy 389.25069 -397.823823) (xy 389.24265 -397.890643)
			(xy 389.226681 -397.956023) (xy 389.203012 -398.019026) (xy 389.171982 -398.078748) (xy 389.134038 -398.134334)
			(xy 389.112252 -398.159986) (xy 389.10643 -398.167113) (xy 389.099932 -398.184318) (xy 389.099552 -398.193514)
			(xy 389.099552 -398.351502) (xy 389.099138 -398.361675) (xy 389.09135 -398.380472) (xy 389.076962 -398.394857)
			(xy 389.058163 -398.40264) (xy 389.04799 -398.403064) (xy 388.33171 -398.403064) (xy 388.321539 -398.402628)
			(xy 388.302745 -398.394847) (xy 388.28836 -398.380465) (xy 388.280574 -398.361673) (xy 388.280148 -398.351502)
			(xy 388.280148 -398.193514) (xy 388.27972 -398.184329) (xy 388.273218 -398.167145) (xy 388.267448 -398.159986)
			(xy 388.245622 -398.134365) (xy 388.207674 -398.078774) (xy 388.176642 -398.019046) (xy 388.152971 -397.956038)
			(xy 388.137 -397.890652) (xy 388.128959 -397.823826) (xy 387.000823 -397.823826) (xy 386.972058 -397.879042)
			(xy 386.933968 -397.934677) (xy 386.912104 -397.960342) (xy 386.906308 -397.967487) (xy 386.899793 -397.984678)
			(xy 386.899404 -397.99387) (xy 386.899404 -398.486376) (xy 386.899825 -398.495562) (xy 386.906331 -398.512747)
			(xy 386.912104 -398.519904) (xy 386.934003 -398.54554) (xy 386.972091 -398.601179) (xy 387.003239 -398.660979)
			(xy 387.027001 -398.72408) (xy 387.043034 -398.789572) (xy 387.051107 -398.856514) (xy 387.051104 -398.92394)
			(xy 387.043025 -398.990881) (xy 387.026985 -399.056372) (xy 387.003217 -399.11947) (xy 386.972063 -399.179268)
			(xy 386.93397 -399.234903) (xy 386.912104 -399.260568) (xy 386.906297 -399.267706) (xy 386.899788 -399.284902)
			(xy 386.899404 -399.294096) (xy 386.899404 -399.451576) (xy 386.898965 -399.461696) (xy 386.891225 -399.480399)
			(xy 386.876916 -399.494714) (xy 386.858216 -399.502461) (xy 386.848096 -399.502884) (xy 386.131816 -399.502884)
			(xy 386.121693 -399.502471) (xy 386.102986 -399.494725) (xy 386.088671 -399.480407) (xy 386.080928 -399.4617)
			(xy 386.080508 -399.451576) (xy 386.080508 -399.294096) (xy 386.080098 -399.284909) (xy 386.073584 -399.267725)
			(xy 386.067808 -399.260568) (xy 386.045979 -399.234874) (xy 386.007889 -399.179244) (xy 385.976736 -399.119451)
			(xy 385.95297 -399.056358) (xy 385.936931 -398.990873) (xy 385.928852 -398.923938) (xy 385.928849 -398.856517)
			(xy 385.936922 -398.789581) (xy 385.952954 -398.724093) (xy 385.976714 -398.660998) (xy 386.007861 -398.601203)
			(xy 386.045946 -398.545569) (xy 386.067808 -398.519904) (xy 386.073586 -398.512746) (xy 386.080112 -398.495565)
			(xy 386.080508 -398.486376) (xy 386.080508 -397.99387) (xy 386.080111 -397.984681) (xy 386.073588 -397.967497)
			(xy 386.067808 -397.960342) (xy 386.045954 -397.934669) (xy 386.007864 -397.879036) (xy 385.976712 -397.819241)
			(xy 385.952947 -397.756145) (xy 385.936911 -397.690657) (xy 385.928834 -397.623719) (xy 385.928833 -397.556296)
			(xy 384.800587 -397.556296) (xy 384.803199 -397.561322) (xy 384.826873 -397.624323) (xy 384.842849 -397.689701)
			(xy 384.850896 -397.75652) (xy 384.850899 -397.823822) (xy 384.842859 -397.890642) (xy 384.82689 -397.956022)
			(xy 384.803222 -398.019025) (xy 384.772193 -398.078748) (xy 384.734249 -398.134334) (xy 384.712464 -398.159986)
			(xy 384.706644 -398.167114) (xy 384.700144 -398.184318) (xy 384.699764 -398.193514) (xy 384.699764 -398.351502)
			(xy 384.699268 -398.36166) (xy 384.691494 -398.380428) (xy 384.677128 -398.394794) (xy 384.65836 -398.402568)
			(xy 384.648202 -398.403064) (xy 383.931922 -398.403064) (xy 383.921752 -398.402618) (xy 383.902958 -398.394841)
			(xy 383.888573 -398.380462) (xy 383.880787 -398.361672) (xy 383.88036 -398.351502) (xy 383.88036 -398.193514)
			(xy 383.87993 -398.184329) (xy 383.873429 -398.167145) (xy 383.86766 -398.159986) (xy 383.845834 -398.134365)
			(xy 383.807885 -398.078775) (xy 383.776852 -398.019047) (xy 383.753181 -397.956038) (xy 383.73721 -397.890652)
			(xy 383.729168 -397.823826) (xy 382.600522 -397.823826) (xy 382.572059 -397.878597) (xy 382.534106 -397.934182)
			(xy 382.512316 -397.959834) (xy 382.506524 -397.966983) (xy 382.500006 -397.98417) (xy 382.499616 -397.993362)
			(xy 382.499616 -398.486884) (xy 382.50003 -398.496071) (xy 382.506541 -398.513255) (xy 382.512316 -398.520412)
			(xy 382.53414 -398.546034) (xy 382.572091 -398.601624) (xy 382.603125 -398.661351) (xy 382.626798 -398.72436)
			(xy 382.64277 -398.789746) (xy 382.650812 -398.856573) (xy 382.650808 -398.923881) (xy 382.64276 -398.990707)
			(xy 382.626782 -399.056092) (xy 382.603103 -399.119098) (xy 382.572063 -399.178822) (xy 382.534107 -399.234408)
			(xy 382.512316 -399.26006) (xy 382.506513 -399.267201) (xy 382.500002 -399.284395) (xy 382.499616 -399.293588)
			(xy 382.499616 -399.451576) (xy 382.499165 -399.461695) (xy 382.491428 -399.480395) (xy 382.477122 -399.49471)
			(xy 382.458427 -399.502459) (xy 382.448308 -399.502884) (xy 381.731774 -399.502884) (xy 381.721649 -399.502396)
			(xy 381.702931 -399.494664) (xy 381.688577 -399.480379) (xy 381.680754 -399.461699) (xy 381.680212 -399.451576)
			(xy 381.680212 -399.293588) (xy 381.679805 -399.284401) (xy 381.673289 -399.267216) (xy 381.667512 -399.26006)
			(xy 381.64576 -399.234378) (xy 381.607812 -399.178796) (xy 381.576779 -399.119076) (xy 381.553105 -399.056075)
			(xy 381.537131 -398.990697) (xy 381.529084 -398.923878) (xy 381.529081 -398.856576) (xy 381.537121 -398.789757)
			(xy 381.553089 -398.724377) (xy 381.576757 -398.661374) (xy 381.607784 -398.601651) (xy 381.645727 -398.546064)
			(xy 381.667512 -398.520412) (xy 381.67333 -398.513282) (xy 381.679831 -398.49608) (xy 381.680212 -398.486884)
			(xy 381.680212 -397.993362) (xy 381.679818 -397.984173) (xy 381.673293 -397.966989) (xy 381.667512 -397.959834)
			(xy 381.645735 -397.934173) (xy 381.607788 -397.878588) (xy 381.576755 -397.818865) (xy 381.553083 -397.755862)
			(xy 381.53711 -397.690481) (xy 381.529066 -397.623659) (xy 381.529065 -397.556356) (xy 380.40085 -397.556356)
			(xy 380.403242 -397.560947) (xy 380.42701 -397.62404) (xy 380.443049 -397.689525) (xy 380.451128 -397.756461)
			(xy 380.451131 -397.823882) (xy 380.443059 -397.890818) (xy 380.427026 -397.956306) (xy 380.403265 -398.019401)
			(xy 380.372117 -398.079196) (xy 380.334031 -398.134829) (xy 380.312168 -398.160494) (xy 380.306387 -398.16765)
			(xy 380.299864 -398.184832) (xy 380.299468 -398.194022) (xy 380.299468 -398.351502) (xy 380.298975 -398.361628)
			(xy 380.291248 -398.380347) (xy 380.276964 -398.394703) (xy 380.258283 -398.402524) (xy 380.24816 -398.403064)
			(xy 379.53188 -398.403064) (xy 379.521752 -398.4027) (xy 379.503041 -398.394938) (xy 379.488726 -398.380605)
			(xy 379.480988 -398.361885) (xy 379.480572 -398.351756) (xy 379.480572 -398.194022) (xy 379.480158 -398.184835)
			(xy 379.473648 -398.16765) (xy 379.467872 -398.160494) (xy 379.445972 -398.134859) (xy 379.407886 -398.07922)
			(xy 379.376738 -398.019419) (xy 379.352978 -397.956318) (xy 379.336946 -397.890826) (xy 379.328873 -397.823885)
			(xy 378.200706 -397.823885) (xy 378.171972 -397.879041) (xy 378.133884 -397.934676) (xy 378.11202 -397.960342)
			(xy 378.106225 -397.967489) (xy 378.099709 -397.984678) (xy 378.09932 -397.99387) (xy 378.09932 -398.486376)
			(xy 378.099737 -398.495563) (xy 378.106245 -398.512747) (xy 378.11202 -398.519904) (xy 378.133919 -398.54554)
			(xy 378.172005 -398.60118) (xy 378.203153 -398.66098) (xy 378.226914 -398.724081) (xy 378.242947 -398.789573)
			(xy 378.251019 -398.856514) (xy 378.251016 -398.92394) (xy 378.242937 -398.99088) (xy 378.226898 -399.056371)
			(xy 378.203131 -399.11947) (xy 378.171977 -399.179267) (xy 378.133885 -399.234902) (xy 378.11202 -399.260568)
			(xy 378.106214 -399.267707) (xy 378.099704 -399.284902) (xy 378.09932 -399.294096) (xy 378.09932 -399.451576)
			(xy 378.098865 -399.461694) (xy 378.091128 -399.480394) (xy 378.076824 -399.494708) (xy 378.05813 -399.502458)
			(xy 378.048012 -399.502884) (xy 377.331732 -399.502884) (xy 377.32161 -399.502458) (xy 377.302903 -399.494717)
			(xy 377.288587 -399.480403) (xy 377.280844 -399.461698) (xy 377.280424 -399.451576) (xy 377.280424 -399.294096)
			(xy 377.280011 -399.284909) (xy 377.273499 -399.267725) (xy 377.267724 -399.260568) (xy 377.245895 -399.234874)
			(xy 377.207803 -399.179244) (xy 377.17665 -399.119452) (xy 377.152882 -399.056359) (xy 377.136844 -398.990873)
			(xy 377.128765 -398.923938) (xy 377.128761 -398.856516) (xy 377.136834 -398.78958) (xy 377.152866 -398.724093)
			(xy 377.176627 -398.660997) (xy 377.207775 -398.601202) (xy 377.245861 -398.545569) (xy 377.267724 -398.519904)
			(xy 377.273504 -398.512747) (xy 377.280028 -398.495565) (xy 377.280424 -398.486376) (xy 377.280424 -397.99387)
			(xy 377.280023 -397.984682) (xy 377.273502 -397.967498) (xy 377.267724 -397.960342) (xy 377.245869 -397.934669)
			(xy 377.207778 -397.879036) (xy 377.176626 -397.819241) (xy 377.15286 -397.756145) (xy 377.136823 -397.690657)
			(xy 377.128746 -397.623719) (xy 377.128745 -397.556296) (xy 376.0005 -397.556296) (xy 376.003112 -397.561323)
			(xy 376.026786 -397.624324) (xy 376.042761 -397.689702) (xy 376.050808 -397.756521) (xy 376.050811 -397.823822)
			(xy 376.042771 -397.890642) (xy 376.026803 -397.956022) (xy 376.003135 -398.019025) (xy 375.972108 -398.078747)
			(xy 375.934165 -398.134333) (xy 375.91238 -398.159986) (xy 375.906562 -398.167116) (xy 375.900061 -398.184318)
			(xy 375.89968 -398.193514) (xy 375.89968 -398.351502) (xy 375.899169 -398.361658) (xy 375.891397 -398.380423)
			(xy 375.877037 -398.394788) (xy 375.858274 -398.402565) (xy 375.848118 -398.403064) (xy 375.131838 -398.403064)
			(xy 375.121669 -398.402605) (xy 375.102876 -398.394833) (xy 375.08849 -398.380458) (xy 375.080703 -398.361671)
			(xy 375.080276 -398.351502) (xy 375.080276 -398.193514) (xy 375.079865 -398.184327) (xy 375.073352 -398.167142)
			(xy 375.067576 -398.159986) (xy 375.04575 -398.134365) (xy 375.007799 -398.078775) (xy 374.976766 -398.019048)
			(xy 374.953093 -397.956039) (xy 374.937122 -397.890652) (xy 374.92908 -397.823826) (xy 347.400682 -397.823826)
			(xy 347.372224 -397.878594) (xy 347.334276 -397.934182) (xy 347.312488 -397.959834) (xy 347.306693 -397.96698)
			(xy 347.300178 -397.98417) (xy 347.299788 -397.993362) (xy 347.299788 -398.486884) (xy 347.300209 -398.49607)
			(xy 347.306715 -398.513254) (xy 347.312488 -398.520412) (xy 347.33431 -398.546035) (xy 347.372256 -398.601627)
			(xy 347.403286 -398.661354) (xy 347.426956 -398.724363) (xy 347.442926 -398.789748) (xy 347.450967 -398.856573)
			(xy 347.450963 -398.923881) (xy 347.442916 -398.990705) (xy 347.42694 -399.056089) (xy 347.403264 -399.119095)
			(xy 347.372228 -399.17882) (xy 347.334277 -399.234407) (xy 347.312488 -399.26006) (xy 347.306682 -399.267199)
			(xy 347.300173 -399.284394) (xy 347.299788 -399.293588) (xy 347.299788 -399.451576) (xy 347.299359 -399.46173)
			(xy 347.291569 -399.480484) (xy 347.277174 -399.494809) (xy 347.258382 -399.502507) (xy 347.248226 -399.502884)
			(xy 346.531946 -399.502884) (xy 346.521825 -399.502336) (xy 346.50311 -399.494628) (xy 346.488753 -399.480361)
			(xy 346.480928 -399.461694) (xy 346.480384 -399.451576) (xy 346.480384 -399.293588) (xy 346.479983 -399.2844)
			(xy 346.473463 -399.267215) (xy 346.467684 -399.26006) (xy 346.44593 -399.234379) (xy 346.407977 -399.178798)
			(xy 346.37694 -399.119079) (xy 346.353263 -399.056078) (xy 346.337287 -398.990699) (xy 346.329239 -398.923879)
			(xy 346.329236 -398.856576) (xy 346.337277 -398.789755) (xy 346.353247 -398.724374) (xy 346.376918 -398.661371)
			(xy 346.40795 -398.601648) (xy 346.445897 -398.546064) (xy 346.467684 -398.520412) (xy 346.473499 -398.513279)
			(xy 346.480003 -398.496079) (xy 346.480384 -398.486884) (xy 346.480384 -397.993362) (xy 346.479996 -397.984172)
			(xy 346.473467 -397.966988) (xy 346.467684 -397.959834) (xy 346.445905 -397.934174) (xy 346.407953 -397.87859)
			(xy 346.376917 -397.818868) (xy 346.353241 -397.755864) (xy 346.337266 -397.690483) (xy 346.329221 -397.62366)
			(xy 346.32922 -397.556355) (xy 345.200497 -397.556355) (xy 345.203078 -397.561321) (xy 345.226754 -397.624322)
			(xy 345.24273 -397.689701) (xy 345.250778 -397.75652) (xy 345.250781 -397.823823) (xy 345.242741 -397.890643)
			(xy 345.226771 -397.956023) (xy 345.203102 -398.019026) (xy 345.172072 -398.078749) (xy 345.134126 -398.134334)
			(xy 345.11234 -398.159986) (xy 345.106517 -398.167112) (xy 345.10002 -398.184318) (xy 345.09964 -398.193514)
			(xy 345.09964 -398.351502) (xy 345.099237 -398.361676) (xy 345.091447 -398.380475) (xy 345.077055 -398.394861)
			(xy 345.058253 -398.402642) (xy 345.048078 -398.403064) (xy 344.331798 -398.403064) (xy 344.32164 -398.402568)
			(xy 344.302872 -398.394794) (xy 344.288506 -398.380428) (xy 344.280732 -398.36166) (xy 344.280236 -398.351502)
			(xy 344.280236 -398.193514) (xy 344.279811 -398.184329) (xy 344.273307 -398.167144) (xy 344.267536 -398.159986)
			(xy 344.245711 -398.134365) (xy 344.207763 -398.078774) (xy 344.176732 -398.019046) (xy 344.153061 -397.956037)
			(xy 344.137091 -397.890651) (xy 344.12905 -397.823825) (xy 343.000914 -397.823825) (xy 342.972147 -397.879042)
			(xy 342.934057 -397.934677) (xy 342.912192 -397.960342) (xy 342.906394 -397.967486) (xy 342.899881 -397.984678)
			(xy 342.899492 -397.99387) (xy 342.899492 -398.486376) (xy 342.899916 -398.495562) (xy 342.90642 -398.512746)
			(xy 342.912192 -398.519904) (xy 342.934092 -398.54554) (xy 342.97218 -398.601178) (xy 343.003329 -398.660979)
			(xy 343.027092 -398.724079) (xy 343.043125 -398.789572) (xy 343.051198 -398.856514) (xy 343.051195 -398.92394)
			(xy 343.043115 -398.990881) (xy 343.027076 -399.056372) (xy 343.003307 -399.119471) (xy 342.972152 -399.179268)
			(xy 342.934058 -399.234903) (xy 342.912192 -399.260568) (xy 342.906383 -399.267704) (xy 342.899876 -399.284902)
			(xy 342.899492 -399.294096) (xy 342.899492 -399.451576) (xy 342.899064 -399.461698) (xy 342.891323 -399.480403)
			(xy 342.877009 -399.494718) (xy 342.858306 -399.502463) (xy 342.848184 -399.502884) (xy 342.131904 -399.502884)
			(xy 342.12178 -399.50248) (xy 342.103073 -399.494731) (xy 342.088758 -399.48041) (xy 342.081016 -399.4617)
			(xy 342.080596 -399.451576) (xy 342.080596 -399.294096) (xy 342.080189 -399.284909) (xy 342.073673 -399.267724)
			(xy 342.067896 -399.260568) (xy 342.046068 -399.234874) (xy 342.007978 -399.179243) (xy 341.976826 -399.119451)
			(xy 341.95306 -399.056358) (xy 341.937022 -398.990872) (xy 341.928943 -398.923937) (xy 341.92894 -398.856517)
			(xy 341.937012 -398.789581) (xy 341.953044 -398.724094) (xy 341.976804 -398.660999) (xy 342.00795 -398.601203)
			(xy 342.046034 -398.545569) (xy 342.067896 -398.519904) (xy 342.073673 -398.512745) (xy 342.080199 -398.495565)
			(xy 342.080596 -398.486376) (xy 342.080596 -397.99387) (xy 342.080201 -397.984681) (xy 342.073677 -397.967497)
			(xy 342.067896 -397.960342) (xy 342.046042 -397.934669) (xy 342.007953 -397.879035) (xy 341.976802 -397.81924)
			(xy 341.953038 -397.756144) (xy 341.937002 -397.690656) (xy 341.928925 -397.623719) (xy 341.928924 -397.556296)
			(xy 340.800676 -397.556296) (xy 340.803288 -397.561322) (xy 340.826964 -397.624322) (xy 340.84294 -397.689701)
			(xy 340.850987 -397.75652) (xy 340.85099 -397.823823) (xy 340.84295 -397.890643) (xy 340.826981 -397.956023)
			(xy 340.803312 -398.019026) (xy 340.772282 -398.078748) (xy 340.734338 -398.134334) (xy 340.712552 -398.159986)
			(xy 340.70673 -398.167113) (xy 340.700232 -398.184318) (xy 340.699852 -398.193514) (xy 340.699852 -398.351502)
			(xy 340.699438 -398.361675) (xy 340.69165 -398.380472) (xy 340.677262 -398.394857) (xy 340.658463 -398.40264)
			(xy 340.64829 -398.403064) (xy 339.93201 -398.403064) (xy 339.921839 -398.402628) (xy 339.903045 -398.394847)
			(xy 339.88866 -398.380465) (xy 339.880874 -398.361673) (xy 339.880448 -398.351502) (xy 339.880448 -398.193514)
			(xy 339.88002 -398.184329) (xy 339.873518 -398.167145) (xy 339.867748 -398.159986) (xy 339.845922 -398.134365)
			(xy 339.807974 -398.078774) (xy 339.776942 -398.019046) (xy 339.753271 -397.956038) (xy 339.7373 -397.890652)
			(xy 339.729259 -397.823826) (xy 338.600595 -397.823826) (xy 338.572138 -397.878594) (xy 338.534191 -397.934181)
			(xy 338.512404 -397.959834) (xy 338.506611 -397.966982) (xy 338.500094 -397.98417) (xy 338.499704 -397.993362)
			(xy 338.499704 -398.486884) (xy 338.500121 -398.49607) (xy 338.50663 -398.513255) (xy 338.512404 -398.520412)
			(xy 338.534226 -398.546036) (xy 338.572171 -398.601627) (xy 338.6032 -398.661355) (xy 338.626869 -398.724363)
			(xy 338.642838 -398.789748) (xy 338.650879 -398.856574) (xy 338.650875 -398.923881) (xy 338.642828 -398.990705)
			(xy 338.626853 -399.056089) (xy 338.603178 -399.119094) (xy 338.572143 -399.178819) (xy 338.534193 -399.234407)
			(xy 338.512404 -399.26006) (xy 338.5066 -399.2672) (xy 338.50009 -399.284394) (xy 338.499704 -399.293588)
			(xy 338.499704 -399.451576) (xy 338.499259 -399.461728) (xy 338.491472 -399.480479) (xy 338.477082 -399.494803)
			(xy 338.458296 -399.502505) (xy 338.448142 -399.502884) (xy 337.731862 -399.502884) (xy 337.721736 -399.502405)
			(xy 337.703018 -399.494669) (xy 337.688664 -399.480381) (xy 337.680842 -399.4617) (xy 337.6803 -399.451576)
			(xy 337.6803 -399.293588) (xy 337.679895 -399.2844) (xy 337.673378 -399.267216) (xy 337.6676 -399.26006)
			(xy 337.645849 -399.234378) (xy 337.607901 -399.178795) (xy 337.576869 -399.119075) (xy 337.553196 -399.056075)
			(xy 337.537221 -398.990697) (xy 337.529175 -398.923878) (xy 337.529172 -398.856576) (xy 337.537212 -398.789757)
			(xy 337.55318 -398.724377) (xy 337.576847 -398.661374) (xy 337.607874 -398.601651) (xy 337.645816 -398.546065)
			(xy 337.6676 -398.520412) (xy 337.673416 -398.513281) (xy 337.679919 -398.49608) (xy 337.6803 -398.486884)
			(xy 337.6803 -397.993362) (xy 337.679908 -397.984173) (xy 337.673382 -397.966989) (xy 337.6676 -397.959834)
			(xy 337.645823 -397.934173) (xy 337.607877 -397.878587) (xy 337.576845 -397.818864) (xy 337.553174 -397.755861)
			(xy 337.537201 -397.69048) (xy 337.529157 -397.623659) (xy 337.529156 -397.556356) (xy 336.40094 -397.556356)
			(xy 336.403332 -397.560946) (xy 336.4271 -397.624039) (xy 336.443139 -397.689525) (xy 336.451219 -397.756461)
			(xy 336.451222 -397.823882) (xy 336.44315 -397.890819) (xy 336.427117 -397.956306) (xy 336.403355 -398.019402)
			(xy 336.372206 -398.079196) (xy 336.334119 -398.13483) (xy 336.312256 -398.160494) (xy 336.306474 -398.167649)
			(xy 336.299952 -398.184832) (xy 336.299556 -398.194022) (xy 336.299556 -398.351502) (xy 336.299075 -398.361629)
			(xy 336.291346 -398.380351) (xy 336.277058 -398.394708) (xy 336.258373 -398.402526) (xy 336.248248 -398.403064)
			(xy 335.531968 -398.403064) (xy 335.521807 -398.402704) (xy 335.503047 -398.394891) (xy 335.488724 -398.380475)
			(xy 335.481032 -398.361665) (xy 335.48066 -398.351502) (xy 335.48066 -398.194022) (xy 335.480226 -398.184838)
			(xy 335.473727 -398.167654) (xy 335.46796 -398.160494) (xy 335.44606 -398.134859) (xy 335.407975 -398.079219)
			(xy 335.376828 -398.019418) (xy 335.353068 -397.956318) (xy 335.337036 -397.890825) (xy 335.328964 -397.823884)
			(xy 334.200796 -397.823884) (xy 334.172062 -397.879042) (xy 334.133972 -397.934677) (xy 334.112108 -397.960342)
			(xy 334.106312 -397.967488) (xy 334.099797 -397.984678) (xy 334.099408 -397.99387) (xy 334.099408 -398.486376)
			(xy 334.099828 -398.495562) (xy 334.106335 -398.512747) (xy 334.112108 -398.519904) (xy 334.134007 -398.54554)
			(xy 334.172094 -398.601179) (xy 334.203243 -398.660979) (xy 334.227005 -398.72408) (xy 334.243037 -398.789573)
			(xy 334.25111 -398.856514) (xy 334.251107 -398.92394) (xy 334.243028 -398.990881) (xy 334.226989 -399.056372)
			(xy 334.203221 -399.11947) (xy 334.172066 -399.179267) (xy 334.133974 -399.234903) (xy 334.112108 -399.260568)
			(xy 334.106301 -399.267706) (xy 334.099792 -399.284902) (xy 334.099408 -399.294096) (xy 334.099408 -399.451576)
			(xy 334.098965 -399.461696) (xy 334.091226 -399.480398) (xy 334.076918 -399.494712) (xy 334.05822 -399.50246)
			(xy 334.0481 -399.502884) (xy 333.33182 -399.502884) (xy 333.321697 -399.502467) (xy 333.302991 -399.494723)
			(xy 333.288675 -399.480406) (xy 333.280932 -399.461699) (xy 333.280512 -399.451576) (xy 333.280512 -399.294096)
			(xy 333.280101 -399.284909) (xy 333.273587 -399.267725) (xy 333.267812 -399.260568) (xy 333.245983 -399.234874)
			(xy 333.207892 -399.179244) (xy 333.176739 -399.119452) (xy 333.152973 -399.056358) (xy 333.136934 -398.990873)
			(xy 333.128855 -398.923938) (xy 333.128852 -398.856516) (xy 333.136925 -398.78958) (xy 333.152957 -398.724093)
			(xy 333.176717 -398.660998) (xy 333.207865 -398.601203) (xy 333.24595 -398.545569) (xy 333.267812 -398.519904)
			(xy 333.273591 -398.512746) (xy 333.280116 -398.495565) (xy 333.280512 -398.486376) (xy 333.280512 -397.99387)
			(xy 333.280114 -397.984682) (xy 333.273592 -397.967497) (xy 333.267812 -397.960342) (xy 333.245957 -397.934669)
			(xy 333.207868 -397.879036) (xy 333.176716 -397.819241) (xy 333.152951 -397.756145) (xy 333.136914 -397.690657)
			(xy 333.128837 -397.623719) (xy 333.128836 -397.556296) (xy 332.00059 -397.556296) (xy 332.003202 -397.561323)
			(xy 332.026877 -397.624323) (xy 332.042852 -397.689701) (xy 332.050899 -397.75652) (xy 332.050902 -397.823822)
			(xy 332.042862 -397.890642) (xy 332.026893 -397.956022) (xy 332.003225 -398.019025) (xy 331.972197 -398.078748)
			(xy 331.934253 -398.134334) (xy 331.912468 -398.159986) (xy 331.906648 -398.167115) (xy 331.900148 -398.184318)
			(xy 331.899768 -398.193514) (xy 331.899768 -398.351502) (xy 331.899268 -398.361659) (xy 331.891494 -398.380427)
			(xy 331.877131 -398.394792) (xy 331.858363 -398.402568) (xy 331.848206 -398.403064) (xy 331.131926 -398.403064)
			(xy 331.121756 -398.402615) (xy 331.102963 -398.394839) (xy 331.088577 -398.380461) (xy 331.080791 -398.361671)
			(xy 331.080364 -398.351502) (xy 331.080364 -398.193514) (xy 331.079933 -398.184329) (xy 331.073432 -398.167146)
			(xy 331.067664 -398.159986) (xy 331.045838 -398.134365) (xy 331.007889 -398.078775) (xy 330.976856 -398.019047)
			(xy 330.953184 -397.956038) (xy 330.937213 -397.890652) (xy 330.929171 -397.823826) (xy 326.525636 -397.823826)
			(xy 326.525636 -401.723737) (xy 330.929183 -401.723737) (xy 330.929184 -401.65643) (xy 330.937231 -401.589605)
			(xy 330.953207 -401.524221) (xy 330.976884 -401.461216) (xy 331.007921 -401.401492) (xy 331.045874 -401.345906)
			(xy 331.067664 -401.320254) (xy 331.07347 -401.313116) (xy 331.079977 -401.29592) (xy 331.080364 -401.286726)
			(xy 331.080364 -400.793458) (xy 331.07996 -400.78427) (xy 331.073441 -400.767087) (xy 331.067664 -400.75993)
			(xy 331.045882 -400.734273) (xy 331.007931 -400.678688) (xy 330.976896 -400.618965) (xy 330.953222 -400.555961)
			(xy 330.937248 -400.490579) (xy 330.929203 -400.423757) (xy 330.929202 -400.356452) (xy 330.937246 -400.289629)
			(xy 330.953219 -400.224247) (xy 330.976892 -400.161243) (xy 331.007926 -400.10152) (xy 331.045876 -400.045934)
			(xy 331.067664 -400.020282) (xy 331.073459 -400.013136) (xy 331.079973 -399.995946) (xy 331.080364 -399.986754)
			(xy 331.080364 -399.828766) (xy 331.080806 -399.818603) (xy 331.088597 -399.799828) (xy 331.102978 -399.785463)
			(xy 331.121762 -399.777694) (xy 331.131926 -399.777204) (xy 331.848206 -399.777204) (xy 331.85836 -399.777728)
			(xy 331.877123 -399.785498) (xy 331.891486 -399.799854) (xy 331.899267 -399.818612) (xy 331.899768 -399.828766)
			(xy 331.899768 -399.986754) (xy 331.900208 -399.995938) (xy 331.906702 -400.013122) (xy 331.912468 -400.020282)
			(xy 331.934262 -400.045929) (xy 331.97221 -400.101517) (xy 332.003242 -400.161241) (xy 332.026915 -400.224246)
			(xy 332.042887 -400.289629) (xy 332.05093 -400.356452) (xy 332.05093 -400.423757) (xy 332.042885 -400.49058)
			(xy 332.026912 -400.555963) (xy 332.003239 -400.618967) (xy 331.972205 -400.678691) (xy 331.934256 -400.734278)
			(xy 331.912468 -400.75993) (xy 331.906672 -400.767076) (xy 331.900158 -400.784266) (xy 331.899768 -400.793458)
			(xy 331.899768 -401.286726) (xy 331.900173 -401.295914) (xy 331.906691 -401.313098) (xy 331.912468 -401.320254)
			(xy 331.934234 -401.345924) (xy 331.972183 -401.401508) (xy 332.003216 -401.461229) (xy 332.02689 -401.524231)
			(xy 332.042864 -401.589611) (xy 332.05091 -401.656432) (xy 332.050912 -401.723735) (xy 332.04287 -401.790556)
			(xy 332.0269 -401.855937) (xy 332.00323 -401.91894) (xy 331.9722 -401.978663) (xy 331.934254 -402.03425)
			(xy 331.912468 -402.059902) (xy 331.906684 -402.067056) (xy 331.900163 -402.08424) (xy 331.899768 -402.09343)
			(xy 331.899768 -402.251418) (xy 331.899282 -402.261576) (xy 331.891502 -402.280345) (xy 331.877135 -402.294709)
			(xy 331.858364 -402.302484) (xy 331.848206 -402.30298) (xy 331.131926 -402.30298) (xy 331.121758 -402.302515)
			(xy 331.102968 -402.294742) (xy 331.088583 -402.280369) (xy 331.080794 -402.261585) (xy 331.080364 -402.251418)
			(xy 331.080364 -402.09343) (xy 331.079925 -402.084246) (xy 331.07343 -402.067062) (xy 331.067664 -402.059902)
			(xy 331.045854 -402.034268) (xy 331.007904 -401.97868) (xy 330.97687 -401.918954) (xy 330.953197 -401.855947)
			(xy 330.937225 -401.790562) (xy 330.929183 -401.723737) (xy 326.525636 -401.723737) (xy 326.525636 -402.823878)
			(xy 333.128796 -402.823878) (xy 333.128801 -402.75645) (xy 333.136882 -402.689508) (xy 333.152922 -402.624016)
			(xy 333.176693 -402.560918) (xy 333.20785 -402.50112) (xy 333.245945 -402.445485) (xy 333.267812 -402.41982)
			(xy 333.273626 -402.412687) (xy 333.28013 -402.395487) (xy 333.280512 -402.386292) (xy 333.280512 -401.89404)
			(xy 333.28008 -401.884855) (xy 333.273581 -401.867671) (xy 333.267812 -401.860512) (xy 333.245928 -401.834863)
			(xy 333.207839 -401.779227) (xy 333.176689 -401.719428) (xy 333.152925 -401.656329) (xy 333.136891 -401.590838)
			(xy 333.128816 -401.523898) (xy 333.128818 -401.456472) (xy 333.136896 -401.389532) (xy 333.152934 -401.324042)
			(xy 333.176701 -401.260944) (xy 333.207855 -401.201148) (xy 333.245946 -401.145513) (xy 333.267812 -401.119848)
			(xy 333.273615 -401.112707) (xy 333.280125 -401.095513) (xy 333.280512 -401.08632) (xy 333.280512 -400.92884)
			(xy 333.280949 -400.918719) (xy 333.288686 -400.900014) (xy 333.302997 -400.885698) (xy 333.321699 -400.877953)
			(xy 333.33182 -400.877532) (xy 334.0481 -400.877532) (xy 334.058226 -400.877917) (xy 334.076936 -400.885671)
			(xy 334.091252 -400.899997) (xy 334.098991 -400.918713) (xy 334.099408 -400.92884) (xy 334.099408 -401.08632)
			(xy 334.099807 -401.095508) (xy 334.106328 -401.112693) (xy 334.112108 -401.119848) (xy 334.133952 -401.14553)
			(xy 334.172041 -401.201162) (xy 334.203192 -401.260956) (xy 334.226957 -401.324051) (xy 334.242994 -401.389538)
			(xy 334.251071 -401.456474) (xy 334.251073 -401.523896) (xy 334.242999 -401.590833) (xy 334.226966 -401.656321)
			(xy 334.203204 -401.719417) (xy 334.200923 -401.723796) (xy 335.328975 -401.723796) (xy 335.328977 -401.656371)
			(xy 335.337055 -401.589432) (xy 335.353091 -401.523942) (xy 335.376856 -401.460845) (xy 335.408007 -401.401048)
			(xy 335.446096 -401.345412) (xy 335.46796 -401.319746) (xy 335.473769 -401.31261) (xy 335.480275 -401.295412)
			(xy 335.48066 -401.286218) (xy 335.48066 -400.793966) (xy 335.480253 -400.784779) (xy 335.473735 -400.767595)
			(xy 335.46796 -400.760438) (xy 335.446103 -400.734767) (xy 335.408017 -400.679133) (xy 335.376868 -400.619337)
			(xy 335.353106 -400.556241) (xy 335.337071 -400.490753) (xy 335.328995 -400.423816) (xy 335.328995 -400.356393)
			(xy 335.337069 -400.289456) (xy 335.353103 -400.223968) (xy 335.376865 -400.160872) (xy 335.408012 -400.101075)
			(xy 335.446098 -400.04544) (xy 335.46796 -400.019774) (xy 335.473757 -400.01263) (xy 335.48027 -399.995438)
			(xy 335.48066 -399.986246) (xy 335.48066 -399.828766) (xy 335.481099 -399.818635) (xy 335.488842 -399.799909)
			(xy 335.503143 -399.785553) (xy 335.521839 -399.777739) (xy 335.531968 -399.777204) (xy 336.248248 -399.777204)
			(xy 336.258406 -399.777583) (xy 336.27716 -399.785395) (xy 336.291482 -399.799804) (xy 336.299179 -399.818606)
			(xy 336.299556 -399.828766) (xy 336.299556 -399.986246) (xy 336.300002 -399.995429) (xy 336.306492 -400.012613)
			(xy 336.312256 -400.019774) (xy 336.334127 -400.045434) (xy 336.372219 -400.101068) (xy 336.403372 -400.160864)
			(xy 336.427138 -400.223962) (xy 336.443174 -400.289452) (xy 336.45125 -400.356392) (xy 336.451249 -400.423817)
			(xy 336.443172 -400.490756) (xy 336.427135 -400.556246) (xy 336.403368 -400.619344) (xy 336.372214 -400.67914)
			(xy 336.334122 -400.734774) (xy 336.312256 -400.760438) (xy 336.306455 -400.76758) (xy 336.299944 -400.784773)
			(xy 336.299556 -400.793966) (xy 336.299556 -401.286218) (xy 336.299967 -401.295405) (xy 336.306481 -401.312589)
			(xy 336.312256 -401.319746) (xy 336.3341 -401.345428) (xy 336.372192 -401.401059) (xy 336.403346 -401.460853)
			(xy 336.427114 -401.523948) (xy 336.443152 -401.589435) (xy 336.45123 -401.656372) (xy 336.451232 -401.723795)
			(xy 336.443158 -401.790732) (xy 336.427123 -401.856221) (xy 336.40336 -401.919317) (xy 336.372209 -401.979112)
			(xy 336.33412 -402.034746) (xy 336.312256 -402.06041) (xy 336.306467 -402.06756) (xy 336.299949 -402.084747)
			(xy 336.299556 -402.093938) (xy 336.299556 -402.251418) (xy 336.299088 -402.261546) (xy 336.291354 -402.280269)
			(xy 336.277062 -402.294625) (xy 336.258374 -402.302443) (xy 336.248248 -402.30298) (xy 335.531968 -402.30298)
			(xy 335.521809 -402.302604) (xy 335.503052 -402.294794) (xy 335.488729 -402.280384) (xy 335.481034 -402.261579)
			(xy 335.48066 -402.251418) (xy 335.48066 -402.093938) (xy 335.480218 -402.084754) (xy 335.473725 -402.06757)
			(xy 335.46796 -402.06041) (xy 335.446076 -402.034762) (xy 335.40799 -401.979124) (xy 335.376843 -401.919325)
			(xy 335.353082 -401.856226) (xy 335.337049 -401.790735) (xy 335.328975 -401.723796) (xy 334.200923 -401.723796)
			(xy 334.172056 -401.779212) (xy 334.13397 -401.834847) (xy 334.112108 -401.860512) (xy 334.106325 -401.867667)
			(xy 334.099802 -401.88485) (xy 334.099408 -401.89404) (xy 334.099408 -402.386292) (xy 334.09982 -402.395479)
			(xy 334.106332 -402.412663) (xy 334.112108 -402.41982) (xy 334.133925 -402.445524) (xy 334.172014 -402.501153)
			(xy 334.203166 -402.560944) (xy 334.226933 -402.624036) (xy 334.242972 -402.68952) (xy 334.251051 -402.756454)
			(xy 334.251055 -402.823818) (xy 337.529116 -402.823818) (xy 337.52912 -402.75651) (xy 337.537169 -402.689685)
			(xy 337.553145 -402.6243) (xy 337.576822 -402.561294) (xy 337.607859 -402.501569) (xy 337.645811 -402.445981)
			(xy 337.6676 -402.420328) (xy 337.67341 -402.413192) (xy 337.679917 -402.395994) (xy 337.6803 -402.3868)
			(xy 337.6803 -401.893532) (xy 337.679874 -401.884346) (xy 337.673371 -401.867162) (xy 337.6676 -401.860004)
			(xy 337.645794 -401.834367) (xy 337.607848 -401.778778) (xy 337.576818 -401.719052) (xy 337.553148 -401.656045)
			(xy 337.537178 -401.590662) (xy 337.529136 -401.523838) (xy 337.529137 -401.456532) (xy 337.537183 -401.389709)
			(xy 337.553157 -401.324326) (xy 337.57683 -401.261321) (xy 337.607864 -401.201596) (xy 337.645812 -401.146009)
			(xy 337.6676 -401.120356) (xy 337.673398 -401.113212) (xy 337.679912 -401.09602) (xy 337.6803 -401.086828)
			(xy 337.6803 -400.92884) (xy 337.680755 -400.918688) (xy 337.688537 -400.899937) (xy 337.702924 -400.885612)
			(xy 337.721709 -400.877911) (xy 337.731862 -400.877532) (xy 338.448142 -400.877532) (xy 338.45827 -400.877992)
			(xy 338.476991 -400.885732) (xy 338.491346 -400.900026) (xy 338.499165 -400.918714) (xy 338.499704 -400.92884)
			(xy 338.499704 -401.086828) (xy 338.5001 -401.096017) (xy 338.506623 -401.113201) (xy 338.512404 -401.120356)
			(xy 338.534171 -401.146025) (xy 338.572117 -401.20161) (xy 338.603149 -401.261332) (xy 338.626821 -401.324334)
			(xy 338.642794 -401.389714) (xy 338.650839 -401.456534) (xy 338.650841 -401.523836) (xy 338.6428 -401.590657)
			(xy 338.62683 -401.656037) (xy 338.603161 -401.719041) (xy 338.600721 -401.723737) (xy 339.72927 -401.723737)
			(xy 339.729272 -401.65643) (xy 339.737319 -401.589606) (xy 339.753294 -401.524222) (xy 339.77697 -401.461217)
			(xy 339.808006 -401.401492) (xy 339.845959 -401.345906) (xy 339.867748 -401.320254) (xy 339.873553 -401.313115)
			(xy 339.880061 -401.295919) (xy 339.880448 -401.286726) (xy 339.880448 -400.793458) (xy 339.880047 -400.78427)
			(xy 339.873526 -400.767086) (xy 339.867748 -400.75993) (xy 339.845966 -400.734273) (xy 339.808017 -400.678687)
			(xy 339.776983 -400.618965) (xy 339.753309 -400.555961) (xy 339.737335 -400.490579) (xy 339.729291 -400.423757)
			(xy 339.72929 -400.356452) (xy 339.737334 -400.28963) (xy 339.753306 -400.224248) (xy 339.776979 -400.161244)
			(xy 339.808012 -400.10152) (xy 339.845961 -400.045934) (xy 339.867748 -400.020282) (xy 339.873541 -400.013134)
			(xy 339.880056 -399.995946) (xy 339.880448 -399.986754) (xy 339.880448 -399.828766) (xy 339.880906 -399.818605)
			(xy 339.888693 -399.799833) (xy 339.90307 -399.785469) (xy 339.921848 -399.777697) (xy 339.93201 -399.777204)
			(xy 340.64829 -399.777204) (xy 340.658443 -399.777741) (xy 340.677205 -399.785506) (xy 340.69157 -399.799858)
			(xy 340.699351 -399.818613) (xy 340.699852 -399.828766) (xy 340.699852 -399.986754) (xy 340.700295 -399.995937)
			(xy 340.706787 -400.013121) (xy 340.712552 -400.020282) (xy 340.734346 -400.045929) (xy 340.772295 -400.101516)
			(xy 340.803329 -400.16124) (xy 340.827002 -400.224245) (xy 340.842975 -400.289628) (xy 340.851018 -400.356452)
			(xy 340.851018 -400.423757) (xy 340.842973 -400.490581) (xy 340.826999 -400.555963) (xy 340.803325 -400.618968)
			(xy 340.772291 -400.678692) (xy 340.734341 -400.734278) (xy 340.712552 -400.75993) (xy 340.706754 -400.767074)
			(xy 340.700242 -400.784266) (xy 340.699852 -400.793458) (xy 340.699852 -401.286726) (xy 340.70026 -401.295913)
			(xy 340.706777 -401.313097) (xy 340.712552 -401.320254) (xy 340.734318 -401.345924) (xy 340.772268 -401.401508)
			(xy 340.803303 -401.461229) (xy 340.826977 -401.524231) (xy 340.842952 -401.589611) (xy 340.850998 -401.656432)
			(xy 340.851 -401.723735) (xy 340.842958 -401.790556) (xy 340.826987 -401.855937) (xy 340.803316 -401.918941)
			(xy 340.772285 -401.978664) (xy 340.734338 -402.03425) (xy 340.712552 -402.059902) (xy 340.706766 -402.067055)
			(xy 340.700246 -402.08424) (xy 340.699852 -402.09343) (xy 340.699852 -402.251418) (xy 340.699381 -402.261578)
			(xy 340.691599 -402.28035) (xy 340.677226 -402.294715) (xy 340.65845 -402.302487) (xy 340.64829 -402.30298)
			(xy 339.93201 -402.30298) (xy 339.921855 -402.302459) (xy 339.90309 -402.294691) (xy 339.888725 -402.280334)
			(xy 339.880947 -402.261573) (xy 339.880448 -402.251418) (xy 339.880448 -402.09343) (xy 339.880013 -402.084246)
			(xy 339.873515 -402.067062) (xy 339.867748 -402.059902) (xy 339.845938 -402.034268) (xy 339.807989 -401.978679)
			(xy 339.776957 -401.918953) (xy 339.753285 -401.855946) (xy 339.737313 -401.790562) (xy 339.72927 -401.723737)
			(xy 338.600721 -401.723737) (xy 338.572133 -401.778764) (xy 338.534189 -401.834351) (xy 338.512404 -401.860004)
			(xy 338.506624 -401.867161) (xy 338.500099 -401.884342) (xy 338.499704 -401.893532) (xy 338.499704 -402.3868)
			(xy 338.500113 -402.395987) (xy 338.506628 -402.413172) (xy 338.512404 -402.420328) (xy 338.534143 -402.44602)
			(xy 338.572091 -402.501601) (xy 338.603124 -402.56132) (xy 338.626797 -402.624319) (xy 338.642772 -402.689696)
			(xy 338.65082 -402.756514) (xy 338.650824 -402.823814) (xy 338.650816 -402.823878) (xy 341.928884 -402.823878)
			(xy 341.928889 -402.75645) (xy 341.936969 -402.689509) (xy 341.95301 -402.624017) (xy 341.976779 -402.560918)
			(xy 342.007935 -402.501121) (xy 342.046029 -402.445485) (xy 342.067896 -402.41982) (xy 342.073709 -402.412686)
			(xy 342.080214 -402.395487) (xy 342.080596 -402.386292) (xy 342.080596 -401.89404) (xy 342.080168 -401.884855)
			(xy 342.073667 -401.86767) (xy 342.067896 -401.860512) (xy 342.046013 -401.834863) (xy 342.007925 -401.779226)
			(xy 341.976775 -401.719428) (xy 341.953012 -401.656329) (xy 341.936978 -401.590838) (xy 341.928904 -401.523898)
			(xy 341.928906 -401.456472) (xy 341.936984 -401.389533) (xy 341.953021 -401.324043) (xy 341.976787 -401.260945)
			(xy 342.00794 -401.201148) (xy 342.046031 -401.145513) (xy 342.067896 -401.119848) (xy 342.073697 -401.112706)
			(xy 342.080209 -401.095513) (xy 342.080596 -401.08632) (xy 342.080596 -400.92884) (xy 342.081049 -400.918721)
			(xy 342.088783 -400.900019) (xy 342.103088 -400.885703) (xy 342.121785 -400.877956) (xy 342.131904 -400.877532)
			(xy 342.848184 -400.877532) (xy 342.858309 -400.87793) (xy 342.877019 -400.885679) (xy 342.891335 -400.900001)
			(xy 342.899075 -400.918714) (xy 342.899492 -400.92884) (xy 342.899492 -401.08632) (xy 342.899894 -401.095508)
			(xy 342.906413 -401.112692) (xy 342.912192 -401.119848) (xy 342.934037 -401.145529) (xy 342.972126 -401.201161)
			(xy 343.003278 -401.260955) (xy 343.027044 -401.32405) (xy 343.043081 -401.389537) (xy 343.051159 -401.456474)
			(xy 343.051161 -401.523896) (xy 343.043087 -401.590833) (xy 343.027053 -401.656321) (xy 343.003291 -401.719417)
			(xy 343.001041 -401.723737) (xy 344.129061 -401.723737) (xy 344.129063 -401.65643) (xy 344.13711 -401.589606)
			(xy 344.153085 -401.524223) (xy 344.17676 -401.461217) (xy 344.207796 -401.401493) (xy 344.245747 -401.345906)
			(xy 344.267536 -401.320254) (xy 344.273339 -401.313114) (xy 344.279849 -401.295919) (xy 344.280236 -401.286726)
			(xy 344.280236 -400.793458) (xy 344.279838 -400.78427) (xy 344.273315 -400.767086) (xy 344.267536 -400.75993)
			(xy 344.245754 -400.734273) (xy 344.207805 -400.678687) (xy 344.176772 -400.618964) (xy 344.153099 -400.55596)
			(xy 344.137126 -400.490579) (xy 344.129081 -400.423757) (xy 344.129081 -400.356452) (xy 344.137124 -400.28963)
			(xy 344.153096 -400.224248) (xy 344.176768 -400.161244) (xy 344.207801 -400.101521) (xy 344.245749 -400.045934)
			(xy 344.267536 -400.020282) (xy 344.273327 -400.013133) (xy 344.279844 -399.995945) (xy 344.280236 -399.986754)
			(xy 344.280236 -399.828766) (xy 344.280705 -399.818606) (xy 344.288491 -399.799837) (xy 344.302864 -399.785473)
			(xy 344.321638 -399.777699) (xy 344.331798 -399.777204) (xy 345.048078 -399.777204) (xy 345.05823 -399.77775)
			(xy 345.076992 -399.785511) (xy 345.091357 -399.799861) (xy 345.099139 -399.818614) (xy 345.09964 -399.828766)
			(xy 345.09964 -399.986754) (xy 345.100086 -399.995937) (xy 345.106576 -400.013121) (xy 345.11234 -400.020282)
			(xy 345.134134 -400.045929) (xy 345.172084 -400.101516) (xy 345.203118 -400.16124) (xy 345.226792 -400.224245)
			(xy 345.242765 -400.289628) (xy 345.250809 -400.356452) (xy 345.250808 -400.423757) (xy 345.242763 -400.490581)
			(xy 345.226789 -400.555964) (xy 345.203115 -400.618968) (xy 345.172079 -400.678692) (xy 345.134129 -400.734278)
			(xy 345.11234 -400.75993) (xy 345.106541 -400.767073) (xy 345.100029 -400.784265) (xy 345.09964 -400.793458)
			(xy 345.09964 -401.286726) (xy 345.100051 -401.295913) (xy 345.106566 -401.313096) (xy 345.11234 -401.320254)
			(xy 345.134107 -401.345924) (xy 345.172057 -401.401507) (xy 345.203093 -401.461228) (xy 345.226768 -401.52423)
			(xy 345.242743 -401.589611) (xy 345.250789 -401.656432) (xy 345.250791 -401.723735) (xy 345.242749 -401.790557)
			(xy 345.226778 -401.855938) (xy 345.203106 -401.918942) (xy 345.172074 -401.978664) (xy 345.134127 -402.03425)
			(xy 345.11234 -402.059902) (xy 345.106553 -402.067053) (xy 345.100034 -402.084239) (xy 345.09964 -402.09343)
			(xy 345.09964 -402.251418) (xy 345.09925 -402.261593) (xy 345.091455 -402.280393) (xy 345.077059 -402.294778)
			(xy 345.058254 -402.302558) (xy 345.048078 -402.30298) (xy 344.331798 -402.30298) (xy 344.321642 -402.302469)
			(xy 344.302877 -402.294697) (xy 344.288512 -402.280337) (xy 344.280735 -402.261574) (xy 344.280236 -402.251418)
			(xy 344.280236 -402.09343) (xy 344.279803 -402.084245) (xy 344.273304 -402.067061) (xy 344.267536 -402.059902)
			(xy 344.245727 -402.034268) (xy 344.207779 -401.978679) (xy 344.176746 -401.918953) (xy 344.153075 -401.855946)
			(xy 344.137104 -401.790561) (xy 344.129061 -401.723737) (xy 343.001041 -401.723737) (xy 342.972142 -401.779213)
			(xy 342.934055 -401.834847) (xy 342.912192 -401.860512) (xy 342.906407 -401.867665) (xy 342.899886 -401.88485)
			(xy 342.899492 -401.89404) (xy 342.899492 -402.386292) (xy 342.899908 -402.395479) (xy 342.906418 -402.412663)
			(xy 342.912192 -402.41982) (xy 342.934009 -402.445524) (xy 342.9721 -402.501153) (xy 343.003253 -402.560944)
			(xy 343.02702 -402.624035) (xy 343.043059 -402.68952) (xy 343.051139 -402.756454) (xy 343.051143 -402.823819)
			(xy 346.329179 -402.823819) (xy 346.329184 -402.756509) (xy 346.337233 -402.689682) (xy 346.353213 -402.624297)
			(xy 346.376893 -402.56129) (xy 346.407934 -402.501566) (xy 346.445892 -402.445979) (xy 346.467684 -402.420328)
			(xy 346.473492 -402.413191) (xy 346.48 -402.395994) (xy 346.480384 -402.3868) (xy 346.480384 -401.893532)
			(xy 346.479962 -401.884346) (xy 346.473457 -401.867161) (xy 346.467684 -401.860004) (xy 346.445875 -401.834369)
			(xy 346.407924 -401.778781) (xy 346.376889 -401.719055) (xy 346.353216 -401.656049) (xy 346.337243 -401.590664)
			(xy 346.3292 -401.523839) (xy 346.329201 -401.456531) (xy 346.337248 -401.389707) (xy 346.353225 -401.324323)
			(xy 346.376902 -401.261317) (xy 346.40794 -401.201593) (xy 346.445894 -401.146008) (xy 346.467684 -401.120356)
			(xy 346.47348 -401.11321) (xy 346.479995 -401.09602) (xy 346.480384 -401.086828) (xy 346.480384 -400.92884)
			(xy 346.480854 -400.91869) (xy 346.488634 -400.899942) (xy 346.503015 -400.885618) (xy 346.521795 -400.877914)
			(xy 346.531946 -400.877532) (xy 347.248226 -400.877532) (xy 347.258353 -400.878005) (xy 347.277074 -400.88574)
			(xy 347.291429 -400.90003) (xy 347.299249 -400.918715) (xy 347.299788 -400.92884) (xy 347.299788 -401.086828)
			(xy 347.300187 -401.096016) (xy 347.306709 -401.1132) (xy 347.312488 -401.120356) (xy 347.334255 -401.146025)
			(xy 347.372203 -401.201609) (xy 347.403236 -401.261331) (xy 347.426908 -401.324333) (xy 347.442882 -401.389713)
			(xy 347.450927 -401.456533) (xy 347.450929 -401.523836) (xy 347.442887 -401.590657) (xy 347.426917 -401.656038)
			(xy 347.403248 -401.719042) (xy 347.400809 -401.723737) (xy 374.929092 -401.723737) (xy 374.929094 -401.65643)
			(xy 374.937141 -401.589605) (xy 374.953117 -401.524221) (xy 374.976794 -401.461216) (xy 375.007832 -401.401492)
			(xy 375.045786 -401.345906) (xy 375.067576 -401.320254) (xy 375.073372 -401.313108) (xy 375.079888 -401.295918)
			(xy 375.080276 -401.286726) (xy 375.080276 -400.793458) (xy 375.079891 -400.784268) (xy 375.07336 -400.767084)
			(xy 375.067576 -400.75993) (xy 375.045793 -400.734273) (xy 375.007842 -400.678688) (xy 374.976806 -400.618966)
			(xy 374.953131 -400.555962) (xy 374.937157 -400.49058) (xy 374.929112 -400.423757) (xy 374.929111 -400.356452)
			(xy 374.937155 -400.289629) (xy 374.953129 -400.224247) (xy 374.976802 -400.161242) (xy 375.007837 -400.101519)
			(xy 375.045788 -400.045934) (xy 375.067576 -400.020282) (xy 375.07336 -400.013128) (xy 375.079883 -399.995944)
			(xy 375.080276 -399.986754) (xy 375.080276 -399.828766) (xy 375.080637 -399.818587) (xy 375.08844 -399.799785)
			(xy 375.102845 -399.7854) (xy 375.121659 -399.777623) (xy 375.131838 -399.777204) (xy 375.848118 -399.777204)
			(xy 375.858273 -399.777718) (xy 375.877036 -399.785492) (xy 375.891399 -399.799851) (xy 375.899179 -399.818611)
			(xy 375.89968 -399.828766) (xy 375.89968 -399.986754) (xy 375.900117 -399.995938) (xy 375.906612 -400.013123)
			(xy 375.91238 -400.020282) (xy 375.934173 -400.045929) (xy 375.972121 -400.101517) (xy 376.003152 -400.161241)
			(xy 376.026824 -400.224247) (xy 376.042796 -400.289629) (xy 376.050839 -400.356452) (xy 376.050839 -400.423757)
			(xy 376.042794 -400.49058) (xy 376.026821 -400.555962) (xy 376.003149 -400.618967) (xy 375.972116 -400.678691)
			(xy 375.934168 -400.734278) (xy 375.91238 -400.75993) (xy 375.906586 -400.767077) (xy 375.90007 -400.784266)
			(xy 375.89968 -400.793458) (xy 375.89968 -401.286726) (xy 375.900082 -401.295914) (xy 375.906602 -401.313098)
			(xy 375.91238 -401.320254) (xy 375.934146 -401.345924) (xy 375.972094 -401.401508) (xy 376.003127 -401.46123)
			(xy 376.0268 -401.524232) (xy 376.042774 -401.589612) (xy 376.05082 -401.656432) (xy 376.050822 -401.723735)
			(xy 376.04278 -401.790556) (xy 376.02681 -401.855937) (xy 376.003141 -401.91894) (xy 375.972111 -401.978663)
			(xy 375.934166 -402.03425) (xy 375.91238 -402.059902) (xy 375.906598 -402.067057) (xy 375.900075 -402.08424)
			(xy 375.89968 -402.09343) (xy 375.89968 -402.251418) (xy 375.899182 -402.261575) (xy 375.891405 -402.280341)
			(xy 375.877041 -402.294705) (xy 375.858275 -402.302482) (xy 375.848118 -402.30298) (xy 375.131838 -402.30298)
			(xy 375.121671 -402.302505) (xy 375.102881 -402.294736) (xy 375.088495 -402.280366) (xy 375.080706 -402.261584)
			(xy 375.080276 -402.251418) (xy 375.080276 -402.09343) (xy 375.079857 -402.084244) (xy 375.07335 -402.067059)
			(xy 375.067576 -402.059902) (xy 375.045766 -402.034268) (xy 375.007815 -401.97868) (xy 374.976781 -401.918954)
			(xy 374.953108 -401.855947) (xy 374.937135 -401.790562) (xy 374.929092 -401.723737) (xy 347.400809 -401.723737)
			(xy 347.372218 -401.778765) (xy 347.334274 -401.834352) (xy 347.312488 -401.860004) (xy 347.306706 -401.867159)
			(xy 347.300183 -401.884342) (xy 347.299788 -401.893532) (xy 347.299788 -402.3868) (xy 347.300201 -402.395987)
			(xy 347.306713 -402.413171) (xy 347.312488 -402.420328) (xy 347.334227 -402.44602) (xy 347.372176 -402.501601)
			(xy 347.40321 -402.561319) (xy 347.426884 -402.624319) (xy 347.442859 -402.689696) (xy 347.450907 -402.756514)
			(xy 347.450911 -402.823814) (xy 347.450903 -402.823878) (xy 377.128705 -402.823878) (xy 377.12871 -402.75645)
			(xy 377.136791 -402.689508) (xy 377.152832 -402.624016) (xy 377.176603 -402.560917) (xy 377.20776 -402.50112)
			(xy 377.245856 -402.445485) (xy 377.267724 -402.41982) (xy 377.27354 -402.412689) (xy 377.280042 -402.395487)
			(xy 377.280424 -402.386292) (xy 377.280424 -401.89404) (xy 377.279989 -401.884856) (xy 377.273492 -401.867671)
			(xy 377.267724 -401.860512) (xy 377.24584 -401.834863) (xy 377.20775 -401.779227) (xy 377.176599 -401.719429)
			(xy 377.152835 -401.65633) (xy 377.1368 -401.590838) (xy 377.128725 -401.523898) (xy 377.128727 -401.456472)
			(xy 377.136805 -401.389532) (xy 377.152843 -401.324042) (xy 377.176611 -401.260944) (xy 377.207765 -401.201147)
			(xy 377.245858 -401.145513) (xy 377.267724 -401.119848) (xy 377.273528 -401.112708) (xy 377.280037 -401.095513)
			(xy 377.280424 -401.08632) (xy 377.280424 -400.92884) (xy 377.280849 -400.918717) (xy 377.288589 -400.90001)
			(xy 377.302903 -400.885693) (xy 377.321609 -400.877951) (xy 377.331732 -400.877532) (xy 378.048012 -400.877532)
			(xy 378.058139 -400.877907) (xy 378.076849 -400.885665) (xy 378.091164 -400.899994) (xy 378.098904 -400.918712)
			(xy 378.09932 -400.92884) (xy 378.09932 -401.08632) (xy 378.099716 -401.095509) (xy 378.106239 -401.112693)
			(xy 378.11202 -401.119848) (xy 378.133864 -401.14553) (xy 378.171952 -401.201162) (xy 378.203102 -401.260957)
			(xy 378.226866 -401.324051) (xy 378.242903 -401.389538) (xy 378.25098 -401.456474) (xy 378.250982 -401.523896)
			(xy 378.242908 -401.590832) (xy 378.226875 -401.65632) (xy 378.203114 -401.719416) (xy 378.200833 -401.723796)
			(xy 379.328885 -401.723796) (xy 379.328887 -401.656371) (xy 379.336964 -401.589432) (xy 379.353001 -401.523942)
			(xy 379.376766 -401.460844) (xy 379.407918 -401.401047) (xy 379.446008 -401.345412) (xy 379.467872 -401.319746)
			(xy 379.473683 -401.312611) (xy 379.480187 -401.295412) (xy 379.480572 -401.286218) (xy 379.480572 -400.793966)
			(xy 379.480184 -400.784776) (xy 379.473656 -400.767592) (xy 379.467872 -400.760438) (xy 379.446015 -400.734767)
			(xy 379.407928 -400.679133) (xy 379.376778 -400.619337) (xy 379.353015 -400.556241) (xy 379.33698 -400.490753)
			(xy 379.328904 -400.423816) (xy 379.328904 -400.356393) (xy 379.336979 -400.289456) (xy 379.353013 -400.223967)
			(xy 379.376775 -400.160871) (xy 379.407923 -400.101075) (xy 379.446009 -400.04544) (xy 379.467872 -400.019774)
			(xy 379.473671 -400.012631) (xy 379.480182 -399.995438) (xy 379.480572 -399.986246) (xy 379.480572 -399.828766)
			(xy 379.481 -399.818633) (xy 379.488744 -399.799905) (xy 379.503049 -399.785549) (xy 379.521749 -399.777737)
			(xy 379.53188 -399.777204) (xy 380.24816 -399.777204) (xy 380.25828 -399.777649) (xy 380.276984 -399.785385)
			(xy 380.2913 -399.799693) (xy 380.299045 -399.818392) (xy 380.299468 -399.828512) (xy 380.299468 -399.986246)
			(xy 380.299911 -399.99543) (xy 380.306403 -400.012614) (xy 380.312168 -400.019774) (xy 380.334039 -400.045434)
			(xy 380.37213 -400.101068) (xy 380.403282 -400.160865) (xy 380.427047 -400.223963) (xy 380.443083 -400.289453)
			(xy 380.451159 -400.356392) (xy 380.451158 -400.423817) (xy 380.443082 -400.490756) (xy 380.427044 -400.556246)
			(xy 380.403278 -400.619343) (xy 380.372125 -400.679139) (xy 380.334033 -400.734773) (xy 380.312168 -400.760438)
			(xy 380.306369 -400.767581) (xy 380.299856 -400.784773) (xy 380.299468 -400.793966) (xy 380.299468 -401.286218)
			(xy 380.299877 -401.295405) (xy 380.306392 -401.312589) (xy 380.312168 -401.319746) (xy 380.334011 -401.345429)
			(xy 380.372103 -401.40106) (xy 380.403256 -401.460853) (xy 380.427023 -401.523948) (xy 380.443061 -401.589435)
			(xy 380.451139 -401.656372) (xy 380.451141 -401.723795) (xy 380.443067 -401.790732) (xy 380.427033 -401.85622)
			(xy 380.40327 -401.919316) (xy 380.37212 -401.979112) (xy 380.334032 -402.034745) (xy 380.312168 -402.06041)
			(xy 380.306381 -402.067562) (xy 380.299861 -402.084747) (xy 380.299468 -402.093938) (xy 380.299468 -402.251418)
			(xy 380.298989 -402.261545) (xy 380.291256 -402.280265) (xy 380.276968 -402.29462) (xy 380.258284 -402.30244)
			(xy 380.24816 -402.30298) (xy 379.53188 -402.30298) (xy 379.521754 -402.3026) (xy 379.503046 -402.294842)
			(xy 379.488731 -402.280514) (xy 379.48099 -402.261799) (xy 379.480572 -402.251672) (xy 379.480572 -402.093938)
			(xy 379.48015 -402.084752) (xy 379.473645 -402.067567) (xy 379.467872 -402.06041) (xy 379.445987 -402.034762)
			(xy 379.407901 -401.979124) (xy 379.376753 -401.919326) (xy 379.352991 -401.856227) (xy 379.336958 -401.790736)
			(xy 379.328885 -401.723796) (xy 378.200833 -401.723796) (xy 378.171967 -401.779212) (xy 378.133882 -401.834846)
			(xy 378.11202 -401.860512) (xy 378.106238 -401.867668) (xy 378.099714 -401.88485) (xy 378.09932 -401.89404)
			(xy 378.09932 -402.386292) (xy 378.099729 -402.395479) (xy 378.106243 -402.412664) (xy 378.11202 -402.41982)
			(xy 378.133836 -402.445524) (xy 378.171925 -402.501154) (xy 378.203077 -402.560945) (xy 378.226843 -402.624037)
			(xy 378.242881 -402.689521) (xy 378.25096 -402.756454) (xy 378.250965 -402.823818) (xy 381.529025 -402.823818)
			(xy 381.529029 -402.75651) (xy 381.537078 -402.689684) (xy 381.553055 -402.6243) (xy 381.576732 -402.561293)
			(xy 381.607769 -402.501568) (xy 381.645722 -402.445981) (xy 381.667512 -402.420328) (xy 381.673323 -402.413193)
			(xy 381.679829 -402.395995) (xy 381.680212 -402.3868) (xy 381.680212 -401.893532) (xy 381.679784 -401.884347)
			(xy 381.673282 -401.867162) (xy 381.667512 -401.860004) (xy 381.645705 -401.834368) (xy 381.607759 -401.778778)
			(xy 381.576728 -401.719052) (xy 381.553058 -401.656046) (xy 381.537087 -401.590662) (xy 381.529045 -401.523838)
			(xy 381.529046 -401.456532) (xy 381.537092 -401.389708) (xy 381.553066 -401.324325) (xy 381.57674 -401.26132)
			(xy 381.607774 -401.201596) (xy 381.645724 -401.146009) (xy 381.667512 -401.120356) (xy 381.673311 -401.113213)
			(xy 381.679824 -401.096021) (xy 381.680212 -401.086828) (xy 381.680212 -400.92884) (xy 381.680649 -400.918719)
			(xy 381.688386 -400.900014) (xy 381.702697 -400.885698) (xy 381.721399 -400.877953) (xy 381.73152 -400.877532)
			(xy 382.448054 -400.877532) (xy 382.458177 -400.878064) (xy 382.476895 -400.885775) (xy 382.491253 -400.900048)
			(xy 382.499075 -400.91872) (xy 382.499616 -400.92884) (xy 382.499616 -401.086828) (xy 382.500009 -401.096017)
			(xy 382.506534 -401.113201) (xy 382.512316 -401.120356) (xy 382.534085 -401.146024) (xy 382.572038 -401.201607)
			(xy 382.603074 -401.261328) (xy 382.62675 -401.32433) (xy 382.642726 -401.389711) (xy 382.650772 -401.456533)
			(xy 382.650774 -401.523837) (xy 382.642731 -401.590659) (xy 382.626759 -401.656041) (xy 382.603087 -401.719045)
			(xy 382.600649 -401.723737) (xy 383.729179 -401.723737) (xy 383.729181 -401.65643) (xy 383.737228 -401.589605)
			(xy 383.753204 -401.524222) (xy 383.77688 -401.461216) (xy 383.807917 -401.401492) (xy 383.84587 -401.345906)
			(xy 383.86766 -401.320254) (xy 383.873466 -401.313116) (xy 383.879973 -401.29592) (xy 383.88036 -401.286726)
			(xy 383.88036 -400.793458) (xy 383.879957 -400.78427) (xy 383.873437 -400.767087) (xy 383.86766 -400.75993)
			(xy 383.845878 -400.734273) (xy 383.807927 -400.678688) (xy 383.776893 -400.618965) (xy 383.753219 -400.555961)
			(xy 383.737245 -400.490579) (xy 383.7292 -400.423757) (xy 383.729199 -400.356452) (xy 383.737243 -400.28963)
			(xy 383.753216 -400.224247) (xy 383.776889 -400.161243) (xy 383.807923 -400.10152) (xy 383.845872 -400.045934)
			(xy 383.86766 -400.020282) (xy 383.873454 -400.013135) (xy 383.879969 -399.995946) (xy 383.88036 -399.986754)
			(xy 383.88036 -399.828766) (xy 383.880806 -399.818603) (xy 383.888596 -399.799829) (xy 383.902976 -399.785464)
			(xy 383.921759 -399.777695) (xy 383.931922 -399.777204) (xy 384.648202 -399.777204) (xy 384.658356 -399.777731)
			(xy 384.677118 -399.7855) (xy 384.691482 -399.799855) (xy 384.699263 -399.818613) (xy 384.699764 -399.828766)
			(xy 384.699764 -399.986754) (xy 384.700205 -399.995938) (xy 384.706698 -400.013122) (xy 384.712464 -400.020282)
			(xy 384.734258 -400.045929) (xy 384.772206 -400.101516) (xy 384.803239 -400.161241) (xy 384.826911 -400.224246)
			(xy 384.842884 -400.289629) (xy 384.850927 -400.356452) (xy 384.850927 -400.423757) (xy 384.842882 -400.49058)
			(xy 384.826909 -400.555963) (xy 384.803235 -400.618968) (xy 384.772201 -400.678691) (xy 384.734252 -400.734278)
			(xy 384.712464 -400.75993) (xy 384.706668 -400.767075) (xy 384.700154 -400.784266) (xy 384.699764 -400.793458)
			(xy 384.699764 -401.286726) (xy 384.70017 -401.295913) (xy 384.706687 -401.313097) (xy 384.712464 -401.320254)
			(xy 384.73423 -401.345924) (xy 384.772179 -401.401508) (xy 384.803213 -401.461229) (xy 384.826887 -401.524231)
			(xy 384.842861 -401.589611) (xy 384.850907 -401.656432) (xy 384.850909 -401.723735) (xy 384.842867 -401.790556)
			(xy 384.826897 -401.855937) (xy 384.803227 -401.918941) (xy 384.772196 -401.978663) (xy 384.73425 -402.03425)
			(xy 384.712464 -402.059902) (xy 384.706679 -402.067056) (xy 384.700158 -402.08424) (xy 384.699764 -402.09343)
			(xy 384.699764 -402.251418) (xy 384.699282 -402.261577) (xy 384.691502 -402.280346) (xy 384.677133 -402.294711)
			(xy 384.658361 -402.302485) (xy 384.648202 -402.30298) (xy 383.931922 -402.30298) (xy 383.921754 -402.302518)
			(xy 383.902963 -402.294744) (xy 383.888578 -402.28037) (xy 383.88079 -402.261586) (xy 383.88036 -402.251418)
			(xy 383.88036 -402.09343) (xy 383.879922 -402.084246) (xy 383.873426 -402.067062) (xy 383.86766 -402.059902)
			(xy 383.84585 -402.034268) (xy 383.8079 -401.97868) (xy 383.776867 -401.918954) (xy 383.753194 -401.855947)
			(xy 383.737222 -401.790562) (xy 383.729179 -401.723737) (xy 382.600649 -401.723737) (xy 382.572053 -401.778767)
			(xy 382.534104 -401.834352) (xy 382.512316 -401.860004) (xy 382.506537 -401.867162) (xy 382.500011 -401.884343)
			(xy 382.499616 -401.893532) (xy 382.499616 -402.3868) (xy 382.500023 -402.395988) (xy 382.506538 -402.413172)
			(xy 382.512316 -402.420328) (xy 382.534058 -402.446018) (xy 382.572011 -402.501598) (xy 382.603049 -402.561316)
			(xy 382.626726 -402.624316) (xy 382.642704 -402.689694) (xy 382.650753 -402.756513) (xy 382.650757 -402.823815)
			(xy 382.650749 -402.823878) (xy 385.928793 -402.823878) (xy 385.928798 -402.75645) (xy 385.936878 -402.689508)
			(xy 385.952919 -402.624017) (xy 385.976689 -402.560918) (xy 386.007846 -402.50112) (xy 386.045941 -402.445485)
			(xy 386.067808 -402.41982) (xy 386.073622 -402.412687) (xy 386.080126 -402.395487) (xy 386.080508 -402.386292)
			(xy 386.080508 -401.89404) (xy 386.080077 -401.884855) (xy 386.073578 -401.867671) (xy 386.067808 -401.860512)
			(xy 386.045924 -401.834863) (xy 386.007835 -401.779226) (xy 385.976685 -401.719428) (xy 385.952922 -401.656329)
			(xy 385.936887 -401.590838) (xy 385.928813 -401.523898) (xy 385.928815 -401.456472) (xy 385.936893 -401.389533)
			(xy 385.952931 -401.324042) (xy 385.976697 -401.260944) (xy 386.007851 -401.201148) (xy 386.045943 -401.145513)
			(xy 386.067808 -401.119848) (xy 386.07361 -401.112707) (xy 386.080121 -401.095513) (xy 386.080508 -401.08632)
			(xy 386.080508 -400.92884) (xy 386.080949 -400.918719) (xy 386.088686 -400.900015) (xy 386.102995 -400.885699)
			(xy 386.121695 -400.877954) (xy 386.131816 -400.877532) (xy 386.848096 -400.877532) (xy 386.858222 -400.87792)
			(xy 386.876932 -400.885673) (xy 386.891247 -400.899998) (xy 386.898987 -400.918714) (xy 386.899404 -400.92884)
			(xy 386.899404 -401.08632) (xy 386.899804 -401.095508) (xy 386.906325 -401.112692) (xy 386.912104 -401.119848)
			(xy 386.933948 -401.14553) (xy 386.972037 -401.201162) (xy 387.003189 -401.260956) (xy 387.026954 -401.324051)
			(xy 387.04299 -401.389538) (xy 387.051068 -401.456474) (xy 387.05107 -401.523896) (xy 387.042996 -401.590833)
			(xy 387.026963 -401.656321) (xy 387.003201 -401.719417) (xy 387.000951 -401.723737) (xy 388.12897 -401.723737)
			(xy 388.128972 -401.65643) (xy 388.137019 -401.589606) (xy 388.152994 -401.524222) (xy 388.17667 -401.461217)
			(xy 388.207706 -401.401492) (xy 388.245659 -401.345906) (xy 388.267448 -401.320254) (xy 388.273253 -401.313115)
			(xy 388.279761 -401.295919) (xy 388.280148 -401.286726) (xy 388.280148 -400.793458) (xy 388.279747 -400.78427)
			(xy 388.273226 -400.767086) (xy 388.267448 -400.75993) (xy 388.245666 -400.734273) (xy 388.207717 -400.678687)
			(xy 388.176683 -400.618965) (xy 388.153009 -400.555961) (xy 388.137035 -400.490579) (xy 388.128991 -400.423757)
			(xy 388.12899 -400.356452) (xy 388.137034 -400.28963) (xy 388.153006 -400.224248) (xy 388.176679 -400.161244)
			(xy 388.207712 -400.10152) (xy 388.245661 -400.045934) (xy 388.267448 -400.020282) (xy 388.273241 -400.013134)
			(xy 388.279756 -399.995946) (xy 388.280148 -399.986754) (xy 388.280148 -399.828766) (xy 388.280606 -399.818605)
			(xy 388.288393 -399.799833) (xy 388.30277 -399.785469) (xy 388.321548 -399.777697) (xy 388.33171 -399.777204)
			(xy 389.04799 -399.777204) (xy 389.058143 -399.777741) (xy 389.076905 -399.785506) (xy 389.09127 -399.799858)
			(xy 389.099051 -399.818613) (xy 389.099552 -399.828766) (xy 389.099552 -399.986754) (xy 389.099995 -399.995937)
			(xy 389.106487 -400.013121) (xy 389.112252 -400.020282) (xy 389.134046 -400.045929) (xy 389.171995 -400.101516)
			(xy 389.203029 -400.16124) (xy 389.226702 -400.224245) (xy 389.242675 -400.289628) (xy 389.250718 -400.356452)
			(xy 389.250718 -400.423757) (xy 389.242673 -400.490581) (xy 389.226699 -400.555963) (xy 389.203025 -400.618968)
			(xy 389.171991 -400.678692) (xy 389.134041 -400.734278) (xy 389.112252 -400.75993) (xy 389.106454 -400.767074)
			(xy 389.099942 -400.784266) (xy 389.099552 -400.793458) (xy 389.099552 -401.286726) (xy 389.09996 -401.295913)
			(xy 389.106477 -401.313097) (xy 389.112252 -401.320254) (xy 389.134018 -401.345924) (xy 389.171968 -401.401508)
			(xy 389.203003 -401.461229) (xy 389.226677 -401.524231) (xy 389.242652 -401.589611) (xy 389.250698 -401.656432)
			(xy 389.2507 -401.723735) (xy 389.242658 -401.790556) (xy 389.226687 -401.855937) (xy 389.203016 -401.918941)
			(xy 389.171985 -401.978664) (xy 389.134038 -402.03425) (xy 389.112252 -402.059902) (xy 389.106466 -402.067055)
			(xy 389.099946 -402.08424) (xy 389.099552 -402.09343) (xy 389.099552 -402.251418) (xy 389.099081 -402.261578)
			(xy 389.091299 -402.28035) (xy 389.076926 -402.294715) (xy 389.05815 -402.302487) (xy 389.04799 -402.30298)
			(xy 388.33171 -402.30298) (xy 388.321555 -402.302459) (xy 388.30279 -402.294691) (xy 388.288425 -402.280334)
			(xy 388.280647 -402.261573) (xy 388.280148 -402.251418) (xy 388.280148 -402.09343) (xy 388.279713 -402.084246)
			(xy 388.273215 -402.067062) (xy 388.267448 -402.059902) (xy 388.245638 -402.034268) (xy 388.207689 -401.978679)
			(xy 388.176657 -401.918953) (xy 388.152985 -401.855946) (xy 388.137013 -401.790562) (xy 388.12897 -401.723737)
			(xy 387.000951 -401.723737) (xy 386.972053 -401.779212) (xy 386.933967 -401.834847) (xy 386.912104 -401.860512)
			(xy 386.90632 -401.867666) (xy 386.899798 -401.88485) (xy 386.899404 -401.89404) (xy 386.899404 -402.386292)
			(xy 386.899817 -402.395479) (xy 386.906329 -402.412663) (xy 386.912104 -402.41982) (xy 386.933921 -402.445524)
			(xy 386.972011 -402.501153) (xy 387.003163 -402.560944) (xy 387.02693 -402.624036) (xy 387.042968 -402.68952)
			(xy 387.051048 -402.756454) (xy 387.051052 -402.823818) (xy 390.329113 -402.823818) (xy 390.329117 -402.75651)
			(xy 390.337166 -402.689685) (xy 390.353142 -402.6243) (xy 390.376819 -402.561294) (xy 390.407855 -402.501569)
			(xy 390.445807 -402.445981) (xy 390.467596 -402.420328) (xy 390.473405 -402.413192) (xy 390.479912 -402.395994)
			(xy 390.480296 -402.3868) (xy 390.480296 -401.893532) (xy 390.479871 -401.884346) (xy 390.473368 -401.867162)
			(xy 390.467596 -401.860004) (xy 390.44579 -401.834367) (xy 390.407845 -401.778778) (xy 390.376815 -401.719052)
			(xy 390.353145 -401.656045) (xy 390.337174 -401.590661) (xy 390.329133 -401.523838) (xy 390.329134 -401.456532)
			(xy 390.33718 -401.389709) (xy 390.353154 -401.324326) (xy 390.376827 -401.261321) (xy 390.40786 -401.201596)
			(xy 390.445808 -401.146009) (xy 390.467596 -401.120356) (xy 390.473393 -401.113211) (xy 390.479908 -401.09602)
			(xy 390.480296 -401.086828) (xy 390.480296 -400.92884) (xy 390.480749 -400.918721) (xy 390.488483 -400.900019)
			(xy 390.502788 -400.885703) (xy 390.521485 -400.877956) (xy 390.531604 -400.877532) (xy 391.248138 -400.877532)
			(xy 391.258266 -400.877995) (xy 391.276987 -400.885734) (xy 391.291341 -400.900027) (xy 391.299161 -400.918714)
			(xy 391.2997 -400.92884) (xy 391.2997 -401.086828) (xy 391.300096 -401.096017) (xy 391.30662 -401.113201)
			(xy 391.3124 -401.120356) (xy 391.334167 -401.146025) (xy 391.372114 -401.20161) (xy 391.403146 -401.261331)
			(xy 391.426818 -401.324334) (xy 391.442791 -401.389713) (xy 391.450836 -401.456534) (xy 391.450838 -401.523836)
			(xy 391.442797 -401.590657) (xy 391.426827 -401.656038) (xy 391.403158 -401.719041) (xy 391.372129 -401.778764)
			(xy 391.334185 -401.834351) (xy 391.3124 -401.860004) (xy 391.306619 -401.86716) (xy 391.300095 -401.884342)
			(xy 391.2997 -401.893532) (xy 391.2997 -402.3868) (xy 391.30011 -402.395987) (xy 391.306624 -402.413171)
			(xy 391.3124 -402.420328) (xy 391.334139 -402.446019) (xy 391.372087 -402.501601) (xy 391.40312 -402.56132)
			(xy 391.426794 -402.624319) (xy 391.442769 -402.689696) (xy 391.450817 -402.756514) (xy 391.450821 -402.823814)
			(xy 391.442782 -402.890633) (xy 391.426815 -402.956012) (xy 391.40315 -403.019014) (xy 391.372124 -403.078737)
			(xy 391.334184 -403.134323) (xy 391.3124 -403.159976) (xy 391.306589 -403.167111) (xy 391.300083 -403.184309)
			(xy 391.2997 -403.193504) (xy 391.2997 -403.351492) (xy 391.299277 -403.361614) (xy 391.291532 -403.380317)
			(xy 391.277217 -403.394632) (xy 391.258514 -403.402377) (xy 391.248392 -403.4028) (xy 390.531858 -403.4028)
			(xy 390.521734 -403.402309) (xy 390.503019 -403.394575) (xy 390.488666 -403.380291) (xy 390.480841 -403.361614)
			(xy 390.480296 -403.351492) (xy 390.480296 -403.193504) (xy 390.479885 -403.184317) (xy 390.473372 -403.167133)
			(xy 390.467596 -403.159976) (xy 390.445763 -403.134362) (xy 390.407818 -403.078769) (xy 390.376789 -403.01904)
			(xy 390.353121 -402.95603) (xy 390.337153 -402.890644) (xy 390.329113 -402.823818) (xy 387.051052 -402.823818)
			(xy 387.051052 -402.823874) (xy 387.042981 -402.890809) (xy 387.026951 -402.956295) (xy 387.003193 -403.01939)
			(xy 386.972048 -403.079185) (xy 386.933965 -403.134819) (xy 386.912104 -403.160484) (xy 386.90629 -403.167617)
			(xy 386.899785 -403.184817) (xy 386.899404 -403.194012) (xy 386.899404 -403.351492) (xy 386.898978 -403.361613)
			(xy 386.891233 -403.380316) (xy 386.87692 -403.394631) (xy 386.858217 -403.402377) (xy 386.848096 -403.4028)
			(xy 386.131816 -403.4028) (xy 386.121695 -403.402371) (xy 386.102991 -403.394628) (xy 386.088676 -403.380315)
			(xy 386.080931 -403.361613) (xy 386.080508 -403.351492) (xy 386.080508 -403.194012) (xy 386.08009 -403.184826)
			(xy 386.073582 -403.167641) (xy 386.067808 -403.160484) (xy 386.045897 -403.134858) (xy 386.007809 -403.079218)
			(xy 385.97666 -403.019416) (xy 385.952898 -402.956314) (xy 385.936865 -402.89082) (xy 385.928793 -402.823878)
			(xy 382.650749 -402.823878) (xy 382.642717 -402.890635) (xy 382.626748 -402.956015) (xy 382.603078 -403.019018)
			(xy 382.572048 -403.07874) (xy 382.534102 -403.134324) (xy 382.512316 -403.159976) (xy 382.506507 -403.167112)
			(xy 382.499999 -403.18431) (xy 382.499616 -403.193504) (xy 382.499616 -403.351492) (xy 382.499109 -403.361598)
			(xy 382.491377 -403.380273) (xy 382.477087 -403.394568) (xy 382.458414 -403.402306) (xy 382.448308 -403.4028)
			(xy 381.731774 -403.4028) (xy 381.721651 -403.402296) (xy 381.702936 -403.394567) (xy 381.688582 -403.380287)
			(xy 381.680757 -403.361613) (xy 381.680212 -403.351492) (xy 381.680212 -403.193504) (xy 381.679797 -403.184317)
			(xy 381.673286 -403.167133) (xy 381.667512 -403.159976) (xy 381.645678 -403.134362) (xy 381.607732 -403.07877)
			(xy 381.576703 -403.019041) (xy 381.553034 -402.956031) (xy 381.537065 -402.890644) (xy 381.529025 -402.823818)
			(xy 378.250965 -402.823818) (xy 378.250965 -402.823874) (xy 378.242894 -402.890808) (xy 378.226864 -402.956294)
			(xy 378.203106 -403.019389) (xy 378.171962 -403.079184) (xy 378.13388 -403.134818) (xy 378.11202 -403.160484)
			(xy 378.106208 -403.167618) (xy 378.099702 -403.184817) (xy 378.09932 -403.194012) (xy 378.09932 -403.351492)
			(xy 378.098809 -403.361598) (xy 378.091078 -403.380272) (xy 378.076789 -403.394566) (xy 378.058118 -403.402305)
			(xy 378.048012 -403.4028) (xy 377.331732 -403.4028) (xy 377.321612 -403.402358) (xy 377.302909 -403.39462)
			(xy 377.288593 -403.380312) (xy 377.280847 -403.361612) (xy 377.280424 -403.351492) (xy 377.280424 -403.194012)
			(xy 377.280002 -403.184826) (xy 377.273496 -403.167642) (xy 377.267724 -403.160484) (xy 377.245812 -403.134858)
			(xy 377.207723 -403.079218) (xy 377.176573 -403.019417) (xy 377.152811 -402.956315) (xy 377.136778 -402.890821)
			(xy 377.128705 -402.823878) (xy 347.450903 -402.823878) (xy 347.442872 -402.890633) (xy 347.426905 -402.956012)
			(xy 347.403239 -403.019015) (xy 347.372213 -403.078737) (xy 347.334272 -403.134323) (xy 347.312488 -403.159976)
			(xy 347.306675 -403.16711) (xy 347.300171 -403.184309) (xy 347.299788 -403.193504) (xy 347.299788 -403.351492)
			(xy 347.299372 -403.361647) (xy 347.291576 -403.380402) (xy 347.277178 -403.394726) (xy 347.258383 -403.402424)
			(xy 347.248226 -403.4028) (xy 346.531946 -403.4028) (xy 346.521827 -403.402237) (xy 346.503115 -403.394532)
			(xy 346.488758 -403.380269) (xy 346.48093 -403.361607) (xy 346.480384 -403.351492) (xy 346.480384 -403.193504)
			(xy 346.479975 -403.184317) (xy 346.473461 -403.167132) (xy 346.467684 -403.159976) (xy 346.445847 -403.134364)
			(xy 346.407897 -403.078772) (xy 346.376863 -403.019044) (xy 346.353191 -402.956034) (xy 346.33722 -402.890646)
			(xy 346.329179 -402.823819) (xy 343.051143 -402.823819) (xy 343.051143 -402.823874) (xy 343.043072 -402.890809)
			(xy 343.027042 -402.956296) (xy 343.003282 -403.019391) (xy 342.972137 -403.079185) (xy 342.934053 -403.134819)
			(xy 342.912192 -403.160484) (xy 342.906376 -403.167616) (xy 342.899873 -403.184817) (xy 342.899492 -403.194012)
			(xy 342.899492 -403.351492) (xy 342.899077 -403.361615) (xy 342.89133 -403.38032) (xy 342.877013 -403.394635)
			(xy 342.858307 -403.402379) (xy 342.848184 -403.4028) (xy 342.131904 -403.4028) (xy 342.121782 -403.402381)
			(xy 342.103078 -403.394634) (xy 342.088764 -403.380318) (xy 342.081019 -403.361614) (xy 342.080596 -403.351492)
			(xy 342.080596 -403.194012) (xy 342.080181 -403.184825) (xy 342.073671 -403.167641) (xy 342.067896 -403.160484)
			(xy 342.045985 -403.134858) (xy 342.007898 -403.079217) (xy 341.97675 -403.019416) (xy 341.952988 -402.956314)
			(xy 341.936956 -402.89082) (xy 341.928884 -402.823878) (xy 338.650816 -402.823878) (xy 338.642785 -402.890633)
			(xy 338.626819 -402.956012) (xy 338.603153 -403.019014) (xy 338.572128 -403.078737) (xy 338.534188 -403.134323)
			(xy 338.512404 -403.159976) (xy 338.506593 -403.167111) (xy 338.500087 -403.184309) (xy 338.499704 -403.193504)
			(xy 338.499704 -403.351492) (xy 338.499272 -403.361645) (xy 338.49148 -403.380397) (xy 338.477086 -403.39472)
			(xy 338.458297 -403.402421) (xy 338.448142 -403.4028) (xy 337.731862 -403.4028) (xy 337.721738 -403.402306)
			(xy 337.703023 -403.394573) (xy 337.68867 -403.38029) (xy 337.680845 -403.361614) (xy 337.6803 -403.351492)
			(xy 337.6803 -403.193504) (xy 337.679888 -403.184317) (xy 337.673375 -403.167133) (xy 337.6676 -403.159976)
			(xy 337.645766 -403.134362) (xy 337.607822 -403.078769) (xy 337.576793 -403.01904) (xy 337.553124 -402.956031)
			(xy 337.537156 -402.890644) (xy 337.529116 -402.823818) (xy 334.251055 -402.823818) (xy 334.251055 -402.823874)
			(xy 334.242984 -402.890809) (xy 334.226954 -402.956295) (xy 334.203196 -403.01939) (xy 334.172051 -403.079185)
			(xy 334.133969 -403.134819) (xy 334.112108 -403.160484) (xy 334.106294 -403.167617) (xy 334.09979 -403.184817)
			(xy 334.099408 -403.194012) (xy 334.099408 -403.351492) (xy 334.098978 -403.361613) (xy 334.091234 -403.380315)
			(xy 334.076922 -403.394629) (xy 334.058221 -403.402376) (xy 334.0481 -403.4028) (xy 333.33182 -403.4028)
			(xy 333.321699 -403.402368) (xy 333.302996 -403.394626) (xy 333.288681 -403.380315) (xy 333.280935 -403.361613)
			(xy 333.280512 -403.351492) (xy 333.280512 -403.194012) (xy 333.280093 -403.184826) (xy 333.273585 -403.167642)
			(xy 333.267812 -403.160484) (xy 333.2459 -403.134858) (xy 333.207812 -403.079218) (xy 333.176663 -403.019417)
			(xy 333.152901 -402.956315) (xy 333.136869 -402.890821) (xy 333.128796 -402.823878) (xy 326.525636 -402.823878)
			(xy 326.525636 -405.623648) (xy 330.929194 -405.623648) (xy 330.929195 -405.556343) (xy 330.93724 -405.489519)
			(xy 330.953214 -405.424136) (xy 330.976889 -405.361131) (xy 331.007924 -405.301408) (xy 331.045875 -405.245822)
			(xy 331.067664 -405.22017) (xy 331.073464 -405.213027) (xy 331.079975 -405.195835) (xy 331.080364 -405.186642)
			(xy 331.080364 -404.693374) (xy 331.079952 -404.684187) (xy 331.073438 -404.667004) (xy 331.067664 -404.659846)
			(xy 331.045897 -404.634176) (xy 331.007946 -404.578593) (xy 330.976911 -404.518872) (xy 330.953235 -404.45587)
			(xy 330.93726 -404.390489) (xy 330.929214 -404.323668) (xy 330.929212 -404.256365) (xy 330.937254 -404.189543)
			(xy 330.953226 -404.124162) (xy 330.976897 -404.061158) (xy 331.007929 -404.001435) (xy 331.045877 -403.94585)
			(xy 331.067664 -403.920198) (xy 331.073452 -403.913047) (xy 331.07997 -403.895861) (xy 331.080364 -403.88667)
			(xy 331.080364 -403.728682) (xy 331.08075 -403.718506) (xy 331.088546 -403.699706) (xy 331.102943 -403.685321)
			(xy 331.12175 -403.677541) (xy 331.131926 -403.67712) (xy 331.848206 -403.67712) (xy 331.858362 -403.677628)
			(xy 331.877128 -403.685401) (xy 331.891492 -403.699762) (xy 331.899269 -403.718526) (xy 331.899768 -403.728682)
			(xy 331.899768 -403.88667) (xy 331.9002 -403.895855) (xy 331.906699 -403.913039) (xy 331.912468 -403.920198)
			(xy 331.934277 -403.945832) (xy 331.972225 -404.001422) (xy 332.003257 -404.061148) (xy 332.026928 -404.124154)
			(xy 332.042899 -404.189539) (xy 332.050942 -404.256363) (xy 332.05094 -404.32367) (xy 332.042893 -404.390494)
			(xy 332.026918 -404.455877) (xy 332.003243 -404.518883) (xy 331.972208 -404.578607) (xy 331.934257 -404.634194)
			(xy 331.912468 -404.659846) (xy 331.906665 -404.666987) (xy 331.900155 -404.684181) (xy 331.899768 -404.693374)
			(xy 331.899768 -405.186642) (xy 331.900165 -405.19583) (xy 331.906689 -405.213014) (xy 331.912468 -405.22017)
			(xy 331.93425 -405.245827) (xy 331.972198 -405.301413) (xy 332.003231 -405.361136) (xy 332.026904 -405.42414)
			(xy 332.042877 -405.489521) (xy 332.050922 -405.556343) (xy 332.050923 -405.623648) (xy 332.042879 -405.69047)
			(xy 332.026907 -405.755852) (xy 332.003235 -405.818856) (xy 331.972203 -405.878579) (xy 331.934255 -405.934166)
			(xy 331.912468 -405.959818) (xy 331.906677 -405.966967) (xy 331.90016 -405.984155) (xy 331.899768 -405.993346)
			(xy 331.899768 -406.151334) (xy 331.899295 -406.161493) (xy 331.89151 -406.180262) (xy 331.877138 -406.194626)
			(xy 331.858365 -406.2024) (xy 331.848206 -406.202896) (xy 331.131926 -406.202896) (xy 331.121774 -406.202346)
			(xy 331.103012 -406.194587) (xy 331.088647 -406.180238) (xy 331.080865 -406.161485) (xy 331.080364 -406.151334)
			(xy 331.080364 -405.993346) (xy 331.079918 -405.984163) (xy 331.073428 -405.966979) (xy 331.067664 -405.959818)
			(xy 331.04587 -405.934171) (xy 331.007919 -405.878584) (xy 330.976885 -405.81886) (xy 330.953212 -405.755855)
			(xy 330.937238 -405.690472) (xy 330.929194 -405.623648) (xy 326.525636 -405.623648) (xy 326.525636 -406.723789)
			(xy 333.128808 -406.723789) (xy 333.128811 -406.656363) (xy 333.13689 -406.589422) (xy 333.152929 -406.523931)
			(xy 333.176697 -406.460833) (xy 333.207852 -406.401036) (xy 333.245946 -406.345401) (xy 333.267812 -406.319736)
			(xy 333.27362 -406.312599) (xy 333.280127 -406.295402) (xy 333.280512 -406.286208) (xy 333.280512 -405.793956)
			(xy 333.28012 -405.784767) (xy 333.273594 -405.767583) (xy 333.267812 -405.760428) (xy 333.245944 -405.734766)
			(xy 333.207854 -405.679131) (xy 333.176703 -405.619335) (xy 333.152939 -405.556238) (xy 333.136903 -405.490748)
			(xy 333.128827 -405.423809) (xy 333.128828 -405.356385) (xy 333.136904 -405.289446) (xy 333.15294 -405.223957)
			(xy 333.176706 -405.16086) (xy 333.207857 -405.101063) (xy 333.245947 -405.045429) (xy 333.267812 -405.019764)
			(xy 333.273608 -405.012618) (xy 333.280123 -404.995428) (xy 333.280512 -404.986236) (xy 333.280512 -404.828756)
			(xy 333.280949 -404.818643) (xy 333.288704 -404.799961) (xy 333.303015 -404.785668) (xy 333.321706 -404.777937)
			(xy 333.33182 -404.777448) (xy 334.0481 -404.777448) (xy 334.058202 -404.777984) (xy 334.076871 -404.785712)
			(xy 334.091163 -404.799993) (xy 334.098907 -404.818654) (xy 334.099408 -404.828756) (xy 334.099408 -404.986236)
			(xy 334.099799 -404.995425) (xy 334.106326 -405.01261) (xy 334.112108 -405.019764) (xy 334.133968 -405.045433)
			(xy 334.172056 -405.101067) (xy 334.203206 -405.160863) (xy 334.226971 -405.223959) (xy 334.243006 -405.289448)
			(xy 334.251082 -405.356385) (xy 334.251082 -405.423809) (xy 334.243007 -405.490746) (xy 334.226972 -405.556235)
			(xy 334.203209 -405.619332) (xy 334.20093 -405.623707) (xy 335.328987 -405.623707) (xy 335.328987 -405.556284)
			(xy 335.337063 -405.489346) (xy 335.353098 -405.423857) (xy 335.376861 -405.36076) (xy 335.40801 -405.300963)
			(xy 335.446097 -405.245328) (xy 335.46796 -405.219662) (xy 335.473763 -405.212521) (xy 335.480272 -405.195327)
			(xy 335.48066 -405.186134) (xy 335.48066 -404.693882) (xy 335.480245 -404.684696) (xy 335.473733 -404.667512)
			(xy 335.46796 -404.660354) (xy 335.446119 -404.63467) (xy 335.408032 -404.579037) (xy 335.376883 -404.519243)
			(xy 335.353119 -404.456149) (xy 335.337083 -404.390663) (xy 335.329006 -404.323727) (xy 335.329004 -404.256306)
			(xy 335.337078 -404.18937) (xy 335.353109 -404.123883) (xy 335.376869 -404.060787) (xy 335.408015 -404.000991)
			(xy 335.446099 -403.945356) (xy 335.46796 -403.91969) (xy 335.473751 -403.912541) (xy 335.480267 -403.895353)
			(xy 335.48066 -403.886162) (xy 335.48066 -403.728682) (xy 335.481112 -403.718552) (xy 335.48885 -403.699826)
			(xy 335.503147 -403.68547) (xy 335.52184 -403.677655) (xy 335.531968 -403.67712) (xy 336.248248 -403.67712)
			(xy 336.258408 -403.677483) (xy 336.277165 -403.685298) (xy 336.291487 -403.699713) (xy 336.299182 -403.71852)
			(xy 336.299556 -403.728682) (xy 336.299556 -403.886162) (xy 336.299995 -403.895346) (xy 336.30649 -403.91253)
			(xy 336.312256 -403.91969) (xy 336.334143 -403.945337) (xy 336.372234 -404.000973) (xy 336.403386 -404.060771)
			(xy 336.427151 -404.123871) (xy 336.443186 -404.189362) (xy 336.451261 -404.256303) (xy 336.451259 -404.32373)
			(xy 336.443181 -404.39067) (xy 336.427141 -404.456161) (xy 336.403373 -404.519259) (xy 336.372217 -404.579056)
			(xy 336.334123 -404.634689) (xy 336.312256 -404.660354) (xy 336.306449 -404.667491) (xy 336.299941 -404.684688)
			(xy 336.299556 -404.693882) (xy 336.299556 -405.186134) (xy 336.29996 -405.195322) (xy 336.306479 -405.212505)
			(xy 336.312256 -405.219662) (xy 336.334116 -405.245331) (xy 336.372207 -405.300964) (xy 336.403361 -405.360759)
			(xy 336.427127 -405.423856) (xy 336.443164 -405.489345) (xy 336.451242 -405.556283) (xy 336.451242 -405.623708)
			(xy 336.443166 -405.690646) (xy 336.42713 -405.756135) (xy 336.403365 -405.819232) (xy 336.372212 -405.879028)
			(xy 336.334121 -405.934662) (xy 336.312256 -405.960326) (xy 336.30646 -405.967472) (xy 336.299946 -405.984662)
			(xy 336.299556 -405.993854) (xy 336.299556 -406.151334) (xy 336.299101 -406.161463) (xy 336.291362 -406.180186)
			(xy 336.277066 -406.194541) (xy 336.258375 -406.202359) (xy 336.248248 -406.202896) (xy 335.531968 -406.202896)
			(xy 335.521811 -406.202505) (xy 335.503057 -406.194698) (xy 335.488735 -406.180292) (xy 335.481037 -406.161493)
			(xy 335.48066 -406.151334) (xy 335.48066 -405.993854) (xy 335.48021 -405.984671) (xy 335.473722 -405.967487)
			(xy 335.46796 -405.960326) (xy 335.446092 -405.934665) (xy 335.408006 -405.879029) (xy 335.376857 -405.819232)
			(xy 335.353095 -405.756134) (xy 335.337062 -405.690645) (xy 335.328987 -405.623707) (xy 334.20093 -405.623707)
			(xy 334.172059 -405.679128) (xy 334.133971 -405.734763) (xy 334.112108 -405.760428) (xy 334.106318 -405.767578)
			(xy 334.099799 -405.784765) (xy 334.099408 -405.793956) (xy 334.099408 -406.286208) (xy 334.099813 -406.295396)
			(xy 334.10633 -406.31258) (xy 334.112108 -406.319736) (xy 334.13394 -406.345427) (xy 334.172029 -406.401058)
			(xy 334.203181 -406.460851) (xy 334.226947 -406.523944) (xy 334.242984 -406.58943) (xy 334.251062 -406.656365)
			(xy 334.251065 -406.723729) (xy 337.529127 -406.723729) (xy 337.52913 -406.656423) (xy 337.537177 -406.589598)
			(xy 337.553152 -406.524215) (xy 337.576827 -406.461209) (xy 337.607861 -406.401484) (xy 337.645812 -406.345897)
			(xy 337.6676 -406.320244) (xy 337.673403 -406.313103) (xy 337.679914 -406.295909) (xy 337.6803 -406.286716)
			(xy 337.6803 -405.793448) (xy 337.679867 -405.784263) (xy 337.673369 -405.767079) (xy 337.6676 -405.75992)
			(xy 337.64581 -405.734271) (xy 337.607863 -405.678683) (xy 337.576832 -405.618958) (xy 337.553162 -405.555954)
			(xy 337.53719 -405.490572) (xy 337.529147 -405.423749) (xy 337.529147 -405.356445) (xy 337.537191 -405.289622)
			(xy 337.553163 -405.224241) (xy 337.576835 -405.161236) (xy 337.607866 -405.101512) (xy 337.645813 -405.045925)
			(xy 337.6676 -405.020272) (xy 337.673391 -405.013123) (xy 337.679909 -404.995935) (xy 337.6803 -404.986744)
			(xy 337.6803 -404.828756) (xy 337.680686 -404.818599) (xy 337.688496 -404.799846) (xy 337.702903 -404.785524)
			(xy 337.721703 -404.777826) (xy 337.731862 -404.777448) (xy 338.448142 -404.777448) (xy 338.458272 -404.777892)
			(xy 338.476996 -404.785635) (xy 338.491351 -404.799934) (xy 338.499167 -404.818628) (xy 338.499704 -404.828756)
			(xy 338.499704 -404.986744) (xy 338.500092 -404.995934) (xy 338.506621 -405.013118) (xy 338.512404 -405.020272)
			(xy 338.534186 -405.045928) (xy 338.572133 -405.101515) (xy 338.603164 -405.161238) (xy 338.626835 -405.224242)
			(xy 338.642807 -405.289624) (xy 338.650851 -405.356445) (xy 338.650851 -405.423749) (xy 338.642808 -405.490571)
			(xy 338.626837 -405.555952) (xy 338.603166 -405.618956) (xy 338.600728 -405.623648) (xy 339.729282 -405.623648)
			(xy 339.729282 -405.556343) (xy 339.737327 -405.489519) (xy 339.753301 -405.424137) (xy 339.776975 -405.361132)
			(xy 339.808009 -405.301408) (xy 339.845959 -405.245822) (xy 339.867748 -405.22017) (xy 339.873546 -405.213026)
			(xy 339.880058 -405.195834) (xy 339.880448 -405.186642) (xy 339.880448 -404.693374) (xy 339.88004 -404.684187)
			(xy 339.873523 -404.667003) (xy 339.867748 -404.659846) (xy 339.845982 -404.634176) (xy 339.808032 -404.578592)
			(xy 339.776997 -404.518871) (xy 339.753323 -404.455869) (xy 339.737348 -404.390489) (xy 339.729302 -404.323668)
			(xy 339.7293 -404.256365) (xy 339.737342 -404.189544) (xy 339.753313 -404.124163) (xy 339.776984 -404.061159)
			(xy 339.808015 -404.001436) (xy 339.845962 -403.94585) (xy 339.867748 -403.920198) (xy 339.873534 -403.913045)
			(xy 339.880054 -403.89586) (xy 339.880448 -403.88667) (xy 339.880448 -403.728682) (xy 339.880919 -403.718522)
			(xy 339.888701 -403.69975) (xy 339.903074 -403.685385) (xy 339.92185 -403.677613) (xy 339.93201 -403.67712)
			(xy 340.64829 -403.67712) (xy 340.658445 -403.677641) (xy 340.67721 -403.685409) (xy 340.691575 -403.699766)
			(xy 340.699353 -403.718527) (xy 340.699852 -403.728682) (xy 340.699852 -403.88667) (xy 340.700287 -403.895854)
			(xy 340.706785 -403.913038) (xy 340.712552 -403.920198) (xy 340.734362 -403.945832) (xy 340.772311 -404.001421)
			(xy 340.803343 -404.061147) (xy 340.827015 -404.124154) (xy 340.842987 -404.189538) (xy 340.85103 -404.256363)
			(xy 340.851028 -404.32367) (xy 340.842981 -404.390494) (xy 340.827006 -404.455878) (xy 340.80333 -404.518883)
			(xy 340.772294 -404.578608) (xy 340.734341 -404.634194) (xy 340.712552 -404.659846) (xy 340.706747 -404.666985)
			(xy 340.700239 -404.684181) (xy 340.699852 -404.693374) (xy 340.699852 -405.186642) (xy 340.700253 -405.19583)
			(xy 340.706774 -405.213014) (xy 340.712552 -405.22017) (xy 340.734334 -405.245827) (xy 340.772283 -405.301413)
			(xy 340.803317 -405.361135) (xy 340.826991 -405.424139) (xy 340.842965 -405.489521) (xy 340.851009 -405.556343)
			(xy 340.85101 -405.623648) (xy 340.842966 -405.69047) (xy 340.826994 -405.755852) (xy 340.803321 -405.818856)
			(xy 340.772288 -405.87858) (xy 340.734339 -405.934166) (xy 340.712552 -405.959818) (xy 340.706759 -405.966966)
			(xy 340.700244 -405.984154) (xy 340.699852 -405.993346) (xy 340.699852 -406.151334) (xy 340.699394 -406.161495)
			(xy 340.691607 -406.180267) (xy 340.67723 -406.194631) (xy 340.658452 -406.202403) (xy 340.64829 -406.202896)
			(xy 339.93201 -406.202896) (xy 339.921857 -406.202359) (xy 339.903095 -406.194594) (xy 339.88873 -406.180242)
			(xy 339.880949 -406.161487) (xy 339.880448 -406.151334) (xy 339.880448 -405.993346) (xy 339.880005 -405.984163)
			(xy 339.873513 -405.966979) (xy 339.867748 -405.959818) (xy 339.845954 -405.934171) (xy 339.808005 -405.878584)
			(xy 339.776971 -405.81886) (xy 339.753298 -405.755855) (xy 339.737325 -405.690472) (xy 339.729282 -405.623648)
			(xy 338.600728 -405.623648) (xy 338.572136 -405.67868) (xy 338.53419 -405.734267) (xy 338.512404 -405.75992)
			(xy 338.506617 -405.767072) (xy 338.500096 -405.784257) (xy 338.499704 -405.793448) (xy 338.499704 -406.286716)
			(xy 338.500106 -406.295904) (xy 338.506625 -406.313088) (xy 338.512404 -406.320244) (xy 338.534159 -406.345923)
			(xy 338.572106 -406.401506) (xy 338.603138 -406.461227) (xy 338.626811 -406.524228) (xy 338.642785 -406.589606)
			(xy 338.650831 -406.656425) (xy 338.650834 -406.723727) (xy 338.650827 -406.723789) (xy 341.928896 -406.723789)
			(xy 341.928898 -406.656363) (xy 341.936977 -406.589423) (xy 341.953016 -406.523932) (xy 341.976784 -406.460834)
			(xy 342.007938 -406.401036) (xy 342.04603 -406.345401) (xy 342.067896 -406.319736) (xy 342.073702 -406.312597)
			(xy 342.080211 -406.295402) (xy 342.080596 -406.286208) (xy 342.080596 -405.793956) (xy 342.080208 -405.784766)
			(xy 342.073679 -405.767582) (xy 342.067896 -405.760428) (xy 342.046028 -405.734766) (xy 342.00794 -405.679131)
			(xy 341.97679 -405.619334) (xy 341.953026 -405.556237) (xy 341.936991 -405.490748) (xy 341.928915 -405.423809)
			(xy 341.928916 -405.356385) (xy 341.936992 -405.289447) (xy 341.953028 -405.223957) (xy 341.976792 -405.16086)
			(xy 342.007943 -405.101064) (xy 342.046032 -405.045429) (xy 342.067896 -405.019764) (xy 342.07369 -405.012617)
			(xy 342.080206 -404.995428) (xy 342.080596 -404.986236) (xy 342.080596 -404.828756) (xy 342.081049 -404.818645)
			(xy 342.0888 -404.799967) (xy 342.103107 -404.785673) (xy 342.121793 -404.77794) (xy 342.131904 -404.777448)
			(xy 342.848184 -404.777448) (xy 342.858285 -404.777997) (xy 342.876953 -404.78572) (xy 342.891247 -404.799996)
			(xy 342.898991 -404.818655) (xy 342.899492 -404.828756) (xy 342.899492 -404.986236) (xy 342.899886 -404.995425)
			(xy 342.906411 -405.012609) (xy 342.912192 -405.019764) (xy 342.934052 -405.045432) (xy 342.972142 -405.101066)
			(xy 343.003293 -405.160862) (xy 343.027058 -405.223958) (xy 343.043094 -405.289447) (xy 343.05117 -405.356385)
			(xy 343.05117 -405.423809) (xy 343.043095 -405.490747) (xy 343.02706 -405.556236) (xy 343.003295 -405.619333)
			(xy 343.001047 -405.623648) (xy 344.129073 -405.623648) (xy 344.129073 -405.556343) (xy 344.137118 -405.48952)
			(xy 344.153091 -405.424137) (xy 344.176765 -405.361132) (xy 344.207799 -405.301409) (xy 344.245748 -405.245822)
			(xy 344.267536 -405.22017) (xy 344.273332 -405.213025) (xy 344.279846 -405.195834) (xy 344.280236 -405.186642)
			(xy 344.280236 -404.693374) (xy 344.27983 -404.684187) (xy 344.273313 -404.667003) (xy 344.267536 -404.659846)
			(xy 344.24577 -404.634176) (xy 344.207821 -404.578592) (xy 344.176787 -404.518871) (xy 344.153113 -404.455869)
			(xy 344.137139 -404.390489) (xy 344.129093 -404.323668) (xy 344.129091 -404.256365) (xy 344.137133 -404.189544)
			(xy 344.153103 -404.124163) (xy 344.176773 -404.061159) (xy 344.207804 -404.001437) (xy 344.24575 -403.94585)
			(xy 344.267536 -403.920198) (xy 344.273321 -403.913044) (xy 344.279842 -403.89586) (xy 344.280236 -403.88667)
			(xy 344.280236 -403.728682) (xy 344.280718 -403.718523) (xy 344.288498 -403.699754) (xy 344.302867 -403.685389)
			(xy 344.321639 -403.677615) (xy 344.331798 -403.67712) (xy 345.048078 -403.67712) (xy 345.058246 -403.677582)
			(xy 345.077037 -403.685356) (xy 345.091422 -403.69973) (xy 345.09921 -403.718514) (xy 345.09964 -403.728682)
			(xy 345.09964 -403.88667) (xy 345.100078 -403.895854) (xy 345.106574 -403.913038) (xy 345.11234 -403.920198)
			(xy 345.13415 -403.945832) (xy 345.1721 -404.00142) (xy 345.203133 -404.061146) (xy 345.226806 -404.124153)
			(xy 345.242778 -404.189538) (xy 345.250821 -404.256363) (xy 345.250819 -404.32367) (xy 345.242772 -404.390495)
			(xy 345.226796 -404.455878) (xy 345.20312 -404.518884) (xy 345.172083 -404.578608) (xy 345.13413 -404.634194)
			(xy 345.11234 -404.659846) (xy 345.106534 -404.666984) (xy 345.100027 -404.68418) (xy 345.09964 -404.693374)
			(xy 345.09964 -405.186642) (xy 345.100043 -405.19583) (xy 345.106563 -405.213013) (xy 345.11234 -405.22017)
			(xy 345.134122 -405.245827) (xy 345.172073 -405.301412) (xy 345.203107 -405.361135) (xy 345.226781 -405.424139)
			(xy 345.242755 -405.489521) (xy 345.2508 -405.556343) (xy 345.250801 -405.623648) (xy 345.242757 -405.69047)
			(xy 345.226784 -405.755853) (xy 345.203111 -405.818857) (xy 345.172077 -405.87858) (xy 345.134128 -405.934166)
			(xy 345.11234 -405.959818) (xy 345.106546 -405.966965) (xy 345.100031 -405.984154) (xy 345.09964 -405.993346)
			(xy 345.09964 -406.151334) (xy 345.099194 -406.161497) (xy 345.091404 -406.180271) (xy 345.077024 -406.194636)
			(xy 345.058241 -406.202405) (xy 345.048078 -406.202896) (xy 344.331798 -406.202896) (xy 344.321644 -406.202369)
			(xy 344.302882 -406.1946) (xy 344.288518 -406.180245) (xy 344.280737 -406.161487) (xy 344.280236 -406.151334)
			(xy 344.280236 -405.993346) (xy 344.279795 -405.984162) (xy 344.273302 -405.966978) (xy 344.267536 -405.959818)
			(xy 344.245742 -405.934171) (xy 344.207794 -405.878584) (xy 344.176761 -405.818859) (xy 344.153089 -405.755854)
			(xy 344.137116 -405.690471) (xy 344.129073 -405.623648) (xy 343.001047 -405.623648) (xy 342.972145 -405.679129)
			(xy 342.934056 -405.734763) (xy 342.912192 -405.760428) (xy 342.9064 -405.767576) (xy 342.899883 -405.784765)
			(xy 342.899492 -405.793956) (xy 342.899492 -406.286208) (xy 342.8999 -406.295395) (xy 342.906416 -406.312579)
			(xy 342.912192 -406.319736) (xy 342.934025 -406.345427) (xy 342.972115 -406.401058) (xy 343.003268 -406.46085)
			(xy 343.027034 -406.523944) (xy 343.043072 -406.58943) (xy 343.05115 -406.656365) (xy 343.051153 -406.72373)
			(xy 346.329191 -406.72373) (xy 346.329194 -406.656422) (xy 346.337242 -406.589596) (xy 346.35322 -406.524212)
			(xy 346.376898 -406.461206) (xy 346.407937 -406.401482) (xy 346.445893 -406.345896) (xy 346.467684 -406.320244)
			(xy 346.473485 -406.313102) (xy 346.479998 -406.295909) (xy 346.480384 -406.286716) (xy 346.480384 -405.793448)
			(xy 346.479955 -405.784263) (xy 346.473455 -405.767078) (xy 346.467684 -405.75992) (xy 346.445891 -405.734272)
			(xy 346.407939 -405.678686) (xy 346.376904 -405.618962) (xy 346.353229 -405.555957) (xy 346.337255 -405.490574)
			(xy 346.329211 -405.42375) (xy 346.329211 -405.356444) (xy 346.337256 -405.28962) (xy 346.353231 -405.224237)
			(xy 346.376906 -405.161232) (xy 346.407942 -405.101509) (xy 346.445895 -405.045924) (xy 346.467684 -405.020272)
			(xy 346.473473 -405.013121) (xy 346.479993 -404.995935) (xy 346.480384 -404.986744) (xy 346.480384 -404.828756)
			(xy 346.480785 -404.818601) (xy 346.488592 -404.799851) (xy 346.502995 -404.78553) (xy 346.521789 -404.777829)
			(xy 346.531946 -404.777448) (xy 347.248226 -404.777448) (xy 347.258355 -404.777905) (xy 347.277079 -404.785643)
			(xy 347.291434 -404.799938) (xy 347.299251 -404.818629) (xy 347.299788 -404.828756) (xy 347.299788 -404.986744)
			(xy 347.30018 -404.995933) (xy 347.306706 -405.013117) (xy 347.312488 -405.020272) (xy 347.334271 -405.045928)
			(xy 347.372218 -405.101514) (xy 347.40325 -405.161238) (xy 347.426922 -405.224242) (xy 347.442894 -405.289623)
			(xy 347.450938 -405.356445) (xy 347.450939 -405.423749) (xy 347.442895 -405.490571) (xy 347.426924 -405.555953)
			(xy 347.403253 -405.618957) (xy 347.400815 -405.623649) (xy 374.929103 -405.623649) (xy 374.929104 -405.556342)
			(xy 374.937149 -405.489519) (xy 374.953124 -405.424136) (xy 374.976799 -405.361131) (xy 375.007835 -405.301407)
			(xy 375.045787 -405.245822) (xy 375.067576 -405.22017) (xy 375.073365 -405.213019) (xy 375.079885 -405.195833)
			(xy 375.080276 -405.186642) (xy 375.080276 -404.693374) (xy 375.079884 -404.684185) (xy 375.073358 -404.667)
			(xy 375.067576 -404.659846) (xy 375.045809 -404.634177) (xy 375.007857 -404.578593) (xy 374.976821 -404.518873)
			(xy 374.953145 -404.45587) (xy 374.937169 -404.39049) (xy 374.929123 -404.323669) (xy 374.929121 -404.256365)
			(xy 374.937164 -404.189543) (xy 374.953135 -404.124161) (xy 374.976807 -404.061158) (xy 375.00784 -404.001435)
			(xy 375.045789 -403.94585) (xy 375.067576 -403.920198) (xy 375.073353 -403.913039) (xy 375.07988 -403.895859)
			(xy 375.080276 -403.88667) (xy 375.080276 -403.728682) (xy 375.08065 -403.718505) (xy 375.088448 -403.699702)
			(xy 375.102849 -403.685317) (xy 375.12166 -403.677539) (xy 375.131838 -403.67712) (xy 375.848118 -403.67712)
			(xy 375.858275 -403.677618) (xy 375.877041 -403.685395) (xy 375.891405 -403.699759) (xy 375.899182 -403.718525)
			(xy 375.89968 -403.728682) (xy 375.89968 -403.88667) (xy 375.900109 -403.895855) (xy 375.90661 -403.913039)
			(xy 375.91238 -403.920198) (xy 375.934189 -403.945833) (xy 375.972136 -404.001422) (xy 376.003167 -404.061148)
			(xy 376.026838 -404.124155) (xy 376.042809 -404.189539) (xy 376.050851 -404.256363) (xy 376.050849 -404.32367)
			(xy 376.042803 -404.390494) (xy 376.026828 -404.455877) (xy 376.003154 -404.518882) (xy 375.972119 -404.578606)
			(xy 375.934169 -404.634194) (xy 375.91238 -404.659846) (xy 375.906579 -404.666988) (xy 375.900068 -404.684181)
			(xy 375.89968 -404.693374) (xy 375.89968 -405.186642) (xy 375.900074 -405.195831) (xy 375.9066 -405.213015)
			(xy 375.91238 -405.22017) (xy 375.934161 -405.245827) (xy 375.972109 -405.301413) (xy 376.003142 -405.361136)
			(xy 376.026814 -405.42414) (xy 376.042787 -405.489522) (xy 376.050831 -405.556343) (xy 376.050832 -405.623648)
			(xy 376.042788 -405.690469) (xy 376.026817 -405.755851) (xy 376.003145 -405.818855) (xy 375.972114 -405.878579)
			(xy 375.934167 -405.934166) (xy 375.91238 -405.959818) (xy 375.906591 -405.966968) (xy 375.900072 -405.984155)
			(xy 375.89968 -405.993346) (xy 375.89968 -406.151334) (xy 375.899195 -406.161492) (xy 375.891413 -406.180258)
			(xy 375.877045 -406.194622) (xy 375.858276 -406.202398) (xy 375.848118 -406.202896) (xy 375.131838 -406.202896)
			(xy 375.121673 -406.202406) (xy 375.102886 -406.19464) (xy 375.088501 -406.180275) (xy 375.080708 -406.161498)
			(xy 375.080276 -406.151334) (xy 375.080276 -405.993346) (xy 375.079849 -405.984161) (xy 375.073347 -405.966976)
			(xy 375.067576 -405.959818) (xy 375.045781 -405.934171) (xy 375.00783 -405.878585) (xy 374.976795 -405.818861)
			(xy 374.953121 -405.755856) (xy 374.937148 -405.690472) (xy 374.929103 -405.623649) (xy 347.400815 -405.623649)
			(xy 347.372221 -405.678681) (xy 347.334275 -405.734268) (xy 347.312488 -405.75992) (xy 347.306699 -405.767071)
			(xy 347.30018 -405.784257) (xy 347.299788 -405.793448) (xy 347.299788 -406.286716) (xy 347.300193 -406.295904)
			(xy 347.30671 -406.313088) (xy 347.312488 -406.320244) (xy 347.334244 -406.345922) (xy 347.372192 -406.401506)
			(xy 347.403225 -406.461226) (xy 347.426898 -406.524227) (xy 347.442873 -406.589606) (xy 347.450919 -406.656425)
			(xy 347.450922 -406.723727) (xy 347.450915 -406.723789) (xy 377.128717 -406.723789) (xy 377.12872 -406.656363)
			(xy 377.136799 -406.589422) (xy 377.152839 -406.523931) (xy 377.176607 -406.460832) (xy 377.207763 -406.401035)
			(xy 377.245857 -406.345401) (xy 377.267724 -406.319736) (xy 377.273533 -406.3126) (xy 377.280039 -406.295402)
			(xy 377.280424 -406.286208) (xy 377.280424 -405.793956) (xy 377.28003 -405.784767) (xy 377.273504 -405.767583)
			(xy 377.267724 -405.760428) (xy 377.245855 -405.734766) (xy 377.207765 -405.679132) (xy 377.176613 -405.619335)
			(xy 377.152848 -405.556238) (xy 377.136812 -405.490748) (xy 377.128736 -405.423809) (xy 377.128737 -405.356385)
			(xy 377.136813 -405.289446) (xy 377.15285 -405.223956) (xy 377.176616 -405.160859) (xy 377.207768 -405.101063)
			(xy 377.245859 -405.045429) (xy 377.267724 -405.019764) (xy 377.273521 -405.012619) (xy 377.280035 -404.995428)
			(xy 377.280424 -404.986236) (xy 377.280424 -404.828756) (xy 377.28085 -404.818641) (xy 377.288606 -404.799958)
			(xy 377.302922 -404.785664) (xy 377.321617 -404.777935) (xy 377.331732 -404.777448) (xy 378.048012 -404.777448)
			(xy 378.058115 -404.777974) (xy 378.076783 -404.785706) (xy 378.091076 -404.79999) (xy 378.098819 -404.818653)
			(xy 378.09932 -404.828756) (xy 378.09932 -404.986236) (xy 378.099709 -404.995426) (xy 378.106237 -405.01261)
			(xy 378.11202 -405.019764) (xy 378.133879 -405.045433) (xy 378.171967 -405.101067) (xy 378.203117 -405.160863)
			(xy 378.22688 -405.22396) (xy 378.242915 -405.289448) (xy 378.250991 -405.356386) (xy 378.250992 -405.423808)
			(xy 378.242916 -405.490746) (xy 378.226882 -405.556235) (xy 378.203119 -405.619331) (xy 378.200839 -405.623707)
			(xy 379.328896 -405.623707) (xy 379.328896 -405.556284) (xy 379.336972 -405.489346) (xy 379.353008 -405.423856)
			(xy 379.376771 -405.360759) (xy 379.407921 -405.300963) (xy 379.446009 -405.245328) (xy 379.467872 -405.219662)
			(xy 379.473676 -405.212522) (xy 379.480184 -405.195327) (xy 379.480572 -405.186134) (xy 379.480572 -404.693882)
			(xy 379.480177 -404.684693) (xy 379.473653 -404.667509) (xy 379.467872 -404.660354) (xy 379.446031 -404.63467)
			(xy 379.407943 -404.579038) (xy 379.376793 -404.519244) (xy 379.353029 -404.45615) (xy 379.336993 -404.390663)
			(xy 379.328915 -404.323727) (xy 379.328913 -404.256306) (xy 379.336987 -404.18937) (xy 379.353019 -404.123882)
			(xy 379.376779 -404.060786) (xy 379.407926 -404.00099) (xy 379.44601 -403.945356) (xy 379.467872 -403.91969)
			(xy 379.473664 -403.912542) (xy 379.480179 -403.895353) (xy 379.480572 -403.886162) (xy 379.480572 -403.728682)
			(xy 379.481013 -403.71855) (xy 379.488752 -403.699822) (xy 379.503053 -403.685466) (xy 379.52175 -403.677653)
			(xy 379.53188 -403.67712) (xy 380.24816 -403.67712) (xy 380.258282 -403.677549) (xy 380.276989 -403.685288)
			(xy 380.291305 -403.699601) (xy 380.299048 -403.718306) (xy 380.299468 -403.728428) (xy 380.299468 -403.886162)
			(xy 380.299904 -403.895346) (xy 380.306401 -403.91253) (xy 380.312168 -403.91969) (xy 380.334055 -403.945337)
			(xy 380.372145 -404.000973) (xy 380.403296 -404.060772) (xy 380.427061 -404.123871) (xy 380.443096 -404.189363)
			(xy 380.45117 -404.256303) (xy 380.451168 -404.32373) (xy 380.44309 -404.39067) (xy 380.427051 -404.456161)
			(xy 380.403283 -404.519259) (xy 380.372128 -404.579055) (xy 380.334034 -404.634689) (xy 380.312168 -404.660354)
			(xy 380.306362 -404.667492) (xy 380.299854 -404.684688) (xy 380.299468 -404.693882) (xy 380.299468 -405.186134)
			(xy 380.299869 -405.195322) (xy 380.30639 -405.212506) (xy 380.312168 -405.219662) (xy 380.334027 -405.245332)
			(xy 380.372118 -405.300965) (xy 380.403271 -405.36076) (xy 380.427037 -405.423856) (xy 380.443074 -405.489345)
			(xy 380.451151 -405.556284) (xy 380.451151 -405.623707) (xy 380.443075 -405.690646) (xy 380.42704 -405.756135)
			(xy 380.403275 -405.819232) (xy 380.372123 -405.879028) (xy 380.334033 -405.934661) (xy 380.312168 -405.960326)
			(xy 380.306374 -405.967473) (xy 380.299858 -405.984662) (xy 380.299468 -405.993854) (xy 380.299468 -406.151334)
			(xy 380.299002 -406.161462) (xy 380.291264 -406.180182) (xy 380.276972 -406.194537) (xy 380.258286 -406.202357)
			(xy 380.24816 -406.202896) (xy 379.53188 -406.202896) (xy 379.521769 -406.202431) (xy 379.50309 -406.194686)
			(xy 379.488796 -406.180383) (xy 379.481062 -406.161699) (xy 379.480572 -406.151588) (xy 379.480572 -405.993854)
			(xy 379.480142 -405.984669) (xy 379.473643 -405.967484) (xy 379.467872 -405.960326) (xy 379.446003 -405.934665)
			(xy 379.407916 -405.879029) (xy 379.376768 -405.819232) (xy 379.353005 -405.756135) (xy 379.336971 -405.690646)
			(xy 379.328896 -405.623707) (xy 378.200839 -405.623707) (xy 378.17197 -405.679128) (xy 378.133883 -405.734762)
			(xy 378.11202 -405.760428) (xy 378.106231 -405.767579) (xy 378.099711 -405.784765) (xy 378.09932 -405.793956)
			(xy 378.09932 -406.286208) (xy 378.099722 -406.295396) (xy 378.106241 -406.312581) (xy 378.11202 -406.319736)
			(xy 378.133852 -406.345428) (xy 378.17194 -406.401059) (xy 378.203091 -406.460852) (xy 378.226856 -406.523945)
			(xy 378.242893 -406.589431) (xy 378.250971 -406.656366) (xy 378.250974 -406.723729) (xy 381.529036 -406.723729)
			(xy 381.529039 -406.656422) (xy 381.537086 -406.589598) (xy 381.553062 -406.524214) (xy 381.576737 -406.461209)
			(xy 381.607772 -406.401484) (xy 381.645723 -406.345897) (xy 381.667512 -406.320244) (xy 381.673316 -406.313104)
			(xy 381.679826 -406.29591) (xy 381.680212 -406.286716) (xy 381.680212 -405.793448) (xy 381.679776 -405.784264)
			(xy 381.67328 -405.767079) (xy 381.667512 -405.75992) (xy 381.645721 -405.734271) (xy 381.607774 -405.678683)
			(xy 381.576743 -405.618959) (xy 381.553071 -405.555954) (xy 381.537099 -405.490572) (xy 381.529056 -405.423749)
			(xy 381.529056 -405.356445) (xy 381.5371 -405.289622) (xy 381.553073 -405.22424) (xy 381.576745 -405.161235)
			(xy 381.607777 -405.101512) (xy 381.645725 -405.045924) (xy 381.667512 -405.020272) (xy 381.673304 -405.013124)
			(xy 381.679821 -404.995936) (xy 381.680212 -404.986744) (xy 381.680212 -404.828756) (xy 381.680649 -404.818643)
			(xy 381.688404 -404.799961) (xy 381.702715 -404.785668) (xy 381.721406 -404.777937) (xy 381.73152 -404.777448)
			(xy 382.448054 -404.777448) (xy 382.458179 -404.777965) (xy 382.4769 -404.785679) (xy 382.491258 -404.799956)
			(xy 382.499078 -404.818634) (xy 382.499616 -404.828756) (xy 382.499616 -404.986744) (xy 382.500001 -404.995934)
			(xy 382.506532 -405.013118) (xy 382.512316 -405.020272) (xy 382.534101 -405.045927) (xy 382.572053 -405.101512)
			(xy 382.603089 -405.161235) (xy 382.626764 -405.224239) (xy 382.642738 -405.289621) (xy 382.650784 -405.356444)
			(xy 382.650784 -405.42375) (xy 382.64274 -405.490573) (xy 382.626766 -405.555955) (xy 382.603091 -405.61896)
			(xy 382.600655 -405.623648) (xy 383.729191 -405.623648) (xy 383.729192 -405.556343) (xy 383.737237 -405.489519)
			(xy 383.753211 -405.424136) (xy 383.776885 -405.361132) (xy 383.807921 -405.301408) (xy 383.845871 -405.245822)
			(xy 383.86766 -405.22017) (xy 383.873459 -405.213027) (xy 383.879971 -405.195835) (xy 383.88036 -405.186642)
			(xy 383.88036 -404.693374) (xy 383.879949 -404.684187) (xy 383.873434 -404.667004) (xy 383.86766 -404.659846)
			(xy 383.845893 -404.634176) (xy 383.807943 -404.578593) (xy 383.776907 -404.518872) (xy 383.753232 -404.45587)
			(xy 383.737257 -404.390489) (xy 383.729211 -404.323668) (xy 383.729209 -404.256365) (xy 383.737251 -404.189543)
			(xy 383.753222 -404.124162) (xy 383.776894 -404.061158) (xy 383.807926 -404.001436) (xy 383.845873 -403.94585)
			(xy 383.86766 -403.920198) (xy 383.873447 -403.913047) (xy 383.879966 -403.895861) (xy 383.88036 -403.88667)
			(xy 383.88036 -403.728682) (xy 383.88075 -403.718507) (xy 383.888545 -403.699707) (xy 383.902941 -403.685322)
			(xy 383.921746 -403.677542) (xy 383.931922 -403.67712) (xy 384.648202 -403.67712) (xy 384.658358 -403.677631)
			(xy 384.677123 -403.685403) (xy 384.691488 -403.699763) (xy 384.699265 -403.718526) (xy 384.699764 -403.728682)
			(xy 384.699764 -403.88667) (xy 384.700197 -403.895855) (xy 384.706696 -403.913039) (xy 384.712464 -403.920198)
			(xy 384.734273 -403.945832) (xy 384.772221 -404.001421) (xy 384.803254 -404.061147) (xy 384.826925 -404.124154)
			(xy 384.842896 -404.189539) (xy 384.850939 -404.256363) (xy 384.850937 -404.32367) (xy 384.84289 -404.390494)
			(xy 384.826915 -404.455877) (xy 384.80324 -404.518883) (xy 384.772204 -404.578607) (xy 384.734253 -404.634194)
			(xy 384.712464 -404.659846) (xy 384.706661 -404.666986) (xy 384.700151 -404.684181) (xy 384.699764 -404.693374)
			(xy 384.699764 -405.186642) (xy 384.700162 -405.19583) (xy 384.706685 -405.213014) (xy 384.712464 -405.22017)
			(xy 384.734246 -405.245827) (xy 384.772195 -405.301413) (xy 384.803228 -405.361136) (xy 384.826901 -405.42414)
			(xy 384.842874 -405.489521) (xy 384.850919 -405.556343) (xy 384.850919 -405.623648) (xy 384.842876 -405.69047)
			(xy 384.826904 -405.755852) (xy 384.803232 -405.818856) (xy 384.772199 -405.878579) (xy 384.734251 -405.934166)
			(xy 384.712464 -405.959818) (xy 384.706673 -405.966967) (xy 384.700156 -405.984155) (xy 384.699764 -405.993346)
			(xy 384.699764 -406.151334) (xy 384.699295 -406.161494) (xy 384.691509 -406.180263) (xy 384.677136 -406.194627)
			(xy 384.658362 -406.202401) (xy 384.648202 -406.202896) (xy 383.931922 -406.202896) (xy 383.92177 -406.20235)
			(xy 383.903008 -406.194589) (xy 383.888643 -406.180239) (xy 383.880861 -406.161486) (xy 383.88036 -406.151334)
			(xy 383.88036 -405.993346) (xy 383.879914 -405.984163) (xy 383.873424 -405.966979) (xy 383.86766 -405.959818)
			(xy 383.845866 -405.934171) (xy 383.807916 -405.878584) (xy 383.776882 -405.81886) (xy 383.753208 -405.755855)
			(xy 383.737235 -405.690472) (xy 383.729191 -405.623648) (xy 382.600655 -405.623648) (xy 382.572056 -405.678683)
			(xy 382.534105 -405.734268) (xy 382.512316 -405.75992) (xy 382.50653 -405.767073) (xy 382.500009 -405.784257)
			(xy 382.499616 -405.793448) (xy 382.499616 -406.286716) (xy 382.500015 -406.295904) (xy 382.506536 -406.313089)
			(xy 382.512316 -406.320244) (xy 382.534074 -406.345921) (xy 382.572026 -406.401503) (xy 382.603063 -406.461223)
			(xy 382.62674 -406.524224) (xy 382.642717 -406.589604) (xy 382.650764 -406.656424) (xy 382.650767 -406.723728)
			(xy 382.65076 -406.723789) (xy 385.928805 -406.723789) (xy 385.928807 -406.656363) (xy 385.936887 -406.589422)
			(xy 385.952926 -406.523931) (xy 385.976694 -406.460833) (xy 386.007849 -406.401036) (xy 386.045942 -406.345401)
			(xy 386.067808 -406.319736) (xy 386.073615 -406.312598) (xy 386.080123 -406.295402) (xy 386.080508 -406.286208)
			(xy 386.080508 -405.793956) (xy 386.080117 -405.784767) (xy 386.07359 -405.767583) (xy 386.067808 -405.760428)
			(xy 386.04594 -405.734766) (xy 386.007851 -405.679131) (xy 385.9767 -405.619335) (xy 385.952935 -405.556237)
			(xy 385.9369 -405.490748) (xy 385.928824 -405.423809) (xy 385.928825 -405.356385) (xy 385.936901 -405.289446)
			(xy 385.952937 -405.223957) (xy 385.976702 -405.16086) (xy 386.007854 -405.101064) (xy 386.045944 -405.045429)
			(xy 386.067808 -405.019764) (xy 386.073603 -405.012618) (xy 386.080118 -404.995428) (xy 386.080508 -404.986236)
			(xy 386.080508 -404.828756) (xy 386.080949 -404.818643) (xy 386.088703 -404.799963) (xy 386.103013 -404.785669)
			(xy 386.121703 -404.777938) (xy 386.131816 -404.777448) (xy 386.848096 -404.777448) (xy 386.858198 -404.777987)
			(xy 386.876866 -404.785714) (xy 386.891159 -404.799993) (xy 386.898903 -404.818654) (xy 386.899404 -404.828756)
			(xy 386.899404 -404.986236) (xy 386.899796 -404.995425) (xy 386.906322 -405.012609) (xy 386.912104 -405.019764)
			(xy 386.933964 -405.045433) (xy 386.972052 -405.101067) (xy 387.003203 -405.160862) (xy 387.026967 -405.223959)
			(xy 387.043003 -405.289448) (xy 387.051079 -405.356385) (xy 387.051079 -405.423809) (xy 387.043004 -405.490747)
			(xy 387.026969 -405.556235) (xy 387.003206 -405.619332) (xy 387.000958 -405.623648) (xy 388.128982 -405.623648)
			(xy 388.128982 -405.556343) (xy 388.137027 -405.489519) (xy 388.153001 -405.424137) (xy 388.176675 -405.361132)
			(xy 388.207709 -405.301408) (xy 388.245659 -405.245822) (xy 388.267448 -405.22017) (xy 388.273246 -405.213026)
			(xy 388.279758 -405.195834) (xy 388.280148 -405.186642) (xy 388.280148 -404.693374) (xy 388.27974 -404.684187)
			(xy 388.273223 -404.667003) (xy 388.267448 -404.659846) (xy 388.245682 -404.634176) (xy 388.207732 -404.578592)
			(xy 388.176697 -404.518871) (xy 388.153023 -404.455869) (xy 388.137048 -404.390489) (xy 388.129002 -404.323668)
			(xy 388.129 -404.256365) (xy 388.137042 -404.189544) (xy 388.153013 -404.124163) (xy 388.176684 -404.061159)
			(xy 388.207715 -404.001436) (xy 388.245662 -403.94585) (xy 388.267448 -403.920198) (xy 388.273234 -403.913045)
			(xy 388.279754 -403.89586) (xy 388.280148 -403.88667) (xy 388.280148 -403.728682) (xy 388.280619 -403.718522)
			(xy 388.288401 -403.69975) (xy 388.302774 -403.685385) (xy 388.32155 -403.677613) (xy 388.33171 -403.67712)
			(xy 389.04799 -403.67712) (xy 389.058145 -403.677641) (xy 389.07691 -403.685409) (xy 389.091275 -403.699766)
			(xy 389.099053 -403.718527) (xy 389.099552 -403.728682) (xy 389.099552 -403.88667) (xy 389.099987 -403.895854)
			(xy 389.106485 -403.913038) (xy 389.112252 -403.920198) (xy 389.134062 -403.945832) (xy 389.172011 -404.001421)
			(xy 389.203043 -404.061147) (xy 389.226715 -404.124154) (xy 389.242687 -404.189538) (xy 389.25073 -404.256363)
			(xy 389.250728 -404.32367) (xy 389.242681 -404.390494) (xy 389.226706 -404.455878) (xy 389.20303 -404.518883)
			(xy 389.171994 -404.578608) (xy 389.134041 -404.634194) (xy 389.112252 -404.659846) (xy 389.106447 -404.666985)
			(xy 389.099939 -404.684181) (xy 389.099552 -404.693374) (xy 389.099552 -405.186642) (xy 389.099953 -405.19583)
			(xy 389.106474 -405.213014) (xy 389.112252 -405.22017) (xy 389.134034 -405.245827) (xy 389.171983 -405.301413)
			(xy 389.203017 -405.361135) (xy 389.226691 -405.424139) (xy 389.242665 -405.489521) (xy 389.250709 -405.556343)
			(xy 389.25071 -405.623648) (xy 389.242666 -405.69047) (xy 389.226694 -405.755852) (xy 389.203021 -405.818856)
			(xy 389.171988 -405.87858) (xy 389.134039 -405.934166) (xy 389.112252 -405.959818) (xy 389.106459 -405.966966)
			(xy 389.099944 -405.984154) (xy 389.099552 -405.993346) (xy 389.099552 -406.151334) (xy 389.099094 -406.161495)
			(xy 389.091307 -406.180267) (xy 389.07693 -406.194631) (xy 389.058152 -406.202403) (xy 389.04799 -406.202896)
			(xy 388.33171 -406.202896) (xy 388.321557 -406.202359) (xy 388.302795 -406.194594) (xy 388.28843 -406.180242)
			(xy 388.280649 -406.161487) (xy 388.280148 -406.151334) (xy 388.280148 -405.993346) (xy 388.279705 -405.984163)
			(xy 388.273213 -405.966979) (xy 388.267448 -405.959818) (xy 388.245654 -405.934171) (xy 388.207705 -405.878584)
			(xy 388.176671 -405.81886) (xy 388.152998 -405.755855) (xy 388.137025 -405.690472) (xy 388.128982 -405.623648)
			(xy 387.000958 -405.623648) (xy 386.972056 -405.679128) (xy 386.933968 -405.734763) (xy 386.912104 -405.760428)
			(xy 386.906314 -405.767578) (xy 386.899795 -405.784765) (xy 386.899404 -405.793956) (xy 386.899404 -406.286208)
			(xy 386.89981 -406.295396) (xy 386.906326 -406.31258) (xy 386.912104 -406.319736) (xy 386.933936 -406.345427)
			(xy 386.972026 -406.401058) (xy 387.003178 -406.460851) (xy 387.026943 -406.523944) (xy 387.042981 -406.58943)
			(xy 387.051059 -406.656365) (xy 387.051062 -406.723729) (xy 390.329124 -406.723729) (xy 390.329127 -406.656423)
			(xy 390.337174 -406.589599) (xy 390.353149 -406.524215) (xy 390.376823 -406.461209) (xy 390.407858 -406.401485)
			(xy 390.445808 -406.345897) (xy 390.467596 -406.320244) (xy 390.473398 -406.313103) (xy 390.47991 -406.295909)
			(xy 390.480296 -406.286716) (xy 390.480296 -405.793448) (xy 390.479864 -405.784263) (xy 390.473366 -405.767078)
			(xy 390.467596 -405.75992) (xy 390.445806 -405.73427) (xy 390.40786 -405.678683) (xy 390.376829 -405.618958)
			(xy 390.353158 -405.555954) (xy 390.337187 -405.490571) (xy 390.329144 -405.423749) (xy 390.329144 -405.356445)
			(xy 390.337188 -405.289623) (xy 390.35316 -405.224241) (xy 390.376832 -405.161236) (xy 390.407863 -405.101512)
			(xy 390.445809 -405.045925) (xy 390.467596 -405.020272) (xy 390.473386 -405.013122) (xy 390.479905 -404.995935)
			(xy 390.480296 -404.986744) (xy 390.480296 -404.828756) (xy 390.480749 -404.818645) (xy 390.4885 -404.799967)
			(xy 390.502807 -404.785673) (xy 390.521493 -404.77794) (xy 390.531604 -404.777448) (xy 391.248138 -404.777448)
			(xy 391.258268 -404.777896) (xy 391.276992 -404.785637) (xy 391.291347 -404.799935) (xy 391.299163 -404.818628)
			(xy 391.2997 -404.828756) (xy 391.2997 -404.986744) (xy 391.300089 -404.995933) (xy 391.306617 -405.013118)
			(xy 391.3124 -405.020272) (xy 391.334183 -405.045928) (xy 391.372129 -405.101515) (xy 391.40316 -405.161238)
			(xy 391.426832 -405.224242) (xy 391.442804 -405.289623) (xy 391.450848 -405.356445) (xy 391.450848 -405.423749)
			(xy 391.442805 -405.490571) (xy 391.426833 -405.555952) (xy 391.403163 -405.618956) (xy 391.372132 -405.67868)
			(xy 391.334186 -405.734267) (xy 391.3124 -405.75992) (xy 391.306612 -405.767072) (xy 391.300092 -405.784257)
			(xy 391.2997 -405.793448) (xy 391.2997 -406.286716) (xy 391.300103 -406.295904) (xy 391.306622 -406.313088)
			(xy 391.3124 -406.320244) (xy 391.334155 -406.345923) (xy 391.372102 -406.401506) (xy 391.403135 -406.461226)
			(xy 391.426808 -406.524227) (xy 391.442782 -406.589606) (xy 391.450828 -406.656425) (xy 391.450831 -406.723727)
			(xy 391.44279 -406.790547) (xy 391.426822 -406.855927) (xy 391.403154 -406.91893) (xy 391.372127 -406.978653)
			(xy 391.334185 -407.034239) (xy 391.3124 -407.059892) (xy 391.306624 -407.067052) (xy 391.300097 -407.084231)
			(xy 391.2997 -407.09342) (xy 391.2997 -407.251408) (xy 391.299221 -407.261517) (xy 391.291481 -407.280196)
			(xy 391.277182 -407.29449) (xy 391.258501 -407.302224) (xy 391.248392 -407.302716) (xy 390.531858 -407.302716)
			(xy 390.521723 -407.302307) (xy 390.502993 -407.294557) (xy 390.488636 -407.280247) (xy 390.480826 -407.261541)
			(xy 390.480296 -407.251408) (xy 390.480296 -407.09342) (xy 390.479877 -407.084234) (xy 390.47337 -407.067049)
			(xy 390.467596 -407.059892) (xy 390.445778 -407.034265) (xy 390.407833 -406.978674) (xy 390.376804 -406.918947)
			(xy 390.353135 -406.855939) (xy 390.337165 -406.790554) (xy 390.329124 -406.723729) (xy 387.051062 -406.723729)
			(xy 387.051062 -406.723787) (xy 387.04299 -406.790723) (xy 387.026958 -406.85621) (xy 387.003197 -406.919305)
			(xy 386.972051 -406.979101) (xy 386.933966 -407.034735) (xy 386.912104 -407.0604) (xy 386.906325 -407.067558)
			(xy 386.8998 -407.084739) (xy 386.899404 -407.093928) (xy 386.899404 -407.251408) (xy 386.898921 -407.261517)
			(xy 386.891182 -407.280194) (xy 386.876884 -407.294489) (xy 386.858205 -407.302224) (xy 386.848096 -407.302716)
			(xy 386.131816 -407.302716) (xy 386.121697 -407.302271) (xy 386.102996 -407.294531) (xy 386.088682 -407.280224)
			(xy 386.080933 -407.261527) (xy 386.080508 -407.251408) (xy 386.080508 -407.093928) (xy 386.080083 -407.084742)
			(xy 386.073579 -407.067558) (xy 386.067808 -407.0604) (xy 386.045912 -407.034761) (xy 386.007824 -406.979123)
			(xy 385.976674 -406.919323) (xy 385.952912 -406.856223) (xy 385.936878 -406.79073) (xy 385.928805 -406.723789)
			(xy 382.65076 -406.723789) (xy 382.642725 -406.790549) (xy 382.626754 -406.85593) (xy 382.603083 -406.918933)
			(xy 382.572051 -406.978655) (xy 382.534103 -407.03424) (xy 382.512316 -407.059892) (xy 382.506542 -407.067053)
			(xy 382.500013 -407.084231) (xy 382.499616 -407.09342) (xy 382.499616 -407.251408) (xy 382.499122 -407.261515)
			(xy 382.491384 -407.28019) (xy 382.47709 -407.294484) (xy 382.458415 -407.302222) (xy 382.448308 -407.302716)
			(xy 381.731774 -407.302716) (xy 381.72164 -407.302294) (xy 381.70291 -407.294549) (xy 381.688553 -407.280243)
			(xy 381.680743 -407.26154) (xy 381.680212 -407.251408) (xy 381.680212 -407.09342) (xy 381.679789 -407.084234)
			(xy 381.673284 -407.06705) (xy 381.667512 -407.059892) (xy 381.645694 -407.034265) (xy 381.607748 -406.978675)
			(xy 381.576717 -406.918947) (xy 381.553047 -406.855939) (xy 381.537077 -406.790554) (xy 381.529036 -406.723729)
			(xy 378.250974 -406.723729) (xy 378.250974 -406.723786) (xy 378.242902 -406.790722) (xy 378.226871 -406.856209)
			(xy 378.203111 -406.919305) (xy 378.171965 -406.9791) (xy 378.133881 -407.034734) (xy 378.11202 -407.0604)
			(xy 378.106243 -407.067559) (xy 378.099716 -407.084739) (xy 378.09932 -407.093928) (xy 378.09932 -407.251408)
			(xy 378.098822 -407.261515) (xy 378.091085 -407.280189) (xy 378.076793 -407.294483) (xy 378.058119 -407.302221)
			(xy 378.048012 -407.302716) (xy 377.331732 -407.302716) (xy 377.321614 -407.302258) (xy 377.302914 -407.294524)
			(xy 377.288599 -407.28022) (xy 377.280849 -407.261526) (xy 377.280424 -407.251408) (xy 377.280424 -407.093928)
			(xy 377.279995 -407.084743) (xy 377.273494 -407.067559) (xy 377.267724 -407.0604) (xy 377.245828 -407.034761)
			(xy 377.207738 -406.979123) (xy 377.176588 -406.919324) (xy 377.152824 -406.856223) (xy 377.13679 -406.790731)
			(xy 377.128717 -406.723789) (xy 347.450915 -406.723789) (xy 347.442881 -406.790547) (xy 347.426912 -406.855927)
			(xy 347.403244 -406.91893) (xy 347.372216 -406.978653) (xy 347.334273 -407.03424) (xy 347.312488 -407.059892)
			(xy 347.306711 -407.067051) (xy 347.300185 -407.084231) (xy 347.299788 -407.09342) (xy 347.299788 -407.251408)
			(xy 347.299385 -407.261564) (xy 347.291584 -407.280319) (xy 347.277182 -407.294642) (xy 347.258384 -407.30234)
			(xy 347.248226 -407.302716) (xy 346.531946 -407.302716) (xy 346.521817 -407.302234) (xy 346.503088 -407.294514)
			(xy 346.488729 -407.280225) (xy 346.480916 -407.261535) (xy 346.480384 -407.251408) (xy 346.480384 -407.09342)
			(xy 346.479968 -407.084233) (xy 346.473459 -407.067049) (xy 346.467684 -407.059892) (xy 346.445864 -407.034266)
			(xy 346.407913 -406.978677) (xy 346.376878 -406.91895) (xy 346.353205 -406.855942) (xy 346.337233 -406.790556)
			(xy 346.329191 -406.72373) (xy 343.051153 -406.72373) (xy 343.051153 -406.723787) (xy 343.04308 -406.790723)
			(xy 343.027048 -406.85621) (xy 343.003287 -406.919306) (xy 342.97214 -406.979101) (xy 342.934054 -407.034735)
			(xy 342.912192 -407.0604) (xy 342.906412 -407.067557) (xy 342.899888 -407.084738) (xy 342.899492 -407.093928)
			(xy 342.899492 -407.251408) (xy 342.89909 -407.261532) (xy 342.891338 -407.280237) (xy 342.877017 -407.294551)
			(xy 342.858308 -407.302295) (xy 342.848184 -407.302716) (xy 342.131904 -407.302716) (xy 342.121798 -407.302212)
			(xy 342.103122 -407.294479) (xy 342.088828 -407.280188) (xy 342.08109 -407.261514) (xy 342.080596 -407.251408)
			(xy 342.080596 -407.093928) (xy 342.080173 -407.084742) (xy 342.073668 -407.067558) (xy 342.067896 -407.0604)
			(xy 342.046001 -407.034761) (xy 342.007913 -406.979122) (xy 341.976764 -406.919322) (xy 341.953002 -406.856222)
			(xy 341.936969 -406.79073) (xy 341.928896 -406.723789) (xy 338.650827 -406.723789) (xy 338.642793 -406.790546)
			(xy 338.626825 -406.855926) (xy 338.603158 -406.918929) (xy 338.572131 -406.978652) (xy 338.534188 -407.034239)
			(xy 338.512404 -407.059892) (xy 338.506629 -407.067052) (xy 338.500101 -407.084231) (xy 338.499704 -407.09342)
			(xy 338.499704 -407.251408) (xy 338.499285 -407.261562) (xy 338.491487 -407.280314) (xy 338.47709 -407.294637)
			(xy 338.458298 -407.302337) (xy 338.448142 -407.302716) (xy 337.731862 -407.302716) (xy 337.721727 -407.302303)
			(xy 337.702997 -407.294555) (xy 337.688641 -407.280246) (xy 337.68083 -407.261541) (xy 337.6803 -407.251408)
			(xy 337.6803 -407.09342) (xy 337.67988 -407.084234) (xy 337.673373 -407.067049) (xy 337.6676 -407.059892)
			(xy 337.645782 -407.034265) (xy 337.607837 -406.978674) (xy 337.576807 -406.918947) (xy 337.553138 -406.855939)
			(xy 337.537168 -406.790554) (xy 337.529127 -406.723729) (xy 334.251065 -406.723729) (xy 334.251065 -406.723786)
			(xy 334.242993 -406.790722) (xy 334.226961 -406.85621) (xy 334.203201 -406.919305) (xy 334.172054 -406.9791)
			(xy 334.13397 -407.034735) (xy 334.112108 -407.0604) (xy 334.10633 -407.067558) (xy 334.099804 -407.084739)
			(xy 334.099408 -407.093928) (xy 334.099408 -407.251408) (xy 334.098921 -407.261516) (xy 334.091183 -407.280193)
			(xy 334.076886 -407.294487) (xy 334.058208 -407.302223) (xy 334.0481 -407.302716) (xy 333.33182 -407.302716)
			(xy 333.321701 -407.302268) (xy 333.303001 -407.29453) (xy 333.288686 -407.280223) (xy 333.280937 -407.261527)
			(xy 333.280512 -407.251408) (xy 333.280512 -407.093928) (xy 333.280086 -407.084743) (xy 333.273583 -407.067558)
			(xy 333.267812 -407.0604) (xy 333.245916 -407.034761) (xy 333.207828 -406.979123) (xy 333.176678 -406.919323)
			(xy 333.152915 -406.856223) (xy 333.136881 -406.790731) (xy 333.128808 -406.723789) (xy 326.525636 -406.723789)
			(xy 326.525636 -409.523827) (xy 330.929173 -409.523827) (xy 330.929176 -409.456519) (xy 330.937224 -409.389693)
			(xy 330.953202 -409.324309) (xy 330.976879 -409.261303) (xy 331.007918 -409.201578) (xy 331.045873 -409.145992)
			(xy 331.067664 -409.12034) (xy 331.073476 -409.113206) (xy 331.07998 -409.096007) (xy 331.080364 -409.086812)
			(xy 331.080364 -408.593544) (xy 331.079919 -408.584361) (xy 331.073428 -408.567177) (xy 331.067664 -408.560016)
			(xy 331.045868 -408.534371) (xy 331.007918 -408.478784) (xy 330.976883 -408.419059) (xy 330.95321 -408.356054)
			(xy 330.937237 -408.290671) (xy 330.929193 -408.223847) (xy 330.929194 -408.156541) (xy 330.937239 -408.089717)
			(xy 330.953213 -408.024334) (xy 330.976888 -407.96133) (xy 331.007924 -407.901606) (xy 331.045875 -407.84602)
			(xy 331.067664 -407.820368) (xy 331.073464 -407.813226) (xy 331.079975 -407.796033) (xy 331.080364 -407.78684)
			(xy 331.080364 -407.628852) (xy 331.080782 -407.618699) (xy 331.088586 -407.599953) (xy 331.102983 -407.585633)
			(xy 331.121771 -407.577928) (xy 331.131926 -407.577544) (xy 331.848206 -407.577544) (xy 331.858334 -407.578022)
			(xy 331.877056 -407.585752) (xy 331.891412 -407.600041) (xy 331.89923 -407.618727) (xy 331.899768 -407.628852)
			(xy 331.899768 -407.78684) (xy 331.900166 -407.796028) (xy 331.906689 -407.813212) (xy 331.912468 -407.820368)
			(xy 331.934248 -407.846027) (xy 331.972196 -407.901612) (xy 332.00323 -407.961335) (xy 332.026903 -408.024339)
			(xy 332.042876 -408.08972) (xy 332.050921 -408.156542) (xy 332.050921 -408.223846) (xy 332.042878 -408.290668)
			(xy 332.026906 -408.35605) (xy 332.003235 -408.419054) (xy 331.972203 -408.478777) (xy 331.934255 -408.534364)
			(xy 331.912468 -408.560016) (xy 331.906678 -408.567166) (xy 331.90016 -408.584353) (xy 331.899768 -408.593544)
			(xy 331.899768 -409.086812) (xy 331.900179 -409.095999) (xy 331.906693 -409.113183) (xy 331.912468 -409.12034)
			(xy 331.93422 -409.146022) (xy 331.972169 -409.201604) (xy 332.003204 -409.261323) (xy 332.026878 -409.324324)
			(xy 332.042853 -409.389703) (xy 332.0509 -409.456522) (xy 332.050904 -409.523824) (xy 332.042863 -409.590644)
			(xy 332.026894 -409.656024) (xy 332.003226 -409.719027) (xy 331.972197 -409.77875) (xy 331.934253 -409.834336)
			(xy 331.912468 -409.859988) (xy 331.906647 -409.867116) (xy 331.900148 -409.88432) (xy 331.899768 -409.893516)
			(xy 331.899768 -410.051504) (xy 331.899381 -410.061662) (xy 331.891578 -410.080421) (xy 331.87717 -410.094745)
			(xy 331.858367 -410.102439) (xy 331.848206 -410.102812) (xy 331.131926 -410.102812) (xy 331.121807 -410.102254)
			(xy 331.103097 -410.094544) (xy 331.088741 -410.08028) (xy 331.080912 -410.061619) (xy 331.080364 -410.051504)
			(xy 331.080364 -409.893516) (xy 331.079932 -409.884331) (xy 331.073432 -409.867148) (xy 331.067664 -409.859988)
			(xy 331.04584 -409.834365) (xy 331.007891 -409.778775) (xy 330.976857 -409.719048) (xy 330.953186 -409.656039)
			(xy 330.937214 -409.590653) (xy 330.929173 -409.523827) (xy 326.525636 -409.523827) (xy 326.525636 -410.623701)
			(xy 333.128819 -410.623701) (xy 333.12882 -410.556275) (xy 333.136898 -410.489336) (xy 333.152936 -410.423846)
			(xy 333.176702 -410.360748) (xy 333.207855 -410.300952) (xy 333.245947 -410.245317) (xy 333.267812 -410.219652)
			(xy 333.273613 -410.21251) (xy 333.280125 -410.195317) (xy 333.280512 -410.186124) (xy 333.280512 -409.693872)
			(xy 333.280113 -409.684684) (xy 333.273591 -409.6675) (xy 333.267812 -409.660344) (xy 333.245959 -409.634669)
			(xy 333.20787 -409.579036) (xy 333.176718 -409.519242) (xy 333.152952 -409.456146) (xy 333.136916 -409.390658)
			(xy 333.128839 -409.32372) (xy 333.128837 -409.256298) (xy 333.136912 -409.18936) (xy 333.152947 -409.123871)
			(xy 333.17671 -409.060775) (xy 333.20786 -409.000979) (xy 333.245948 -408.945345) (xy 333.267812 -408.91968)
			(xy 333.273601 -408.912529) (xy 333.28012 -408.895343) (xy 333.280512 -408.886152) (xy 333.280512 -408.728672)
			(xy 333.280962 -408.71856) (xy 333.288711 -408.699879) (xy 333.303019 -408.685585) (xy 333.321708 -408.677853)
			(xy 333.33182 -408.677364) (xy 334.0481 -408.677364) (xy 334.058204 -408.677884) (xy 334.076876 -408.685615)
			(xy 334.091169 -408.699901) (xy 334.09891 -408.718568) (xy 334.099408 -408.728672) (xy 334.099408 -408.886152)
			(xy 334.099839 -408.895337) (xy 334.106338 -408.912522) (xy 334.112108 -408.91968) (xy 334.133983 -408.945336)
			(xy 334.172071 -409.000972) (xy 334.203221 -409.060769) (xy 334.226984 -409.123867) (xy 334.243019 -409.189358)
			(xy 334.251093 -409.256297) (xy 334.251092 -409.323721) (xy 334.243015 -409.39066) (xy 334.226979 -409.45615)
			(xy 334.203214 -409.519247) (xy 334.200797 -409.523886) (xy 335.328966 -409.523886) (xy 335.328969 -409.45646)
			(xy 335.337048 -409.38952) (xy 335.353086 -409.32403) (xy 335.376852 -409.260931) (xy 335.408005 -409.201134)
			(xy 335.446095 -409.145498) (xy 335.46796 -409.119832) (xy 335.473775 -409.1127) (xy 335.480277 -409.095499)
			(xy 335.48066 -409.086304) (xy 335.48066 -408.594052) (xy 335.480211 -408.584869) (xy 335.473723 -408.567685)
			(xy 335.46796 -408.560524) (xy 335.44609 -408.534865) (xy 335.408004 -408.479228) (xy 335.376856 -408.419431)
			(xy 335.353094 -408.356333) (xy 335.33706 -408.290844) (xy 335.328985 -408.223906) (xy 335.328986 -408.156482)
			(xy 335.337062 -408.089544) (xy 335.353097 -408.024055) (xy 335.376861 -407.960958) (xy 335.40801 -407.901161)
			(xy 335.446097 -407.845526) (xy 335.46796 -407.81986) (xy 335.473763 -407.81272) (xy 335.480272 -407.795525)
			(xy 335.48066 -407.786332) (xy 335.48066 -407.628852) (xy 335.481145 -407.618745) (xy 335.488891 -407.600074)
			(xy 335.503187 -407.585782) (xy 335.521861 -407.578042) (xy 335.531968 -407.577544) (xy 336.248248 -407.577544)
			(xy 336.258353 -407.578045) (xy 336.277021 -407.585788) (xy 336.291312 -407.600079) (xy 336.299055 -407.618747)
			(xy 336.299556 -407.628852) (xy 336.299556 -407.786332) (xy 336.299961 -407.79552) (xy 336.306479 -407.812703)
			(xy 336.312256 -407.81986) (xy 336.334114 -407.845531) (xy 336.372205 -407.901164) (xy 336.403359 -407.960959)
			(xy 336.427126 -408.024055) (xy 336.443163 -408.089544) (xy 336.45124 -408.156482) (xy 336.451241 -408.223906)
			(xy 336.443165 -408.290844) (xy 336.427129 -408.356334) (xy 336.403364 -408.41943) (xy 336.372212 -408.479226)
			(xy 336.334121 -408.53486) (xy 336.312256 -408.560524) (xy 336.306461 -408.56767) (xy 336.299947 -408.58486)
			(xy 336.299556 -408.594052) (xy 336.299556 -409.086304) (xy 336.299974 -409.09549) (xy 336.306483 -409.112674)
			(xy 336.312256 -409.119832) (xy 336.334086 -409.145526) (xy 336.372179 -409.201155) (xy 336.403334 -409.260947)
			(xy 336.427102 -409.32404) (xy 336.443141 -409.389526) (xy 336.45122 -409.456462) (xy 336.451224 -409.523884)
			(xy 336.443151 -409.59082) (xy 336.427118 -409.656308) (xy 336.403356 -409.719404) (xy 336.372207 -409.779198)
			(xy 336.334119 -409.834832) (xy 336.312256 -409.860496) (xy 336.306473 -409.867651) (xy 336.299951 -409.884834)
			(xy 336.299556 -409.894024) (xy 336.299556 -410.051504) (xy 336.299019 -410.061606) (xy 336.291291 -410.080274)
			(xy 336.277011 -410.094566) (xy 336.25835 -410.102311) (xy 336.248248 -410.102812) (xy 335.531968 -410.102812)
			(xy 335.521859 -410.102341) (xy 335.503182 -410.094595) (xy 335.488889 -410.080294) (xy 335.481153 -410.061614)
			(xy 335.48066 -410.051504) (xy 335.48066 -409.894024) (xy 335.480225 -409.88484) (xy 335.473727 -409.867656)
			(xy 335.46796 -409.860496) (xy 335.446062 -409.834859) (xy 335.407977 -409.77922) (xy 335.37683 -409.719419)
			(xy 335.35307 -409.656319) (xy 335.337038 -409.590827) (xy 335.328966 -409.523886) (xy 334.200797 -409.523886)
			(xy 334.172062 -409.579044) (xy 334.133972 -409.634679) (xy 334.112108 -409.660344) (xy 334.106311 -409.667489)
			(xy 334.099796 -409.68468) (xy 334.099408 -409.693872) (xy 334.099408 -410.186124) (xy 334.099805 -410.195313)
			(xy 334.106328 -410.212497) (xy 334.112108 -410.219652) (xy 334.133956 -410.24533) (xy 334.172045 -410.300963)
			(xy 334.203196 -410.360758) (xy 334.22696 -410.423853) (xy 334.242997 -410.48934) (xy 334.251074 -410.556277)
			(xy 334.251075 -410.623641) (xy 337.529138 -410.623641) (xy 337.52914 -410.556335) (xy 337.537185 -410.489512)
			(xy 337.553158 -410.42413) (xy 337.576831 -410.361125) (xy 337.607864 -410.3014) (xy 337.645813 -410.245813)
			(xy 337.6676 -410.22016) (xy 337.673396 -410.213014) (xy 337.679911 -410.195824) (xy 337.6803 -410.186632)
			(xy 337.6803 -409.693364) (xy 337.679907 -409.684175) (xy 337.673382 -409.666991) (xy 337.6676 -409.659836)
			(xy 337.645825 -409.634174) (xy 337.607879 -409.578588) (xy 337.576847 -409.518865) (xy 337.553175 -409.455862)
			(xy 337.537203 -409.390482) (xy 337.529158 -409.323661) (xy 337.529157 -409.256357) (xy 337.537199 -409.189536)
			(xy 337.55317 -409.124155) (xy 337.57684 -409.061151) (xy 337.607869 -409.001428) (xy 337.645814 -408.945841)
			(xy 337.6676 -408.920188) (xy 337.673384 -408.913034) (xy 337.679906 -408.89585) (xy 337.6803 -408.88666)
			(xy 337.6803 -408.728672) (xy 337.680699 -408.718516) (xy 337.688503 -408.699763) (xy 337.702907 -408.685441)
			(xy 337.721704 -408.677742) (xy 337.731862 -408.677364) (xy 338.448142 -408.677364) (xy 338.458274 -408.677793)
			(xy 338.477001 -408.685539) (xy 338.491357 -408.699843) (xy 338.49917 -408.718542) (xy 338.499704 -408.728672)
			(xy 338.499704 -408.88666) (xy 338.500132 -408.895845) (xy 338.506633 -408.91303) (xy 338.512404 -408.920188)
			(xy 338.534202 -408.945831) (xy 338.572148 -409.00142) (xy 338.603178 -409.061145) (xy 338.626848 -409.124151)
			(xy 338.642819 -409.189534) (xy 338.650862 -409.256356) (xy 338.650861 -409.323662) (xy 338.642816 -409.390484)
			(xy 338.626843 -409.455867) (xy 338.603171 -409.518871) (xy 338.600596 -409.523827) (xy 339.729261 -409.523827)
			(xy 339.729264 -409.456519) (xy 339.737312 -409.389694) (xy 339.753289 -409.324309) (xy 339.776966 -409.261303)
			(xy 339.808004 -409.201579) (xy 339.845958 -409.145992) (xy 339.867748 -409.12034) (xy 339.873559 -409.113205)
			(xy 339.880064 -409.096006) (xy 339.880448 -409.086812) (xy 339.880448 -408.593544) (xy 339.880006 -408.58436)
			(xy 339.873513 -408.567176) (xy 339.867748 -408.560016) (xy 339.845952 -408.534371) (xy 339.808003 -408.478783)
			(xy 339.776969 -408.419059) (xy 339.753297 -408.356054) (xy 339.737324 -408.29067) (xy 339.72928 -408.223847)
			(xy 339.729281 -408.156541) (xy 339.737326 -408.089718) (xy 339.7533 -408.024335) (xy 339.776974 -407.96133)
			(xy 339.808009 -407.901606) (xy 339.845959 -407.84602) (xy 339.867748 -407.820368) (xy 339.873547 -407.813224)
			(xy 339.880059 -407.796032) (xy 339.880448 -407.78684) (xy 339.880448 -407.628852) (xy 339.880881 -407.618701)
			(xy 339.888683 -407.599958) (xy 339.903075 -407.585638) (xy 339.921857 -407.577931) (xy 339.93201 -407.577544)
			(xy 340.64829 -407.577544) (xy 340.658417 -407.578035) (xy 340.677138 -407.58576) (xy 340.691495 -407.600045)
			(xy 340.699314 -407.618728) (xy 340.699852 -407.628852) (xy 340.699852 -407.78684) (xy 340.700254 -407.796028)
			(xy 340.706775 -407.813211) (xy 340.712552 -407.820368) (xy 340.734332 -407.846027) (xy 340.772282 -407.901612)
			(xy 340.803316 -407.961335) (xy 340.826989 -408.024338) (xy 340.842963 -408.08972) (xy 340.851008 -408.156542)
			(xy 340.851009 -408.223846) (xy 340.842965 -408.290668) (xy 340.826993 -408.35605) (xy 340.803321 -408.419054)
			(xy 340.772288 -408.478778) (xy 340.734339 -408.534364) (xy 340.712552 -408.560016) (xy 340.70676 -408.567164)
			(xy 340.700244 -408.584353) (xy 340.699852 -408.593544) (xy 340.699852 -409.086812) (xy 340.700267 -409.095998)
			(xy 340.706779 -409.113182) (xy 340.712552 -409.12034) (xy 340.734304 -409.146021) (xy 340.772255 -409.201603)
			(xy 340.80329 -409.261323) (xy 340.826965 -409.324323) (xy 340.842941 -409.389702) (xy 340.850988 -409.456522)
			(xy 340.850992 -409.523824) (xy 340.842951 -409.590644) (xy 340.826981 -409.656025) (xy 340.803312 -409.719028)
			(xy 340.772283 -409.77875) (xy 340.734338 -409.834336) (xy 340.712552 -409.859988) (xy 340.70673 -409.867115)
			(xy 340.700232 -409.88432) (xy 340.699852 -409.893516) (xy 340.699852 -410.051504) (xy 340.699383 -410.061652)
			(xy 340.691595 -410.080394) (xy 340.677214 -410.094716) (xy 340.65844 -410.102424) (xy 340.64829 -410.102812)
			(xy 339.93201 -410.102812) (xy 339.92189 -410.102267) (xy 339.903179 -410.094552) (xy 339.888824 -410.080284)
			(xy 339.880996 -410.061621) (xy 339.880448 -410.051504) (xy 339.880448 -409.893516) (xy 339.88002 -409.884331)
			(xy 339.873517 -409.867147) (xy 339.867748 -409.859988) (xy 339.845924 -409.834365) (xy 339.807976 -409.778775)
			(xy 339.776944 -409.719047) (xy 339.753273 -409.656039) (xy 339.737302 -409.590653) (xy 339.729261 -409.523827)
			(xy 338.600596 -409.523827) (xy 338.572139 -409.578596) (xy 338.534191 -409.634183) (xy 338.512404 -409.659836)
			(xy 338.50661 -409.666983) (xy 338.500094 -409.684172) (xy 338.499704 -409.693364) (xy 338.499704 -410.186632)
			(xy 338.500098 -410.195821) (xy 338.506623 -410.213005) (xy 338.512404 -410.22016) (xy 338.534175 -410.245826)
			(xy 338.572121 -410.301411) (xy 338.603153 -410.361133) (xy 338.626825 -410.424136) (xy 338.642797 -410.489516)
			(xy 338.650842 -410.556336) (xy 338.650844 -410.623639) (xy 338.650837 -410.6237) (xy 341.928907 -410.6237)
			(xy 341.928908 -410.556276) (xy 341.936986 -410.489336) (xy 341.953023 -410.423846) (xy 341.976789 -410.360749)
			(xy 342.007941 -410.300952) (xy 342.046031 -410.245317) (xy 342.067896 -410.219652) (xy 342.073695 -410.212508)
			(xy 342.080208 -410.195317) (xy 342.080596 -410.186124) (xy 342.080596 -409.693872) (xy 342.0802 -409.684683)
			(xy 342.073677 -409.667499) (xy 342.067896 -409.660344) (xy 342.046044 -409.634669) (xy 342.007955 -409.579036)
			(xy 341.976804 -409.519241) (xy 341.953039 -409.456145) (xy 341.937003 -409.390657) (xy 341.928927 -409.32372)
			(xy 341.928925 -409.256298) (xy 341.937 -409.18936) (xy 341.953034 -409.123872) (xy 341.976797 -409.060776)
			(xy 342.007946 -409.00098) (xy 342.046033 -408.945345) (xy 342.067896 -408.91968) (xy 342.073683 -408.912528)
			(xy 342.080204 -408.895343) (xy 342.080596 -408.886152) (xy 342.080596 -408.728672) (xy 342.081062 -408.718562)
			(xy 342.088808 -408.699884) (xy 342.103111 -408.68559) (xy 342.121794 -408.677856) (xy 342.131904 -408.677364)
			(xy 342.848184 -408.677364) (xy 342.858287 -408.677897) (xy 342.876958 -408.685623) (xy 342.891252 -408.699905)
			(xy 342.898994 -408.718569) (xy 342.899492 -408.728672) (xy 342.899492 -408.886152) (xy 342.899927 -408.895337)
			(xy 342.906424 -408.912521) (xy 342.912192 -408.91968) (xy 342.934068 -408.945335) (xy 342.972157 -409.000971)
			(xy 343.003308 -409.060769) (xy 343.027071 -409.123867) (xy 343.043106 -409.189357) (xy 343.051181 -409.256297)
			(xy 343.05118 -409.323721) (xy 343.043103 -409.390661) (xy 343.027066 -409.45615) (xy 343.0033 -409.519248)
			(xy 343.000914 -409.523827) (xy 344.129052 -409.523827) (xy 344.129055 -409.456519) (xy 344.137102 -409.389694)
			(xy 344.153079 -409.32431) (xy 344.176756 -409.261304) (xy 344.207793 -409.201579) (xy 344.245746 -409.145992)
			(xy 344.267536 -409.12034) (xy 344.273345 -409.113204) (xy 344.279851 -409.096006) (xy 344.280236 -409.086812)
			(xy 344.280236 -408.593544) (xy 344.279796 -408.58436) (xy 344.273302 -408.567176) (xy 344.267536 -408.560016)
			(xy 344.24574 -408.53437) (xy 344.207792 -408.478783) (xy 344.176759 -408.419058) (xy 344.153087 -408.356053)
			(xy 344.137115 -408.29067) (xy 344.129071 -408.223847) (xy 344.129072 -408.156541) (xy 344.137117 -408.089718)
			(xy 344.153091 -408.024335) (xy 344.176764 -407.961331) (xy 344.207798 -407.901607) (xy 344.245748 -407.84602)
			(xy 344.267536 -407.820368) (xy 344.273333 -407.813223) (xy 344.279847 -407.796032) (xy 344.280236 -407.78684)
			(xy 344.280236 -407.628852) (xy 344.280583 -407.61869) (xy 344.288401 -407.59993) (xy 344.302821 -407.585607)
			(xy 344.321634 -407.577916) (xy 344.331798 -407.577544) (xy 345.048078 -407.577544) (xy 345.058204 -407.578045)
			(xy 345.076925 -407.585766) (xy 345.091283 -407.600048) (xy 345.099102 -407.618729) (xy 345.09964 -407.628852)
			(xy 345.09964 -407.78684) (xy 345.100044 -407.796028) (xy 345.106563 -407.813211) (xy 345.11234 -407.820368)
			(xy 345.13412 -407.846026) (xy 345.172071 -407.901611) (xy 345.203106 -407.961334) (xy 345.22678 -408.024338)
			(xy 345.242754 -408.089719) (xy 345.250799 -408.156542) (xy 345.2508 -408.223846) (xy 345.242756 -408.290669)
			(xy 345.226783 -408.356051) (xy 345.20311 -408.419055) (xy 345.172077 -408.478778) (xy 345.134128 -408.534364)
			(xy 345.11234 -408.560016) (xy 345.106547 -408.567163) (xy 345.100032 -408.584352) (xy 345.09964 -408.593544)
			(xy 345.09964 -409.086812) (xy 345.100058 -409.095998) (xy 345.106568 -409.113182) (xy 345.11234 -409.12034)
			(xy 345.134093 -409.146021) (xy 345.172044 -409.201603) (xy 345.20308 -409.261322) (xy 345.226756 -409.324323)
			(xy 345.242732 -409.389702) (xy 345.250779 -409.456522) (xy 345.250783 -409.523824) (xy 345.242742 -409.590645)
			(xy 345.226772 -409.656025) (xy 345.203102 -409.719028) (xy 345.172072 -409.778751) (xy 345.134126 -409.834336)
			(xy 345.11234 -409.859988) (xy 345.106516 -409.867114) (xy 345.100019 -409.884319) (xy 345.09964 -409.893516)
			(xy 345.09964 -410.051504) (xy 345.099182 -410.061653) (xy 345.091393 -410.080398) (xy 345.077008 -410.09472)
			(xy 345.058229 -410.102427) (xy 345.048078 -410.102812) (xy 344.331798 -410.102812) (xy 344.321678 -410.102277)
			(xy 344.302966 -410.094558) (xy 344.288612 -410.080287) (xy 344.280784 -410.061621) (xy 344.280236 -410.051504)
			(xy 344.280236 -409.893516) (xy 344.27981 -409.884331) (xy 344.273307 -409.867146) (xy 344.267536 -409.859988)
			(xy 344.245713 -409.834365) (xy 344.207765 -409.778774) (xy 344.176734 -409.719047) (xy 344.153063 -409.656038)
			(xy 344.137093 -409.590653) (xy 344.129052 -409.523827) (xy 343.000914 -409.523827) (xy 342.972148 -409.579044)
			(xy 342.934057 -409.634679) (xy 342.912192 -409.660344) (xy 342.906393 -409.667488) (xy 342.89988 -409.684679)
			(xy 342.899492 -409.693872) (xy 342.899492 -410.186124) (xy 342.899892 -410.195312) (xy 342.906413 -410.212496)
			(xy 342.912192 -410.219652) (xy 342.934041 -410.24533) (xy 342.97213 -410.300963) (xy 343.003282 -410.360757)
			(xy 343.027048 -410.423852) (xy 343.043084 -410.48934) (xy 343.051162 -410.556277) (xy 343.051163 -410.623642)
			(xy 346.329202 -410.623642) (xy 346.329204 -410.556334) (xy 346.33725 -410.48951) (xy 346.353226 -410.424126)
			(xy 346.376903 -410.361121) (xy 346.40794 -410.301397) (xy 346.445894 -410.245812) (xy 346.467684 -410.22016)
			(xy 346.473478 -410.213013) (xy 346.479995 -410.195824) (xy 346.480384 -410.186632) (xy 346.480384 -409.693364)
			(xy 346.479995 -409.684175) (xy 346.473467 -409.66699) (xy 346.467684 -409.659836) (xy 346.445907 -409.634175)
			(xy 346.407955 -409.578591) (xy 346.376918 -409.518869) (xy 346.353243 -409.455865) (xy 346.337268 -409.390484)
			(xy 346.329222 -409.323661) (xy 346.329221 -409.256357) (xy 346.337265 -409.189534) (xy 346.353238 -409.124152)
			(xy 346.376911 -409.061148) (xy 346.407945 -409.001425) (xy 346.445896 -408.94584) (xy 346.467684 -408.920188)
			(xy 346.473466 -408.913033) (xy 346.47999 -408.89585) (xy 346.480384 -408.88666) (xy 346.480384 -408.728672)
			(xy 346.480798 -408.718518) (xy 346.4886 -408.699768) (xy 346.502999 -408.685446) (xy 346.52179 -408.677745)
			(xy 346.531946 -408.677364) (xy 347.248226 -408.677364) (xy 347.258357 -408.677806) (xy 347.277084 -408.685547)
			(xy 347.29144 -408.699847) (xy 347.299254 -408.718543) (xy 347.299788 -408.728672) (xy 347.299788 -408.88666)
			(xy 347.30022 -408.895845) (xy 347.306719 -408.913029) (xy 347.312488 -408.920188) (xy 347.334287 -408.945831)
			(xy 347.372233 -409.001419) (xy 347.403265 -409.061144) (xy 347.426936 -409.12415) (xy 347.442907 -409.189533)
			(xy 347.45095 -409.256356) (xy 347.450949 -409.323662) (xy 347.442904 -409.390485) (xy 347.42693 -409.455867)
			(xy 347.403257 -409.518872) (xy 347.400682 -409.523827) (xy 374.929082 -409.523827) (xy 374.929085 -409.456519)
			(xy 374.937133 -409.389693) (xy 374.953111 -409.324308) (xy 374.97679 -409.261302) (xy 375.007829 -409.201578)
			(xy 375.045785 -409.145991) (xy 375.067576 -409.12034) (xy 375.073378 -409.113198) (xy 375.07989 -409.096005)
			(xy 375.080276 -409.086812) (xy 375.080276 -408.593544) (xy 375.07985 -408.584358) (xy 375.073348 -408.567174)
			(xy 375.067576 -408.560016) (xy 375.045779 -408.534371) (xy 375.007828 -408.478784) (xy 374.976793 -408.41906)
			(xy 374.953119 -408.356055) (xy 374.937146 -408.290671) (xy 374.929102 -408.223847) (xy 374.929103 -408.156541)
			(xy 374.937148 -408.089717) (xy 374.953123 -408.024334) (xy 374.976798 -407.961329) (xy 375.007835 -407.901605)
			(xy 375.045787 -407.84602) (xy 375.067576 -407.820368) (xy 375.073366 -407.813218) (xy 375.079885 -407.796031)
			(xy 375.080276 -407.78684) (xy 375.080276 -407.628852) (xy 375.080682 -407.618698) (xy 375.088489 -407.599949)
			(xy 375.10289 -407.585628) (xy 375.121682 -407.577926) (xy 375.131838 -407.577544) (xy 375.848118 -407.577544)
			(xy 375.858246 -407.578012) (xy 375.876969 -407.585746) (xy 375.891325 -407.600038) (xy 375.899143 -407.618726)
			(xy 375.89968 -407.628852) (xy 375.89968 -407.78684) (xy 375.900075 -407.796029) (xy 375.9066 -407.813213)
			(xy 375.91238 -407.820368) (xy 375.934159 -407.846027) (xy 375.972107 -407.901613) (xy 376.00314 -407.961336)
			(xy 376.026812 -408.024339) (xy 376.042785 -408.08972) (xy 376.05083 -408.156542) (xy 376.05083 -408.223846)
			(xy 376.042787 -408.290668) (xy 376.026816 -408.356049) (xy 376.003145 -408.419053) (xy 375.972113 -408.478777)
			(xy 375.934167 -408.534364) (xy 375.91238 -408.560016) (xy 375.906592 -408.567167) (xy 375.900073 -408.584353)
			(xy 375.89968 -408.593544) (xy 375.89968 -409.086812) (xy 375.900089 -409.095999) (xy 375.906604 -409.113183)
			(xy 375.91238 -409.12034) (xy 375.934131 -409.146022) (xy 375.97208 -409.201604) (xy 376.003114 -409.261324)
			(xy 376.026788 -409.324325) (xy 376.042763 -409.389703) (xy 376.050809 -409.456522) (xy 376.050813 -409.523824)
			(xy 376.042772 -409.590644) (xy 376.026804 -409.656024) (xy 376.003136 -409.719026) (xy 375.972108 -409.778749)
			(xy 375.934165 -409.834335) (xy 375.91238 -409.859988) (xy 375.906561 -409.867117) (xy 375.90006 -409.88432)
			(xy 375.89968 -409.893516) (xy 375.89968 -410.051504) (xy 375.899281 -410.061661) (xy 375.891481 -410.080417)
			(xy 375.877077 -410.094741) (xy 375.858277 -410.102437) (xy 375.848118 -410.102812) (xy 375.131838 -410.102812)
			(xy 375.12172 -410.102244) (xy 375.10301 -410.094538) (xy 375.088654 -410.080277) (xy 375.080824 -410.061618)
			(xy 375.080276 -410.051504) (xy 375.080276 -409.893516) (xy 375.079864 -409.884329) (xy 375.073352 -409.867144)
			(xy 375.067576 -409.859988) (xy 375.045751 -409.834366) (xy 375.007801 -409.778776) (xy 374.976768 -409.719048)
			(xy 374.953095 -409.65604) (xy 374.937124 -409.590654) (xy 374.929082 -409.523827) (xy 347.400682 -409.523827)
			(xy 347.372224 -409.578596) (xy 347.334276 -409.634184) (xy 347.312488 -409.659836) (xy 347.306692 -409.666982)
			(xy 347.300177 -409.684172) (xy 347.299788 -409.693364) (xy 347.299788 -410.186632) (xy 347.300185 -410.195821)
			(xy 347.306708 -410.213005) (xy 347.312488 -410.22016) (xy 347.334259 -410.245825) (xy 347.372207 -410.301411)
			(xy 347.403239 -410.361133) (xy 347.426912 -410.424135) (xy 347.442885 -410.489516) (xy 347.45093 -410.556336)
			(xy 347.450931 -410.62364) (xy 347.450924 -410.623701) (xy 377.128728 -410.623701) (xy 377.128729 -410.556275)
			(xy 377.136807 -410.489335) (xy 377.152845 -410.423845) (xy 377.176612 -410.360748) (xy 377.207766 -410.300951)
			(xy 377.245858 -410.245317) (xy 377.267724 -410.219652) (xy 377.273526 -410.212511) (xy 377.280037 -410.195317)
			(xy 377.280424 -410.186124) (xy 377.280424 -409.693872) (xy 377.280022 -409.684684) (xy 377.273502 -409.6675)
			(xy 377.267724 -409.660344) (xy 377.245871 -409.634669) (xy 377.20778 -409.579037) (xy 377.176628 -409.519242)
			(xy 377.152862 -409.456146) (xy 377.136825 -409.390658) (xy 377.128748 -409.323721) (xy 377.128747 -409.256297)
			(xy 377.136822 -409.18936) (xy 377.152857 -409.123871) (xy 377.17662 -409.060774) (xy 377.207771 -409.000979)
			(xy 377.24586 -408.945345) (xy 377.267724 -408.91968) (xy 377.273514 -408.912531) (xy 377.280032 -408.895343)
			(xy 377.280424 -408.886152) (xy 377.280424 -408.728672) (xy 377.280794 -408.718545) (xy 377.288555 -408.699836)
			(xy 377.302886 -408.685522) (xy 377.321604 -408.677782) (xy 377.331732 -408.677364) (xy 378.048012 -408.677364)
			(xy 378.058117 -408.677875) (xy 378.076789 -408.685609) (xy 378.091082 -408.699898) (xy 378.098822 -408.718567)
			(xy 378.09932 -408.728672) (xy 378.09932 -408.886152) (xy 378.099749 -408.895337) (xy 378.106249 -408.912522)
			(xy 378.11202 -408.91968) (xy 378.133895 -408.945336) (xy 378.171982 -409.000972) (xy 378.203131 -409.06077)
			(xy 378.226894 -409.123868) (xy 378.242928 -409.189358) (xy 378.251002 -409.256297) (xy 378.251001 -409.323721)
			(xy 378.242925 -409.39066) (xy 378.226888 -409.456149) (xy 378.203124 -409.519247) (xy 378.200707 -409.523886)
			(xy 379.328875 -409.523886) (xy 379.328878 -409.45646) (xy 379.336957 -409.38952) (xy 379.352995 -409.324029)
			(xy 379.376762 -409.260931) (xy 379.407916 -409.201133) (xy 379.446007 -409.145498) (xy 379.467872 -409.119832)
			(xy 379.473689 -409.112701) (xy 379.480189 -409.095499) (xy 379.480572 -409.086304) (xy 379.480572 -408.594052)
			(xy 379.480143 -408.584867) (xy 379.473643 -408.567682) (xy 379.467872 -408.560524) (xy 379.446001 -408.534865)
			(xy 379.407915 -408.479229) (xy 379.376766 -408.419431) (xy 379.353003 -408.356334) (xy 379.336969 -408.290844)
			(xy 379.328894 -408.223906) (xy 379.328895 -408.156482) (xy 379.336971 -408.089544) (xy 379.353007 -408.024055)
			(xy 379.376771 -407.960958) (xy 379.407921 -407.901161) (xy 379.446009 -407.845526) (xy 379.467872 -407.81986)
			(xy 379.473677 -407.812721) (xy 379.480185 -407.795525) (xy 379.480572 -407.786332) (xy 379.480572 -407.628852)
			(xy 379.481045 -407.618744) (xy 379.488793 -407.60007) (xy 379.503093 -407.585778) (xy 379.521771 -407.57804)
			(xy 379.53188 -407.577544) (xy 380.24816 -407.577544) (xy 380.258259 -407.578117) (xy 380.276926 -407.585831)
			(xy 380.29122 -407.6001) (xy 380.298966 -407.618754) (xy 380.299468 -407.628852) (xy 380.299468 -407.786332)
			(xy 380.29987 -407.79552) (xy 380.30639 -407.812704) (xy 380.312168 -407.81986) (xy 380.334025 -407.845531)
			(xy 380.372116 -407.901164) (xy 380.403269 -407.960959) (xy 380.427035 -408.024055) (xy 380.443072 -408.089544)
			(xy 380.451149 -408.156482) (xy 380.45115 -408.223906) (xy 380.443074 -408.290844) (xy 380.427039 -408.356333)
			(xy 380.403274 -408.41943) (xy 380.372122 -408.479226) (xy 380.334033 -408.534859) (xy 380.312168 -408.560524)
			(xy 380.306375 -408.567671) (xy 380.299859 -408.58486) (xy 380.299468 -408.594052) (xy 380.299468 -409.086304)
			(xy 380.299883 -409.09549) (xy 380.306394 -409.112675) (xy 380.312168 -409.119832) (xy 380.333998 -409.145526)
			(xy 380.37209 -409.201156) (xy 380.403244 -409.260947) (xy 380.427011 -409.324041) (xy 380.44305 -409.389527)
			(xy 380.451129 -409.456462) (xy 380.451133 -409.523884) (xy 380.44306 -409.59082) (xy 380.427027 -409.656308)
			(xy 380.403266 -409.719403) (xy 380.372117 -409.779198) (xy 380.334031 -409.834831) (xy 380.312168 -409.860496)
			(xy 380.306386 -409.867652) (xy 380.299864 -409.884834) (xy 380.299468 -409.894024) (xy 380.299468 -410.051504)
			(xy 380.299086 -410.061631) (xy 380.291331 -410.08034) (xy 380.277003 -410.094656) (xy 380.258287 -410.102395)
			(xy 380.24816 -410.102812) (xy 379.53188 -410.102812) (xy 379.521771 -410.102332) (xy 379.503095 -410.09459)
			(xy 379.488801 -410.080292) (xy 379.481065 -410.061613) (xy 379.480572 -410.051504) (xy 379.480572 -409.894024)
			(xy 379.480157 -409.884837) (xy 379.473647 -409.867652) (xy 379.467872 -409.860496) (xy 379.445974 -409.834859)
			(xy 379.407888 -409.77922) (xy 379.37674 -409.71942) (xy 379.352979 -409.656319) (xy 379.336947 -409.590827)
			(xy 379.328875 -409.523886) (xy 378.200707 -409.523886) (xy 378.171973 -409.579043) (xy 378.133884 -409.634678)
			(xy 378.11202 -409.660344) (xy 378.106225 -409.66749) (xy 378.099709 -409.68468) (xy 378.09932 -409.693872)
			(xy 378.09932 -410.186124) (xy 378.099714 -410.195313) (xy 378.106239 -410.212497) (xy 378.11202 -410.219652)
			(xy 378.133868 -410.245331) (xy 378.171955 -410.300964) (xy 378.203106 -410.360758) (xy 378.22687 -410.423853)
			(xy 378.242906 -410.48934) (xy 378.250983 -410.556277) (xy 378.250984 -410.623641) (xy 381.529047 -410.623641)
			(xy 381.529049 -410.556335) (xy 381.537094 -410.489512) (xy 381.553068 -410.424129) (xy 381.576742 -410.361124)
			(xy 381.607775 -410.3014) (xy 381.645724 -410.245812) (xy 381.667512 -410.22016) (xy 381.673309 -410.213015)
			(xy 381.679823 -410.195824) (xy 381.680212 -410.186632) (xy 381.680212 -409.693364) (xy 381.679817 -409.684175)
			(xy 381.673292 -409.666991) (xy 381.667512 -409.659836) (xy 381.645737 -409.634174) (xy 381.607789 -409.578588)
			(xy 381.576757 -409.518866) (xy 381.553085 -409.455863) (xy 381.537112 -409.390482) (xy 381.529067 -409.323661)
			(xy 381.529066 -409.256357) (xy 381.537109 -409.189536) (xy 381.553079 -409.124155) (xy 381.57675 -409.061151)
			(xy 381.60778 -409.001427) (xy 381.645726 -408.94584) (xy 381.667512 -408.920188) (xy 381.673298 -408.913035)
			(xy 381.679818 -408.89585) (xy 381.680212 -408.88666) (xy 381.680212 -408.728672) (xy 381.680662 -408.71856)
			(xy 381.688411 -408.699879) (xy 381.702719 -408.685585) (xy 381.721408 -408.677853) (xy 381.73152 -408.677364)
			(xy 382.448054 -408.677364) (xy 382.458181 -408.677865) (xy 382.476905 -408.685582) (xy 382.491264 -408.699865)
			(xy 382.499081 -408.718548) (xy 382.499616 -408.728672) (xy 382.499616 -408.88666) (xy 382.500042 -408.895846)
			(xy 382.506544 -408.91303) (xy 382.512316 -408.920188) (xy 382.534117 -408.94583) (xy 382.572068 -409.001417)
			(xy 382.603103 -409.061141) (xy 382.626778 -409.124147) (xy 382.642751 -409.189531) (xy 382.650795 -409.256356)
			(xy 382.650794 -409.323662) (xy 382.642748 -409.390487) (xy 382.626772 -409.45587) (xy 382.603096 -409.518875)
			(xy 382.600523 -409.523827) (xy 383.72917 -409.523827) (xy 383.729173 -409.456519) (xy 383.737221 -409.389693)
			(xy 383.753198 -409.324309) (xy 383.776876 -409.261303) (xy 383.807915 -409.201578) (xy 383.845869 -409.145992)
			(xy 383.86766 -409.12034) (xy 383.873472 -409.113206) (xy 383.879976 -409.096007) (xy 383.88036 -409.086812)
			(xy 383.88036 -408.593544) (xy 383.879915 -408.584361) (xy 383.873424 -408.567177) (xy 383.86766 -408.560016)
			(xy 383.845864 -408.53437) (xy 383.807914 -408.478784) (xy 383.77688 -408.419059) (xy 383.753207 -408.356054)
			(xy 383.737234 -408.290671) (xy 383.72919 -408.223847) (xy 383.729191 -408.156541) (xy 383.737236 -408.089717)
			(xy 383.75321 -408.024335) (xy 383.776885 -407.96133) (xy 383.80792 -407.901606) (xy 383.845871 -407.84602)
			(xy 383.86766 -407.820368) (xy 383.87346 -407.813226) (xy 383.879971 -407.796033) (xy 383.88036 -407.78684)
			(xy 383.88036 -407.628852) (xy 383.880845 -407.618745) (xy 383.888591 -407.600074) (xy 383.902887 -407.585782)
			(xy 383.921561 -407.578042) (xy 383.931668 -407.577544) (xy 384.648202 -407.577544) (xy 384.658329 -407.578025)
			(xy 384.677051 -407.585754) (xy 384.691408 -407.600042) (xy 384.699226 -407.618727) (xy 384.699764 -407.628852)
			(xy 384.699764 -407.78684) (xy 384.700163 -407.796028) (xy 384.706685 -407.813212) (xy 384.712464 -407.820368)
			(xy 384.734244 -407.846027) (xy 384.772193 -407.901612) (xy 384.803226 -407.961335) (xy 384.826899 -408.024339)
			(xy 384.842873 -408.08972) (xy 384.850918 -408.156542) (xy 384.850918 -408.223846) (xy 384.842875 -408.290668)
			(xy 384.826903 -408.35605) (xy 384.803231 -408.419054) (xy 384.772199 -408.478778) (xy 384.734251 -408.534364)
			(xy 384.712464 -408.560016) (xy 384.706674 -408.567165) (xy 384.700156 -408.584353) (xy 384.699764 -408.593544)
			(xy 384.699764 -409.086812) (xy 384.700176 -409.095999) (xy 384.706689 -409.113183) (xy 384.712464 -409.12034)
			(xy 384.734216 -409.146021) (xy 384.772166 -409.201604) (xy 384.8032 -409.261323) (xy 384.826875 -409.324324)
			(xy 384.84285 -409.389703) (xy 384.850897 -409.456522) (xy 384.850901 -409.523824) (xy 384.84286 -409.590644)
			(xy 384.826891 -409.656024) (xy 384.803222 -409.719027) (xy 384.772194 -409.77875) (xy 384.734249 -409.834336)
			(xy 384.712464 -409.859988) (xy 384.706643 -409.867116) (xy 384.700144 -409.88432) (xy 384.699764 -409.893516)
			(xy 384.699764 -410.051504) (xy 384.699386 -410.061631) (xy 384.69163 -410.080342) (xy 384.677301 -410.094657)
			(xy 384.658584 -410.102396) (xy 384.648456 -410.102812) (xy 383.931922 -410.102812) (xy 383.921803 -410.102257)
			(xy 383.903092 -410.094546) (xy 383.888737 -410.080281) (xy 383.880908 -410.06162) (xy 383.88036 -410.051504)
			(xy 383.88036 -409.893516) (xy 383.879929 -409.884331) (xy 383.873428 -409.867147) (xy 383.86766 -409.859988)
			(xy 383.845836 -409.834365) (xy 383.807887 -409.778775) (xy 383.776854 -409.719048) (xy 383.753182 -409.656039)
			(xy 383.737211 -409.590653) (xy 383.72917 -409.523827) (xy 382.600523 -409.523827) (xy 382.572059 -409.578599)
			(xy 382.534106 -409.634184) (xy 382.512316 -409.659836) (xy 382.506523 -409.666984) (xy 382.500006 -409.684172)
			(xy 382.499616 -409.693364) (xy 382.499616 -410.186632) (xy 382.500007 -410.195821) (xy 382.506534 -410.213006)
			(xy 382.512316 -410.22016) (xy 382.534089 -410.245824) (xy 382.572042 -410.301408) (xy 382.603078 -410.36113)
			(xy 382.626754 -410.424133) (xy 382.642729 -410.489514) (xy 382.650775 -410.556336) (xy 382.650777 -410.62364)
			(xy 382.65077 -410.623701) (xy 385.928816 -410.623701) (xy 385.928817 -410.556275) (xy 385.936895 -410.489336)
			(xy 385.952932 -410.423846) (xy 385.976699 -410.360748) (xy 386.007852 -410.300952) (xy 386.045943 -410.245317)
			(xy 386.067808 -410.219652) (xy 386.073608 -410.21251) (xy 386.080121 -410.195317) (xy 386.080508 -410.186124)
			(xy 386.080508 -409.693872) (xy 386.08011 -409.684684) (xy 386.073588 -409.667499) (xy 386.067808 -409.660344)
			(xy 386.045956 -409.634669) (xy 386.007866 -409.579036) (xy 385.976714 -409.519241) (xy 385.952949 -409.456146)
			(xy 385.936913 -409.390658) (xy 385.928836 -409.32372) (xy 385.928834 -409.256298) (xy 385.936909 -409.18936)
			(xy 385.952944 -409.123871) (xy 385.976707 -409.060775) (xy 386.007857 -409.000979) (xy 386.045944 -408.945345)
			(xy 386.067808 -408.91968) (xy 386.073596 -408.912529) (xy 386.080116 -408.895343) (xy 386.080508 -408.886152)
			(xy 386.080508 -408.728672) (xy 386.080962 -408.71856) (xy 386.088711 -408.69988) (xy 386.103017 -408.685586)
			(xy 386.121704 -408.677854) (xy 386.131816 -408.677364) (xy 386.848096 -408.677364) (xy 386.8582 -408.677888)
			(xy 386.876871 -408.685617) (xy 386.891165 -408.699902) (xy 386.898906 -408.718568) (xy 386.899404 -408.728672)
			(xy 386.899404 -408.886152) (xy 386.899836 -408.895337) (xy 386.906334 -408.912522) (xy 386.912104 -408.91968)
			(xy 386.93398 -408.945336) (xy 386.972068 -409.000972) (xy 387.003218 -409.060769) (xy 387.026981 -409.123867)
			(xy 387.043016 -409.189357) (xy 387.05109 -409.256297) (xy 387.051089 -409.323721) (xy 387.043012 -409.39066)
			(xy 387.026976 -409.45615) (xy 387.00321 -409.519247) (xy 387.000824 -409.523827) (xy 388.128961 -409.523827)
			(xy 388.128964 -409.456519) (xy 388.137012 -409.389694) (xy 388.152989 -409.324309) (xy 388.176666 -409.261303)
			(xy 388.207704 -409.201579) (xy 388.245658 -409.145992) (xy 388.267448 -409.12034) (xy 388.273259 -409.113205)
			(xy 388.279764 -409.096006) (xy 388.280148 -409.086812) (xy 388.280148 -408.593544) (xy 388.279706 -408.58436)
			(xy 388.273213 -408.567176) (xy 388.267448 -408.560016) (xy 388.245652 -408.534371) (xy 388.207703 -408.478783)
			(xy 388.176669 -408.419059) (xy 388.152997 -408.356054) (xy 388.137024 -408.29067) (xy 388.12898 -408.223847)
			(xy 388.128981 -408.156541) (xy 388.137026 -408.089718) (xy 388.153 -408.024335) (xy 388.176674 -407.96133)
			(xy 388.207709 -407.901606) (xy 388.245659 -407.84602) (xy 388.267448 -407.820368) (xy 388.273247 -407.813224)
			(xy 388.279759 -407.796032) (xy 388.280148 -407.78684) (xy 388.280148 -407.628852) (xy 388.280645 -407.618747)
			(xy 388.288388 -407.600077) (xy 388.302681 -407.585786) (xy 388.321351 -407.578044) (xy 388.331456 -407.577544)
			(xy 389.04799 -407.577544) (xy 389.058117 -407.578035) (xy 389.076838 -407.58576) (xy 389.091195 -407.600045)
			(xy 389.099014 -407.618728) (xy 389.099552 -407.628852) (xy 389.099552 -407.78684) (xy 389.099954 -407.796028)
			(xy 389.106475 -407.813211) (xy 389.112252 -407.820368) (xy 389.134032 -407.846027) (xy 389.171982 -407.901612)
			(xy 389.203016 -407.961335) (xy 389.226689 -408.024338) (xy 389.242663 -408.08972) (xy 389.250708 -408.156542)
			(xy 389.250709 -408.223846) (xy 389.242665 -408.290668) (xy 389.226693 -408.35605) (xy 389.203021 -408.419054)
			(xy 389.171988 -408.478778) (xy 389.134039 -408.534364) (xy 389.112252 -408.560016) (xy 389.10646 -408.567164)
			(xy 389.099944 -408.584353) (xy 389.099552 -408.593544) (xy 389.099552 -409.086812) (xy 389.099967 -409.095998)
			(xy 389.106479 -409.113182) (xy 389.112252 -409.12034) (xy 389.134004 -409.146021) (xy 389.171955 -409.201603)
			(xy 389.20299 -409.261323) (xy 389.226665 -409.324323) (xy 389.242641 -409.389702) (xy 389.250688 -409.456522)
			(xy 389.250692 -409.523824) (xy 389.242651 -409.590644) (xy 389.226681 -409.656025) (xy 389.203012 -409.719028)
			(xy 389.171983 -409.77875) (xy 389.134038 -409.834336) (xy 389.112252 -409.859988) (xy 389.10643 -409.867115)
			(xy 389.099932 -409.88432) (xy 389.099552 -409.893516) (xy 389.099552 -410.051504) (xy 389.099019 -410.061607)
			(xy 389.09129 -410.080275) (xy 389.077008 -410.094568) (xy 389.058346 -410.102311) (xy 389.048244 -410.102812)
			(xy 388.33171 -410.102812) (xy 388.32159 -410.102267) (xy 388.302879 -410.094552) (xy 388.288524 -410.080284)
			(xy 388.280696 -410.061621) (xy 388.280148 -410.051504) (xy 388.280148 -409.893516) (xy 388.27972 -409.884331)
			(xy 388.273217 -409.867147) (xy 388.267448 -409.859988) (xy 388.245624 -409.834365) (xy 388.207676 -409.778775)
			(xy 388.176644 -409.719047) (xy 388.152973 -409.656039) (xy 388.137002 -409.590653) (xy 388.128961 -409.523827)
			(xy 387.000824 -409.523827) (xy 386.972058 -409.579044) (xy 386.933969 -409.634679) (xy 386.912104 -409.660344)
			(xy 386.906307 -409.667489) (xy 386.899792 -409.68468) (xy 386.899404 -409.693872) (xy 386.899404 -410.186124)
			(xy 386.899801 -410.195313) (xy 386.906324 -410.212497) (xy 386.912104 -410.219652) (xy 386.933952 -410.24533)
			(xy 386.972041 -410.300963) (xy 387.003192 -410.360757) (xy 387.026957 -410.423853) (xy 387.042994 -410.48934)
			(xy 387.051071 -410.556277) (xy 387.051072 -410.623641) (xy 390.329135 -410.623641) (xy 390.329137 -410.556335)
			(xy 390.337182 -410.489512) (xy 390.353155 -410.42413) (xy 390.376828 -410.361125) (xy 390.407861 -410.3014)
			(xy 390.445809 -410.245813) (xy 390.467596 -410.22016) (xy 390.473392 -410.213014) (xy 390.479907 -410.195824)
			(xy 390.480296 -410.186632) (xy 390.480296 -409.693364) (xy 390.479904 -409.684175) (xy 390.473378 -409.666991)
			(xy 390.467596 -409.659836) (xy 390.445821 -409.634174) (xy 390.407875 -409.578588) (xy 390.376844 -409.518865)
			(xy 390.353172 -409.455862) (xy 390.3372 -409.390481) (xy 390.329155 -409.323661) (xy 390.329154 -409.256357)
			(xy 390.337196 -409.189536) (xy 390.353167 -409.124155) (xy 390.376836 -409.061151) (xy 390.407866 -409.001428)
			(xy 390.44581 -408.945841) (xy 390.467596 -408.920188) (xy 390.47338 -408.913034) (xy 390.479902 -408.89585)
			(xy 390.480296 -408.88666) (xy 390.480296 -408.728672) (xy 390.480762 -408.718562) (xy 390.488508 -408.699884)
			(xy 390.502811 -408.68559) (xy 390.521494 -408.677856) (xy 390.531604 -408.677364) (xy 391.248138 -408.677364)
			(xy 391.25827 -408.677796) (xy 391.276997 -408.685541) (xy 391.291352 -408.699844) (xy 391.299166 -408.718542)
			(xy 391.2997 -408.728672) (xy 391.2997 -408.88666) (xy 391.300129 -408.895845) (xy 391.30663 -408.91303)
			(xy 391.3124 -408.920188) (xy 391.334198 -408.945831) (xy 391.372144 -409.00142) (xy 391.403175 -409.061145)
			(xy 391.426845 -409.12415) (xy 391.442816 -409.189533) (xy 391.450859 -409.256356) (xy 391.450858 -409.323662)
			(xy 391.442813 -409.390484) (xy 391.42684 -409.455867) (xy 391.403167 -409.518872) (xy 391.372135 -409.578596)
			(xy 391.334187 -409.634183) (xy 391.3124 -409.659836) (xy 391.306606 -409.666983) (xy 391.30009 -409.684172)
			(xy 391.2997 -409.693364) (xy 391.2997 -410.186632) (xy 391.300095 -410.195821) (xy 391.306619 -410.213005)
			(xy 391.3124 -410.22016) (xy 391.334171 -410.245826) (xy 391.372118 -410.301411) (xy 391.403149 -410.361133)
			(xy 391.426821 -410.424136) (xy 391.442794 -410.489516) (xy 391.450839 -410.556336) (xy 391.450841 -410.623639)
			(xy 391.442799 -410.69046) (xy 391.426828 -410.755841) (xy 391.403159 -410.818845) (xy 391.37213 -410.878568)
			(xy 391.334186 -410.934155) (xy 391.3124 -410.959808) (xy 391.306618 -410.966963) (xy 391.300094 -410.984146)
			(xy 391.2997 -410.993336) (xy 391.2997 -411.151324) (xy 391.299235 -411.161434) (xy 391.291489 -411.180113)
			(xy 391.277186 -411.194407) (xy 391.258503 -411.202141) (xy 391.248392 -411.202632) (xy 390.531858 -411.202632)
			(xy 390.521725 -411.202207) (xy 390.502998 -411.19446) (xy 390.488642 -411.180155) (xy 390.480829 -411.161455)
			(xy 390.480296 -411.151324) (xy 390.480296 -410.993336) (xy 390.479869 -410.984151) (xy 390.473367 -410.966966)
			(xy 390.467596 -410.959808) (xy 390.445794 -410.934168) (xy 390.407848 -410.878579) (xy 390.376818 -410.818853)
			(xy 390.353148 -410.755847) (xy 390.337178 -410.690464) (xy 390.329135 -410.623641) (xy 387.051072 -410.623641)
			(xy 387.051072 -410.623699) (xy 387.042998 -410.690636) (xy 387.026964 -410.756124) (xy 387.003202 -410.819221)
			(xy 386.972053 -410.879016) (xy 386.933967 -410.934651) (xy 386.912104 -410.960316) (xy 386.906319 -410.967469)
			(xy 386.899797 -410.984654) (xy 386.899404 -410.993844) (xy 386.899404 -411.151324) (xy 386.898935 -411.161434)
			(xy 386.89119 -411.180112) (xy 386.876888 -411.194406) (xy 386.858206 -411.20214) (xy 386.848096 -411.202632)
			(xy 386.131816 -411.202632) (xy 386.121712 -411.202103) (xy 386.10304 -411.194376) (xy 386.088746 -411.180093)
			(xy 386.081005 -411.161427) (xy 386.080508 -411.151324) (xy 386.080508 -410.993844) (xy 386.080075 -410.984659)
			(xy 386.073577 -410.967475) (xy 386.067808 -410.960316) (xy 386.045928 -410.934664) (xy 386.007839 -410.879028)
			(xy 385.976689 -410.81923) (xy 385.952925 -410.756131) (xy 385.936891 -410.69064) (xy 385.928816 -410.623701)
			(xy 382.65077 -410.623701) (xy 382.642733 -410.690463) (xy 382.626761 -410.755844) (xy 382.603088 -410.818848)
			(xy 382.572054 -410.878571) (xy 382.534104 -410.934156) (xy 382.512316 -410.959808) (xy 382.506535 -410.966965)
			(xy 382.500011 -410.984146) (xy 382.499616 -410.993336) (xy 382.499616 -411.151324) (xy 382.499135 -411.161432)
			(xy 382.491392 -411.180108) (xy 382.477095 -411.194401) (xy 382.458416 -411.202138) (xy 382.448308 -411.202632)
			(xy 381.731774 -411.202632) (xy 381.721642 -411.202194) (xy 381.702915 -411.194453) (xy 381.688559 -411.180151)
			(xy 381.680745 -411.161454) (xy 381.680212 -411.151324) (xy 381.680212 -410.993336) (xy 381.679782 -410.984151)
			(xy 381.673282 -410.966967) (xy 381.667512 -410.959808) (xy 381.645709 -410.934168) (xy 381.607763 -410.87858)
			(xy 381.576732 -410.818854) (xy 381.553061 -410.755848) (xy 381.53709 -410.690464) (xy 381.529047 -410.623641)
			(xy 378.250984 -410.623641) (xy 378.250984 -410.623699) (xy 378.24291 -410.690636) (xy 378.226877 -410.756124)
			(xy 378.203116 -410.81922) (xy 378.171968 -410.879016) (xy 378.133882 -410.93465) (xy 378.11202 -410.960316)
			(xy 378.106236 -410.967471) (xy 378.099713 -410.984654) (xy 378.09932 -410.993844) (xy 378.09932 -411.151324)
			(xy 378.098835 -411.161432) (xy 378.091093 -411.180107) (xy 378.076797 -411.1944) (xy 378.05812 -411.202138)
			(xy 378.048012 -411.202632) (xy 377.331732 -411.202632) (xy 377.321615 -411.202159) (xy 377.302919 -411.194427)
			(xy 377.288604 -411.180128) (xy 377.280852 -411.16144) (xy 377.280424 -411.151324) (xy 377.280424 -410.993844)
			(xy 377.279987 -410.98466) (xy 377.273491 -410.967475) (xy 377.267724 -410.960316) (xy 377.245843 -410.934664)
			(xy 377.207754 -410.879028) (xy 377.176602 -410.81923) (xy 377.152838 -410.756132) (xy 377.136803 -410.690641)
			(xy 377.128728 -410.623701) (xy 347.450924 -410.623701) (xy 347.442889 -410.690461) (xy 347.426919 -410.755842)
			(xy 347.403249 -410.818845) (xy 347.372219 -410.878569) (xy 347.334274 -410.934156) (xy 347.312488 -410.959808)
			(xy 347.306704 -410.966962) (xy 347.300182 -410.984146) (xy 347.299788 -410.993336) (xy 347.299788 -411.151324)
			(xy 347.299398 -411.161481) (xy 347.291592 -411.180236) (xy 347.277186 -411.194559) (xy 347.258386 -411.202256)
			(xy 347.248226 -411.202632) (xy 346.531946 -411.202632) (xy 346.521819 -411.202135) (xy 346.503093 -411.194417)
			(xy 346.488735 -411.180133) (xy 346.480919 -411.161449) (xy 346.480384 -411.151324) (xy 346.480384 -410.993336)
			(xy 346.47996 -410.98415) (xy 346.473456 -410.966965) (xy 346.467684 -410.959808) (xy 346.445879 -410.934169)
			(xy 346.407928 -410.878582) (xy 346.376893 -410.818857) (xy 346.353219 -410.755851) (xy 346.337246 -410.690466)
			(xy 346.329202 -410.623642) (xy 343.051163 -410.623642) (xy 343.051163 -410.623699) (xy 343.043089 -410.690637)
			(xy 343.027055 -410.756125) (xy 343.003292 -410.819221) (xy 342.972143 -410.879017) (xy 342.934055 -410.934651)
			(xy 342.912192 -410.960316) (xy 342.906405 -410.967468) (xy 342.899885 -410.984653) (xy 342.899492 -410.993844)
			(xy 342.899492 -411.151324) (xy 342.899034 -411.161435) (xy 342.891287 -411.180116) (xy 342.876982 -411.19441)
			(xy 342.858296 -411.202142) (xy 342.848184 -411.202632) (xy 342.131904 -411.202632) (xy 342.121799 -411.202112)
			(xy 342.103128 -411.194382) (xy 342.088834 -411.180096) (xy 342.081093 -411.161428) (xy 342.080596 -411.151324)
			(xy 342.080596 -410.993844) (xy 342.080166 -410.984659) (xy 342.073666 -410.967474) (xy 342.067896 -410.960316)
			(xy 342.046016 -410.934664) (xy 342.007928 -410.879027) (xy 341.976779 -410.819229) (xy 341.953016 -410.756131)
			(xy 341.936981 -410.69064) (xy 341.928907 -410.6237) (xy 338.650837 -410.6237) (xy 338.642802 -410.69046)
			(xy 338.626832 -410.755841) (xy 338.603163 -410.818845) (xy 338.572134 -410.878568) (xy 338.534189 -410.934155)
			(xy 338.512404 -410.959808) (xy 338.506622 -410.966964) (xy 338.500098 -410.984146) (xy 338.499704 -410.993336)
			(xy 338.499704 -411.151324) (xy 338.499298 -411.161479) (xy 338.491495 -411.180231) (xy 338.477094 -411.194554)
			(xy 338.458299 -411.202253) (xy 338.448142 -411.202632) (xy 337.731862 -411.202632) (xy 337.721729 -411.202204)
			(xy 337.703002 -411.194458) (xy 337.688646 -411.180154) (xy 337.680833 -411.161455) (xy 337.6803 -411.151324)
			(xy 337.6803 -410.993336) (xy 337.679873 -410.984151) (xy 337.673371 -410.966966) (xy 337.6676 -410.959808)
			(xy 337.645798 -410.934168) (xy 337.607852 -410.878579) (xy 337.576822 -410.818853) (xy 337.553151 -410.755847)
			(xy 337.537181 -410.690464) (xy 337.529138 -410.623641) (xy 334.251075 -410.623641) (xy 334.251075 -410.623699)
			(xy 334.243001 -410.690636) (xy 334.226967 -410.756124) (xy 334.203205 -410.81922) (xy 334.172057 -410.879016)
			(xy 334.133971 -410.934651) (xy 334.112108 -410.960316) (xy 334.106323 -410.96747) (xy 334.099801 -410.984654)
			(xy 334.099408 -410.993844) (xy 334.099408 -411.151324) (xy 334.098935 -411.161433) (xy 334.091191 -411.180111)
			(xy 334.07689 -411.194404) (xy 334.05821 -411.20214) (xy 334.0481 -411.202632) (xy 333.33182 -411.202632)
			(xy 333.321716 -411.202099) (xy 333.303045 -411.194374) (xy 333.28875 -411.180092) (xy 333.281009 -411.161427)
			(xy 333.280512 -411.151324) (xy 333.280512 -410.993844) (xy 333.280078 -410.984659) (xy 333.273581 -410.967475)
			(xy 333.267812 -410.960316) (xy 333.245932 -410.934664) (xy 333.207843 -410.879028) (xy 333.176692 -410.81923)
			(xy 333.152928 -410.756131) (xy 333.136894 -410.69064) (xy 333.128819 -410.623701) (xy 326.525636 -410.623701)
			(xy 326.525636 -417.379404) (xy 326.525636 -417.533836) (xy 401.074128 -417.533836) (xy 401.074128 -417.366196)
			(xy 401.074128 -394.27912) (xy 414.451292 -394.27912) (xy 414.525968 -394.353542) (xy 414.525968 -397.823826)
			(xy 418.92899 -397.823826) (xy 418.928993 -397.756517) (xy 418.937042 -397.689691) (xy 418.95302 -397.624306)
			(xy 418.9767 -397.5613) (xy 419.00774 -397.501575) (xy 419.045697 -397.44599) (xy 419.067488 -397.420338)
			(xy 419.073292 -397.413198) (xy 419.079803 -397.396004) (xy 419.080188 -397.38681) (xy 419.080188 -396.893542)
			(xy 419.07976 -396.884357) (xy 419.073259 -396.867172) (xy 419.067488 -396.860014) (xy 419.045689 -396.834371)
			(xy 419.007737 -396.778784) (xy 418.976702 -396.71906) (xy 418.953027 -396.656054) (xy 418.937054 -396.59067)
			(xy 418.92901 -396.523846) (xy 418.92901 -396.456539) (xy 418.937056 -396.389715) (xy 418.953032 -396.324332)
			(xy 418.976708 -396.261327) (xy 419.007745 -396.201603) (xy 419.045698 -396.146018) (xy 419.067488 -396.120366)
			(xy 419.07328 -396.113218) (xy 419.079798 -396.09603) (xy 419.080188 -396.086838) (xy 419.080188 -395.92885)
			(xy 419.080606 -395.918675) (xy 419.088384 -395.899872) (xy 419.102772 -395.885484) (xy 419.121575 -395.877706)
			(xy 419.13175 -395.877288) (xy 419.84803 -395.877288) (xy 419.85821 -395.87764) (xy 419.877015 -395.885445)
			(xy 419.8914 -395.899852) (xy 419.899175 -395.91867) (xy 419.899592 -395.92885) (xy 419.899592 -396.086838)
			(xy 419.899986 -396.096027) (xy 419.906511 -396.113211) (xy 419.912292 -396.120366) (xy 419.934069 -396.146027)
			(xy 419.972016 -396.201613) (xy 420.003048 -396.261335) (xy 420.02672 -396.324339) (xy 420.042693 -396.389719)
			(xy 420.050737 -396.456541) (xy 420.050738 -396.523844) (xy 420.042695 -396.590666) (xy 420.026725 -396.656047)
			(xy 420.003054 -396.719051) (xy 419.972024 -396.778774) (xy 419.934078 -396.834361) (xy 419.912292 -396.860014)
			(xy 419.906506 -396.867167) (xy 419.899985 -396.884351) (xy 419.899592 -396.893542) (xy 419.899592 -397.38681)
			(xy 419.899999 -397.395998) (xy 419.906515 -397.413182) (xy 419.912292 -397.420338) (xy 419.934041 -397.446021)
			(xy 419.971989 -397.501604) (xy 420.00041 -397.556296) (xy 421.128654 -397.556296) (xy 421.13673 -397.489357)
			(xy 421.152765 -397.423869) (xy 421.17653 -397.360772) (xy 421.207681 -397.300976) (xy 421.245771 -397.245343)
			(xy 421.267636 -397.219678) (xy 421.273429 -397.21253) (xy 421.279945 -397.195342) (xy 421.280336 -397.18615)
			(xy 421.280336 -397.028924) (xy 421.280736 -397.018799) (xy 421.288483 -397.000089) (xy 421.302805 -396.985772)
			(xy 421.321518 -396.978032) (xy 421.331644 -396.977616) (xy 422.047924 -396.977616) (xy 422.058036 -396.978066)
			(xy 422.076718 -396.985814) (xy 422.091013 -397.000122) (xy 422.098744 -397.018811) (xy 422.099232 -397.028924)
			(xy 422.099232 -397.18615) (xy 422.099681 -397.195333) (xy 422.106169 -397.212517) (xy 422.111932 -397.219678)
			(xy 422.133805 -397.245336) (xy 422.171891 -397.300972) (xy 422.203039 -397.36077) (xy 422.226802 -397.423867)
			(xy 422.242835 -397.489357) (xy 422.25091 -397.556296) (xy 422.250909 -397.623719) (xy 422.242833 -397.690658)
			(xy 422.226797 -397.756147) (xy 422.203033 -397.819244) (xy 422.200615 -397.823885) (xy 423.328782 -397.823885)
			(xy 423.328786 -397.756458) (xy 423.336865 -397.689518) (xy 423.352904 -397.624027) (xy 423.376672 -397.560928)
			(xy 423.407826 -397.501131) (xy 423.445918 -397.445496) (xy 423.467784 -397.41983) (xy 423.473591 -397.412692)
			(xy 423.4801 -397.395496) (xy 423.480484 -397.386302) (xy 423.480484 -396.89405) (xy 423.480054 -396.884865)
			(xy 423.473554 -396.86768) (xy 423.467784 -396.860522) (xy 423.445911 -396.834865) (xy 423.407823 -396.779229)
			(xy 423.376674 -396.719431) (xy 423.352911 -396.656333) (xy 423.336877 -396.590843) (xy 423.328802 -396.523905)
			(xy 423.328803 -396.45648) (xy 423.33688 -396.389542) (xy 423.352916 -396.324052) (xy 423.37668 -396.260955)
			(xy 423.407831 -396.201159) (xy 423.44592 -396.145524) (xy 423.467784 -396.119858) (xy 423.473579 -396.112712)
			(xy 423.480095 -396.095522) (xy 423.480484 -396.08633) (xy 423.480484 -395.92885) (xy 423.480969 -395.918721)
			(xy 423.488688 -395.899993) (xy 423.502976 -395.885633) (xy 423.521666 -395.87782) (xy 423.531792 -395.877288)
			(xy 424.248072 -395.877288) (xy 424.258223 -395.877744) (xy 424.276972 -395.885528) (xy 424.291296 -395.899914)
			(xy 424.298999 -395.918697) (xy 424.29938 -395.92885) (xy 424.29938 -396.08633) (xy 424.29978 -396.095518)
			(xy 424.306301 -396.112702) (xy 424.31208 -396.119858) (xy 424.333935 -396.145531) (xy 424.372025 -396.201164)
			(xy 424.403177 -396.260959) (xy 424.426943 -396.324055) (xy 424.44298 -396.389543) (xy 424.451057 -396.456481)
			(xy 424.451058 -396.523904) (xy 424.442983 -396.590842) (xy 424.426948 -396.656331) (xy 424.403184 -396.719427)
			(xy 424.372033 -396.779223) (xy 424.333944 -396.834857) (xy 424.31208 -396.860522) (xy 424.306289 -396.867671)
			(xy 424.299772 -396.884859) (xy 424.29938 -396.89405) (xy 424.29938 -397.386302) (xy 424.299793 -397.395489)
			(xy 424.306305 -397.412673) (xy 424.31208 -397.41983) (xy 424.333907 -397.445526) (xy 424.371998 -397.501155)
			(xy 424.40076 -397.556356) (xy 425.528974 -397.556356) (xy 425.537017 -397.489534) (xy 425.552988 -397.424152)
			(xy 425.576659 -397.361148) (xy 425.607691 -397.301425) (xy 425.645637 -397.245838) (xy 425.667424 -397.220186)
			(xy 425.673212 -397.213035) (xy 425.679731 -397.195849) (xy 425.680124 -397.186658) (xy 425.680124 -397.028924)
			(xy 425.680542 -397.018768) (xy 425.688334 -397.000012) (xy 425.702732 -396.985687) (xy 425.721528 -396.97799)
			(xy 425.731686 -396.977616) (xy 426.447966 -396.977616) (xy 426.458088 -396.978154) (xy 426.476803 -396.985866)
			(xy 426.49116 -397.000137) (xy 426.498984 -397.018806) (xy 426.499528 -397.028924) (xy 426.499528 -397.186658)
			(xy 426.499952 -397.195844) (xy 426.506456 -397.213029) (xy 426.512228 -397.220186) (xy 426.534026 -397.24583)
			(xy 426.571977 -397.301417) (xy 426.603012 -397.361141) (xy 426.626685 -397.424147) (xy 426.642659 -397.48953)
			(xy 426.650703 -397.556354) (xy 426.650702 -397.623661) (xy 426.642656 -397.690485) (xy 426.626681 -397.755868)
			(xy 426.603006 -397.818873) (xy 426.600432 -397.823826) (xy 427.729077 -397.823826) (xy 427.729081 -397.756517)
			(xy 427.737129 -397.689691) (xy 427.753107 -397.624307) (xy 427.776786 -397.5613) (xy 427.807825 -397.501576)
			(xy 427.845781 -397.44599) (xy 427.867572 -397.420338) (xy 427.873386 -397.413206) (xy 427.879888 -397.396005)
			(xy 427.880272 -397.38681) (xy 427.880272 -396.893542) (xy 427.879848 -396.884356) (xy 427.873344 -396.867171)
			(xy 427.867572 -396.860014) (xy 427.845774 -396.83437) (xy 427.807823 -396.778783) (xy 427.776788 -396.719059)
			(xy 427.753115 -396.656053) (xy 427.737141 -396.59067) (xy 427.729097 -396.523846) (xy 427.729098 -396.456539)
			(xy 427.737144 -396.389715) (xy 427.753119 -396.324332) (xy 427.776794 -396.261327) (xy 427.807831 -396.201604)
			(xy 427.845783 -396.146018) (xy 427.867572 -396.120366) (xy 427.873374 -396.113225) (xy 427.879883 -396.096031)
			(xy 427.880272 -396.086838) (xy 427.880272 -395.92885) (xy 427.880706 -395.918677) (xy 427.88848 -395.899877)
			(xy 427.902864 -395.885489) (xy 427.921662 -395.877709) (xy 427.931834 -395.877288) (xy 428.648114 -395.877288)
			(xy 428.658293 -395.877654) (xy 428.677097 -395.885453) (xy 428.691483 -395.899857) (xy 428.699259 -395.918671)
			(xy 428.699676 -395.92885) (xy 428.699676 -396.086838) (xy 428.700073 -396.096026) (xy 428.706596 -396.11321)
			(xy 428.712376 -396.120366) (xy 428.734154 -396.146026) (xy 428.772102 -396.201612) (xy 428.803135 -396.261335)
			(xy 428.826807 -396.324338) (xy 428.84278 -396.389719) (xy 428.850825 -396.45654) (xy 428.850826 -396.523844)
			(xy 428.842783 -396.590666) (xy 428.826812 -396.656048) (xy 428.803141 -396.719052) (xy 428.772109 -396.778775)
			(xy 428.734163 -396.834362) (xy 428.712376 -396.860014) (xy 428.706588 -396.867165) (xy 428.700069 -396.884351)
			(xy 428.699676 -396.893542) (xy 428.699676 -397.38681) (xy 428.700087 -397.395997) (xy 428.7066 -397.413181)
			(xy 428.712376 -397.420338) (xy 428.734126 -397.446021) (xy 428.772075 -397.501604) (xy 428.800497 -397.556296)
			(xy 429.928742 -397.556296) (xy 429.936817 -397.489358) (xy 429.952852 -397.423869) (xy 429.976616 -397.360773)
			(xy 430.007767 -397.300977) (xy 430.045856 -397.245343) (xy 430.06772 -397.219678) (xy 430.073511 -397.212529)
			(xy 430.080028 -397.195341) (xy 430.08042 -397.18615) (xy 430.08042 -397.028924) (xy 430.080836 -397.018801)
			(xy 430.08858 -397.000094) (xy 430.102897 -396.985778) (xy 430.121605 -396.978035) (xy 430.131728 -396.977616)
			(xy 430.848008 -396.977616) (xy 430.858133 -396.97801) (xy 430.87684 -396.985764) (xy 430.891154 -397.000087)
			(xy 430.898896 -397.018799) (xy 430.899316 -397.028924) (xy 430.899316 -397.18615) (xy 430.899746 -397.195335)
			(xy 430.906246 -397.21252) (xy 430.912016 -397.219678) (xy 430.933889 -397.245335) (xy 430.971977 -397.300971)
			(xy 431.003126 -397.360769) (xy 431.026889 -397.423867) (xy 431.042923 -397.489357) (xy 431.050998 -397.556295)
			(xy 431.050997 -397.62372) (xy 431.04292 -397.690658) (xy 431.026884 -397.756148) (xy 431.00312 -397.819245)
			(xy 431.000734 -397.823826) (xy 432.128868 -397.823826) (xy 432.128872 -397.756517) (xy 432.13692 -397.689692)
			(xy 432.152898 -397.624307) (xy 432.176576 -397.561301) (xy 432.207614 -397.501576) (xy 432.245569 -397.44599)
			(xy 432.26736 -397.420338) (xy 432.273173 -397.413205) (xy 432.279676 -397.396005) (xy 432.28006 -397.38681)
			(xy 432.28006 -396.893542) (xy 432.279616 -396.884359) (xy 432.273125 -396.867175) (xy 432.26736 -396.860014)
			(xy 432.245562 -396.83437) (xy 432.207612 -396.778783) (xy 432.176578 -396.719058) (xy 432.152905 -396.656053)
			(xy 432.136932 -396.590669) (xy 432.128888 -396.523846) (xy 432.128889 -396.456539) (xy 432.136935 -396.389716)
			(xy 432.152909 -396.324333) (xy 432.176584 -396.261328) (xy 432.20762 -396.201604) (xy 432.245571 -396.146018)
			(xy 432.26736 -396.120366) (xy 432.273161 -396.113224) (xy 432.279671 -396.096031) (xy 432.28006 -396.086838)
			(xy 432.28006 -395.92885) (xy 432.280505 -395.918679) (xy 432.288278 -395.899881) (xy 432.302658 -395.885494)
			(xy 432.321451 -395.877711) (xy 432.331622 -395.877288) (xy 433.047902 -395.877288) (xy 433.05808 -395.877663)
			(xy 433.076884 -395.885458) (xy 433.091271 -395.899859) (xy 433.099047 -395.918672) (xy 433.099464 -395.92885)
			(xy 433.099464 -396.086838) (xy 433.099864 -396.096026) (xy 433.106386 -396.11321) (xy 433.112164 -396.120366)
			(xy 433.133942 -396.146026) (xy 433.171891 -396.201612) (xy 433.202924 -396.261334) (xy 433.226598 -396.324337)
			(xy 433.242571 -396.389719) (xy 433.250616 -396.45654) (xy 433.250617 -396.523845) (xy 433.242574 -396.590666)
			(xy 433.226602 -396.656048) (xy 433.202931 -396.719052) (xy 433.171899 -396.778776) (xy 433.133951 -396.834362)
			(xy 433.112164 -396.860014) (xy 433.106374 -396.867164) (xy 433.099856 -396.884351) (xy 433.099464 -396.893542)
			(xy 433.099464 -397.38681) (xy 433.099877 -397.395997) (xy 433.10639 -397.413181) (xy 433.112164 -397.420338)
			(xy 433.133914 -397.446021) (xy 433.171864 -397.501603) (xy 433.200318 -397.556356) (xy 434.329062 -397.556356)
			(xy 434.337105 -397.489534) (xy 434.353075 -397.424153) (xy 434.376746 -397.361149) (xy 434.407776 -397.301426)
			(xy 434.445722 -397.245839) (xy 434.467508 -397.220186) (xy 434.473294 -397.213033) (xy 434.479815 -397.195849)
			(xy 434.480208 -397.186658) (xy 434.480208 -397.028924) (xy 434.480641 -397.01877) (xy 434.48843 -397.000017)
			(xy 434.502824 -396.985692) (xy 434.521614 -396.977993) (xy 434.53177 -396.977616) (xy 435.24805 -396.977616)
			(xy 435.258171 -396.978167) (xy 435.276886 -396.985874) (xy 435.291243 -397.00014) (xy 435.299068 -397.018807)
			(xy 435.299612 -397.028924) (xy 435.299612 -397.186658) (xy 435.30004 -397.195843) (xy 435.306541 -397.213028)
			(xy 435.312312 -397.220186) (xy 435.334111 -397.245829) (xy 435.372063 -397.301416) (xy 435.403098 -397.36114)
			(xy 435.426773 -397.424146) (xy 435.442746 -397.48953) (xy 435.45079 -397.556354) (xy 435.45079 -397.623661)
			(xy 435.442744 -397.690485) (xy 435.426768 -397.755868) (xy 435.403092 -397.818873) (xy 435.372055 -397.878597)
			(xy 435.334102 -397.934182) (xy 435.312312 -397.959834) (xy 435.30652 -397.966982) (xy 435.300002 -397.98417)
			(xy 435.299612 -397.993362) (xy 435.299612 -398.100042) (xy 459.541382 -398.100042) (xy 459.545364 -397.972056)
			(xy 459.557296 -397.844565) (xy 459.57713 -397.718062) (xy 459.604791 -397.593037) (xy 459.640171 -397.469974)
			(xy 459.683133 -397.349348) (xy 459.733511 -397.231627) (xy 459.791111 -397.117265) (xy 459.855709 -397.006706)
			(xy 459.927056 -396.900376) (xy 460.004875 -396.798688) (xy 460.088865 -396.702034) (xy 460.178702 -396.610789)
			(xy 460.274038 -396.525306) (xy 460.374503 -396.445915) (xy 460.479711 -396.372923) (xy 460.589252 -396.306614)
			(xy 460.702704 -396.247243) (xy 460.819628 -396.195039) (xy 460.939571 -396.150206) (xy 461.062069 -396.112917)
			(xy 461.186649 -396.083315) (xy 461.312827 -396.061516) (xy 461.440117 -396.047603) (xy 461.568026 -396.041631)
			(xy 461.696059 -396.043622) (xy 461.82372 -396.05357) (xy 461.950516 -396.071434) (xy 462.075955 -396.097147)
			(xy 462.199554 -396.130609) (xy 462.320833 -396.17169) (xy 462.439324 -396.220232) (xy 462.554568 -396.276046)
			(xy 462.666118 -396.338917) (xy 462.773545 -396.408601) (xy 462.876431 -396.484829) (xy 462.974379 -396.567306)
			(xy 463.06701 -396.655713) (xy 463.153966 -396.749708) (xy 463.23491 -396.848927) (xy 463.309529 -396.952986)
			(xy 463.377534 -397.061483) (xy 463.438662 -397.173998) (xy 463.492677 -397.290096) (xy 463.53937 -397.409327)
			(xy 463.57856 -397.531231) (xy 463.610096 -397.655335) (xy 463.633855 -397.781159) (xy 463.649745 -397.908218)
			(xy 463.657706 -398.036018) (xy 463.658204 -398.100042) (xy 463.657706 -398.164066) (xy 463.649745 -398.291866)
			(xy 463.633855 -398.418925) (xy 463.610096 -398.544749) (xy 463.57856 -398.668853) (xy 463.53937 -398.790757)
			(xy 463.492677 -398.909988) (xy 463.438662 -399.026086) (xy 463.377534 -399.138601) (xy 463.309529 -399.247098)
			(xy 463.23491 -399.351157) (xy 463.153966 -399.450376) (xy 463.06701 -399.544371) (xy 462.974379 -399.632778)
			(xy 462.876431 -399.715255) (xy 462.773545 -399.791483) (xy 462.666118 -399.861167) (xy 462.554568 -399.924038)
			(xy 462.439324 -399.979852) (xy 462.320833 -400.028394) (xy 462.199554 -400.069475) (xy 462.075955 -400.102937)
			(xy 461.950516 -400.12865) (xy 461.82372 -400.146514) (xy 461.696059 -400.156462) (xy 461.568026 -400.158453)
			(xy 461.440117 -400.152481) (xy 461.312827 -400.138568) (xy 461.186649 -400.116769) (xy 461.062069 -400.087167)
			(xy 460.939571 -400.049878) (xy 460.819628 -400.005045) (xy 460.702704 -399.952841) (xy 460.589252 -399.89347)
			(xy 460.479711 -399.827161) (xy 460.374503 -399.754169) (xy 460.274038 -399.674778) (xy 460.178702 -399.589295)
			(xy 460.088865 -399.49805) (xy 460.004875 -399.401396) (xy 459.927056 -399.299708) (xy 459.855709 -399.193378)
			(xy 459.791111 -399.082819) (xy 459.733511 -398.968457) (xy 459.683133 -398.850736) (xy 459.640171 -398.73011)
			(xy 459.604791 -398.607047) (xy 459.57713 -398.482022) (xy 459.557296 -398.355519) (xy 459.545364 -398.228028)
			(xy 459.541382 -398.100042) (xy 435.299612 -398.100042) (xy 435.299612 -398.486884) (xy 435.300027 -398.496071)
			(xy 435.306537 -398.513255) (xy 435.312312 -398.520412) (xy 435.334137 -398.546034) (xy 435.372087 -398.601624)
			(xy 435.403122 -398.661351) (xy 435.426795 -398.72436) (xy 435.442767 -398.789746) (xy 435.450809 -398.856573)
			(xy 435.450805 -398.923881) (xy 435.442757 -398.990707) (xy 435.426779 -399.056092) (xy 435.4031 -399.119098)
			(xy 435.37206 -399.178823) (xy 435.334103 -399.234408) (xy 435.312312 -399.26006) (xy 435.306509 -399.267201)
			(xy 435.299998 -399.284395) (xy 435.299612 -399.293588) (xy 435.299612 -399.451576) (xy 435.299159 -399.461727)
			(xy 435.291374 -399.480477) (xy 435.276987 -399.494801) (xy 435.258203 -399.502503) (xy 435.24805 -399.502884)
			(xy 434.53177 -399.502884) (xy 434.521644 -399.502399) (xy 434.502927 -399.494666) (xy 434.488573 -399.480379)
			(xy 434.48075 -399.461699) (xy 434.480208 -399.451576) (xy 434.480208 -399.293588) (xy 434.479802 -399.2844)
			(xy 434.473285 -399.267216) (xy 434.467508 -399.26006) (xy 434.445757 -399.234378) (xy 434.407809 -399.178795)
			(xy 434.376776 -399.119076) (xy 434.353102 -399.056075) (xy 434.337128 -398.990697) (xy 434.329081 -398.923878)
			(xy 434.329078 -398.856576) (xy 434.337118 -398.789757) (xy 434.353086 -398.724377) (xy 434.376753 -398.661374)
			(xy 434.407781 -398.601651) (xy 434.445723 -398.546064) (xy 434.467508 -398.520412) (xy 434.473325 -398.513282)
			(xy 434.479827 -398.49608) (xy 434.480208 -398.486884) (xy 434.480208 -397.993362) (xy 434.479814 -397.984173)
			(xy 434.473289 -397.966989) (xy 434.467508 -397.959834) (xy 434.445731 -397.934173) (xy 434.407784 -397.878587)
			(xy 434.376752 -397.818865) (xy 434.35308 -397.755861) (xy 434.337107 -397.690481) (xy 434.329063 -397.623659)
			(xy 434.329062 -397.556356) (xy 433.200318 -397.556356) (xy 433.202899 -397.561322) (xy 433.226573 -397.624323)
			(xy 433.242549 -397.689701) (xy 433.250596 -397.75652) (xy 433.250599 -397.823822) (xy 433.242559 -397.890642)
			(xy 433.22659 -397.956022) (xy 433.202922 -398.019025) (xy 433.171893 -398.078748) (xy 433.133949 -398.134334)
			(xy 433.112164 -398.159986) (xy 433.106344 -398.167114) (xy 433.099844 -398.184318) (xy 433.099464 -398.193514)
			(xy 433.099464 -398.351502) (xy 433.098968 -398.36166) (xy 433.091194 -398.380428) (xy 433.076828 -398.394794)
			(xy 433.05806 -398.402568) (xy 433.047902 -398.403064) (xy 432.331622 -398.403064) (xy 432.321452 -398.402618)
			(xy 432.302658 -398.394841) (xy 432.288273 -398.380462) (xy 432.280487 -398.361672) (xy 432.28006 -398.351502)
			(xy 432.28006 -398.193514) (xy 432.27963 -398.184329) (xy 432.273129 -398.167145) (xy 432.26736 -398.159986)
			(xy 432.245534 -398.134365) (xy 432.207585 -398.078775) (xy 432.176552 -398.019047) (xy 432.152881 -397.956038)
			(xy 432.13691 -397.890652) (xy 432.128868 -397.823826) (xy 431.000734 -397.823826) (xy 430.971969 -397.879041)
			(xy 430.93388 -397.934676) (xy 430.912016 -397.960342) (xy 430.906221 -397.967488) (xy 430.899705 -397.984678)
			(xy 430.899316 -397.99387) (xy 430.899316 -398.486376) (xy 430.899734 -398.495562) (xy 430.906242 -398.512747)
			(xy 430.912016 -398.519904) (xy 430.933915 -398.54554) (xy 430.972001 -398.601179) (xy 431.00315 -398.66098)
			(xy 431.026911 -398.72408) (xy 431.042944 -398.789573) (xy 431.051016 -398.856514) (xy 431.051013 -398.92394)
			(xy 431.042934 -398.990881) (xy 431.026895 -399.056371) (xy 431.003128 -399.11947) (xy 430.971974 -399.179267)
			(xy 430.933882 -399.234902) (xy 430.912016 -399.260568) (xy 430.90621 -399.267707) (xy 430.8997 -399.284902)
			(xy 430.899316 -399.294096) (xy 430.899316 -399.451576) (xy 430.898865 -399.461695) (xy 430.891128 -399.480395)
			(xy 430.876822 -399.49471) (xy 430.858127 -399.502459) (xy 430.848008 -399.502884) (xy 430.131728 -399.502884)
			(xy 430.121605 -399.502461) (xy 430.102899 -399.494719) (xy 430.088583 -399.480404) (xy 430.08084 -399.461699)
			(xy 430.08042 -399.451576) (xy 430.08042 -399.294096) (xy 430.080008 -399.284909) (xy 430.073495 -399.267725)
			(xy 430.06772 -399.260568) (xy 430.045891 -399.234874) (xy 430.0078 -399.179244) (xy 429.976646 -399.119452)
			(xy 429.952879 -399.056359) (xy 429.936841 -398.990873) (xy 429.928761 -398.923938) (xy 429.928758 -398.856516)
			(xy 429.936831 -398.78958) (xy 429.952863 -398.724093) (xy 429.976624 -398.660997) (xy 430.007772 -398.601202)
			(xy 430.045857 -398.545569) (xy 430.06772 -398.519904) (xy 430.0735 -398.512747) (xy 430.080024 -398.495565)
			(xy 430.08042 -398.486376) (xy 430.08042 -397.99387) (xy 430.08002 -397.984682) (xy 430.073499 -397.967498)
			(xy 430.06772 -397.960342) (xy 430.045865 -397.934669) (xy 430.007775 -397.879036) (xy 429.976623 -397.819241)
			(xy 429.952857 -397.756145) (xy 429.93682 -397.690657) (xy 429.928743 -397.623719) (xy 429.928742 -397.556296)
			(xy 428.800497 -397.556296) (xy 428.803109 -397.561323) (xy 428.826783 -397.624323) (xy 428.842758 -397.689702)
			(xy 428.850805 -397.756521) (xy 428.850808 -397.823822) (xy 428.842768 -397.890642) (xy 428.8268 -397.956022)
			(xy 428.803132 -398.019025) (xy 428.772104 -398.078747) (xy 428.734161 -398.134333) (xy 428.712376 -398.159986)
			(xy 428.706558 -398.167116) (xy 428.700057 -398.184318) (xy 428.699676 -398.193514) (xy 428.699676 -398.351502)
			(xy 428.699169 -398.361658) (xy 428.691396 -398.380425) (xy 428.677035 -398.394789) (xy 428.65827 -398.402566)
			(xy 428.648114 -398.403064) (xy 427.931834 -398.403064) (xy 427.921665 -398.402608) (xy 427.902871 -398.394835)
			(xy 427.888485 -398.380459) (xy 427.880699 -398.361671) (xy 427.880272 -398.351502) (xy 427.880272 -398.193514)
			(xy 427.879861 -398.184327) (xy 427.873349 -398.167142) (xy 427.867572 -398.159986) (xy 427.845746 -398.134365)
			(xy 427.807796 -398.078775) (xy 427.776762 -398.019047) (xy 427.75309 -397.956039) (xy 427.737119 -397.890652)
			(xy 427.729077 -397.823826) (xy 426.600432 -397.823826) (xy 426.571969 -397.878596) (xy 426.534017 -397.934182)
			(xy 426.512228 -397.959834) (xy 426.506426 -397.966975) (xy 426.499917 -397.984169) (xy 426.499528 -397.993362)
			(xy 426.499528 -398.486884) (xy 426.499939 -398.496071) (xy 426.506451 -398.513256) (xy 426.512228 -398.520412)
			(xy 426.534052 -398.546034) (xy 426.572002 -398.601624) (xy 426.603036 -398.661352) (xy 426.626708 -398.72436)
			(xy 426.64268 -398.789746) (xy 426.650721 -398.856573) (xy 426.650718 -398.923881) (xy 426.64267 -398.990707)
			(xy 426.626692 -399.056092) (xy 426.603014 -399.119098) (xy 426.571974 -399.178822) (xy 426.534019 -399.234408)
			(xy 426.512228 -399.26006) (xy 426.506415 -399.267193) (xy 426.499912 -399.284393) (xy 426.499528 -399.293588)
			(xy 426.499528 -399.451576) (xy 426.499059 -399.461725) (xy 426.491277 -399.480472) (xy 426.476895 -399.494795)
			(xy 426.458117 -399.502501) (xy 426.447966 -399.502884) (xy 425.731686 -399.502884) (xy 425.721561 -399.502385)
			(xy 425.702845 -399.494657) (xy 425.68849 -399.480375) (xy 425.680667 -399.461698) (xy 425.680124 -399.451576)
			(xy 425.680124 -399.293588) (xy 425.679714 -399.284401) (xy 425.6732 -399.267217) (xy 425.667424 -399.26006)
			(xy 425.645672 -399.234378) (xy 425.607723 -399.178796) (xy 425.576689 -399.119076) (xy 425.553015 -399.056076)
			(xy 425.53704 -398.990697) (xy 425.528994 -398.923878) (xy 425.52899 -398.856576) (xy 425.537031 -398.789756)
			(xy 425.552999 -398.724376) (xy 425.576667 -398.661373) (xy 425.607696 -398.601651) (xy 425.645639 -398.546065)
			(xy 425.667424 -398.520412) (xy 425.673243 -398.513283) (xy 425.679744 -398.49608) (xy 425.680124 -398.486884)
			(xy 425.680124 -397.993362) (xy 425.679727 -397.984174) (xy 425.673204 -397.96699) (xy 425.667424 -397.959834)
			(xy 425.645646 -397.934174) (xy 425.607698 -397.878588) (xy 425.576665 -397.818865) (xy 425.552993 -397.755862)
			(xy 425.53702 -397.690481) (xy 425.528975 -397.62366) (xy 425.528974 -397.556356) (xy 424.40076 -397.556356)
			(xy 424.403152 -397.560947) (xy 424.426919 -397.62404) (xy 424.442958 -397.689526) (xy 424.451037 -397.756461)
			(xy 424.451041 -397.823882) (xy 424.442968 -397.890818) (xy 424.426936 -397.956305) (xy 424.403175 -398.019401)
			(xy 424.372028 -398.079196) (xy 424.333942 -398.134829) (xy 424.31208 -398.160494) (xy 424.306301 -398.167652)
			(xy 424.299777 -398.184833) (xy 424.29938 -398.194022) (xy 424.29938 -398.351502) (xy 424.298876 -398.361626)
			(xy 424.291151 -398.380344) (xy 424.27687 -398.394699) (xy 424.258194 -398.402522) (xy 424.248072 -398.403064)
			(xy 423.531792 -398.403064) (xy 423.521633 -398.402684) (xy 423.502873 -398.394879) (xy 423.488549 -398.380469)
			(xy 423.480856 -398.361663) (xy 423.480484 -398.351502) (xy 423.480484 -398.194022) (xy 423.480067 -398.184835)
			(xy 423.473558 -398.167651) (xy 423.467784 -398.160494) (xy 423.445883 -398.134859) (xy 423.407797 -398.07922)
			(xy 423.376649 -398.019419) (xy 423.352887 -397.956319) (xy 423.336855 -397.890826) (xy 423.328782 -397.823885)
			(xy 422.200615 -397.823885) (xy 422.171883 -397.879041) (xy 422.133795 -397.934676) (xy 422.111932 -397.960342)
			(xy 422.106127 -397.967481) (xy 422.099619 -397.984676) (xy 422.099232 -397.99387) (xy 422.099232 -398.486376)
			(xy 422.099669 -398.49556) (xy 422.106166 -398.512744) (xy 422.111932 -398.519904) (xy 422.13383 -398.545541)
			(xy 422.171916 -398.60118) (xy 422.203063 -398.66098) (xy 422.226824 -398.724081) (xy 422.242856 -398.789573)
			(xy 422.250928 -398.856514) (xy 422.250925 -398.92394) (xy 422.242846 -398.99088) (xy 422.226808 -399.056371)
			(xy 422.203041 -399.119469) (xy 422.171888 -399.179266) (xy 422.133797 -399.234902) (xy 422.111932 -399.260568)
			(xy 422.106116 -399.267699) (xy 422.099615 -399.284901) (xy 422.099232 -399.294096) (xy 422.099232 -399.451576)
			(xy 422.098696 -399.461679) (xy 422.090972 -399.480351) (xy 422.076691 -399.494645) (xy 422.058027 -399.502387)
			(xy 422.047924 -399.502884) (xy 421.331644 -399.502884) (xy 421.321522 -399.502447) (xy 421.302817 -399.494711)
			(xy 421.2885 -399.4804) (xy 421.280756 -399.461697) (xy 421.280336 -399.451576) (xy 421.280336 -399.294096)
			(xy 421.27992 -399.28491) (xy 421.27341 -399.267726) (xy 421.267636 -399.260568) (xy 421.245806 -399.234874)
			(xy 421.207714 -399.179245) (xy 421.17656 -399.119453) (xy 421.152792 -399.056359) (xy 421.136753 -398.990873)
			(xy 421.128674 -398.923938) (xy 421.12867 -398.856516) (xy 421.136743 -398.78958) (xy 421.152776 -398.724092)
			(xy 421.176538 -398.660997) (xy 421.207686 -398.601202) (xy 421.245773 -398.545569) (xy 421.267636 -398.519904)
			(xy 421.273418 -398.512749) (xy 421.27994 -398.495566) (xy 421.280336 -398.486376) (xy 421.280336 -397.99387)
			(xy 421.279932 -397.984682) (xy 421.273413 -397.967498) (xy 421.267636 -397.960342) (xy 421.245781 -397.934669)
			(xy 421.207689 -397.879037) (xy 421.176536 -397.819242) (xy 421.15277 -397.756146) (xy 421.136732 -397.690657)
			(xy 421.128655 -397.623719) (xy 421.128654 -397.556296) (xy 420.00041 -397.556296) (xy 420.003023 -397.561324)
			(xy 420.026696 -397.624324) (xy 420.042671 -397.689702) (xy 420.050718 -397.756521) (xy 420.050721 -397.823822)
			(xy 420.042681 -397.890642) (xy 420.026713 -397.956021) (xy 420.003046 -398.019024) (xy 419.972019 -398.078747)
			(xy 419.934077 -398.134334) (xy 419.912292 -398.159986) (xy 419.906475 -398.167117) (xy 419.899973 -398.184318)
			(xy 419.899592 -398.193514) (xy 419.899592 -398.351502) (xy 419.899069 -398.361656) (xy 419.891299 -398.38042)
			(xy 419.876943 -398.394784) (xy 419.858184 -398.402563) (xy 419.84803 -398.403064) (xy 419.13175 -398.403064)
			(xy 419.121582 -398.402595) (xy 419.102789 -398.394827) (xy 419.088402 -398.380455) (xy 419.080615 -398.36167)
			(xy 419.080188 -398.351502) (xy 419.080188 -398.193514) (xy 419.079774 -398.184327) (xy 419.073263 -398.167143)
			(xy 419.067488 -398.159986) (xy 419.045661 -398.134365) (xy 419.007711 -398.078775) (xy 418.976676 -398.019048)
			(xy 418.953004 -397.956039) (xy 418.937032 -397.890653) (xy 418.92899 -397.823826) (xy 414.525968 -397.823826)
			(xy 414.525968 -401.723737) (xy 418.929001 -401.723737) (xy 418.929003 -401.65643) (xy 418.93705 -401.589605)
			(xy 418.953027 -401.524221) (xy 418.976704 -401.461215) (xy 419.007743 -401.401491) (xy 419.045697 -401.345906)
			(xy 419.067488 -401.320254) (xy 419.073285 -401.313109) (xy 419.0798 -401.295918) (xy 419.080188 -401.286726)
			(xy 419.080188 -400.793458) (xy 419.079801 -400.784268) (xy 419.073272 -400.767084) (xy 419.067488 -400.75993)
			(xy 419.045705 -400.734274) (xy 419.007752 -400.678689) (xy 418.976716 -400.618966) (xy 418.953041 -400.555962)
			(xy 418.937066 -400.49058) (xy 418.929021 -400.423757) (xy 418.92902 -400.356452) (xy 418.937065 -400.289629)
			(xy 418.953038 -400.224246) (xy 418.976713 -400.161242) (xy 419.007748 -400.101519) (xy 419.045699 -400.045933)
			(xy 419.067488 -400.020282) (xy 419.073273 -400.013129) (xy 419.079795 -399.995944) (xy 419.080188 -399.986754)
			(xy 419.080188 -399.828766) (xy 419.080537 -399.818586) (xy 419.088343 -399.799781) (xy 419.102752 -399.785395)
			(xy 419.121569 -399.777621) (xy 419.13175 -399.777204) (xy 419.84803 -399.777204) (xy 419.858186 -399.777708)
			(xy 419.876949 -399.785486) (xy 419.891312 -399.799848) (xy 419.899091 -399.818611) (xy 419.899592 -399.828766)
			(xy 419.899592 -399.986754) (xy 419.900026 -399.995939) (xy 419.906523 -400.013123) (xy 419.912292 -400.020282)
			(xy 419.934085 -400.04593) (xy 419.972031 -400.101518) (xy 420.003063 -400.161242) (xy 420.026734 -400.224247)
			(xy 420.042705 -400.289629) (xy 420.050749 -400.356452) (xy 420.050748 -400.423757) (xy 420.042704 -400.490579)
			(xy 420.026731 -400.555962) (xy 420.003059 -400.618966) (xy 419.972027 -400.67869) (xy 419.934079 -400.734277)
			(xy 419.912292 -400.75993) (xy 419.906499 -400.767078) (xy 419.899983 -400.784266) (xy 419.899592 -400.793458)
			(xy 419.899592 -401.286726) (xy 419.899991 -401.295914) (xy 419.906513 -401.313099) (xy 419.912292 -401.320254)
			(xy 419.934057 -401.345924) (xy 419.972005 -401.401509) (xy 420.003037 -401.46123) (xy 420.02671 -401.524232)
			(xy 420.042683 -401.589612) (xy 420.050729 -401.656432) (xy 420.050731 -401.723735) (xy 420.042689 -401.790555)
			(xy 420.02672 -401.855936) (xy 420.003051 -401.918939) (xy 419.972022 -401.978663) (xy 419.934077 -402.034249)
			(xy 419.912292 -402.059902) (xy 419.906511 -402.067058) (xy 419.899987 -402.08424) (xy 419.899592 -402.09343)
			(xy 419.899592 -402.251418) (xy 419.899082 -402.261573) (xy 419.891308 -402.280337) (xy 419.876947 -402.294701)
			(xy 419.858185 -402.30248) (xy 419.84803 -402.30298) (xy 419.13175 -402.30298) (xy 419.121584 -402.302496)
			(xy 419.102794 -402.29473) (xy 419.088408 -402.280363) (xy 419.080618 -402.261584) (xy 419.080188 -402.251418)
			(xy 419.080188 -402.09343) (xy 419.079766 -402.084244) (xy 419.073261 -402.067059) (xy 419.067488 -402.059902)
			(xy 419.045677 -402.034268) (xy 419.007726 -401.97868) (xy 418.976691 -401.918955) (xy 418.953017 -401.855948)
			(xy 418.937044 -401.790563) (xy 418.929001 -401.723737) (xy 414.525968 -401.723737) (xy 414.525968 -402.823878)
			(xy 421.128614 -402.823878) (xy 421.128619 -402.75645) (xy 421.1367 -402.689508) (xy 421.152742 -402.624016)
			(xy 421.176513 -402.560916) (xy 421.207671 -402.501119) (xy 421.245768 -402.445485) (xy 421.267636 -402.41982)
			(xy 421.273454 -402.41269) (xy 421.279955 -402.395488) (xy 421.280336 -402.386292) (xy 421.280336 -401.89404)
			(xy 421.279898 -401.884856) (xy 421.273403 -401.867672) (xy 421.267636 -401.860512) (xy 421.245751 -401.834864)
			(xy 421.207661 -401.779227) (xy 421.176509 -401.719429) (xy 421.152744 -401.65633) (xy 421.136709 -401.590839)
			(xy 421.128634 -401.523898) (xy 421.128636 -401.456472) (xy 421.136714 -401.389532) (xy 421.152753 -401.324041)
			(xy 421.176521 -401.260943) (xy 421.207676 -401.201147) (xy 421.24577 -401.145513) (xy 421.267636 -401.119848)
			(xy 421.273442 -401.112709) (xy 421.27995 -401.095514) (xy 421.280336 -401.08632) (xy 421.280336 -400.92884)
			(xy 421.28075 -400.918716) (xy 421.288491 -400.900006) (xy 421.302809 -400.885689) (xy 421.32152 -400.877949)
			(xy 421.331644 -400.877532) (xy 422.047924 -400.877532) (xy 422.058052 -400.877897) (xy 422.076762 -400.885659)
			(xy 422.091077 -400.899991) (xy 422.098816 -400.918711) (xy 422.099232 -400.92884) (xy 422.099232 -401.08632)
			(xy 422.099648 -401.095506) (xy 422.106159 -401.11269) (xy 422.111932 -401.119848) (xy 422.133775 -401.14553)
			(xy 422.171862 -401.201163) (xy 422.203012 -401.260957) (xy 422.226776 -401.324052) (xy 422.242812 -401.389538)
			(xy 422.250889 -401.456474) (xy 422.250891 -401.523896) (xy 422.242817 -401.590832) (xy 422.226785 -401.65632)
			(xy 422.203024 -401.719415) (xy 422.200742 -401.723796) (xy 423.328794 -401.723796) (xy 423.328796 -401.656371)
			(xy 423.336873 -401.589431) (xy 423.352911 -401.523941) (xy 423.376677 -401.460844) (xy 423.407829 -401.401047)
			(xy 423.445919 -401.345412) (xy 423.467784 -401.319746) (xy 423.473584 -401.312603) (xy 423.480097 -401.295411)
			(xy 423.480484 -401.286218) (xy 423.480484 -400.793966) (xy 423.480094 -400.784777) (xy 423.473566 -400.767592)
			(xy 423.467784 -400.760438) (xy 423.445926 -400.734768) (xy 423.407839 -400.679133) (xy 423.376689 -400.619338)
			(xy 423.352925 -400.556242) (xy 423.336889 -400.490753) (xy 423.328813 -400.423816) (xy 423.328813 -400.356393)
			(xy 423.336888 -400.289455) (xy 423.352922 -400.223967) (xy 423.376685 -400.16087) (xy 423.407834 -400.101074)
			(xy 423.445921 -400.045439) (xy 423.467784 -400.019774) (xy 423.473572 -400.012623) (xy 423.480092 -399.995437)
			(xy 423.480484 -399.986246) (xy 423.480484 -399.828766) (xy 423.4809 -399.818632) (xy 423.488647 -399.799901)
			(xy 423.502955 -399.785545) (xy 423.521659 -399.777735) (xy 423.531792 -399.777204) (xy 424.248072 -399.777204)
			(xy 424.258225 -399.777644) (xy 424.276977 -399.785431) (xy 424.291302 -399.799823) (xy 424.299002 -399.818611)
			(xy 424.29938 -399.828766) (xy 424.29938 -399.986246) (xy 424.299821 -399.99543) (xy 424.306314 -400.012614)
			(xy 424.31208 -400.019774) (xy 424.333951 -400.045434) (xy 424.37204 -400.101069) (xy 424.403192 -400.160866)
			(xy 424.426957 -400.223963) (xy 424.442992 -400.289453) (xy 424.451068 -400.356392) (xy 424.451068 -400.423817)
			(xy 424.442991 -400.490756) (xy 424.426954 -400.556245) (xy 424.403188 -400.619343) (xy 424.372036 -400.679139)
			(xy 424.333945 -400.734773) (xy 424.31208 -400.760438) (xy 424.306282 -400.767582) (xy 424.299769 -400.784774)
			(xy 424.29938 -400.793966) (xy 424.29938 -401.286218) (xy 424.299786 -401.295406) (xy 424.306303 -401.31259)
			(xy 424.31208 -401.319746) (xy 424.333923 -401.345429) (xy 424.372014 -401.40106) (xy 424.403167 -401.460854)
			(xy 424.426933 -401.523949) (xy 424.44297 -401.589436) (xy 424.451048 -401.656372) (xy 424.45105 -401.723795)
			(xy 424.442976 -401.790732) (xy 424.426943 -401.85622) (xy 424.40318 -401.919316) (xy 424.372031 -401.979111)
			(xy 424.333943 -402.034745) (xy 424.31208 -402.06041) (xy 424.306294 -402.067563) (xy 424.299774 -402.084748)
			(xy 424.29938 -402.093938) (xy 424.29938 -402.251418) (xy 424.298889 -402.261543) (xy 424.291159 -402.280261)
			(xy 424.276874 -402.294616) (xy 424.258195 -402.302438) (xy 424.248072 -402.30298) (xy 423.531792 -402.30298)
			(xy 423.521635 -402.302584) (xy 423.502879 -402.294782) (xy 423.488555 -402.280378) (xy 423.480859 -402.261577)
			(xy 423.480484 -402.251418) (xy 423.480484 -402.093938) (xy 423.480059 -402.084752) (xy 423.473556 -402.067568)
			(xy 423.467784 -402.06041) (xy 423.445899 -402.034762) (xy 423.407812 -401.979125) (xy 423.376663 -401.919326)
			(xy 423.352901 -401.856227) (xy 423.336867 -401.790736) (xy 423.328794 -401.723796) (xy 422.200742 -401.723796)
			(xy 422.171878 -401.779211) (xy 422.133794 -401.834846) (xy 422.111932 -401.860512) (xy 422.10614 -401.86766)
			(xy 422.099624 -401.884849) (xy 422.099232 -401.89404) (xy 422.099232 -402.386292) (xy 422.099661 -402.395477)
			(xy 422.106163 -402.412661) (xy 422.111932 -402.41982) (xy 422.133748 -402.445525) (xy 422.171836 -402.501154)
			(xy 422.202987 -402.560945) (xy 422.226752 -402.624037) (xy 422.24279 -402.689521) (xy 422.250869 -402.756454)
			(xy 422.250874 -402.823818) (xy 425.528934 -402.823818) (xy 425.528938 -402.75651) (xy 425.536987 -402.689684)
			(xy 425.552965 -402.624299) (xy 425.576642 -402.561293) (xy 425.60768 -402.501568) (xy 425.645634 -402.44598)
			(xy 425.667424 -402.420328) (xy 425.673236 -402.413194) (xy 425.679741 -402.395995) (xy 425.680124 -402.3868)
			(xy 425.680124 -401.893532) (xy 425.679693 -401.884347) (xy 425.673193 -401.867163) (xy 425.667424 -401.860004)
			(xy 425.645617 -401.834368) (xy 425.60767 -401.778779) (xy 425.576638 -401.719053) (xy 425.552967 -401.656046)
			(xy 425.536996 -401.590662) (xy 425.528954 -401.523838) (xy 425.528956 -401.456532) (xy 425.537001 -401.389708)
			(xy 425.552976 -401.324325) (xy 425.57665 -401.26132) (xy 425.607685 -401.201595) (xy 425.645635 -401.146008)
			(xy 425.667424 -401.120356) (xy 425.673225 -401.113214) (xy 425.679736 -401.096021) (xy 425.680124 -401.086828)
			(xy 425.680124 -400.92884) (xy 425.680555 -400.918686) (xy 425.688342 -400.899929) (xy 425.702736 -400.885604)
			(xy 425.72153 -400.877907) (xy 425.731686 -400.877532) (xy 426.447966 -400.877532) (xy 426.45809 -400.878054)
			(xy 426.476808 -400.88577) (xy 426.491165 -400.900045) (xy 426.498987 -400.918719) (xy 426.499528 -400.92884)
			(xy 426.499528 -401.086828) (xy 426.499918 -401.096017) (xy 426.506445 -401.113202) (xy 426.512228 -401.120356)
			(xy 426.533997 -401.146024) (xy 426.571949 -401.201607) (xy 426.602985 -401.261328) (xy 426.62666 -401.324331)
			(xy 426.642635 -401.389712) (xy 426.650681 -401.456533) (xy 426.650683 -401.523837) (xy 426.642641 -401.590659)
			(xy 426.626669 -401.65604) (xy 426.602997 -401.719044) (xy 426.600558 -401.723737) (xy 427.729089 -401.723737)
			(xy 427.729091 -401.65643) (xy 427.737138 -401.589605) (xy 427.753114 -401.524221) (xy 427.776791 -401.461216)
			(xy 427.807828 -401.401492) (xy 427.845782 -401.345906) (xy 427.867572 -401.320254) (xy 427.873379 -401.313117)
			(xy 427.879886 -401.29592) (xy 427.880272 -401.286726) (xy 427.880272 -400.793458) (xy 427.879888 -400.784268)
			(xy 427.873357 -400.767084) (xy 427.867572 -400.75993) (xy 427.845789 -400.734273) (xy 427.807838 -400.678688)
			(xy 427.776803 -400.618966) (xy 427.753128 -400.555962) (xy 427.737154 -400.49058) (xy 427.729109 -400.423757)
			(xy 427.729108 -400.356452) (xy 427.737152 -400.289629) (xy 427.753126 -400.224247) (xy 427.776799 -400.161243)
			(xy 427.807833 -400.101519) (xy 427.845784 -400.045934) (xy 427.867572 -400.020282) (xy 427.873367 -400.013136)
			(xy 427.879881 -399.995946) (xy 427.880272 -399.986754) (xy 427.880272 -399.828766) (xy 427.880706 -399.818602)
			(xy 427.888498 -399.799825) (xy 427.902883 -399.78546) (xy 427.921669 -399.777693) (xy 427.931834 -399.777204)
			(xy 428.648114 -399.777204) (xy 428.658268 -399.777721) (xy 428.677031 -399.785494) (xy 428.691395 -399.799852)
			(xy 428.699175 -399.818612) (xy 428.699676 -399.828766) (xy 428.699676 -399.986754) (xy 428.700114 -399.995938)
			(xy 428.706609 -400.013122) (xy 428.712376 -400.020282) (xy 428.734169 -400.045929) (xy 428.772117 -400.101517)
			(xy 428.803149 -400.161241) (xy 428.826821 -400.224246) (xy 428.842793 -400.289629) (xy 428.850836 -400.356452)
			(xy 428.850836 -400.423757) (xy 428.842791 -400.49058) (xy 428.826818 -400.555962) (xy 428.803145 -400.618967)
			(xy 428.772112 -400.678691) (xy 428.734164 -400.734278) (xy 428.712376 -400.75993) (xy 428.706581 -400.767076)
			(xy 428.700066 -400.784266) (xy 428.699676 -400.793458) (xy 428.699676 -401.286726) (xy 428.700079 -401.295914)
			(xy 428.706598 -401.313098) (xy 428.712376 -401.320254) (xy 428.734142 -401.345924) (xy 428.77209 -401.401508)
			(xy 428.803124 -401.46123) (xy 428.826797 -401.524232) (xy 428.842771 -401.589612) (xy 428.850817 -401.656432)
			(xy 428.850819 -401.723735) (xy 428.842777 -401.790556) (xy 428.826807 -401.855937) (xy 428.803137 -401.91894)
			(xy 428.772107 -401.978663) (xy 428.734162 -402.03425) (xy 428.712376 -402.059902) (xy 428.706593 -402.067057)
			(xy 428.700071 -402.08424) (xy 428.699676 -402.09343) (xy 428.699676 -402.251418) (xy 428.699182 -402.261575)
			(xy 428.691404 -402.280342) (xy 428.677039 -402.294706) (xy 428.658271 -402.302483) (xy 428.648114 -402.30298)
			(xy 427.931834 -402.30298) (xy 427.921667 -402.302509) (xy 427.902876 -402.294738) (xy 427.888491 -402.280367)
			(xy 427.880702 -402.261585) (xy 427.880272 -402.251418) (xy 427.880272 -402.09343) (xy 427.879854 -402.084244)
			(xy 427.873347 -402.067059) (xy 427.867572 -402.059902) (xy 427.845762 -402.034268) (xy 427.807811 -401.97868)
			(xy 427.776777 -401.918954) (xy 427.753104 -401.855947) (xy 427.737132 -401.790562) (xy 427.729089 -401.723737)
			(xy 426.600558 -401.723737) (xy 426.571964 -401.778767) (xy 426.534015 -401.834352) (xy 426.512228 -401.860004)
			(xy 426.506438 -401.867154) (xy 426.499922 -401.884341) (xy 426.499528 -401.893532) (xy 426.499528 -402.3868)
			(xy 426.499932 -402.395988) (xy 426.506449 -402.413173) (xy 426.512228 -402.420328) (xy 426.53397 -402.446019)
			(xy 426.571922 -402.501599) (xy 426.602959 -402.561317) (xy 426.626636 -402.624316) (xy 426.642613 -402.689694)
			(xy 426.650662 -402.756513) (xy 426.650666 -402.823815) (xy 426.650658 -402.823878) (xy 429.928702 -402.823878)
			(xy 429.928707 -402.75645) (xy 429.936788 -402.689508) (xy 429.952829 -402.624016) (xy 429.976599 -402.560917)
			(xy 430.007757 -402.50112) (xy 430.045852 -402.445485) (xy 430.06772 -402.41982) (xy 430.073535 -402.412688)
			(xy 430.080038 -402.395487) (xy 430.08042 -402.386292) (xy 430.08042 -401.89404) (xy 430.079986 -401.884855)
			(xy 430.073488 -401.867671) (xy 430.06772 -401.860512) (xy 430.045836 -401.834863) (xy 430.007746 -401.779227)
			(xy 429.976595 -401.719429) (xy 429.952831 -401.656329) (xy 429.936797 -401.590838) (xy 429.928722 -401.523898)
			(xy 429.928724 -401.456472) (xy 429.936802 -401.389532) (xy 429.95284 -401.324042) (xy 429.976608 -401.260944)
			(xy 430.007762 -401.201147) (xy 430.045854 -401.145513) (xy 430.06772 -401.119848) (xy 430.073523 -401.112708)
			(xy 430.080033 -401.095513) (xy 430.08042 -401.08632) (xy 430.08042 -400.92884) (xy 430.080849 -400.918718)
			(xy 430.088588 -400.900011) (xy 430.102901 -400.885695) (xy 430.121606 -400.877952) (xy 430.131728 -400.877532)
			(xy 430.848008 -400.877532) (xy 430.858135 -400.87791) (xy 430.876845 -400.885667) (xy 430.89116 -400.899996)
			(xy 430.898899 -400.918713) (xy 430.899316 -400.92884) (xy 430.899316 -401.08632) (xy 430.899713 -401.095509)
			(xy 430.906236 -401.112693) (xy 430.912016 -401.119848) (xy 430.93386 -401.14553) (xy 430.971948 -401.201162)
			(xy 431.003099 -401.260956) (xy 431.026863 -401.324051) (xy 431.0429 -401.389538) (xy 431.050977 -401.456474)
			(xy 431.050979 -401.523896) (xy 431.042905 -401.590832) (xy 431.026872 -401.65632) (xy 431.003111 -401.719416)
			(xy 431.00086 -401.723737) (xy 432.128879 -401.723737) (xy 432.128881 -401.65643) (xy 432.136928 -401.589605)
			(xy 432.152904 -401.524222) (xy 432.17658 -401.461216) (xy 432.207617 -401.401492) (xy 432.24557 -401.345906)
			(xy 432.26736 -401.320254) (xy 432.273166 -401.313116) (xy 432.279673 -401.29592) (xy 432.28006 -401.286726)
			(xy 432.28006 -400.793458) (xy 432.279657 -400.78427) (xy 432.273137 -400.767087) (xy 432.26736 -400.75993)
			(xy 432.245578 -400.734273) (xy 432.207627 -400.678688) (xy 432.176593 -400.618965) (xy 432.152919 -400.555961)
			(xy 432.136945 -400.490579) (xy 432.1289 -400.423757) (xy 432.128899 -400.356452) (xy 432.136943 -400.28963)
			(xy 432.152916 -400.224247) (xy 432.176589 -400.161243) (xy 432.207623 -400.10152) (xy 432.245572 -400.045934)
			(xy 432.26736 -400.020282) (xy 432.273154 -400.013135) (xy 432.279669 -399.995946) (xy 432.28006 -399.986754)
			(xy 432.28006 -399.828766) (xy 432.280506 -399.818603) (xy 432.288296 -399.799829) (xy 432.302676 -399.785464)
			(xy 432.321459 -399.777695) (xy 432.331622 -399.777204) (xy 433.047902 -399.777204) (xy 433.058056 -399.777731)
			(xy 433.076818 -399.7855) (xy 433.091182 -399.799855) (xy 433.098963 -399.818613) (xy 433.099464 -399.828766)
			(xy 433.099464 -399.986754) (xy 433.099905 -399.995938) (xy 433.106398 -400.013122) (xy 433.112164 -400.020282)
			(xy 433.133958 -400.045929) (xy 433.171906 -400.101516) (xy 433.202939 -400.161241) (xy 433.226611 -400.224246)
			(xy 433.242584 -400.289629) (xy 433.250627 -400.356452) (xy 433.250627 -400.423757) (xy 433.242582 -400.49058)
			(xy 433.226609 -400.555963) (xy 433.202935 -400.618968) (xy 433.171901 -400.678691) (xy 433.133952 -400.734278)
			(xy 433.112164 -400.75993) (xy 433.106368 -400.767075) (xy 433.099854 -400.784266) (xy 433.099464 -400.793458)
			(xy 433.099464 -401.286726) (xy 433.09987 -401.295913) (xy 433.106387 -401.313097) (xy 433.112164 -401.320254)
			(xy 433.13393 -401.345924) (xy 433.171879 -401.401508) (xy 433.202913 -401.461229) (xy 433.226587 -401.524231)
			(xy 433.242561 -401.589611) (xy 433.250607 -401.656432) (xy 433.250609 -401.723735) (xy 433.242567 -401.790556)
			(xy 433.226597 -401.855937) (xy 433.202927 -401.918941) (xy 433.171896 -401.978663) (xy 433.13395 -402.03425)
			(xy 433.112164 -402.059902) (xy 433.106379 -402.067056) (xy 433.099858 -402.08424) (xy 433.099464 -402.09343)
			(xy 433.099464 -402.251418) (xy 433.098982 -402.261577) (xy 433.091202 -402.280346) (xy 433.076833 -402.294711)
			(xy 433.058061 -402.302485) (xy 433.047902 -402.30298) (xy 432.331622 -402.30298) (xy 432.321454 -402.302518)
			(xy 432.302663 -402.294744) (xy 432.288278 -402.28037) (xy 432.28049 -402.261586) (xy 432.28006 -402.251418)
			(xy 432.28006 -402.09343) (xy 432.279622 -402.084246) (xy 432.273126 -402.067062) (xy 432.26736 -402.059902)
			(xy 432.24555 -402.034268) (xy 432.2076 -401.97868) (xy 432.176567 -401.918954) (xy 432.152894 -401.855947)
			(xy 432.136922 -401.790562) (xy 432.128879 -401.723737) (xy 431.00086 -401.723737) (xy 430.971963 -401.779212)
			(xy 430.933878 -401.834847) (xy 430.912016 -401.860512) (xy 430.906234 -401.867667) (xy 430.89971 -401.88485)
			(xy 430.899316 -401.89404) (xy 430.899316 -402.386292) (xy 430.899726 -402.395479) (xy 430.90624 -402.412664)
			(xy 430.912016 -402.41982) (xy 430.933832 -402.445524) (xy 430.971921 -402.501154) (xy 431.003073 -402.560945)
			(xy 431.026839 -402.624036) (xy 431.042878 -402.68952) (xy 431.050957 -402.756454) (xy 431.050962 -402.823818)
			(xy 434.329022 -402.823818) (xy 434.329026 -402.75651) (xy 434.337075 -402.689684) (xy 434.353052 -402.6243)
			(xy 434.376729 -402.561294) (xy 434.407766 -402.501568) (xy 434.445718 -402.445981) (xy 434.467508 -402.420328)
			(xy 434.473319 -402.413193) (xy 434.479825 -402.395995) (xy 434.480208 -402.3868) (xy 434.480208 -401.893532)
			(xy 434.479781 -401.884347) (xy 434.473279 -401.867162) (xy 434.467508 -401.860004) (xy 434.445702 -401.834368)
			(xy 434.407755 -401.778778) (xy 434.376725 -401.719052) (xy 434.353054 -401.656046) (xy 434.337084 -401.590662)
			(xy 434.329042 -401.523838) (xy 434.329043 -401.456532) (xy 434.337089 -401.389709) (xy 434.353063 -401.324326)
			(xy 434.376737 -401.26132) (xy 434.407771 -401.201596) (xy 434.44572 -401.146009) (xy 434.467508 -401.120356)
			(xy 434.473307 -401.113212) (xy 434.47982 -401.096021) (xy 434.480208 -401.086828) (xy 434.480208 -400.92884)
			(xy 434.480655 -400.918688) (xy 434.488438 -400.899934) (xy 434.502828 -400.885609) (xy 434.521616 -400.87791)
			(xy 434.53177 -400.877532) (xy 435.24805 -400.877532) (xy 435.258173 -400.878067) (xy 435.276891 -400.885777)
			(xy 435.291249 -400.900049) (xy 435.299071 -400.918721) (xy 435.299612 -400.92884) (xy 435.299612 -401.086828)
			(xy 435.300006 -401.096017) (xy 435.306531 -401.113201) (xy 435.312312 -401.120356) (xy 435.334082 -401.146024)
			(xy 435.372034 -401.201607) (xy 435.403071 -401.261328) (xy 435.426747 -401.32433) (xy 435.442723 -401.389711)
			(xy 435.450769 -401.456533) (xy 435.450771 -401.523837) (xy 435.442728 -401.590659) (xy 435.426756 -401.656041)
			(xy 435.403083 -401.719045) (xy 435.37205 -401.778767) (xy 435.3341 -401.834353) (xy 435.312312 -401.860004)
			(xy 435.306533 -401.867161) (xy 435.300007 -401.884343) (xy 435.299612 -401.893532) (xy 435.299612 -402.3868)
			(xy 435.30002 -402.395988) (xy 435.306535 -402.413172) (xy 435.312312 -402.420328) (xy 435.334054 -402.446018)
			(xy 435.372008 -402.501598) (xy 435.403046 -402.561316) (xy 435.426723 -402.624316) (xy 435.442701 -402.689694)
			(xy 435.45075 -402.756513) (xy 435.450754 -402.823815) (xy 435.442714 -402.890635) (xy 435.426745 -402.956015)
			(xy 435.403075 -403.019018) (xy 435.372045 -403.07874) (xy 435.334098 -403.134325) (xy 435.312312 -403.159976)
			(xy 435.306502 -403.167112) (xy 435.299995 -403.184309) (xy 435.299612 -403.193504) (xy 435.299612 -403.351492)
			(xy 435.299172 -403.361644) (xy 435.291381 -403.380394) (xy 435.27699 -403.394717) (xy 435.258204 -403.402419)
			(xy 435.24805 -403.4028) (xy 434.53177 -403.4028) (xy 434.521646 -403.402299) (xy 434.502932 -403.394569)
			(xy 434.488578 -403.380288) (xy 434.480753 -403.361613) (xy 434.480208 -403.351492) (xy 434.480208 -403.193504)
			(xy 434.479794 -403.184317) (xy 434.473283 -403.167133) (xy 434.467508 -403.159976) (xy 434.445674 -403.134362)
			(xy 434.407729 -403.07877) (xy 434.376699 -403.01904) (xy 434.353031 -402.956031) (xy 434.337062 -402.890644)
			(xy 434.329022 -402.823818) (xy 431.050962 -402.823818) (xy 431.050962 -402.823874) (xy 431.042891 -402.890808)
			(xy 431.026861 -402.956295) (xy 431.003103 -403.019389) (xy 430.971958 -403.079184) (xy 430.933877 -403.134819)
			(xy 430.912016 -403.160484) (xy 430.906203 -403.167618) (xy 430.899698 -403.184817) (xy 430.899316 -403.194012)
			(xy 430.899316 -403.351492) (xy 430.898809 -403.361598) (xy 430.891077 -403.380273) (xy 430.876787 -403.394568)
			(xy 430.858114 -403.402306) (xy 430.848008 -403.4028) (xy 430.131728 -403.4028) (xy 430.121607 -403.402361)
			(xy 430.102904 -403.394622) (xy 430.088589 -403.380313) (xy 430.080843 -403.361613) (xy 430.08042 -403.351492)
			(xy 430.08042 -403.194012) (xy 430.079999 -403.184826) (xy 430.073492 -403.167642) (xy 430.06772 -403.160484)
			(xy 430.045808 -403.134858) (xy 430.00772 -403.079218) (xy 429.97657 -403.019417) (xy 429.952807 -402.956315)
			(xy 429.936775 -402.890821) (xy 429.928702 -402.823878) (xy 426.650658 -402.823878) (xy 426.642626 -402.890635)
			(xy 426.626657 -402.956015) (xy 426.602989 -403.019017) (xy 426.571959 -403.078739) (xy 426.534014 -403.134324)
			(xy 426.512228 -403.159976) (xy 426.506408 -403.167104) (xy 426.499909 -403.184308) (xy 426.499528 -403.193504)
			(xy 426.499528 -403.351492) (xy 426.499072 -403.361642) (xy 426.491285 -403.380389) (xy 426.476899 -403.394712)
			(xy 426.458118 -403.402417) (xy 426.447966 -403.4028) (xy 425.731686 -403.4028) (xy 425.721563 -403.402286)
			(xy 425.70285 -403.394561) (xy 425.688495 -403.380284) (xy 425.68067 -403.361612) (xy 425.680124 -403.351492)
			(xy 425.680124 -403.193504) (xy 425.679707 -403.184318) (xy 425.673198 -403.167133) (xy 425.667424 -403.159976)
			(xy 425.64559 -403.134362) (xy 425.607643 -403.07877) (xy 425.576613 -403.019041) (xy 425.552943 -402.956032)
			(xy 425.536974 -402.890645) (xy 425.528934 -402.823818) (xy 422.250874 -402.823818) (xy 422.250874 -402.823874)
			(xy 422.242803 -402.890808) (xy 422.226774 -402.956294) (xy 422.203016 -403.019389) (xy 422.171873 -403.079184)
			(xy 422.133792 -403.134818) (xy 422.111932 -403.160484) (xy 422.106109 -403.16761) (xy 422.099612 -403.184816)
			(xy 422.099232 -403.194012) (xy 422.099232 -403.351492) (xy 422.098709 -403.361596) (xy 422.09098 -403.380268)
			(xy 422.076695 -403.394562) (xy 422.058028 -403.402303) (xy 422.047924 -403.4028) (xy 421.331644 -403.4028)
			(xy 421.321524 -403.402348) (xy 421.302822 -403.394614) (xy 421.288506 -403.380308) (xy 421.280759 -403.361611)
			(xy 421.280336 -403.351492) (xy 421.280336 -403.194012) (xy 421.279912 -403.184826) (xy 421.273407 -403.167642)
			(xy 421.267636 -403.160484) (xy 421.245724 -403.134858) (xy 421.207634 -403.079219) (xy 421.176483 -403.019418)
			(xy 421.15272 -402.956315) (xy 421.136687 -402.890821) (xy 421.128614 -402.823878) (xy 414.525968 -402.823878)
			(xy 414.525968 -405.623649) (xy 418.929012 -405.623649) (xy 418.929013 -405.556342) (xy 418.937058 -405.489518)
			(xy 418.953033 -405.424135) (xy 418.976709 -405.36113) (xy 419.007746 -405.301407) (xy 419.045698 -405.245822)
			(xy 419.067488 -405.22017) (xy 419.073278 -405.21302) (xy 419.079797 -405.195833) (xy 419.080188 -405.186642)
			(xy 419.080188 -404.693374) (xy 419.079793 -404.684185) (xy 419.073269 -404.667001) (xy 419.067488 -404.659846)
			(xy 419.04572 -404.634177) (xy 419.007768 -404.578594) (xy 418.976731 -404.518873) (xy 418.953055 -404.455871)
			(xy 418.937079 -404.39049) (xy 418.929032 -404.323669) (xy 418.92903 -404.256364) (xy 418.937073 -404.189542)
			(xy 418.953045 -404.124161) (xy 418.976717 -404.061157) (xy 419.007751 -404.001435) (xy 419.0457 -403.945849)
			(xy 419.067488 -403.920198) (xy 419.073267 -403.91304) (xy 419.079792 -403.895859) (xy 419.080188 -403.88667)
			(xy 419.080188 -403.728682) (xy 419.08055 -403.718503) (xy 419.088351 -403.699698) (xy 419.102756 -403.685313)
			(xy 419.12157 -403.677537) (xy 419.13175 -403.67712) (xy 419.84803 -403.67712) (xy 419.858187 -403.677608)
			(xy 419.876954 -403.685389) (xy 419.891317 -403.699756) (xy 419.899094 -403.718524) (xy 419.899592 -403.728682)
			(xy 419.899592 -403.88667) (xy 419.900018 -403.895855) (xy 419.906521 -403.91304) (xy 419.912292 -403.920198)
			(xy 419.9341 -403.945833) (xy 419.972047 -404.001422) (xy 420.003077 -404.061149) (xy 420.026747 -404.124155)
			(xy 420.042718 -404.189539) (xy 420.05076 -404.256363) (xy 420.050758 -404.32367) (xy 420.042712 -404.390493)
			(xy 420.026738 -404.455876) (xy 420.003064 -404.518882) (xy 419.97203 -404.578606) (xy 419.93408 -404.634193)
			(xy 419.912292 -404.659846) (xy 419.906492 -404.666989) (xy 419.89998 -404.684181) (xy 419.899592 -404.693374)
			(xy 419.899592 -405.186642) (xy 419.899984 -405.195831) (xy 419.90651 -405.213015) (xy 419.912292 -405.22017)
			(xy 419.934073 -405.245827) (xy 419.97202 -405.301414) (xy 420.003052 -405.361137) (xy 420.026723 -405.424141)
			(xy 420.042696 -405.489522) (xy 420.05074 -405.556343) (xy 420.050741 -405.623647) (xy 420.042698 -405.690469)
			(xy 420.026726 -405.755851) (xy 420.003055 -405.818855) (xy 419.972025 -405.878578) (xy 419.934078 -405.934165)
			(xy 419.912292 -405.959818) (xy 419.906504 -405.96697) (xy 419.899985 -405.984155) (xy 419.899592 -405.993346)
			(xy 419.899592 -406.151334) (xy 419.899095 -406.16149) (xy 419.891315 -406.180254) (xy 419.876951 -406.194617)
			(xy 419.858186 -406.202396) (xy 419.84803 -406.202896) (xy 419.13175 -406.202896) (xy 419.121586 -406.202396)
			(xy 419.102799 -406.194634) (xy 419.088413 -406.180272) (xy 419.08062 -406.161497) (xy 419.080188 -406.151334)
			(xy 419.080188 -405.993346) (xy 419.079759 -405.984161) (xy 419.073259 -405.966976) (xy 419.067488 -405.959818)
			(xy 419.045693 -405.934171) (xy 419.007741 -405.878585) (xy 418.976705 -405.818861) (xy 418.953031 -405.755856)
			(xy 418.937057 -405.690473) (xy 418.929012 -405.623649) (xy 414.525968 -405.623649) (xy 414.525968 -406.723789)
			(xy 421.128626 -406.723789) (xy 421.128629 -406.656363) (xy 421.136708 -406.589421) (xy 421.152748 -406.52393)
			(xy 421.176518 -406.460832) (xy 421.207674 -406.401035) (xy 421.245769 -406.345401) (xy 421.267636 -406.319736)
			(xy 421.273447 -406.312601) (xy 421.279952 -406.295403) (xy 421.280336 -406.286208) (xy 421.280336 -405.793956)
			(xy 421.279939 -405.784768) (xy 421.273415 -405.767584) (xy 421.267636 -405.760428) (xy 421.245767 -405.734767)
			(xy 421.207676 -405.679132) (xy 421.176523 -405.619336) (xy 421.152758 -405.556239) (xy 421.136722 -405.490749)
			(xy 421.128645 -405.423809) (xy 421.128646 -405.356385) (xy 421.136723 -405.289445) (xy 421.15276 -405.223956)
			(xy 421.176526 -405.160859) (xy 421.207679 -405.101062) (xy 421.245771 -405.045429) (xy 421.267636 -405.019764)
			(xy 421.273435 -405.012621) (xy 421.279947 -404.995429) (xy 421.280336 -404.986236) (xy 421.280336 -404.828756)
			(xy 421.28075 -404.81864) (xy 421.288509 -404.799954) (xy 421.302828 -404.785659) (xy 421.321527 -404.777933)
			(xy 421.331644 -404.777448) (xy 422.047924 -404.777448) (xy 422.058028 -404.777964) (xy 422.076697 -404.7857)
			(xy 422.090989 -404.799986) (xy 422.098732 -404.818652) (xy 422.099232 -404.828756) (xy 422.099232 -404.986236)
			(xy 422.09964 -404.995423) (xy 422.106157 -405.012607) (xy 422.111932 -405.019764) (xy 422.133791 -405.045433)
			(xy 422.171878 -405.101068) (xy 422.203027 -405.160864) (xy 422.22679 -405.22396) (xy 422.242825 -405.289448)
			(xy 422.2509 -405.356386) (xy 422.250901 -405.423808) (xy 422.242826 -405.490746) (xy 422.226792 -405.556234)
			(xy 422.203029 -405.619331) (xy 422.20075 -405.623707) (xy 423.328805 -405.623707) (xy 423.328805 -405.556284)
			(xy 423.336882 -405.489345) (xy 423.352917 -405.423856) (xy 423.376681 -405.360759) (xy 423.407832 -405.300962)
			(xy 423.44592 -405.245328) (xy 423.467784 -405.219662) (xy 423.473577 -405.212514) (xy 423.480094 -405.195326)
			(xy 423.480484 -405.186134) (xy 423.480484 -404.693882) (xy 423.480086 -404.684693) (xy 423.473564 -404.667509)
			(xy 423.467784 -404.660354) (xy 423.445942 -404.634671) (xy 423.407854 -404.579038) (xy 423.376703 -404.519245)
			(xy 423.352938 -404.45615) (xy 423.336902 -404.390663) (xy 423.328825 -404.323727) (xy 423.328823 -404.256306)
			(xy 423.336896 -404.189369) (xy 423.352929 -404.123882) (xy 423.37669 -404.060786) (xy 423.407837 -404.00099)
			(xy 423.445922 -403.945355) (xy 423.467784 -403.91969) (xy 423.473565 -403.912534) (xy 423.48009 -403.895352)
			(xy 423.480484 -403.886162) (xy 423.480484 -403.728682) (xy 423.480913 -403.718549) (xy 423.488655 -403.699819)
			(xy 423.502959 -403.685461) (xy 423.521661 -403.677651) (xy 423.531792 -403.67712) (xy 424.248072 -403.67712)
			(xy 424.258227 -403.677545) (xy 424.276983 -403.685335) (xy 424.291308 -403.699731) (xy 424.299005 -403.718525)
			(xy 424.29938 -403.728682) (xy 424.29938 -403.886162) (xy 424.299813 -403.895347) (xy 424.306311 -403.912531)
			(xy 424.31208 -403.91969) (xy 424.333966 -403.945337) (xy 424.372056 -404.000974) (xy 424.403207 -404.060772)
			(xy 424.42697 -404.123872) (xy 424.443005 -404.189363) (xy 424.451079 -404.256304) (xy 424.451077 -404.323729)
			(xy 424.442999 -404.39067) (xy 424.426961 -404.45616) (xy 424.403193 -404.519258) (xy 424.372039 -404.579055)
			(xy 424.333946 -404.634689) (xy 424.31208 -404.660354) (xy 424.306276 -404.667494) (xy 424.299766 -404.684688)
			(xy 424.29938 -404.693882) (xy 424.29938 -405.186134) (xy 424.299778 -405.195322) (xy 424.306301 -405.212506)
			(xy 424.31208 -405.219662) (xy 424.333939 -405.245332) (xy 424.372029 -405.300965) (xy 424.403181 -405.360761)
			(xy 424.426946 -405.423857) (xy 424.442983 -405.489346) (xy 424.45106 -405.556284) (xy 424.45106 -405.623707)
			(xy 424.442985 -405.690646) (xy 424.426949 -405.756134) (xy 424.403185 -405.819231) (xy 424.372034 -405.879027)
			(xy 424.333944 -405.934661) (xy 424.31208 -405.960326) (xy 424.306288 -405.967474) (xy 424.299771 -405.984662)
			(xy 424.29938 -405.993854) (xy 424.29938 -406.151334) (xy 424.298902 -406.16146) (xy 424.291167 -406.180179)
			(xy 424.276878 -406.194533) (xy 424.258196 -406.202355) (xy 424.248072 -406.202896) (xy 423.531792 -406.202896)
			(xy 423.521637 -406.202485) (xy 423.502884 -406.194686) (xy 423.48856 -406.180286) (xy 423.480862 -406.161491)
			(xy 423.480484 -406.151334) (xy 423.480484 -405.993854) (xy 423.480051 -405.984669) (xy 423.473553 -405.967484)
			(xy 423.467784 -405.960326) (xy 423.445915 -405.934665) (xy 423.407827 -405.87903) (xy 423.376678 -405.819233)
			(xy 423.352915 -405.756135) (xy 423.33688 -405.690646) (xy 423.328805 -405.623707) (xy 422.20075 -405.623707)
			(xy 422.171881 -405.679127) (xy 422.133795 -405.734762) (xy 422.111932 -405.760428) (xy 422.106133 -405.767571)
			(xy 422.099622 -405.784763) (xy 422.099232 -405.793956) (xy 422.099232 -406.286208) (xy 422.099654 -406.295394)
			(xy 422.106161 -406.312577) (xy 422.111932 -406.319736) (xy 422.133763 -406.345428) (xy 422.171851 -406.401059)
			(xy 422.203001 -406.460852) (xy 422.226766 -406.523945) (xy 422.242803 -406.589431) (xy 422.250881 -406.656366)
			(xy 422.250883 -406.72373) (xy 425.528945 -406.72373) (xy 425.528948 -406.656422) (xy 425.536995 -406.589598)
			(xy 425.552971 -406.524214) (xy 425.576647 -406.461208) (xy 425.607683 -406.401484) (xy 425.645635 -406.345896)
			(xy 425.667424 -406.320244) (xy 425.67323 -406.313105) (xy 425.679738 -406.29591) (xy 425.680124 -406.286716)
			(xy 425.680124 -405.793448) (xy 425.679685 -405.784264) (xy 425.673191 -405.76708) (xy 425.667424 -405.75992)
			(xy 425.645633 -405.734271) (xy 425.607685 -405.678684) (xy 425.576653 -405.61896) (xy 425.552981 -405.555955)
			(xy 425.537009 -405.490572) (xy 425.528965 -405.42375) (xy 425.528965 -405.356444) (xy 425.53701 -405.289622)
			(xy 425.552983 -405.22424) (xy 425.576655 -405.161235) (xy 425.607688 -405.101511) (xy 425.645636 -405.045924)
			(xy 425.667424 -405.020272) (xy 425.673218 -405.013125) (xy 425.679733 -404.995936) (xy 425.680124 -404.986744)
			(xy 425.680124 -404.828756) (xy 425.680486 -404.818596) (xy 425.688301 -404.799838) (xy 425.702716 -404.785515)
			(xy 425.721523 -404.777822) (xy 425.731686 -404.777448) (xy 426.447966 -404.777448) (xy 426.458091 -404.777955)
			(xy 426.476813 -404.785673) (xy 426.491171 -404.799953) (xy 426.49899 -404.818633) (xy 426.499528 -404.828756)
			(xy 426.499528 -404.986744) (xy 426.499911 -404.995934) (xy 426.506443 -405.013119) (xy 426.512228 -405.020272)
			(xy 426.534013 -405.045927) (xy 426.571964 -405.101512) (xy 426.602999 -405.161235) (xy 426.626674 -405.224239)
			(xy 426.642648 -405.289622) (xy 426.650693 -405.356444) (xy 426.650693 -405.42375) (xy 426.642649 -405.490573)
			(xy 426.626675 -405.555955) (xy 426.603002 -405.618959) (xy 426.600565 -405.623649) (xy 427.7291 -405.623649)
			(xy 427.729101 -405.556342) (xy 427.737146 -405.489519) (xy 427.753121 -405.424136) (xy 427.776796 -405.361131)
			(xy 427.807831 -405.301408) (xy 427.845783 -405.245822) (xy 427.867572 -405.22017) (xy 427.873373 -405.213028)
			(xy 427.879883 -405.195835) (xy 427.880272 -405.186642) (xy 427.880272 -404.693374) (xy 427.879881 -404.684185)
			(xy 427.873355 -404.667) (xy 427.867572 -404.659846) (xy 427.845805 -404.634176) (xy 427.807853 -404.578593)
			(xy 427.776817 -404.518872) (xy 427.753142 -404.45587) (xy 427.737166 -404.39049) (xy 427.72912 -404.323668)
			(xy 427.729118 -404.256365) (xy 427.73716 -404.189543) (xy 427.753132 -404.124162) (xy 427.776804 -404.061158)
			(xy 427.807836 -404.001435) (xy 427.845785 -403.94585) (xy 427.867572 -403.920198) (xy 427.873361 -403.913048)
			(xy 427.879878 -403.895861) (xy 427.880272 -403.88667) (xy 427.880272 -403.728682) (xy 427.88065 -403.718505)
			(xy 427.888447 -403.699703) (xy 427.902847 -403.685318) (xy 427.921657 -403.67754) (xy 427.931834 -403.67712)
			(xy 428.648114 -403.67712) (xy 428.65827 -403.677622) (xy 428.677036 -403.685397) (xy 428.6914 -403.69976)
			(xy 428.699178 -403.718526) (xy 428.699676 -403.728682) (xy 428.699676 -403.88667) (xy 428.700106 -403.895855)
			(xy 428.706607 -403.913039) (xy 428.712376 -403.920198) (xy 428.734185 -403.945833) (xy 428.772132 -404.001422)
			(xy 428.803164 -404.061148) (xy 428.826835 -404.124155) (xy 428.842806 -404.189539) (xy 428.850848 -404.256363)
			(xy 428.850846 -404.32367) (xy 428.8428 -404.390494) (xy 428.826825 -404.455877) (xy 428.80315 -404.518882)
			(xy 428.772115 -404.578607) (xy 428.734165 -404.634194) (xy 428.712376 -404.659846) (xy 428.706575 -404.666988)
			(xy 428.700064 -404.684181) (xy 428.699676 -404.693374) (xy 428.699676 -405.186642) (xy 428.700071 -405.195831)
			(xy 428.706596 -405.213015) (xy 428.712376 -405.22017) (xy 428.734157 -405.245827) (xy 428.772106 -405.301413)
			(xy 428.803138 -405.361136) (xy 428.826811 -405.42414) (xy 428.842784 -405.489522) (xy 428.850828 -405.556343)
			(xy 428.850829 -405.623648) (xy 428.842785 -405.69047) (xy 428.826813 -405.755851) (xy 428.803142 -405.818856)
			(xy 428.77211 -405.878579) (xy 428.734163 -405.934166) (xy 428.712376 -405.959818) (xy 428.706587 -405.966968)
			(xy 428.700068 -405.984155) (xy 428.699676 -405.993346) (xy 428.699676 -406.151334) (xy 428.699195 -406.161492)
			(xy 428.691412 -406.180259) (xy 428.677043 -406.194623) (xy 428.658272 -406.202399) (xy 428.648114 -406.202896)
			(xy 427.931834 -406.202896) (xy 427.921683 -406.202339) (xy 427.902921 -406.194583) (xy 427.888556 -406.180236)
			(xy 427.880774 -406.161485) (xy 427.880272 -406.151334) (xy 427.880272 -405.993346) (xy 427.879846 -405.98416)
			(xy 427.873344 -405.966976) (xy 427.867572 -405.959818) (xy 427.845777 -405.934171) (xy 427.807827 -405.878585)
			(xy 427.776792 -405.818861) (xy 427.753118 -405.755855) (xy 427.737144 -405.690472) (xy 427.7291 -405.623649)
			(xy 426.600565 -405.623649) (xy 426.571967 -405.678683) (xy 426.534016 -405.734268) (xy 426.512228 -405.75992)
			(xy 426.506432 -405.767065) (xy 426.499919 -405.784256) (xy 426.499528 -405.793448) (xy 426.499528 -406.286716)
			(xy 426.499924 -406.295905) (xy 426.506447 -406.313089) (xy 426.512228 -406.320244) (xy 426.533985 -406.345922)
			(xy 426.571937 -406.401504) (xy 426.602974 -406.461223) (xy 426.62665 -406.524225) (xy 426.642626 -406.589604)
			(xy 426.650673 -406.656424) (xy 426.650676 -406.723728) (xy 426.650669 -406.723789) (xy 429.928714 -406.723789)
			(xy 429.928717 -406.656363) (xy 429.936796 -406.589422) (xy 429.952835 -406.523931) (xy 429.976604 -406.460832)
			(xy 430.00776 -406.401036) (xy 430.045853 -406.345401) (xy 430.06772 -406.319736) (xy 430.073529 -406.312599)
			(xy 430.080035 -406.295402) (xy 430.08042 -406.286208) (xy 430.08042 -405.793956) (xy 430.080027 -405.784767)
			(xy 430.073501 -405.767583) (xy 430.06772 -405.760428) (xy 430.045851 -405.734766) (xy 430.007761 -405.679132)
			(xy 429.97661 -405.619335) (xy 429.952845 -405.556238) (xy 429.936809 -405.490748) (xy 429.928733 -405.423809)
			(xy 429.928734 -405.356385) (xy 429.93681 -405.289446) (xy 429.952847 -405.223956) (xy 429.976612 -405.160859)
			(xy 430.007765 -405.101063) (xy 430.045855 -405.045429) (xy 430.06772 -405.019764) (xy 430.073517 -405.012619)
			(xy 430.080031 -404.995428) (xy 430.08042 -404.986236) (xy 430.08042 -404.828756) (xy 430.08085 -404.818642)
			(xy 430.088605 -404.799959) (xy 430.102919 -404.785665) (xy 430.121613 -404.777935) (xy 430.131728 -404.777448)
			(xy 430.848008 -404.777448) (xy 430.858111 -404.777977) (xy 430.876779 -404.785708) (xy 430.891072 -404.799991)
			(xy 430.898815 -404.818654) (xy 430.899316 -404.828756) (xy 430.899316 -404.986236) (xy 430.899705 -404.995425)
			(xy 430.906233 -405.01261) (xy 430.912016 -405.019764) (xy 430.933875 -405.045433) (xy 430.971963 -405.101067)
			(xy 431.003113 -405.160863) (xy 431.026877 -405.223959) (xy 431.042912 -405.289448) (xy 431.050988 -405.356385)
			(xy 431.050989 -405.423809) (xy 431.042913 -405.490746) (xy 431.026879 -405.556235) (xy 431.003116 -405.619331)
			(xy 431.000867 -405.623648) (xy 432.128891 -405.623648) (xy 432.128892 -405.556343) (xy 432.136937 -405.489519)
			(xy 432.152911 -405.424136) (xy 432.176585 -405.361132) (xy 432.207621 -405.301408) (xy 432.245571 -405.245822)
			(xy 432.26736 -405.22017) (xy 432.273159 -405.213027) (xy 432.279671 -405.195835) (xy 432.28006 -405.186642)
			(xy 432.28006 -404.693374) (xy 432.279649 -404.684187) (xy 432.273134 -404.667004) (xy 432.26736 -404.659846)
			(xy 432.245593 -404.634176) (xy 432.207643 -404.578593) (xy 432.176607 -404.518872) (xy 432.152932 -404.45587)
			(xy 432.136957 -404.390489) (xy 432.128911 -404.323668) (xy 432.128909 -404.256365) (xy 432.136951 -404.189543)
			(xy 432.152922 -404.124162) (xy 432.176594 -404.061158) (xy 432.207626 -404.001436) (xy 432.245573 -403.94585)
			(xy 432.26736 -403.920198) (xy 432.273147 -403.913047) (xy 432.279666 -403.895861) (xy 432.28006 -403.88667)
			(xy 432.28006 -403.728682) (xy 432.28045 -403.718507) (xy 432.288245 -403.699707) (xy 432.302641 -403.685322)
			(xy 432.321446 -403.677542) (xy 432.331622 -403.67712) (xy 433.047902 -403.67712) (xy 433.058058 -403.677631)
			(xy 433.076823 -403.685403) (xy 433.091188 -403.699763) (xy 433.098965 -403.718526) (xy 433.099464 -403.728682)
			(xy 433.099464 -403.88667) (xy 433.099897 -403.895855) (xy 433.106396 -403.913039) (xy 433.112164 -403.920198)
			(xy 433.133973 -403.945832) (xy 433.171921 -404.001421) (xy 433.202954 -404.061147) (xy 433.226625 -404.124154)
			(xy 433.242596 -404.189539) (xy 433.250639 -404.256363) (xy 433.250637 -404.32367) (xy 433.24259 -404.390494)
			(xy 433.226615 -404.455877) (xy 433.20294 -404.518883) (xy 433.171904 -404.578607) (xy 433.133953 -404.634194)
			(xy 433.112164 -404.659846) (xy 433.106361 -404.666986) (xy 433.099851 -404.684181) (xy 433.099464 -404.693374)
			(xy 433.099464 -405.186642) (xy 433.099862 -405.19583) (xy 433.106385 -405.213014) (xy 433.112164 -405.22017)
			(xy 433.133946 -405.245827) (xy 433.171895 -405.301413) (xy 433.202928 -405.361136) (xy 433.226601 -405.42414)
			(xy 433.242574 -405.489521) (xy 433.250619 -405.556343) (xy 433.250619 -405.623648) (xy 433.242576 -405.69047)
			(xy 433.226604 -405.755852) (xy 433.202932 -405.818856) (xy 433.171899 -405.878579) (xy 433.133951 -405.934166)
			(xy 433.112164 -405.959818) (xy 433.106373 -405.966967) (xy 433.099856 -405.984155) (xy 433.099464 -405.993346)
			(xy 433.099464 -406.151334) (xy 433.098995 -406.161494) (xy 433.091209 -406.180263) (xy 433.076836 -406.194627)
			(xy 433.058062 -406.202401) (xy 433.047902 -406.202896) (xy 432.331622 -406.202896) (xy 432.32147 -406.20235)
			(xy 432.302708 -406.194589) (xy 432.288343 -406.180239) (xy 432.280561 -406.161486) (xy 432.28006 -406.151334)
			(xy 432.28006 -405.993346) (xy 432.279614 -405.984163) (xy 432.273124 -405.966979) (xy 432.26736 -405.959818)
			(xy 432.245566 -405.934171) (xy 432.207616 -405.878584) (xy 432.176582 -405.81886) (xy 432.152908 -405.755855)
			(xy 432.136935 -405.690472) (xy 432.128891 -405.623648) (xy 431.000867 -405.623648) (xy 430.971966 -405.679128)
			(xy 430.933879 -405.734762) (xy 430.912016 -405.760428) (xy 430.906227 -405.767579) (xy 430.899707 -405.784765)
			(xy 430.899316 -405.793956) (xy 430.899316 -406.286208) (xy 430.899719 -406.295396) (xy 430.906237 -406.31258)
			(xy 430.912016 -406.319736) (xy 430.933848 -406.345427) (xy 430.971937 -406.401059) (xy 431.003088 -406.460851)
			(xy 431.026853 -406.523945) (xy 431.04289 -406.58943) (xy 431.050968 -406.656366) (xy 431.050971 -406.723729)
			(xy 434.329033 -406.723729) (xy 434.329036 -406.656422) (xy 434.337083 -406.589598) (xy 434.353058 -406.524215)
			(xy 434.376733 -406.461209) (xy 434.407769 -406.401484) (xy 434.445719 -406.345897) (xy 434.467508 -406.320244)
			(xy 434.473312 -406.313104) (xy 434.479822 -406.295909) (xy 434.480208 -406.286716) (xy 434.480208 -405.793448)
			(xy 434.479773 -405.784263) (xy 434.473276 -405.767079) (xy 434.467508 -405.75992) (xy 434.445717 -405.734271)
			(xy 434.407771 -405.678683) (xy 434.376739 -405.618959) (xy 434.353068 -405.555954) (xy 434.337096 -405.490572)
			(xy 434.329053 -405.423749) (xy 434.329053 -405.356445) (xy 434.337097 -405.289622) (xy 434.35307 -405.22424)
			(xy 434.376742 -405.161236) (xy 434.407774 -405.101512) (xy 434.445721 -405.045925) (xy 434.467508 -405.020272)
			(xy 434.4733 -405.013124) (xy 434.479817 -404.995935) (xy 434.480208 -404.986744) (xy 434.480208 -404.828756)
			(xy 434.480586 -404.818598) (xy 434.488397 -404.799843) (xy 434.502807 -404.785521) (xy 434.52161 -404.777824)
			(xy 434.53177 -404.777448) (xy 435.24805 -404.777448) (xy 435.258175 -404.777968) (xy 435.276896 -404.785681)
			(xy 435.291254 -404.799957) (xy 435.299074 -404.818634) (xy 435.299612 -404.828756) (xy 435.299612 -404.986744)
			(xy 435.299998 -404.995934) (xy 435.306528 -405.013118) (xy 435.312312 -405.020272) (xy 435.334097 -405.045927)
			(xy 435.372049 -405.101512) (xy 435.403086 -405.161234) (xy 435.426761 -405.224239) (xy 435.442735 -405.289621)
			(xy 435.450781 -405.356444) (xy 435.450781 -405.42375) (xy 435.442736 -405.490573) (xy 435.426762 -405.555956)
			(xy 435.403088 -405.61896) (xy 435.372052 -405.678683) (xy 435.334101 -405.734269) (xy 435.312312 -405.75992)
			(xy 435.306526 -405.767073) (xy 435.300005 -405.784257) (xy 435.299612 -405.793448) (xy 435.299612 -406.286716)
			(xy 435.300012 -406.295904) (xy 435.306532 -406.313089) (xy 435.312312 -406.320244) (xy 435.33407 -406.345921)
			(xy 435.372023 -406.401503) (xy 435.40306 -406.461223) (xy 435.426737 -406.524224) (xy 435.442713 -406.589604)
			(xy 435.450761 -406.656424) (xy 435.450764 -406.723728) (xy 435.442722 -406.790549) (xy 435.426751 -406.85593)
			(xy 435.40308 -406.918933) (xy 435.372048 -406.978656) (xy 435.334099 -407.034241) (xy 435.312312 -407.059892)
			(xy 435.306538 -407.067053) (xy 435.300009 -407.084231) (xy 435.299612 -407.09342) (xy 435.299612 -407.251408)
			(xy 435.299185 -407.261561) (xy 435.291389 -407.280311) (xy 435.276994 -407.294634) (xy 435.258205 -407.302335)
			(xy 435.24805 -407.302716) (xy 434.53177 -407.302716) (xy 434.521636 -407.302297) (xy 434.502906 -407.294551)
			(xy 434.488549 -407.280244) (xy 434.480739 -407.26154) (xy 434.480208 -407.251408) (xy 434.480208 -407.09342)
			(xy 434.479786 -407.084234) (xy 434.47328 -407.06705) (xy 434.467508 -407.059892) (xy 434.44569 -407.034265)
			(xy 434.407744 -406.978674) (xy 434.376714 -406.918947) (xy 434.353044 -406.855939) (xy 434.337074 -406.790554)
			(xy 434.329033 -406.723729) (xy 431.050971 -406.723729) (xy 431.050971 -406.723786) (xy 431.042899 -406.790722)
			(xy 431.026867 -406.856209) (xy 431.003107 -406.919305) (xy 430.971961 -406.9791) (xy 430.933877 -407.034735)
			(xy 430.912016 -407.0604) (xy 430.906239 -407.067559) (xy 430.899712 -407.084739) (xy 430.899316 -407.093928)
			(xy 430.899316 -407.251408) (xy 430.898822 -407.261515) (xy 430.891084 -407.28019) (xy 430.87679 -407.294484)
			(xy 430.858115 -407.302222) (xy 430.848008 -407.302716) (xy 430.131728 -407.302716) (xy 430.121609 -407.302262)
			(xy 430.102909 -407.294526) (xy 430.088595 -407.280221) (xy 430.080845 -407.261526) (xy 430.08042 -407.251408)
			(xy 430.08042 -407.093928) (xy 430.079992 -407.084743) (xy 430.07349 -407.067559) (xy 430.06772 -407.0604)
			(xy 430.045824 -407.034761) (xy 430.007735 -406.979123) (xy 429.976584 -406.919324) (xy 429.952821 -406.856223)
			(xy 429.936787 -406.790731) (xy 429.928714 -406.723789) (xy 426.650669 -406.723789) (xy 426.642634 -406.790548)
			(xy 426.626664 -406.855929) (xy 426.602993 -406.918933) (xy 426.571962 -406.978655) (xy 426.534015 -407.03424)
			(xy 426.512228 -407.059892) (xy 426.506444 -407.067045) (xy 426.499924 -407.08423) (xy 426.499528 -407.09342)
			(xy 426.499528 -407.251408) (xy 426.499085 -407.261559) (xy 426.491292 -407.280306) (xy 426.476903 -407.294628)
			(xy 426.458119 -407.302333) (xy 426.447966 -407.302716) (xy 425.731686 -407.302716) (xy 425.721553 -407.302283)
			(xy 425.702823 -407.294543) (xy 425.688466 -407.28024) (xy 425.680655 -407.261539) (xy 425.680124 -407.251408)
			(xy 425.680124 -407.09342) (xy 425.679699 -407.084235) (xy 425.673195 -407.06705) (xy 425.667424 -407.059892)
			(xy 425.645605 -407.034266) (xy 425.607658 -406.978675) (xy 425.576627 -406.918948) (xy 425.552957 -406.85594)
			(xy 425.536987 -406.790555) (xy 425.528945 -406.72373) (xy 422.250883 -406.72373) (xy 422.250883 -406.723786)
			(xy 422.242811 -406.790722) (xy 422.22678 -406.856209) (xy 422.203021 -406.919304) (xy 422.171876 -406.9791)
			(xy 422.133793 -407.034734) (xy 422.111932 -407.0604) (xy 422.106145 -407.067551) (xy 422.099626 -407.084737)
			(xy 422.099232 -407.093928) (xy 422.099232 -407.251408) (xy 422.098722 -407.261513) (xy 422.090988 -407.280185)
			(xy 422.076699 -407.294479) (xy 422.058029 -407.302219) (xy 422.047924 -407.302716) (xy 421.331644 -407.302716)
			(xy 421.321526 -407.302248) (xy 421.302827 -407.294518) (xy 421.288512 -407.280217) (xy 421.280762 -407.261525)
			(xy 421.280336 -407.251408) (xy 421.280336 -407.093928) (xy 421.279904 -407.084743) (xy 421.273405 -407.067559)
			(xy 421.267636 -407.0604) (xy 421.245739 -407.034761) (xy 421.207649 -406.979124) (xy 421.176498 -406.919324)
			(xy 421.152734 -406.856224) (xy 421.1367 -406.790731) (xy 421.128626 -406.723789) (xy 414.525968 -406.723789)
			(xy 414.525968 -409.523827) (xy 418.928991 -409.523827) (xy 418.928995 -409.456519) (xy 418.937043 -409.389693)
			(xy 418.953021 -409.324308) (xy 418.9767 -409.261302) (xy 419.00774 -409.201577) (xy 419.045697 -409.145992)
			(xy 419.067488 -409.12034) (xy 419.073291 -409.113199) (xy 419.079802 -409.096005) (xy 419.080188 -409.086812)
			(xy 419.080188 -408.593544) (xy 419.079759 -408.584359) (xy 419.073259 -408.567174) (xy 419.067488 -408.560016)
			(xy 419.045691 -408.534371) (xy 419.007739 -408.478785) (xy 418.976704 -408.419061) (xy 418.953029 -408.356055)
			(xy 418.937055 -408.290671) (xy 418.929011 -408.223847) (xy 418.929012 -408.156541) (xy 418.937057 -408.089717)
			(xy 418.953033 -408.024333) (xy 418.976708 -407.961328) (xy 419.007745 -407.901605) (xy 419.045698 -407.84602)
			(xy 419.067488 -407.820368) (xy 419.073279 -407.813219) (xy 419.079797 -407.796031) (xy 419.080188 -407.78684)
			(xy 419.080188 -407.628852) (xy 419.080582 -407.618696) (xy 419.088391 -407.599945) (xy 419.102796 -407.585624)
			(xy 419.121592 -407.577924) (xy 419.13175 -407.577544) (xy 419.84803 -407.577544) (xy 419.858159 -407.578002)
			(xy 419.876882 -407.58574) (xy 419.891237 -407.600035) (xy 419.899055 -407.618725) (xy 419.899592 -407.628852)
			(xy 419.899592 -407.78684) (xy 419.899985 -407.796029) (xy 419.906511 -407.813213) (xy 419.912292 -407.820368)
			(xy 419.934071 -407.846027) (xy 419.972018 -407.901613) (xy 420.00305 -407.961336) (xy 420.026722 -408.02434)
			(xy 420.042694 -408.089721) (xy 420.050739 -408.156542) (xy 420.050739 -408.223846) (xy 420.042697 -408.290667)
			(xy 420.026725 -408.356049) (xy 420.003055 -408.419053) (xy 419.972024 -408.478776) (xy 419.934078 -408.534363)
			(xy 419.912292 -408.560016) (xy 419.906505 -408.567168) (xy 419.899985 -408.584353) (xy 419.899592 -408.593544)
			(xy 419.899592 -409.086812) (xy 419.899998 -409.096) (xy 419.906515 -409.113184) (xy 419.912292 -409.12034)
			(xy 419.934043 -409.146022) (xy 419.971991 -409.201605) (xy 420.003024 -409.261324) (xy 420.026698 -409.324325)
			(xy 420.042672 -409.389703) (xy 420.050719 -409.456522) (xy 420.050722 -409.523824) (xy 420.042682 -409.590643)
			(xy 420.026714 -409.656023) (xy 420.003047 -409.719026) (xy 419.972019 -409.778749) (xy 419.934077 -409.834336)
			(xy 419.912292 -409.859988) (xy 419.906475 -409.867118) (xy 419.899973 -409.88432) (xy 419.899592 -409.893516)
			(xy 419.899592 -410.051504) (xy 419.899181 -410.061659) (xy 419.891383 -410.080413) (xy 419.876983 -410.094737)
			(xy 419.858187 -410.102435) (xy 419.84803 -410.102812) (xy 419.13175 -410.102812) (xy 419.121633 -410.102234)
			(xy 419.102923 -410.094532) (xy 419.088567 -410.080274) (xy 419.080736 -410.061618) (xy 419.080188 -410.051504)
			(xy 419.080188 -409.893516) (xy 419.079773 -409.884329) (xy 419.073263 -409.867145) (xy 419.067488 -409.859988)
			(xy 419.045663 -409.834366) (xy 419.007713 -409.778776) (xy 418.976678 -409.719049) (xy 418.953005 -409.65604)
			(xy 418.937033 -409.590654) (xy 418.928991 -409.523827) (xy 414.525968 -409.523827) (xy 414.525968 -410.623701)
			(xy 421.128637 -410.623701) (xy 421.128638 -410.556275) (xy 421.136716 -410.489335) (xy 421.152755 -410.423845)
			(xy 421.176522 -410.360747) (xy 421.207677 -410.300951) (xy 421.24577 -410.245317) (xy 421.267636 -410.219652)
			(xy 421.27344 -410.212512) (xy 421.279949 -410.195317) (xy 421.280336 -410.186124) (xy 421.280336 -409.693872)
			(xy 421.279931 -409.684684) (xy 421.273413 -409.667501) (xy 421.267636 -409.660344) (xy 421.245783 -409.63467)
			(xy 421.207691 -409.579037) (xy 421.176538 -409.519243) (xy 421.152771 -409.456147) (xy 421.136734 -409.390659)
			(xy 421.128657 -409.323721) (xy 421.128656 -409.256297) (xy 421.136731 -409.189359) (xy 421.152766 -409.12387)
			(xy 421.176531 -409.060774) (xy 421.207682 -409.000978) (xy 421.245771 -408.945345) (xy 421.267636 -408.91968)
			(xy 421.273428 -408.912532) (xy 421.279945 -408.895343) (xy 421.280336 -408.886152) (xy 421.280336 -408.728672)
			(xy 421.280694 -408.718543) (xy 421.288458 -408.699832) (xy 421.302793 -408.685517) (xy 421.321515 -408.67778)
			(xy 421.331644 -408.677364) (xy 422.047924 -408.677364) (xy 422.05803 -408.677864) (xy 422.076702 -408.685603)
			(xy 422.090994 -408.699895) (xy 422.098735 -408.718566) (xy 422.099232 -408.728672) (xy 422.099232 -408.886152)
			(xy 422.09968 -408.895335) (xy 422.106169 -408.912519) (xy 422.111932 -408.91968) (xy 422.133807 -408.945336)
			(xy 422.171893 -409.000973) (xy 422.203041 -409.06077) (xy 422.226803 -409.123868) (xy 422.242837 -409.189358)
			(xy 422.250911 -409.256297) (xy 422.25091 -409.323721) (xy 422.242834 -409.39066) (xy 422.226798 -409.456149)
			(xy 422.203034 -409.519246) (xy 422.200617 -409.523886) (xy 423.328784 -409.523886) (xy 423.328787 -409.45646)
			(xy 423.336866 -409.389519) (xy 423.352905 -409.324029) (xy 423.376672 -409.26093) (xy 423.407826 -409.201133)
			(xy 423.445918 -409.145498) (xy 423.467784 -409.119832) (xy 423.47359 -409.112693) (xy 423.4801 -409.095498)
			(xy 423.480484 -409.086304) (xy 423.480484 -408.594052) (xy 423.480052 -408.584867) (xy 423.473554 -408.567682)
			(xy 423.467784 -408.560524) (xy 423.445913 -408.534865) (xy 423.407825 -408.479229) (xy 423.376676 -408.419432)
			(xy 423.352913 -408.356334) (xy 423.336878 -408.290845) (xy 423.328803 -408.223906) (xy 423.328804 -408.156482)
			(xy 423.336881 -408.089543) (xy 423.352916 -408.024054) (xy 423.376681 -407.960957) (xy 423.407832 -407.901161)
			(xy 423.44592 -407.845526) (xy 423.467784 -407.81986) (xy 423.473578 -407.812713) (xy 423.480095 -407.795524)
			(xy 423.480484 -407.786332) (xy 423.480484 -407.628852) (xy 423.480946 -407.618742) (xy 423.488696 -407.600066)
			(xy 423.503 -407.585774) (xy 423.521682 -407.578038) (xy 423.531792 -407.577544) (xy 424.248072 -407.577544)
			(xy 424.258172 -407.578106) (xy 424.276839 -407.585825) (xy 424.291133 -407.600097) (xy 424.298879 -407.618753)
			(xy 424.29938 -407.628852) (xy 424.29938 -407.786332) (xy 424.299779 -407.79552) (xy 424.306301 -407.812704)
			(xy 424.31208 -407.81986) (xy 424.333937 -407.845531) (xy 424.372027 -407.901165) (xy 424.403179 -407.96096)
			(xy 424.426945 -408.024056) (xy 424.442981 -408.089544) (xy 424.451058 -408.156482) (xy 424.451059 -408.223906)
			(xy 424.442984 -408.290844) (xy 424.426948 -408.356333) (xy 424.403184 -408.419429) (xy 424.372033 -408.479225)
			(xy 424.333944 -408.534859) (xy 424.31208 -408.560524) (xy 424.306288 -408.567673) (xy 424.299771 -408.584861)
			(xy 424.29938 -408.594052) (xy 424.29938 -409.086304) (xy 424.299792 -409.095491) (xy 424.306305 -409.112675)
			(xy 424.31208 -409.119832) (xy 424.333909 -409.145526) (xy 424.372 -409.201156) (xy 424.403154 -409.260948)
			(xy 424.426921 -409.324041) (xy 424.442959 -409.389527) (xy 424.451039 -409.456462) (xy 424.451042 -409.523884)
			(xy 424.442969 -409.59082) (xy 424.426937 -409.656307) (xy 424.403176 -409.719403) (xy 424.372028 -409.779198)
			(xy 424.333943 -409.834831) (xy 424.31208 -409.860496) (xy 424.3063 -409.867653) (xy 424.299776 -409.884835)
			(xy 424.29938 -409.894024) (xy 424.29938 -410.051504) (xy 424.298987 -410.061629) (xy 424.291234 -410.080337)
			(xy 424.27691 -410.094651) (xy 424.258197 -410.102393) (xy 424.248072 -410.102812) (xy 423.531792 -410.102812)
			(xy 423.521684 -410.102322) (xy 423.503008 -410.094584) (xy 423.488714 -410.080288) (xy 423.480978 -410.061612)
			(xy 423.480484 -410.051504) (xy 423.480484 -409.894024) (xy 423.480066 -409.884838) (xy 423.473558 -409.867653)
			(xy 423.467784 -409.860496) (xy 423.445885 -409.83486) (xy 423.407799 -409.779221) (xy 423.37665 -409.71942)
			(xy 423.352889 -409.65632) (xy 423.336856 -409.590827) (xy 423.328784 -409.523886) (xy 422.200617 -409.523886)
			(xy 422.171884 -409.579043) (xy 422.133796 -409.634678) (xy 422.111932 -409.660344) (xy 422.106126 -409.667482)
			(xy 422.099619 -409.684678) (xy 422.099232 -409.693872) (xy 422.099232 -410.186124) (xy 422.099646 -410.19531)
			(xy 422.106159 -410.212494) (xy 422.111932 -410.219652) (xy 422.133779 -410.245331) (xy 422.171866 -410.300964)
			(xy 422.203016 -410.360759) (xy 422.22678 -410.423854) (xy 422.242815 -410.489341) (xy 422.250892 -410.556277)
			(xy 422.250893 -410.623641) (xy 425.528957 -410.623641) (xy 425.528958 -410.556335) (xy 425.537003 -410.489512)
			(xy 425.552978 -410.424129) (xy 425.576652 -410.361123) (xy 425.607686 -410.301399) (xy 425.645636 -410.245812)
			(xy 425.667424 -410.22016) (xy 425.673223 -410.213017) (xy 425.679735 -410.195825) (xy 425.680124 -410.186632)
			(xy 425.680124 -409.693364) (xy 425.679726 -409.684176) (xy 425.673203 -409.666992) (xy 425.667424 -409.659836)
			(xy 425.645648 -409.634174) (xy 425.6077 -409.578589) (xy 425.576667 -409.518866) (xy 425.552994 -409.455863)
			(xy 425.537021 -409.390482) (xy 425.528976 -409.323661) (xy 425.528975 -409.256357) (xy 425.537018 -409.189536)
			(xy 425.552989 -409.124154) (xy 425.57666 -409.06115) (xy 425.607691 -409.001427) (xy 425.645637 -408.94584)
			(xy 425.667424 -408.920188) (xy 425.673211 -408.913036) (xy 425.679731 -408.895851) (xy 425.680124 -408.88666)
			(xy 425.680124 -408.728672) (xy 425.680499 -408.718513) (xy 425.688308 -408.699755) (xy 425.70272 -408.685432)
			(xy 425.721525 -408.677738) (xy 425.731686 -408.677364) (xy 426.447966 -408.677364) (xy 426.458093 -408.677855)
			(xy 426.476818 -408.685576) (xy 426.491177 -408.699862) (xy 426.498993 -408.718547) (xy 426.499528 -408.728672)
			(xy 426.499528 -408.88666) (xy 426.499951 -408.895846) (xy 426.506455 -408.913031) (xy 426.512228 -408.920188)
			(xy 426.534028 -408.94583) (xy 426.571979 -409.001417) (xy 426.603014 -409.061142) (xy 426.626687 -409.124148)
			(xy 426.64266 -409.189532) (xy 426.650704 -409.256356) (xy 426.650703 -409.323662) (xy 426.642657 -409.390486)
			(xy 426.626682 -409.45587) (xy 426.603006 -409.518875) (xy 426.600433 -409.523827) (xy 427.729079 -409.523827)
			(xy 427.729082 -409.456519) (xy 427.73713 -409.389693) (xy 427.753108 -409.324308) (xy 427.776786 -409.261302)
			(xy 427.807826 -409.201578) (xy 427.845781 -409.145992) (xy 427.867572 -409.12034) (xy 427.873385 -409.113207)
			(xy 427.879888 -409.096007) (xy 427.880272 -409.086812) (xy 427.880272 -408.593544) (xy 427.879847 -408.584358)
			(xy 427.873344 -408.567174) (xy 427.867572 -408.560016) (xy 427.845776 -408.534371) (xy 427.807825 -408.478784)
			(xy 427.77679 -408.41906) (xy 427.753116 -408.356054) (xy 427.737143 -408.290671) (xy 427.729099 -408.223847)
			(xy 427.7291 -408.156541) (xy 427.737145 -408.089717) (xy 427.75312 -408.024334) (xy 427.776795 -407.961329)
			(xy 427.807831 -407.901606) (xy 427.845783 -407.84602) (xy 427.867572 -407.820368) (xy 427.873373 -407.813227)
			(xy 427.879883 -407.796033) (xy 427.880272 -407.78684) (xy 427.880272 -407.628852) (xy 427.880682 -407.618698)
			(xy 427.888488 -407.59995) (xy 427.902887 -407.58563) (xy 427.921678 -407.577927) (xy 427.931834 -407.577544)
			(xy 428.648114 -407.577544) (xy 428.658242 -407.578015) (xy 428.676964 -407.585749) (xy 428.69132 -407.600039)
			(xy 428.699138 -407.618726) (xy 428.699676 -407.628852) (xy 428.699676 -407.78684) (xy 428.700072 -407.796029)
			(xy 428.706596 -407.813212) (xy 428.712376 -407.820368) (xy 428.734155 -407.846027) (xy 428.772104 -407.901613)
			(xy 428.803136 -407.961335) (xy 428.826809 -408.024339) (xy 428.842782 -408.08972) (xy 428.850827 -408.156542)
			(xy 428.850827 -408.223846) (xy 428.842784 -408.290668) (xy 428.826813 -408.356049) (xy 428.803141 -408.419054)
			(xy 428.77211 -408.478777) (xy 428.734163 -408.534364) (xy 428.712376 -408.560016) (xy 428.706587 -408.567167)
			(xy 428.700069 -408.584353) (xy 428.699676 -408.593544) (xy 428.699676 -409.086812) (xy 428.700086 -409.095999)
			(xy 428.7066 -409.113183) (xy 428.712376 -409.12034) (xy 428.734128 -409.146022) (xy 428.772077 -409.201604)
			(xy 428.803111 -409.261324) (xy 428.826785 -409.324324) (xy 428.84276 -409.389703) (xy 428.850806 -409.456522)
			(xy 428.85081 -409.523824) (xy 428.842769 -409.590644) (xy 428.826801 -409.656024) (xy 428.803133 -409.719027)
			(xy 428.772104 -409.778749) (xy 428.734161 -409.834335) (xy 428.712376 -409.859988) (xy 428.706557 -409.867117)
			(xy 428.700056 -409.88432) (xy 428.699676 -409.893516) (xy 428.699676 -410.051504) (xy 428.699281 -410.061661)
			(xy 428.69148 -410.080418) (xy 428.677074 -410.094742) (xy 428.658274 -410.102438) (xy 428.648114 -410.102812)
			(xy 427.931834 -410.102812) (xy 427.921716 -410.102247) (xy 427.903005 -410.09454) (xy 427.88865 -410.080278)
			(xy 427.88082 -410.061619) (xy 427.880272 -410.051504) (xy 427.880272 -409.893516) (xy 427.879861 -409.884329)
			(xy 427.873349 -409.867144) (xy 427.867572 -409.859988) (xy 427.845748 -409.834366) (xy 427.807798 -409.778776)
			(xy 427.776764 -409.719048) (xy 427.753092 -409.65604) (xy 427.73712 -409.590654) (xy 427.729079 -409.523827)
			(xy 426.600433 -409.523827) (xy 426.57197 -409.578598) (xy 426.534017 -409.634184) (xy 426.512228 -409.659836)
			(xy 426.506425 -409.666976) (xy 426.499916 -409.684171) (xy 426.499528 -409.693364) (xy 426.499528 -410.186632)
			(xy 426.499917 -410.195822) (xy 426.506445 -410.213006) (xy 426.512228 -410.22016) (xy 426.534001 -410.245825)
			(xy 426.571952 -410.301409) (xy 426.602988 -410.36113) (xy 426.626663 -410.424133) (xy 426.642638 -410.489514)
			(xy 426.650684 -410.556336) (xy 426.650686 -410.62364) (xy 426.650679 -410.623701) (xy 429.928725 -410.623701)
			(xy 429.928726 -410.556275) (xy 429.936804 -410.489336) (xy 429.952842 -410.423845) (xy 429.976609 -410.360748)
			(xy 430.007762 -410.300951) (xy 430.045854 -410.245317) (xy 430.06772 -410.219652) (xy 430.073522 -410.212511)
			(xy 430.080033 -410.195317) (xy 430.08042 -410.186124) (xy 430.08042 -409.693872) (xy 430.080019 -409.684684)
			(xy 430.073498 -409.6675) (xy 430.06772 -409.660344) (xy 430.045867 -409.634669) (xy 430.007777 -409.579037)
			(xy 429.976624 -409.519242) (xy 429.952859 -409.456146) (xy 429.936822 -409.390658) (xy 429.928745 -409.323721)
			(xy 429.928744 -409.256297) (xy 429.936819 -409.18936) (xy 429.952853 -409.123871) (xy 429.976617 -409.060775)
			(xy 430.007767 -409.000979) (xy 430.045856 -408.945345) (xy 430.06772 -408.91968) (xy 430.07351 -408.91253)
			(xy 430.080028 -408.895343) (xy 430.08042 -408.886152) (xy 430.08042 -408.728672) (xy 430.080863 -408.718559)
			(xy 430.088613 -408.699876) (xy 430.102923 -408.685582) (xy 430.121614 -408.677852) (xy 430.131728 -408.677364)
			(xy 430.848008 -408.677364) (xy 430.858113 -408.677878) (xy 430.876784 -408.685611) (xy 430.891077 -408.699899)
			(xy 430.898818 -408.718567) (xy 430.899316 -408.728672) (xy 430.899316 -408.886152) (xy 430.899745 -408.895337)
			(xy 430.906245 -408.912522) (xy 430.912016 -408.91968) (xy 430.933891 -408.945336) (xy 430.971979 -409.000972)
			(xy 431.003128 -409.06077) (xy 431.026891 -409.123868) (xy 431.042925 -409.189358) (xy 431.050999 -409.256297)
			(xy 431.050998 -409.323721) (xy 431.042922 -409.39066) (xy 431.026885 -409.456149) (xy 431.00312 -409.519247)
			(xy 431.000734 -409.523827) (xy 432.12887 -409.523827) (xy 432.128873 -409.456519) (xy 432.136921 -409.389693)
			(xy 432.152898 -409.324309) (xy 432.176576 -409.261303) (xy 432.207615 -409.201578) (xy 432.245569 -409.145992)
			(xy 432.26736 -409.12034) (xy 432.273172 -409.113206) (xy 432.279676 -409.096007) (xy 432.28006 -409.086812)
			(xy 432.28006 -408.593544) (xy 432.279615 -408.584361) (xy 432.273124 -408.567177) (xy 432.26736 -408.560016)
			(xy 432.245564 -408.53437) (xy 432.207614 -408.478784) (xy 432.17658 -408.419059) (xy 432.152907 -408.356054)
			(xy 432.136934 -408.290671) (xy 432.12889 -408.223847) (xy 432.128891 -408.156541) (xy 432.136936 -408.089717)
			(xy 432.15291 -408.024335) (xy 432.176585 -407.96133) (xy 432.20762 -407.901606) (xy 432.245571 -407.84602)
			(xy 432.26736 -407.820368) (xy 432.27316 -407.813226) (xy 432.279671 -407.796033) (xy 432.28006 -407.78684)
			(xy 432.28006 -407.628852) (xy 432.280482 -407.6187) (xy 432.288286 -407.599954) (xy 432.302681 -407.585634)
			(xy 432.321468 -407.577929) (xy 432.331622 -407.577544) (xy 433.047902 -407.577544) (xy 433.058029 -407.578025)
			(xy 433.076751 -407.585754) (xy 433.091108 -407.600042) (xy 433.098926 -407.618727) (xy 433.099464 -407.628852)
			(xy 433.099464 -407.78684) (xy 433.099863 -407.796028) (xy 433.106385 -407.813212) (xy 433.112164 -407.820368)
			(xy 433.133944 -407.846027) (xy 433.171893 -407.901612) (xy 433.202926 -407.961335) (xy 433.226599 -408.024339)
			(xy 433.242573 -408.08972) (xy 433.250618 -408.156542) (xy 433.250618 -408.223846) (xy 433.242575 -408.290668)
			(xy 433.226603 -408.35605) (xy 433.202931 -408.419054) (xy 433.171899 -408.478778) (xy 433.133951 -408.534364)
			(xy 433.112164 -408.560016) (xy 433.106374 -408.567165) (xy 433.099856 -408.584353) (xy 433.099464 -408.593544)
			(xy 433.099464 -409.086812) (xy 433.099876 -409.095999) (xy 433.106389 -409.113183) (xy 433.112164 -409.12034)
			(xy 433.133916 -409.146021) (xy 433.171866 -409.201604) (xy 433.2029 -409.261323) (xy 433.226575 -409.324324)
			(xy 433.24255 -409.389703) (xy 433.250597 -409.456522) (xy 433.250601 -409.523824) (xy 433.24256 -409.590644)
			(xy 433.226591 -409.656024) (xy 433.202922 -409.719027) (xy 433.171894 -409.77875) (xy 433.133949 -409.834336)
			(xy 433.112164 -409.859988) (xy 433.106343 -409.867116) (xy 433.099844 -409.88432) (xy 433.099464 -409.893516)
			(xy 433.099464 -410.051504) (xy 433.099081 -410.061663) (xy 433.091277 -410.080422) (xy 433.076868 -410.094747)
			(xy 433.058063 -410.10244) (xy 433.047902 -410.102812) (xy 432.331622 -410.102812) (xy 432.321503 -410.102257)
			(xy 432.302792 -410.094546) (xy 432.288437 -410.080281) (xy 432.280608 -410.06162) (xy 432.28006 -410.051504)
			(xy 432.28006 -409.893516) (xy 432.279629 -409.884331) (xy 432.273128 -409.867147) (xy 432.26736 -409.859988)
			(xy 432.245536 -409.834365) (xy 432.207587 -409.778775) (xy 432.176554 -409.719048) (xy 432.152882 -409.656039)
			(xy 432.136911 -409.590653) (xy 432.12887 -409.523827) (xy 431.000734 -409.523827) (xy 430.971969 -409.579043)
			(xy 430.93388 -409.634678) (xy 430.912016 -409.660344) (xy 430.90622 -409.66749) (xy 430.899705 -409.68468)
			(xy 430.899316 -409.693872) (xy 430.899316 -410.186124) (xy 430.899711 -410.195313) (xy 430.906235 -410.212497)
			(xy 430.912016 -410.219652) (xy 430.933864 -410.24533) (xy 430.971952 -410.300963) (xy 431.003102 -410.360758)
			(xy 431.026867 -410.423853) (xy 431.042903 -410.48934) (xy 431.05098 -410.556277) (xy 431.050981 -410.623641)
			(xy 434.329044 -410.623641) (xy 434.329046 -410.556335) (xy 434.337091 -410.489512) (xy 434.353065 -410.424129)
			(xy 434.376738 -410.361124) (xy 434.407772 -410.3014) (xy 434.44572 -410.245813) (xy 434.467508 -410.22016)
			(xy 434.473305 -410.213015) (xy 434.479819 -410.195824) (xy 434.480208 -410.186632) (xy 434.480208 -409.693364)
			(xy 434.479814 -409.684175) (xy 434.473289 -409.666991) (xy 434.467508 -409.659836) (xy 434.445733 -409.634174)
			(xy 434.407786 -409.578588) (xy 434.376754 -409.518866) (xy 434.353082 -409.455862) (xy 434.337109 -409.390482)
			(xy 434.329064 -409.323661) (xy 434.329063 -409.256357) (xy 434.337106 -409.189536) (xy 434.353076 -409.124155)
			(xy 434.376746 -409.061151) (xy 434.407777 -409.001427) (xy 434.445722 -408.945841) (xy 434.467508 -408.920188)
			(xy 434.473293 -408.913035) (xy 434.479814 -408.89585) (xy 434.480208 -408.88666) (xy 434.480208 -408.728672)
			(xy 434.480599 -408.718515) (xy 434.488405 -408.69976) (xy 434.502811 -408.685438) (xy 434.521611 -408.67774)
			(xy 434.53177 -408.677364) (xy 435.24805 -408.677364) (xy 435.258176 -408.677868) (xy 435.276901 -408.685584)
			(xy 435.29126 -408.699866) (xy 435.299077 -408.718548) (xy 435.299612 -408.728672) (xy 435.299612 -408.88666)
			(xy 435.300039 -408.895846) (xy 435.30654 -408.91303) (xy 435.312312 -408.920188) (xy 435.334113 -408.94583)
			(xy 435.372065 -409.001417) (xy 435.4031 -409.061141) (xy 435.426774 -409.124147) (xy 435.442748 -409.189531)
			(xy 435.450792 -409.256356) (xy 435.450791 -409.323662) (xy 435.442745 -409.390487) (xy 435.426769 -409.45587)
			(xy 435.403093 -409.518875) (xy 435.372055 -409.578599) (xy 435.334102 -409.634184) (xy 435.312312 -409.659836)
			(xy 435.306519 -409.666984) (xy 435.300002 -409.684172) (xy 435.299612 -409.693364) (xy 435.299612 -410.186632)
			(xy 435.300004 -410.195821) (xy 435.30653 -410.213006) (xy 435.312312 -410.22016) (xy 435.334085 -410.245824)
			(xy 435.372038 -410.301408) (xy 435.403075 -410.361129) (xy 435.42675 -410.424132) (xy 435.442726 -410.489514)
			(xy 435.450772 -410.556336) (xy 435.450774 -410.62364) (xy 435.44273 -410.690463) (xy 435.426758 -410.755845)
			(xy 435.403084 -410.818849) (xy 435.37205 -410.878571) (xy 435.3341 -410.934157) (xy 435.312312 -410.959808)
			(xy 435.306531 -410.966964) (xy 435.300007 -410.984146) (xy 435.299612 -410.993336) (xy 435.299612 -411.151324)
			(xy 435.299198 -411.161478) (xy 435.291397 -411.180229) (xy 435.276998 -411.194551) (xy 435.258206 -411.202252)
			(xy 435.24805 -411.202632) (xy 434.53177 -411.202632) (xy 434.521638 -411.202197) (xy 434.502911 -411.194454)
			(xy 434.488554 -411.180152) (xy 434.480741 -411.161454) (xy 434.480208 -411.151324) (xy 434.480208 -410.993336)
			(xy 434.479779 -410.984151) (xy 434.473278 -410.966966) (xy 434.467508 -410.959808) (xy 434.445706 -410.934168)
			(xy 434.407759 -410.878579) (xy 434.376728 -410.818854) (xy 434.353058 -410.755848) (xy 434.337087 -410.690464)
			(xy 434.329044 -410.623641) (xy 431.050981 -410.623641) (xy 431.050981 -410.623699) (xy 431.042907 -410.690636)
			(xy 431.026874 -410.756124) (xy 431.003112 -410.81922) (xy 430.971964 -410.879016) (xy 430.933878 -410.934651)
			(xy 430.912016 -410.960316) (xy 430.906232 -410.96747) (xy 430.899709 -410.984654) (xy 430.899316 -410.993844)
			(xy 430.899316 -411.151324) (xy 430.898835 -411.161432) (xy 430.891092 -411.180108) (xy 430.876795 -411.194401)
			(xy 430.858116 -411.202138) (xy 430.848008 -411.202632) (xy 430.131728 -411.202632) (xy 430.121611 -411.202162)
			(xy 430.102914 -411.194429) (xy 430.0886 -411.180129) (xy 430.080848 -411.16144) (xy 430.08042 -411.151324)
			(xy 430.08042 -410.993844) (xy 430.079984 -410.98466) (xy 430.073488 -410.967475) (xy 430.06772 -410.960316)
			(xy 430.04584 -410.934664) (xy 430.00775 -410.879028) (xy 429.976599 -410.81923) (xy 429.952835 -410.756132)
			(xy 429.9368 -410.690641) (xy 429.928725 -410.623701) (xy 426.650679 -410.623701) (xy 426.642643 -410.690462)
			(xy 426.62667 -410.755844) (xy 426.602998 -410.818848) (xy 426.571965 -410.878571) (xy 426.534016 -410.934156)
			(xy 426.512228 -410.959808) (xy 426.506437 -410.966957) (xy 426.499921 -410.984145) (xy 426.499528 -410.993336)
			(xy 426.499528 -411.151324) (xy 426.499099 -411.161476) (xy 426.4913 -411.180224) (xy 426.476907 -411.194545)
			(xy 426.45812 -411.202249) (xy 426.447966 -411.202632) (xy 425.731686 -411.202632) (xy 425.721555 -411.202184)
			(xy 425.702828 -411.194446) (xy 425.688472 -411.180148) (xy 425.680658 -411.161453) (xy 425.680124 -411.151324)
			(xy 425.680124 -410.993336) (xy 425.679691 -410.984151) (xy 425.673193 -410.966967) (xy 425.667424 -410.959808)
			(xy 425.645621 -410.934169) (xy 425.607674 -410.87858) (xy 425.576642 -410.818855) (xy 425.552971 -410.755848)
			(xy 425.536999 -410.690465) (xy 425.528957 -410.623641) (xy 422.250893 -410.623641) (xy 422.250893 -410.623699)
			(xy 422.242819 -410.690635) (xy 422.226787 -410.756123) (xy 422.203026 -410.819219) (xy 422.171879 -410.879015)
			(xy 422.133794 -410.93465) (xy 422.111932 -410.960316) (xy 422.106138 -410.967463) (xy 422.099624 -410.984652)
			(xy 422.099232 -410.993844) (xy 422.099232 -411.151324) (xy 422.098735 -411.16143) (xy 422.090996 -411.180103)
			(xy 422.076703 -411.194396) (xy 422.05803 -411.202135) (xy 422.047924 -411.202632) (xy 421.331644 -411.202632)
			(xy 421.321528 -411.202149) (xy 421.302832 -411.194421) (xy 421.288517 -411.180125) (xy 421.280765 -411.161439)
			(xy 421.280336 -411.151324) (xy 421.280336 -410.993844) (xy 421.279896 -410.98466) (xy 421.273402 -410.967476)
			(xy 421.267636 -410.960316) (xy 421.245755 -410.934664) (xy 421.207664 -410.879029) (xy 421.176512 -410.819231)
			(xy 421.152748 -410.756132) (xy 421.136712 -410.690641) (xy 421.128637 -410.623701) (xy 414.525968 -410.623701)
			(xy 414.525968 -417.366196) (xy 414.52546 -417.366196) (xy 414.52546 -417.533836) (xy 414.525117 -417.545925)
			(xy 414.517634 -417.568917) (xy 414.503411 -417.588471) (xy 414.483842 -417.602672) (xy 414.460842 -417.61013)
			(xy 414.448752 -417.610544) (xy 401.15109 -417.610544) (xy 401.138998 -417.610101) (xy 401.115995 -417.602639)
			(xy 401.096414 -417.588447) (xy 401.082164 -417.568908) (xy 401.074635 -417.545926) (xy 401.074128 -417.533836)
			(xy 326.525636 -417.533836) (xy 326.525172 -417.545885) (xy 326.517733 -417.568805) (xy 326.503592 -417.588317)
			(xy 326.484126 -417.602521) (xy 326.461229 -417.610032) (xy 326.449182 -417.610544) (xy 313.151012 -417.610544)
			(xy 313.138942 -417.610026) (xy 313.115981 -417.602571) (xy 313.096447 -417.588387) (xy 313.082251 -417.568862)
			(xy 313.074781 -417.545906) (xy 313.074304 -417.533836) (xy 313.074304 -417.379404) (xy 313.073796 -417.379404)
			(xy 273.434939 -417.379404) (xy 273.506495 -417.442585) (xy 273.605798 -417.540617) (xy 273.652996 -417.592002)
			(xy 273.691387 -417.633573) (xy 273.773525 -417.71142) (xy 273.861325 -417.782821) (xy 273.954282 -417.847364)
			(xy 274.051862 -417.90468) (xy 274.153504 -417.954438) (xy 274.258623 -417.996352) (xy 274.366616 -418.030181)
			(xy 274.476862 -418.055732) (xy 274.588726 -418.072856) (xy 274.701566 -418.081457) (xy 274.75815 -418.081968)
			(xy 465.600034 -418.081968) (xy 465.65584 -418.081445) (xy 465.767139 -418.073102) (xy 465.877504 -418.056464)
			(xy 465.986317 -418.031626) (xy 466.092969 -417.998726) (xy 466.196865 -417.957947) (xy 466.297422 -417.909518)
			(xy 466.39408 -417.85371) (xy 466.486296 -417.790835) (xy 466.573556 -417.721245) (xy 466.655372 -417.645328)
			(xy 466.731285 -417.563509) (xy 466.800872 -417.476246) (xy 466.863743 -417.384027) (xy 466.919547 -417.287367)
			(xy 466.967972 -417.186808) (xy 467.008746 -417.082911) (xy 467.041642 -416.976257) (xy 467.066476 -416.867443)
			(xy 467.083109 -416.757078) (xy 467.091447 -416.645778) (xy 467.09203 -416.589972) (xy 467.09203 -246.48795)
			(xy 467.091546 -246.4347) (xy 467.083933 -246.328473) (xy 467.068764 -246.223059) (xy 467.046116 -246.118995)
			(xy 467.016104 -246.016811) (xy 466.978881 -245.917028) (xy 466.934637 -245.820154) (xy 466.883597 -245.726681)
			(xy 466.82602 -245.637087) (xy 466.762201 -245.551827) (xy 466.692464 -245.471335) (xy 466.65515 -245.433342)
			(xy 464.026504 -242.80495) (xy 463.9771 -242.754859) (xy 463.883341 -242.649941) (xy 463.795613 -242.53993)
			(xy 463.714192 -242.425173) (xy 463.639333 -242.306031) (xy 463.571273 -242.182879) (xy 463.510225 -242.056105)
			(xy 463.456381 -241.926107) (xy 463.409911 -241.793295) (xy 463.370962 -241.658086) (xy 463.339655 -241.520905)
			(xy 463.31609 -241.382185) (xy 463.300339 -241.242362) (xy 463.292454 -241.101876) (xy 463.291936 -241.031522)
			(xy 463.291936 -87.588344) (xy 463.292417 -87.517998) (xy 463.3003 -87.377526) (xy 463.316048 -87.237717)
			(xy 463.339614 -87.099011) (xy 463.370921 -86.961846) (xy 463.409872 -86.826652) (xy 463.456344 -86.693856)
			(xy 463.510191 -86.563875) (xy 463.571243 -86.437119) (xy 463.639308 -86.313987) (xy 463.714172 -86.194865)
			(xy 463.7956 -86.08013) (xy 463.883333 -85.970143) (xy 463.977098 -85.865249) (xy 464.026504 -85.81517)
			(xy 466.65515 -83.186524) (xy 466.692477 -83.148543) (xy 466.762224 -83.068056) (xy 466.826051 -82.982799)
			(xy 466.883632 -82.893206) (xy 466.934676 -82.799733) (xy 466.978921 -82.702856) (xy 467.016141 -82.60307)
			(xy 467.046149 -82.500883) (xy 467.068789 -82.396815) (xy 467.083947 -82.291397) (xy 467.091547 -82.185167)
			(xy 467.09203 -82.131916) (xy 467.09203 -1.999996) (xy 467.091508 -1.944189) (xy 467.083167 -1.832886)
			(xy 467.066532 -1.722518) (xy 467.041695 -1.613701) (xy 467.008796 -1.507045) (xy 466.968019 -1.403146)
			(xy 466.919592 -1.302584) (xy 466.863785 -1.205923) (xy 466.800911 -1.113702) (xy 466.731321 -1.026437)
			(xy 466.655404 -0.944617) (xy 466.573586 -0.868699) (xy 466.486322 -0.799107) (xy 466.394103 -0.736231)
			(xy 466.297442 -0.680422) (xy 466.196882 -0.631993) (xy 466.092983 -0.591214) (xy 465.986328 -0.558313)
			(xy 465.877512 -0.533474) (xy 465.767144 -0.516836) (xy 465.655841 -0.508493) (xy 465.600034 -0.508)
			(xy 446.265046 -0.508) (xy 446.209237 -0.508508) (xy 446.097932 -0.516845) (xy 445.987561 -0.533478)
			(xy 445.878741 -0.558312) (xy 445.772082 -0.591209) (xy 445.668179 -0.631985) (xy 445.567615 -0.680412)
			(xy 445.47095 -0.736218) (xy 445.378726 -0.799093) (xy 445.291459 -0.868683) (xy 445.209636 -0.944601)
			(xy 445.133716 -1.026421) (xy 445.064123 -1.113686) (xy 445.001245 -1.205908) (xy 444.945435 -1.30257)
			(xy 444.897005 -1.403134) (xy 444.856226 -1.507035) (xy 444.823325 -1.613693) (xy 444.798487 -1.722512)
			(xy 444.781851 -1.832882) (xy 444.773509 -1.944187) (xy 444.77305 -1.999996) (xy 444.77305 -11.850116)
			(xy 444.77258 -11.903957) (xy 444.764897 -12.011363) (xy 444.749571 -12.117948) (xy 444.726681 -12.223168)
			(xy 444.696342 -12.326487) (xy 444.65871 -12.427378) (xy 444.613976 -12.525327) (xy 444.562368 -12.619836)
			(xy 444.504149 -12.710422) (xy 444.439617 -12.796624) (xy 444.369099 -12.878002) (xy 444.292955 -12.954143)
			(xy 444.211574 -13.024657) (xy 444.125369 -13.089186) (xy 444.034781 -13.147401) (xy 443.94027 -13.199004)
			(xy 443.842319 -13.243734) (xy 443.741426 -13.281362) (xy 443.638106 -13.311696) (xy 443.532885 -13.334583)
			(xy 443.4263 -13.349904) (xy 443.318893 -13.357583) (xy 443.265052 -13.358114) (xy 435.265068 -13.358114)
			(xy 435.211227 -13.357632) (xy 435.103821 -13.349948) (xy 434.997236 -13.334622) (xy 434.892016 -13.311731)
			(xy 434.788697 -13.281392) (xy 434.687806 -13.24376) (xy 434.589856 -13.199026) (xy 434.495347 -13.147419)
			(xy 434.40476 -13.089201) (xy 434.318558 -13.024669) (xy 434.237178 -12.954153) (xy 434.161036 -12.87801)
			(xy 434.090521 -12.79663) (xy 434.02599 -12.710426) (xy 433.967773 -12.619839) (xy 433.916167 -12.52533)
			(xy 433.871434 -12.42738) (xy 433.833803 -12.326488) (xy 433.803465 -12.223169) (xy 433.780576 -12.117948)
			(xy 433.76525 -12.011363) (xy 433.757567 -11.903957) (xy 433.75707 -11.850116) (xy 433.75707 -1.999996)
			(xy 433.756561 -1.944189) (xy 433.748219 -1.832887) (xy 433.731584 -1.72252) (xy 433.706747 -1.613704)
			(xy 433.673847 -1.507049) (xy 433.633069 -1.40315) (xy 433.584641 -1.30259) (xy 433.528833 -1.20593)
			(xy 433.465958 -1.11371) (xy 433.396367 -1.026448) (xy 433.320449 -0.944629) (xy 433.23863 -0.868713)
			(xy 433.151366 -0.799124) (xy 433.059145 -0.736251) (xy 432.962484 -0.680445) (xy 432.861922 -0.632019)
			(xy 432.758023 -0.591243) (xy 432.651367 -0.558346) (xy 432.542551 -0.533511) (xy 432.432183 -0.516877)
			(xy 432.320881 -0.508538) (xy 432.265074 -0.508) (xy 420.265098 -0.508) (xy 420.209291 -0.508522)
			(xy 420.097989 -0.516863) (xy 419.987622 -0.533498) (xy 419.878806 -0.558335) (xy 419.772151 -0.591234)
			(xy 419.668252 -0.632011) (xy 419.567691 -0.680438) (xy 419.471031 -0.736245) (xy 419.378811 -0.79912)
			(xy 419.291547 -0.86871) (xy 419.209728 -0.944627) (xy 419.133811 -1.026446) (xy 419.064221 -1.113709)
			(xy 419.001346 -1.205929) (xy 418.945539 -1.302589) (xy 418.897112 -1.40315) (xy 418.856334 -1.507049)
			(xy 418.823435 -1.613704) (xy 418.798599 -1.72252) (xy 418.781963 -1.832887) (xy 418.773622 -1.944189)
			(xy 418.773102 -1.999996) (xy 418.773102 -11.850116) (xy 418.772621 -11.903957) (xy 418.764938 -12.011364)
			(xy 418.749612 -12.117949) (xy 418.726722 -12.22317) (xy 418.696384 -12.326489) (xy 418.658752 -12.427381)
			(xy 418.614019 -12.525332) (xy 418.562412 -12.619841) (xy 418.504194 -12.710429) (xy 418.439663 -12.796632)
			(xy 418.369146 -12.878012) (xy 418.293003 -12.954154) (xy 418.211622 -13.02467) (xy 418.125419 -13.089201)
			(xy 418.034831 -13.147418) (xy 417.940321 -13.199024) (xy 417.84237 -13.243756) (xy 417.741478 -13.281387)
			(xy 417.638158 -13.311725) (xy 417.532938 -13.334614) (xy 417.426352 -13.349939) (xy 417.318945 -13.357621)
			(xy 417.265104 -13.358114) (xy 409.26512 -13.358114) (xy 409.211278 -13.357646) (xy 409.103868 -13.349965)
			(xy 408.997279 -13.334641) (xy 408.892055 -13.311753) (xy 408.788733 -13.281416) (xy 408.687837 -13.243785)
			(xy 408.589884 -13.199053) (xy 408.495371 -13.147446) (xy 408.40478 -13.089229) (xy 408.318573 -13.024697)
			(xy 408.23719 -12.95418) (xy 408.161045 -12.878036) (xy 408.090526 -12.796655) (xy 408.025992 -12.71045)
			(xy 407.967772 -12.61986) (xy 407.916164 -12.525349) (xy 407.871429 -12.427396) (xy 407.833796 -12.326502)
			(xy 407.803456 -12.223179) (xy 407.780565 -12.117956) (xy 407.765239 -12.011368) (xy 407.757556 -11.903958)
			(xy 407.757122 -11.850116) (xy 407.757122 -1.999996) (xy 407.7566 -1.944189) (xy 407.748259 -1.832886)
			(xy 407.731624 -1.722518) (xy 407.706787 -1.613702) (xy 407.673888 -1.507046) (xy 407.633111 -1.403147)
			(xy 407.584684 -1.302586) (xy 407.528877 -1.205924) (xy 407.466002 -1.113704) (xy 407.396412 -1.02644)
			(xy 407.320496 -0.94462) (xy 407.238677 -0.868702) (xy 407.151414 -0.799111) (xy 407.059194 -0.736235)
			(xy 406.962534 -0.680427) (xy 406.861973 -0.631998) (xy 406.758075 -0.591219) (xy 406.651419 -0.558319)
			(xy 406.542603 -0.53348) (xy 406.432236 -0.516843) (xy 406.320933 -0.508501) (xy 406.265126 -0.508)
			(xy 394.264896 -0.508) (xy 394.209089 -0.508522) (xy 394.097787 -0.516863) (xy 393.98742 -0.533498)
			(xy 393.878604 -0.558335) (xy 393.771949 -0.591234) (xy 393.668051 -0.632011) (xy 393.56749 -0.680439)
			(xy 393.470829 -0.736246) (xy 393.37861 -0.799121) (xy 393.291346 -0.868711) (xy 393.209528 -0.944628)
			(xy 393.133611 -1.026446) (xy 393.064021 -1.11371) (xy 393.001146 -1.205929) (xy 392.945339 -1.30259)
			(xy 392.896911 -1.403151) (xy 392.856134 -1.507049) (xy 392.823235 -1.613704) (xy 392.798398 -1.72252)
			(xy 392.781763 -1.832887) (xy 392.773422 -1.944189) (xy 392.7729 -1.999996) (xy 392.7729 -11.850116)
			(xy 392.772419 -11.903957) (xy 392.764736 -12.011364) (xy 392.74941 -12.117949) (xy 392.72652 -12.22317)
			(xy 392.696182 -12.326489) (xy 392.65855 -12.427381) (xy 392.613817 -12.525331) (xy 392.56221 -12.619841)
			(xy 392.503992 -12.710428) (xy 392.43946 -12.796631) (xy 392.368944 -12.878011) (xy 392.292801 -12.954153)
			(xy 392.21142 -13.024669) (xy 392.125217 -13.0892) (xy 392.034629 -13.147417) (xy 391.940119 -13.199023)
			(xy 391.842168 -13.243755) (xy 391.741276 -13.281386) (xy 391.637956 -13.311723) (xy 391.532735 -13.334613)
			(xy 391.42615 -13.349937) (xy 391.318743 -13.357619) (xy 391.264902 -13.358114) (xy 383.264918 -13.358114)
			(xy 383.211076 -13.357645) (xy 383.103666 -13.349965) (xy 382.997077 -13.334641) (xy 382.891854 -13.311752)
			(xy 382.788531 -13.281415) (xy 382.687636 -13.243785) (xy 382.589682 -13.199052) (xy 382.495169 -13.147445)
			(xy 382.404579 -13.089228) (xy 382.318373 -13.024696) (xy 382.236989 -12.954179) (xy 382.160844 -12.878035)
			(xy 382.090325 -12.796654) (xy 382.025791 -12.710449) (xy 381.967572 -12.61986) (xy 381.915963 -12.525348)
			(xy 381.871228 -12.427396) (xy 381.833596 -12.326501) (xy 381.803256 -12.223179) (xy 381.780365 -12.117956)
			(xy 381.765039 -12.011368) (xy 381.757356 -11.903958) (xy 381.75692 -11.850116) (xy 381.75692 -1.999996)
			(xy 381.756398 -1.944189) (xy 381.748057 -1.832886) (xy 381.731422 -1.722518) (xy 381.706585 -1.613702)
			(xy 381.673686 -1.507047) (xy 381.632909 -1.403147) (xy 381.584482 -1.302586) (xy 381.528675 -1.205925)
			(xy 381.4658 -1.113704) (xy 381.39621 -1.02644) (xy 381.320294 -0.944621) (xy 381.238475 -0.868703)
			(xy 381.151212 -0.799112) (xy 381.058992 -0.736236) (xy 380.962332 -0.680428) (xy 380.861771 -0.631999)
			(xy 380.757872 -0.59122) (xy 380.651217 -0.55832) (xy 380.542401 -0.533482) (xy 380.432034 -0.516845)
			(xy 380.320731 -0.508503) (xy 380.264924 -0.508) (xy 368.264948 -0.508) (xy 368.209139 -0.508507)
			(xy 368.097834 -0.516845) (xy 367.987463 -0.533478) (xy 367.878643 -0.558312) (xy 367.771984 -0.591209)
			(xy 367.668081 -0.631985) (xy 367.567516 -0.680411) (xy 367.470851 -0.736218) (xy 367.378627 -0.799092)
			(xy 367.29136 -0.868683) (xy 367.209537 -0.9446) (xy 367.133617 -1.02642) (xy 367.064023 -1.113685)
			(xy 367.001145 -1.205907) (xy 366.945336 -1.30257) (xy 366.896905 -1.403133) (xy 366.856126 -1.507034)
			(xy 366.823225 -1.613693) (xy 366.798387 -1.722511) (xy 366.781751 -1.832882) (xy 366.773409 -1.944187)
			(xy 366.772952 -1.999996) (xy 366.772952 -11.850116) (xy 366.772482 -11.903957) (xy 366.764799 -12.011363)
			(xy 366.749473 -12.117948) (xy 366.726583 -12.223168) (xy 366.696244 -12.326487) (xy 366.658612 -12.427378)
			(xy 366.613878 -12.525328) (xy 366.56227 -12.619836) (xy 366.504051 -12.710422) (xy 366.439519 -12.796624)
			(xy 366.369001 -12.878003) (xy 366.292858 -12.954143) (xy 366.211476 -13.024658) (xy 366.125271 -13.089187)
			(xy 366.034683 -13.147402) (xy 365.940172 -13.199005) (xy 365.842221 -13.243735) (xy 365.741328 -13.281363)
			(xy 365.638008 -13.311698) (xy 365.532787 -13.334584) (xy 365.426202 -13.349906) (xy 365.318795 -13.357584)
			(xy 365.264954 -13.358114) (xy 357.26497 -13.358114) (xy 357.211129 -13.357632) (xy 357.103723 -13.349948)
			(xy 356.997138 -13.334622) (xy 356.891918 -13.311731) (xy 356.788599 -13.281392) (xy 356.687707 -13.24376)
			(xy 356.589757 -13.199027) (xy 356.495248 -13.147419) (xy 356.404661 -13.089202) (xy 356.318459 -13.02467)
			(xy 356.237079 -12.954153) (xy 356.160937 -12.878011) (xy 356.090421 -12.796631) (xy 356.02589 -12.710427)
			(xy 355.967673 -12.61984) (xy 355.916067 -12.52533) (xy 355.871335 -12.42738) (xy 355.833703 -12.326488)
			(xy 355.803366 -12.223169) (xy 355.780476 -12.117949) (xy 355.76515 -12.011363) (xy 355.757467 -11.903957)
			(xy 355.756972 -11.850116) (xy 355.756972 -1.999996) (xy 355.756463 -1.944189) (xy 355.748121 -1.832887)
			(xy 355.731486 -1.722519) (xy 355.706649 -1.613704) (xy 355.673749 -1.507049) (xy 355.632971 -1.40315)
			(xy 355.584543 -1.30259) (xy 355.528735 -1.205929) (xy 355.46586 -1.11371) (xy 355.396269 -1.026447)
			(xy 355.320352 -0.944629) (xy 355.238532 -0.868713) (xy 355.151268 -0.799123) (xy 355.059047 -0.73625)
			(xy 354.962386 -0.680444) (xy 354.861824 -0.632017) (xy 354.757925 -0.591241) (xy 354.651269 -0.558344)
			(xy 354.542453 -0.533509) (xy 354.432085 -0.516876) (xy 354.320783 -0.508536) (xy 354.264976 -0.508)
			(xy 330.164948 -0.508) (xy 330.109139 -0.508507) (xy 329.997834 -0.516845) (xy 329.887463 -0.533478)
			(xy 329.778643 -0.558312) (xy 329.671984 -0.591209) (xy 329.568081 -0.631985) (xy 329.467516 -0.680411)
			(xy 329.370851 -0.736218) (xy 329.278627 -0.799092) (xy 329.19136 -0.868683) (xy 329.109537 -0.9446)
			(xy 329.033617 -1.02642) (xy 328.964023 -1.113685) (xy 328.901145 -1.205907) (xy 328.845336 -1.30257)
			(xy 328.796905 -1.403133) (xy 328.756126 -1.507034) (xy 328.723225 -1.613693) (xy 328.698387 -1.722511)
			(xy 328.681751 -1.832882) (xy 328.673409 -1.944187) (xy 328.672952 -1.999996) (xy 328.672952 -11.850116)
			(xy 328.672482 -11.903957) (xy 328.664799 -12.011363) (xy 328.649473 -12.117948) (xy 328.626583 -12.223168)
			(xy 328.596244 -12.326487) (xy 328.558612 -12.427378) (xy 328.513878 -12.525328) (xy 328.46227 -12.619836)
			(xy 328.404051 -12.710422) (xy 328.339519 -12.796624) (xy 328.269001 -12.878003) (xy 328.192858 -12.954143)
			(xy 328.111476 -13.024658) (xy 328.025271 -13.089187) (xy 327.934683 -13.147402) (xy 327.840172 -13.199005)
			(xy 327.742221 -13.243735) (xy 327.641328 -13.281363) (xy 327.538008 -13.311698) (xy 327.432787 -13.334584)
			(xy 327.326202 -13.349906) (xy 327.218795 -13.357584) (xy 327.164954 -13.358114) (xy 319.16497 -13.358114)
			(xy 319.111129 -13.357632) (xy 319.003723 -13.349948) (xy 318.897138 -13.334622) (xy 318.791918 -13.311731)
			(xy 318.688599 -13.281392) (xy 318.587707 -13.24376) (xy 318.489757 -13.199027) (xy 318.395248 -13.147419)
			(xy 318.304661 -13.089202) (xy 318.218459 -13.02467) (xy 318.137079 -12.954153) (xy 318.060937 -12.878011)
			(xy 317.990421 -12.796631) (xy 317.92589 -12.710427) (xy 317.867673 -12.61984) (xy 317.816067 -12.52533)
			(xy 317.771335 -12.42738) (xy 317.733703 -12.326488) (xy 317.703366 -12.223169) (xy 317.680476 -12.117949)
			(xy 317.66515 -12.011363) (xy 317.657467 -11.903957) (xy 317.656972 -11.850116) (xy 317.656972 -1.999996)
			(xy 317.656463 -1.944189) (xy 317.648121 -1.832887) (xy 317.631486 -1.722519) (xy 317.606649 -1.613704)
			(xy 317.573749 -1.507049) (xy 317.532971 -1.40315) (xy 317.484543 -1.30259) (xy 317.428735 -1.205929)
			(xy 317.36586 -1.11371) (xy 317.296269 -1.026447) (xy 317.220352 -0.944629) (xy 317.138532 -0.868713)
			(xy 317.051268 -0.799123) (xy 316.959047 -0.73625) (xy 316.862386 -0.680444) (xy 316.761824 -0.632017)
			(xy 316.657925 -0.591241) (xy 316.551269 -0.558344) (xy 316.442453 -0.533509) (xy 316.332085 -0.516876)
			(xy 316.220783 -0.508536) (xy 316.164976 -0.508) (xy 304.165 -0.508) (xy 304.109193 -0.508522) (xy 303.997891 -0.516863)
			(xy 303.887523 -0.533498) (xy 303.778708 -0.558334) (xy 303.672052 -0.591233) (xy 303.568153 -0.63201)
			(xy 303.467592 -0.680438) (xy 303.370932 -0.736245) (xy 303.278712 -0.799119) (xy 303.191448 -0.868709)
			(xy 303.109629 -0.944626) (xy 303.033712 -1.026445) (xy 302.964122 -1.113708) (xy 302.901247 -1.205928)
			(xy 302.84544 -1.302589) (xy 302.797012 -1.40315) (xy 302.756234 -1.507048) (xy 302.723335 -1.613704)
			(xy 302.698499 -1.722519) (xy 302.681863 -1.832887) (xy 302.673522 -1.944189) (xy 302.673004 -1.999996)
			(xy 302.673004 -11.850116) (xy 302.672523 -11.903957) (xy 302.66484 -12.011364) (xy 302.649514 -12.11795)
			(xy 302.626624 -12.22317) (xy 302.596286 -12.32649) (xy 302.558654 -12.427382) (xy 302.513921 -12.525332)
			(xy 302.462314 -12.619842) (xy 302.404096 -12.710429) (xy 302.339565 -12.796632) (xy 302.269048 -12.878012)
			(xy 302.192905 -12.954155) (xy 302.111525 -13.024671) (xy 302.025321 -13.089202) (xy 301.934733 -13.147419)
			(xy 301.840223 -13.199025) (xy 301.742272 -13.243758) (xy 301.64138 -13.281389) (xy 301.53806 -13.311726)
			(xy 301.43284 -13.334616) (xy 301.326254 -13.349941) (xy 301.218847 -13.357623) (xy 301.165006 -13.358114)
			(xy 293.165022 -13.358114) (xy 293.11118 -13.357646) (xy 293.00377 -13.349965) (xy 292.897181 -13.334641)
			(xy 292.791957 -13.311753) (xy 292.688634 -13.281416) (xy 292.587739 -13.243786) (xy 292.489785 -13.199053)
			(xy 292.395272 -13.147447) (xy 292.304681 -13.089229) (xy 292.218474 -13.024698) (xy 292.137091 -12.95418)
			(xy 292.060946 -12.878037) (xy 291.990426 -12.796655) (xy 291.925892 -12.71045) (xy 291.867673 -12.619861)
			(xy 291.816064 -12.525349) (xy 291.771329 -12.427396) (xy 291.733696 -12.326502) (xy 291.703356 -12.22318)
			(xy 291.680465 -12.117956) (xy 291.665139 -12.011368) (xy 291.657456 -11.903958) (xy 291.657024 -11.850116)
			(xy 291.657024 -1.999996) (xy 291.656502 -1.944189) (xy 291.648161 -1.832886) (xy 291.631526 -1.722518)
			(xy 291.606689 -1.613702) (xy 291.57379 -1.507046) (xy 291.533013 -1.403147) (xy 291.484586 -1.302585)
			(xy 291.428779 -1.205924) (xy 291.365905 -1.113703) (xy 291.296314 -1.026439) (xy 291.220398 -0.944619)
			(xy 291.138579 -0.868701) (xy 291.051316 -0.79911) (xy 290.959096 -0.736234) (xy 290.862436 -0.680426)
			(xy 290.761875 -0.631997) (xy 290.657977 -0.591218) (xy 290.551321 -0.558317) (xy 290.442505 -0.533479)
			(xy 290.332138 -0.516842) (xy 290.220835 -0.508499) (xy 290.165028 -0.508) (xy 278.165052 -0.508)
			(xy 278.109246 -0.508523) (xy 277.997947 -0.516868) (xy 277.887582 -0.533506) (xy 277.778769 -0.558345)
			(xy 277.672116 -0.591246) (xy 277.568221 -0.632024) (xy 277.467663 -0.680453) (xy 277.371005 -0.736261)
			(xy 277.278789 -0.799136) (xy 277.191528 -0.868726) (xy 277.109712 -0.944643) (xy 277.033798 -1.026461)
			(xy 276.96421 -1.113724) (xy 276.901338 -1.205943) (xy 276.845533 -1.302602) (xy 276.797107 -1.403161)
			(xy 276.756331 -1.507058) (xy 276.723433 -1.613711) (xy 276.698598 -1.722525) (xy 276.681963 -1.83289)
			(xy 276.673622 -1.94419) (xy 276.673056 -1.999996) (xy 276.673056 -11.850116) (xy 276.672586 -11.903957)
			(xy 276.664903 -12.011363) (xy 276.649577 -12.117948) (xy 276.626687 -12.223169) (xy 276.596348 -12.326487)
			(xy 276.558716 -12.427379) (xy 276.513982 -12.525328) (xy 276.462374 -12.619837) (xy 276.404156 -12.710423)
			(xy 276.339623 -12.796626) (xy 276.269105 -12.878004) (xy 276.192962 -12.954145) (xy 276.11158 -13.02466)
			(xy 276.025376 -13.089189) (xy 275.934787 -13.147404) (xy 275.840277 -13.199008) (xy 275.742325 -13.243738)
			(xy 275.641432 -13.281366) (xy 275.538112 -13.311701) (xy 275.432891 -13.334588) (xy 275.326306 -13.349909)
			(xy 275.218899 -13.357588) (xy 275.165058 -13.358114) (xy 267.165074 -13.358114) (xy 267.111233 -13.357632)
			(xy 267.003826 -13.349949) (xy 266.897241 -13.334623) (xy 266.792021 -13.311732) (xy 266.688702 -13.281393)
			(xy 266.58781 -13.243761) (xy 266.48986 -13.199028) (xy 266.39535 -13.147421) (xy 266.304763 -13.089203)
			(xy 266.21856 -13.024672) (xy 266.13718 -12.954155) (xy 266.061038 -12.878012) (xy 265.990522 -12.796632)
			(xy 265.925991 -12.710428) (xy 265.867774 -12.619841) (xy 265.816168 -12.525331) (xy 265.771435 -12.427381)
			(xy 265.733804 -12.326489) (xy 265.703466 -12.22317) (xy 265.680576 -12.117949) (xy 265.66525 -12.011364)
			(xy 265.657567 -11.903957) (xy 265.657076 -11.850116) (xy 265.657076 -1.999996) (xy 265.656567 -1.944189)
			(xy 265.648225 -1.832887) (xy 265.63159 -1.722519) (xy 265.606753 -1.613703) (xy 265.573853 -1.507048)
			(xy 265.533076 -1.403149) (xy 265.484647 -1.302589) (xy 265.42884 -1.205928) (xy 265.365964 -1.113709)
			(xy 265.296373 -1.026446) (xy 265.220456 -0.944627) (xy 265.138636 -0.868711) (xy 265.051372 -0.799121)
			(xy 264.959151 -0.736248) (xy 264.86249 -0.680441) (xy 264.761929 -0.632015) (xy 264.658029 -0.591239)
			(xy 264.551373 -0.558341) (xy 264.442557 -0.533506) (xy 264.332189 -0.516872) (xy 264.220887 -0.508532)
			(xy 264.16508 -0.508) (xy 252.165104 -0.508) (xy 252.109297 -0.508522) (xy 251.997995 -0.516862)
			(xy 251.887627 -0.533497) (xy 251.778811 -0.558333) (xy 251.672155 -0.591232) (xy 251.568256 -0.632009)
			(xy 251.467695 -0.680436) (xy 251.371034 -0.736243) (xy 251.278814 -0.799118) (xy 251.19155 -0.868708)
			(xy 251.10973 -0.944625) (xy 251.033813 -1.026444) (xy 250.964222 -1.113707) (xy 250.901348 -1.205927)
			(xy 250.84554 -1.302588) (xy 250.797112 -1.403149) (xy 250.756335 -1.507047) (xy 250.723435 -1.613703)
			(xy 250.698599 -1.722519) (xy 250.681963 -1.832887) (xy 250.673622 -1.944189) (xy 250.673108 -1.999996)
			(xy 250.673108 -11.850116) (xy 250.672627 -11.903957) (xy 250.664944 -12.011364) (xy 250.649618 -12.11795)
			(xy 250.626728 -12.223171) (xy 250.59639 -12.32649) (xy 250.558758 -12.427382) (xy 250.514025 -12.525333)
			(xy 250.462418 -12.619843) (xy 250.4042 -12.71043) (xy 250.339669 -12.796633) (xy 250.269152 -12.878014)
			(xy 250.193009 -12.954156) (xy 250.111629 -13.024673) (xy 250.025425 -13.089204) (xy 249.934837 -13.147421)
			(xy 249.840327 -13.199027) (xy 249.742377 -13.24376) (xy 249.641484 -13.281392) (xy 249.538165 -13.311729)
			(xy 249.432944 -13.334619) (xy 249.326358 -13.349944) (xy 249.218951 -13.357627) (xy 249.16511 -13.358114)
			(xy 241.164872 -13.358114) (xy 241.111035 -13.357619) (xy 241.003638 -13.34991) (xy 240.897064 -13.334562)
			(xy 240.791856 -13.311652) (xy 240.688549 -13.281298) (xy 240.58767 -13.243654) (xy 240.489733 -13.198912)
			(xy 240.395235 -13.1473) (xy 240.304659 -13.08908) (xy 240.218466 -13.024548) (xy 240.137093 -12.954035)
			(xy 240.060957 -12.877898) (xy 239.990444 -12.796525) (xy 239.925914 -12.710331) (xy 239.867694 -12.619754)
			(xy 239.816083 -12.525256) (xy 239.771341 -12.427319) (xy 239.733698 -12.326439) (xy 239.703345 -12.223133)
			(xy 239.680436 -12.117924) (xy 239.665089 -12.01135) (xy 239.657381 -11.903953) (xy 239.656874 -11.850116)
			(xy 239.656874 -1.999996) (xy 239.656365 -1.944189) (xy 239.648023 -1.832887) (xy 239.631388 -1.722519)
			(xy 239.606551 -1.613704) (xy 239.573651 -1.507048) (xy 239.532873 -1.40315) (xy 239.484445 -1.302589)
			(xy 239.428638 -1.205929) (xy 239.365762 -1.113709) (xy 239.296171 -1.026446) (xy 239.220254 -0.944628)
			(xy 239.138434 -0.868712) (xy 239.05117 -0.799122) (xy 238.958949 -0.736249) (xy 238.862288 -0.680443)
			(xy 238.761726 -0.632016) (xy 238.657827 -0.59124) (xy 238.551171 -0.558343) (xy 238.442355 -0.533507)
			(xy 238.331987 -0.516874) (xy 238.220685 -0.508534) (xy 238.164878 -0.508) (xy 214.065104 -0.508)
			(xy 214.009297 -0.508522) (xy 213.897995 -0.516862) (xy 213.787627 -0.533497) (xy 213.678811 -0.558333)
			(xy 213.572155 -0.591232) (xy 213.468256 -0.632009) (xy 213.367695 -0.680436) (xy 213.271034 -0.736243)
			(xy 213.178814 -0.799118) (xy 213.09155 -0.868708) (xy 213.00973 -0.944625) (xy 212.933813 -1.026444)
			(xy 212.864222 -1.113707) (xy 212.801348 -1.205927) (xy 212.74554 -1.302588) (xy 212.697112 -1.403149)
			(xy 212.656335 -1.507047) (xy 212.623435 -1.613703) (xy 212.598599 -1.722519) (xy 212.581963 -1.832887)
			(xy 212.573622 -1.944189) (xy 212.573108 -1.999996) (xy 212.573108 -11.850116) (xy 212.572627 -11.903957)
			(xy 212.564944 -12.011364) (xy 212.549618 -12.11795) (xy 212.526728 -12.223171) (xy 212.49639 -12.32649)
			(xy 212.458758 -12.427382) (xy 212.414025 -12.525333) (xy 212.362418 -12.619843) (xy 212.3042 -12.71043)
			(xy 212.239669 -12.796633) (xy 212.169152 -12.878014) (xy 212.093009 -12.954156) (xy 212.011629 -13.024673)
			(xy 211.925425 -13.089204) (xy 211.834837 -13.147421) (xy 211.740327 -13.199027) (xy 211.642377 -13.24376)
			(xy 211.541484 -13.281392) (xy 211.438165 -13.311729) (xy 211.332944 -13.334619) (xy 211.226358 -13.349944)
			(xy 211.118951 -13.357627) (xy 211.06511 -13.358114) (xy 203.064872 -13.358114) (xy 203.011035 -13.357619)
			(xy 202.903638 -13.34991) (xy 202.797064 -13.334562) (xy 202.691856 -13.311652) (xy 202.588549 -13.281298)
			(xy 202.48767 -13.243654) (xy 202.389733 -13.198912) (xy 202.295235 -13.1473) (xy 202.204659 -13.08908)
			(xy 202.118466 -13.024548) (xy 202.037093 -12.954035) (xy 201.960957 -12.877898) (xy 201.890444 -12.796525)
			(xy 201.825914 -12.710331) (xy 201.767694 -12.619754) (xy 201.716083 -12.525256) (xy 201.671341 -12.427319)
			(xy 201.633698 -12.326439) (xy 201.603345 -12.223133) (xy 201.580436 -12.117924) (xy 201.565089 -12.01135)
			(xy 201.557381 -11.903953) (xy 201.556874 -11.850116) (xy 201.556874 -1.999996) (xy 201.556365 -1.944189)
			(xy 201.548023 -1.832887) (xy 201.531388 -1.722519) (xy 201.506551 -1.613704) (xy 201.473651 -1.507048)
			(xy 201.432873 -1.40315) (xy 201.384445 -1.302589) (xy 201.328638 -1.205929) (xy 201.265762 -1.113709)
			(xy 201.196171 -1.026446) (xy 201.120254 -0.944628) (xy 201.038434 -0.868712) (xy 200.95117 -0.799122)
			(xy 200.858949 -0.736249) (xy 200.762288 -0.680443) (xy 200.661726 -0.632016) (xy 200.557827 -0.59124)
			(xy 200.451171 -0.558343) (xy 200.342355 -0.533507) (xy 200.231987 -0.516874) (xy 200.120685 -0.508534)
			(xy 200.064878 -0.508) (xy 188.064902 -0.508) (xy 188.009095 -0.508522) (xy 187.897793 -0.516862)
			(xy 187.787425 -0.533498) (xy 187.678609 -0.558334) (xy 187.571954 -0.591233) (xy 187.468055 -0.63201)
			(xy 187.367494 -0.680437) (xy 187.270833 -0.736244) (xy 187.178613 -0.799118) (xy 187.091349 -0.868709)
			(xy 187.00953 -0.944625) (xy 186.933613 -1.026444) (xy 186.864022 -1.113708) (xy 186.801147 -1.205928)
			(xy 186.74534 -1.302588) (xy 186.696912 -1.403149) (xy 186.656135 -1.507048) (xy 186.623235 -1.613703)
			(xy 186.598399 -1.722519) (xy 186.581763 -1.832887) (xy 186.573422 -1.944189) (xy 186.572906 -1.999996)
			(xy 186.572906 -11.850116) (xy 186.572425 -11.903957) (xy 186.564742 -12.011364) (xy 186.549416 -12.11795)
			(xy 186.526526 -12.22317) (xy 186.496188 -12.32649) (xy 186.458556 -12.427382) (xy 186.413823 -12.525332)
			(xy 186.362216 -12.619842) (xy 186.303998 -12.71043) (xy 186.239467 -12.796633) (xy 186.16895 -12.878013)
			(xy 186.092807 -12.954155) (xy 186.011427 -13.024672) (xy 185.925223 -13.089203) (xy 185.834635 -13.14742)
			(xy 185.740125 -13.199026) (xy 185.642175 -13.243759) (xy 185.541282 -13.28139) (xy 185.437963 -13.311728)
			(xy 185.332742 -13.334618) (xy 185.226156 -13.349943) (xy 185.118749 -13.357625) (xy 185.064908 -13.358114)
			(xy 177.064924 -13.358114) (xy 177.011082 -13.357646) (xy 176.903671 -13.349965) (xy 176.797083 -13.334642)
			(xy 176.691859 -13.311753) (xy 176.588536 -13.281417) (xy 176.48764 -13.243786) (xy 176.389686 -13.199054)
			(xy 176.295173 -13.147447) (xy 176.204582 -13.08923) (xy 176.118375 -13.024698) (xy 176.036992 -12.954181)
			(xy 175.960846 -12.878038) (xy 175.890327 -12.796656) (xy 175.825793 -12.710451) (xy 175.767573 -12.619862)
			(xy 175.715964 -12.52535) (xy 175.671229 -12.427397) (xy 175.633596 -12.326502) (xy 175.603257 -12.22318)
			(xy 175.580365 -12.117957) (xy 175.565039 -12.011368) (xy 175.557356 -11.903958) (xy 175.556926 -11.850116)
			(xy 175.556926 -1.999996) (xy 175.556404 -1.944189) (xy 175.548063 -1.832886) (xy 175.531428 -1.722518)
			(xy 175.506591 -1.613702) (xy 175.473692 -1.507046) (xy 175.432915 -1.403146) (xy 175.384488 -1.302585)
			(xy 175.328681 -1.205923) (xy 175.265807 -1.113703) (xy 175.196217 -1.026438) (xy 175.1203 -0.944618)
			(xy 175.038481 -0.8687) (xy 174.951218 -0.799109) (xy 174.858999 -0.736233) (xy 174.762338 -0.680424)
			(xy 174.661777 -0.631995) (xy 174.557879 -0.591216) (xy 174.451223 -0.558316) (xy 174.342408 -0.533477)
			(xy 174.23204 -0.51684) (xy 174.120737 -0.508497) (xy 174.06493 -0.508) (xy 162.064954 -0.508) (xy 162.009148 -0.508523)
			(xy 161.897848 -0.516867) (xy 161.787483 -0.533505) (xy 161.67867 -0.558344) (xy 161.572018 -0.591245)
			(xy 161.468122 -0.632024) (xy 161.367564 -0.680453) (xy 161.270907 -0.73626) (xy 161.17869 -0.799135)
			(xy 161.091429 -0.868726) (xy 161.009613 -0.944642) (xy 160.933698 -1.026461) (xy 160.86411 -1.113723)
			(xy 160.801238 -1.205942) (xy 160.745433 -1.302601) (xy 160.697007 -1.403161) (xy 160.656231 -1.507058)
			(xy 160.623333 -1.613711) (xy 160.598498 -1.722525) (xy 160.581863 -1.83289) (xy 160.573522 -1.94419)
			(xy 160.572958 -1.999996) (xy 160.572958 -11.850116) (xy 160.572488 -11.903957) (xy 160.564805 -12.011363)
			(xy 160.549479 -12.117949) (xy 160.526589 -12.223169) (xy 160.49625 -12.326488) (xy 160.458618 -12.427379)
			(xy 160.413884 -12.525329) (xy 160.362276 -12.619838) (xy 160.304058 -12.710424) (xy 160.239525 -12.796626)
			(xy 160.169008 -12.878005) (xy 160.092864 -12.954146) (xy 160.011483 -13.02466) (xy 159.925278 -13.08919)
			(xy 159.834689 -13.147405) (xy 159.740179 -13.199009) (xy 159.642227 -13.243739) (xy 159.541335 -13.281368)
			(xy 159.438014 -13.311702) (xy 159.332793 -13.334589) (xy 159.226208 -13.349911) (xy 159.118801 -13.35759)
			(xy 159.06496 -13.358114) (xy 151.064976 -13.358114) (xy 151.011135 -13.357633) (xy 150.903728 -13.349949)
			(xy 150.797143 -13.334623) (xy 150.691922 -13.311732) (xy 150.588603 -13.281394) (xy 150.487711 -13.243762)
			(xy 150.389761 -13.199028) (xy 150.295252 -13.147421) (xy 150.204664 -13.089204) (xy 150.118461 -13.024672)
			(xy 150.037081 -12.954156) (xy 149.960939 -12.878013) (xy 149.890423 -12.796633) (xy 149.825892 -12.710429)
			(xy 149.767674 -12.619842) (xy 149.716068 -12.525332) (xy 149.671335 -12.427381) (xy 149.633704 -12.326489)
			(xy 149.603366 -12.22317) (xy 149.580476 -12.117949) (xy 149.56515 -12.011364) (xy 149.557467 -11.903957)
			(xy 149.556978 -11.850116) (xy 149.556978 -1.999996) (xy 149.556469 -1.944189) (xy 149.548127 -1.832887)
			(xy 149.531492 -1.722519) (xy 149.506655 -1.613703) (xy 149.473755 -1.507048) (xy 149.432978 -1.403149)
			(xy 149.384549 -1.302588) (xy 149.328742 -1.205928) (xy 149.265867 -1.113708) (xy 149.196276 -1.026445)
			(xy 149.120358 -0.944627) (xy 149.038538 -0.86871) (xy 148.951274 -0.79912) (xy 148.859054 -0.736247)
			(xy 148.762392 -0.68044) (xy 148.661831 -0.632014) (xy 148.557931 -0.591237) (xy 148.451276 -0.55834)
			(xy 148.342459 -0.533504) (xy 148.232091 -0.51687) (xy 148.120789 -0.508531) (xy 148.064982 -0.508)
			(xy 136.065006 -0.508) (xy 136.009198 -0.508509) (xy 135.897895 -0.51685) (xy 135.787526 -0.533485)
			(xy 135.678709 -0.558321) (xy 135.572052 -0.59122) (xy 135.468152 -0.631997) (xy 135.36759 -0.680425)
			(xy 135.270928 -0.736232) (xy 135.178707 -0.799107) (xy 135.091442 -0.868698) (xy 135.009622 -0.944615)
			(xy 134.933704 -1.026435) (xy 134.864113 -1.113699) (xy 134.801237 -1.20592) (xy 134.745429 -1.302581)
			(xy 134.697001 -1.403143) (xy 134.656223 -1.507043) (xy 134.623324 -1.613699) (xy 134.598486 -1.722516)
			(xy 134.581851 -1.832885) (xy 134.573509 -1.944188) (xy 134.57301 -1.999996) (xy 134.57301 -11.850116)
			(xy 134.572529 -11.903957) (xy 134.564846 -12.011364) (xy 134.54952 -12.11795) (xy 134.52663 -12.223171)
			(xy 134.496292 -12.32649) (xy 134.45866 -12.427383) (xy 134.413927 -12.525333) (xy 134.36232 -12.619843)
			(xy 134.304102 -12.710431) (xy 134.239571 -12.796634) (xy 134.169054 -12.878014) (xy 134.092911 -12.954157)
			(xy 134.011531 -13.024673) (xy 133.925327 -13.089205) (xy 133.83474 -13.147422) (xy 133.74023 -13.199029)
			(xy 133.642279 -13.243762) (xy 133.541387 -13.281393) (xy 133.438067 -13.311731) (xy 133.332846 -13.334621)
			(xy 133.22626 -13.349946) (xy 133.118853 -13.357629) (xy 133.065012 -13.358114) (xy 125.065028 -13.358114)
			(xy 125.011186 -13.357646) (xy 124.903775 -13.349966) (xy 124.797186 -13.334642) (xy 124.691962 -13.311754)
			(xy 124.588639 -13.281418) (xy 124.487743 -13.243787) (xy 124.389789 -13.199055) (xy 124.295275 -13.147449)
			(xy 124.204684 -13.089231) (xy 124.118477 -13.0247) (xy 124.037093 -12.954182) (xy 123.960948 -12.878039)
			(xy 123.890428 -12.796657) (xy 123.825894 -12.710452) (xy 123.767674 -12.619863) (xy 123.716065 -12.525351)
			(xy 123.671329 -12.427398) (xy 123.633696 -12.326503) (xy 123.603357 -12.223181) (xy 123.580465 -12.117957)
			(xy 123.565139 -12.011369) (xy 123.557456 -11.903958) (xy 123.55703 -11.850116) (xy 123.55703 -1.999996)
			(xy 123.556508 -1.944189) (xy 123.548167 -1.832886) (xy 123.531532 -1.722518) (xy 123.506695 -1.613701)
			(xy 123.473796 -1.507045) (xy 123.433019 -1.403146) (xy 123.384592 -1.302584) (xy 123.328785 -1.205923)
			(xy 123.265911 -1.113702) (xy 123.196321 -1.026437) (xy 123.120404 -0.944617) (xy 123.038586 -0.868699)
			(xy 122.951322 -0.799107) (xy 122.859103 -0.736231) (xy 122.762442 -0.680422) (xy 122.661882 -0.631993)
			(xy 122.557983 -0.591214) (xy 122.451328 -0.558313) (xy 122.342512 -0.533474) (xy 122.232144 -0.516836)
			(xy 122.120841 -0.508493) (xy 122.065034 -0.508) (xy 97.965006 -0.508) (xy 97.909198 -0.508509) (xy 97.797895 -0.51685)
			(xy 97.687526 -0.533485) (xy 97.578709 -0.558321) (xy 97.472052 -0.59122) (xy 97.368152 -0.631997)
			(xy 97.26759 -0.680425) (xy 97.170928 -0.736232) (xy 97.078707 -0.799107) (xy 96.991442 -0.868698)
			(xy 96.909622 -0.944615) (xy 96.833704 -1.026435) (xy 96.764113 -1.113699) (xy 96.701237 -1.20592)
			(xy 96.645429 -1.302581) (xy 96.597001 -1.403143) (xy 96.556223 -1.507043) (xy 96.523324 -1.613699)
			(xy 96.498486 -1.722516) (xy 96.481851 -1.832885) (xy 96.473509 -1.944188) (xy 96.47301 -1.999996)
			(xy 96.47301 -11.850116) (xy 96.472529 -11.903957) (xy 96.464846 -12.011364) (xy 96.44952 -12.11795)
			(xy 96.42663 -12.223171) (xy 96.396292 -12.32649) (xy 96.35866 -12.427383) (xy 96.313927 -12.525333)
			(xy 96.26232 -12.619843) (xy 96.204102 -12.710431) (xy 96.139571 -12.796634) (xy 96.069054 -12.878014)
			(xy 95.992911 -12.954157) (xy 95.911531 -13.024673) (xy 95.825327 -13.089205) (xy 95.73474 -13.147422)
			(xy 95.64023 -13.199029) (xy 95.542279 -13.243762) (xy 95.441387 -13.281393) (xy 95.338067 -13.311731)
			(xy 95.232846 -13.334621) (xy 95.12626 -13.349946) (xy 95.018853 -13.357629) (xy 94.965012 -13.358114)
			(xy 86.965028 -13.358114) (xy 86.911186 -13.357646) (xy 86.803775 -13.349966) (xy 86.697186 -13.334642)
			(xy 86.591962 -13.311754) (xy 86.488639 -13.281418) (xy 86.387743 -13.243787) (xy 86.289789 -13.199055)
			(xy 86.195275 -13.147449) (xy 86.104684 -13.089231) (xy 86.018477 -13.0247) (xy 85.937093 -12.954182)
			(xy 85.860948 -12.878039) (xy 85.790428 -12.796657) (xy 85.725894 -12.710452) (xy 85.667674 -12.619863)
			(xy 85.616065 -12.525351) (xy 85.571329 -12.427398) (xy 85.533696 -12.326503) (xy 85.503357 -12.223181)
			(xy 85.480465 -12.117957) (xy 85.465139 -12.011369) (xy 85.457456 -11.903958) (xy 85.45703 -11.850116)
			(xy 85.45703 -1.999996) (xy 85.456508 -1.944189) (xy 85.448167 -1.832886) (xy 85.431532 -1.722518)
			(xy 85.406695 -1.613701) (xy 85.373796 -1.507045) (xy 85.333019 -1.403146) (xy 85.284592 -1.302584)
			(xy 85.228785 -1.205923) (xy 85.165911 -1.113702) (xy 85.096321 -1.026437) (xy 85.020404 -0.944617)
			(xy 84.938586 -0.868699) (xy 84.851322 -0.799107) (xy 84.759103 -0.736231) (xy 84.662442 -0.680422)
			(xy 84.561882 -0.631993) (xy 84.457983 -0.591214) (xy 84.351328 -0.558313) (xy 84.242512 -0.533474)
			(xy 84.132144 -0.516836) (xy 84.020841 -0.508493) (xy 83.965034 -0.508) (xy 71.965058 -0.508) (xy 71.909252 -0.508523)
			(xy 71.797952 -0.516867) (xy 71.687587 -0.533505) (xy 71.578774 -0.558343) (xy 71.472121 -0.591244)
			(xy 71.368225 -0.632023) (xy 71.267667 -0.680451) (xy 71.171009 -0.736259) (xy 71.078791 -0.799134)
			(xy 70.991531 -0.868724) (xy 70.909714 -0.944641) (xy 70.8338 -1.026459) (xy 70.764211 -1.113722)
			(xy 70.701339 -1.205941) (xy 70.645534 -1.3026) (xy 70.597107 -1.40316) (xy 70.556331 -1.507057)
			(xy 70.523434 -1.61371) (xy 70.498598 -1.722524) (xy 70.481963 -1.83289) (xy 70.473622 -1.94419)
			(xy 70.473062 -1.999996) (xy 70.473062 -11.850116) (xy 70.472592 -11.903957) (xy 70.464909 -12.011364)
			(xy 70.449583 -12.117949) (xy 70.426693 -12.223169) (xy 70.396354 -12.326488) (xy 70.358722 -12.42738)
			(xy 70.313988 -12.52533) (xy 70.26238 -12.619839) (xy 70.204162 -12.710425) (xy 70.139629 -12.796627)
			(xy 70.069112 -12.878006) (xy 69.992968 -12.954147) (xy 69.911587 -13.024662) (xy 69.825382 -13.089192)
			(xy 69.734794 -13.147407) (xy 69.640283 -13.199011) (xy 69.542332 -13.243742) (xy 69.441439 -13.28137)
			(xy 69.338119 -13.311705) (xy 69.232898 -13.334592) (xy 69.126312 -13.349915) (xy 69.018905 -13.357594)
			(xy 68.965064 -13.358114) (xy 60.96508 -13.358114) (xy 60.911239 -13.357633) (xy 60.803832 -13.349949)
			(xy 60.697246 -13.334624) (xy 60.592026 -13.311733) (xy 60.488706 -13.281395) (xy 60.387814 -13.243763)
			(xy 60.289864 -13.19903) (xy 60.195354 -13.147423) (xy 60.104766 -13.089205) (xy 60.018563 -13.024674)
			(xy 59.937183 -12.954157) (xy 59.86104 -12.878014) (xy 59.790524 -12.796634) (xy 59.725992 -12.71043)
			(xy 59.667775 -12.619843) (xy 59.616169 -12.525333) (xy 59.571435 -12.427382) (xy 59.533804 -12.32649)
			(xy 59.503466 -12.22317) (xy 59.480576 -12.11795) (xy 59.46525 -12.011364) (xy 59.457567 -11.903957)
			(xy 59.457082 -11.850116) (xy 59.457082 -1.999996) (xy 59.456573 -1.944189) (xy 59.448231 -1.832886)
			(xy 59.431596 -1.722519) (xy 59.406759 -1.613703) (xy 59.373859 -1.507047) (xy 59.333082 -1.403148)
			(xy 59.284653 -1.302588) (xy 59.228846 -1.205927) (xy 59.165971 -1.113707) (xy 59.09638 -1.026444)
			(xy 59.020462 -0.944625) (xy 58.938643 -0.868709) (xy 58.851378 -0.799119) (xy 58.759158 -0.736245)
			(xy 58.662496 -0.680438) (xy 58.561935 -0.632011) (xy 58.458036 -0.591235) (xy 58.35138 -0.558337)
			(xy 58.242564 -0.533501) (xy 58.132196 -0.516867) (xy 58.020893 -0.508527) (xy 57.965086 -0.508)
			(xy 45.96511 -0.508) (xy 45.909302 -0.508509) (xy 45.797999 -0.516849) (xy 45.68763 -0.533484) (xy 45.578812 -0.55832)
			(xy 45.472155 -0.591219) (xy 45.368255 -0.631996) (xy 45.267693 -0.680423) (xy 45.17103 -0.736231)
			(xy 45.078809 -0.799106) (xy 44.991544 -0.868696) (xy 44.909724 -0.944614) (xy 44.833805 -1.026433)
			(xy 44.764214 -1.113698) (xy 44.701338 -1.205919) (xy 44.64553 -1.30258) (xy 44.597101 -1.403142)
			(xy 44.556323 -1.507042) (xy 44.523424 -1.613699) (xy 44.498587 -1.722516) (xy 44.481951 -1.832885)
			(xy 44.473609 -1.944188) (xy 44.473114 -1.999996) (xy 44.473114 -11.850116) (xy 44.472633 -11.903957)
			(xy 44.46495 -12.011364) (xy 44.449624 -12.11795) (xy 44.426734 -12.223171) (xy 44.396396 -12.326491)
			(xy 44.358764 -12.427383) (xy 44.314031 -12.525334) (xy 44.262424 -12.619844) (xy 44.204207 -12.710432)
			(xy 44.139675 -12.796635) (xy 44.069158 -12.878016) (xy 43.993016 -12.954158) (xy 43.911635 -13.024675)
			(xy 43.825432 -13.089207) (xy 43.734844 -13.147424) (xy 43.640334 -13.199031) (xy 43.542383 -13.243764)
			(xy 43.441491 -13.281396) (xy 43.338171 -13.311734) (xy 43.23295 -13.334624) (xy 43.126364 -13.34995)
			(xy 43.018957 -13.357633) (xy 42.965116 -13.358114) (xy 34.964878 -13.358114) (xy 34.911037 -13.357633)
			(xy 34.80363 -13.349949) (xy 34.697045 -13.334623) (xy 34.591824 -13.311733) (xy 34.488505 -13.281394)
			(xy 34.387613 -13.243762) (xy 34.289662 -13.199029) (xy 34.195153 -13.147422) (xy 34.104565 -13.089205)
			(xy 34.018362 -13.024673) (xy 33.936982 -12.954156) (xy 33.86084 -12.878014) (xy 33.790323 -12.796633)
			(xy 33.725792 -12.71043) (xy 33.667575 -12.619842) (xy 33.615968 -12.525332) (xy 33.571235 -12.427382)
			(xy 33.533604 -12.32649) (xy 33.503266 -12.22317) (xy 33.480376 -12.11795) (xy 33.46505 -12.011364)
			(xy 33.457367 -11.903957) (xy 33.45688 -11.850116) (xy 33.45688 -1.999996) (xy 33.456371 -1.944189)
			(xy 33.448029 -1.832887) (xy 33.431394 -1.722519) (xy 33.406557 -1.613703) (xy 33.373657 -1.507048)
			(xy 33.33288 -1.403149) (xy 33.284451 -1.302588) (xy 33.228644 -1.205927) (xy 33.165769 -1.113708)
			(xy 33.096178 -1.026444) (xy 33.02026 -0.944626) (xy 32.93844 -0.868709) (xy 32.851176 -0.79912)
			(xy 32.758956 -0.736246) (xy 32.662294 -0.680439) (xy 32.561733 -0.632012) (xy 32.457834 -0.591236)
			(xy 32.351178 -0.558338) (xy 32.242361 -0.533503) (xy 32.131994 -0.516868) (xy 32.020691 -0.508529)
			(xy 31.964884 -0.508) (xy 19.964908 -0.508) (xy 19.9091 -0.508509) (xy 19.797797 -0.516849) (xy 19.687428 -0.533484)
			(xy 19.578611 -0.55832) (xy 19.471954 -0.591219) (xy 19.368054 -0.631996) (xy 19.267491 -0.680424)
			(xy 19.170829 -0.736231) (xy 19.078608 -0.799106) (xy 18.991343 -0.868697) (xy 18.909523 -0.944614)
			(xy 18.833605 -1.026434) (xy 18.764013 -1.113698) (xy 18.701138 -1.205919) (xy 18.64533 -1.302581)
			(xy 18.596901 -1.403143) (xy 18.556123 -1.507043) (xy 18.523224 -1.613699) (xy 18.498386 -1.722516)
			(xy 18.481751 -1.832885) (xy 18.473409 -1.944188) (xy 18.472912 -1.999996) (xy 18.472912 -11.850116)
			(xy 18.472443 -11.903958) (xy 18.464761 -12.011366) (xy 18.449437 -12.117953) (xy 18.426547 -12.223176)
			(xy 18.396209 -12.326497) (xy 18.358578 -12.42739) (xy 18.313845 -12.525342) (xy 18.262238 -12.619854)
			(xy 18.20402 -12.710442) (xy 18.139488 -12.796647) (xy 18.068971 -12.878029) (xy 17.992827 -12.954172)
			(xy 17.911446 -13.024689) (xy 17.825241 -13.089221) (xy 17.734652 -13.147439) (xy 17.640141 -13.199046)
			(xy 17.542189 -13.243779) (xy 17.441295 -13.28141) (xy 17.337974 -13.311748) (xy 17.232751 -13.334637)
			(xy 17.126164 -13.349961) (xy 17.018756 -13.357643) (xy 16.964914 -13.358114) (xy 8.96493 -13.358114)
			(xy 8.911089 -13.357645) (xy 8.80368 -13.349963) (xy 8.697093 -13.334638) (xy 8.591871 -13.311748)
			(xy 8.48855 -13.28141) (xy 8.387656 -13.243779) (xy 8.289705 -13.199046) (xy 8.195194 -13.147439)
			(xy 8.104605 -13.089221) (xy 8.0184 -13.024689) (xy 7.937019 -12.954171) (xy 7.860876 -12.878028)
			(xy 7.790359 -12.796646) (xy 7.725827 -12.710442) (xy 7.667609 -12.619853) (xy 7.616002 -12.525342)
			(xy 7.57127 -12.42739) (xy 7.533638 -12.326496) (xy 7.503301 -12.223175) (xy 7.480411 -12.117953)
			(xy 7.465087 -12.011366) (xy 7.457405 -11.903957) (xy 7.456932 -11.850116) (xy 7.456932 -1.999996)
			(xy 7.45641 -1.944189) (xy 7.448069 -1.832887) (xy 7.431434 -1.72252) (xy 7.406597 -1.613704) (xy 7.373698 -1.507049)
			(xy 7.332921 -1.40315) (xy 7.284493 -1.30259) (xy 7.228686 -1.205929) (xy 7.165812 -1.113709) (xy 7.096221 -1.026446)
			(xy 7.020305 -0.944627) (xy 6.938486 -0.86871) (xy 6.851222 -0.79912) (xy 6.759003 -0.736245) (xy 6.662342 -0.680438)
			(xy 6.561782 -0.63201) (xy 6.457883 -0.591233) (xy 6.351228 -0.558334) (xy 6.242412 -0.533497) (xy 6.132045 -0.516861)
			(xy 6.020743 -0.50852) (xy 5.964936 -0.508) (xy 1.999996 -0.508) (xy 1.944189 -0.508522) (xy 1.832887 -0.516863)
			(xy 1.72252 -0.533498) (xy 1.613704 -0.558335) (xy 1.507049 -0.591234) (xy 1.403151 -0.632011) (xy 1.30259 -0.680439)
			(xy 1.205929 -0.736246) (xy 1.11371 -0.799121) (xy 1.026446 -0.868711) (xy 0.944628 -0.944628) (xy 0.868711 -1.026446)
			(xy 0.799121 -1.11371) (xy 0.736246 -1.205929) (xy 0.680439 -1.30259) (xy 0.632011 -1.403151) (xy 0.591234 -1.507049)
			(xy 0.558335 -1.613704) (xy 0.533498 -1.72252) (xy 0.516863 -1.832887) (xy 0.508522 -1.944189) (xy 0.508 -1.999996)
			(xy 0.508 -15.200122) (xy 459.541372 -15.200122) (xy 459.541372 -13.599922) (xy 459.54188 -13.535242)
			(xy 459.550003 -13.406136) (xy 459.566216 -13.277796) (xy 459.590456 -13.150726) (xy 459.622626 -13.02543)
			(xy 459.662601 -12.9024) (xy 459.710222 -12.782124) (xy 459.765301 -12.665075) (xy 459.827621 -12.551715)
			(xy 459.896936 -12.442492) (xy 459.972972 -12.337837) (xy 460.05543 -12.238163) (xy 460.143983 -12.143863)
			(xy 460.238283 -12.05531) (xy 460.337957 -11.972852) (xy 460.442612 -11.896816) (xy 460.551835 -11.827501)
			(xy 460.665195 -11.765181) (xy 460.782244 -11.710102) (xy 460.90252 -11.662481) (xy 461.02555 -11.622506)
			(xy 461.150846 -11.590336) (xy 461.277916 -11.566096) (xy 461.406256 -11.549883) (xy 461.535362 -11.54176)
			(xy 461.664722 -11.54176) (xy 461.793828 -11.549883) (xy 461.922168 -11.566096) (xy 462.049238 -11.590336)
			(xy 462.174534 -11.622506) (xy 462.297564 -11.662481) (xy 462.41784 -11.710102) (xy 462.534889 -11.765181)
			(xy 462.648249 -11.827501) (xy 462.757472 -11.896816) (xy 462.862127 -11.972852) (xy 462.961801 -12.05531)
			(xy 463.056101 -12.143863) (xy 463.144654 -12.238163) (xy 463.227112 -12.337837) (xy 463.303148 -12.442492)
			(xy 463.372463 -12.551715) (xy 463.434783 -12.665075) (xy 463.489862 -12.782124) (xy 463.537483 -12.9024)
			(xy 463.577458 -13.02543) (xy 463.609628 -13.150726) (xy 463.633868 -13.277796) (xy 463.650081 -13.406136)
			(xy 463.658204 -13.535242) (xy 463.658712 -13.599922) (xy 463.658712 -15.200122) (xy 463.658204 -15.264802)
			(xy 463.650081 -15.393908) (xy 463.633868 -15.522248) (xy 463.609628 -15.649318) (xy 463.577458 -15.774614)
			(xy 463.537483 -15.897644) (xy 463.489862 -16.01792) (xy 463.434783 -16.134969) (xy 463.372463 -16.248329)
			(xy 463.303148 -16.357552) (xy 463.227112 -16.462207) (xy 463.144654 -16.561881) (xy 463.056101 -16.656181)
			(xy 462.961801 -16.744734) (xy 462.862127 -16.827192) (xy 462.757472 -16.903228) (xy 462.648249 -16.972543)
			(xy 462.534889 -17.034863) (xy 462.41784 -17.089942) (xy 462.297564 -17.137563) (xy 462.174534 -17.177538)
			(xy 462.049238 -17.209708) (xy 461.922168 -17.233948) (xy 461.793828 -17.250161) (xy 461.664722 -17.258284)
			(xy 461.535362 -17.258284) (xy 461.406256 -17.250161) (xy 461.277916 -17.233948) (xy 461.150846 -17.209708)
			(xy 461.02555 -17.177538) (xy 460.90252 -17.137563) (xy 460.782244 -17.089942) (xy 460.665195 -17.034863)
			(xy 460.551835 -16.972543) (xy 460.442612 -16.903228) (xy 460.337957 -16.827192) (xy 460.238283 -16.744734)
			(xy 460.143983 -16.656181) (xy 460.05543 -16.561881) (xy 459.972972 -16.462207) (xy 459.896936 -16.357552)
			(xy 459.827621 -16.248329) (xy 459.765301 -16.134969) (xy 459.710222 -16.01792) (xy 459.662601 -15.897644)
			(xy 459.622626 -15.774614) (xy 459.590456 -15.649318) (xy 459.566216 -15.522248) (xy 459.550003 -15.393908)
			(xy 459.54188 -15.264802) (xy 459.541372 -15.200122) (xy 0.508 -15.200122) (xy 0.508 -16.969994)
			(xy 13.748265 -16.969994) (xy 13.75227 -16.882086) (xy 13.764253 -16.794906) (xy 13.784113 -16.709177)
			(xy 13.811688 -16.625609) (xy 13.846747 -16.544895) (xy 13.889 -16.467703) (xy 13.938098 -16.394674)
			(xy 13.993634 -16.326412) (xy 14.055146 -16.263482) (xy 14.122127 -16.206408) (xy 14.19402 -16.15566)
			(xy 14.270229 -16.11166) (xy 14.350124 -16.074773) (xy 14.433043 -16.045304) (xy 14.518298 -16.023497)
			(xy 14.605182 -16.009533) (xy 14.692976 -16.003527) (xy 14.780953 -16.005531) (xy 14.868383 -16.015526)
			(xy 14.954542 -16.03343) (xy 15.038716 -16.059094) (xy 15.120207 -16.092307) (xy 15.198341 -16.132793)
			(xy 15.272469 -16.180215) (xy 15.341977 -16.234182) (xy 15.406291 -16.294247) (xy 15.464875 -16.359911)
			(xy 15.517246 -16.43063) (xy 15.562969 -16.505818) (xy 15.601666 -16.584853) (xy 15.633015 -16.667079)
			(xy 15.656757 -16.751815) (xy 15.672695 -16.838359) (xy 15.680697 -16.925994) (xy 15.681198 -16.969994)
			(xy 39.748213 -16.969994) (xy 39.752218 -16.882086) (xy 39.764201 -16.794906) (xy 39.784061 -16.709177)
			(xy 39.811636 -16.625609) (xy 39.846695 -16.544895) (xy 39.888948 -16.467703) (xy 39.938046 -16.394674)
			(xy 39.993582 -16.326412) (xy 40.055094 -16.263482) (xy 40.122075 -16.206408) (xy 40.193968 -16.15566)
			(xy 40.270177 -16.11166) (xy 40.350072 -16.074773) (xy 40.432991 -16.045304) (xy 40.518246 -16.023497)
			(xy 40.60513 -16.009533) (xy 40.692924 -16.003527) (xy 40.780901 -16.005531) (xy 40.868331 -16.015526)
			(xy 40.95449 -16.03343) (xy 41.038664 -16.059094) (xy 41.120155 -16.092307) (xy 41.198289 -16.132793)
			(xy 41.272417 -16.180215) (xy 41.341925 -16.234182) (xy 41.406239 -16.294247) (xy 41.464823 -16.359911)
			(xy 41.517194 -16.43063) (xy 41.562917 -16.505818) (xy 41.601614 -16.584853) (xy 41.632963 -16.667079)
			(xy 41.656705 -16.751815) (xy 41.672643 -16.838359) (xy 41.680645 -16.925994) (xy 41.681146 -16.969994)
			(xy 65.748161 -16.969994) (xy 65.752166 -16.882086) (xy 65.764149 -16.794906) (xy 65.784009 -16.709177)
			(xy 65.811584 -16.625609) (xy 65.846643 -16.544895) (xy 65.888896 -16.467703) (xy 65.937994 -16.394674)
			(xy 65.99353 -16.326412) (xy 66.055042 -16.263482) (xy 66.122023 -16.206408) (xy 66.193916 -16.15566)
			(xy 66.270125 -16.11166) (xy 66.35002 -16.074773) (xy 66.432939 -16.045304) (xy 66.518194 -16.023497)
			(xy 66.605078 -16.009533) (xy 66.692872 -16.003527) (xy 66.780849 -16.005531) (xy 66.868279 -16.015526)
			(xy 66.954438 -16.03343) (xy 67.038612 -16.059094) (xy 67.120103 -16.092307) (xy 67.198237 -16.132793)
			(xy 67.272365 -16.180215) (xy 67.341873 -16.234182) (xy 67.406187 -16.294247) (xy 67.464771 -16.359911)
			(xy 67.517142 -16.43063) (xy 67.562865 -16.505818) (xy 67.601562 -16.584853) (xy 67.632911 -16.667079)
			(xy 67.656653 -16.751815) (xy 67.672591 -16.838359) (xy 67.680593 -16.925994) (xy 67.681094 -16.969994)
			(xy 91.748109 -16.969994) (xy 91.752114 -16.882086) (xy 91.764097 -16.794906) (xy 91.783957 -16.709177)
			(xy 91.811532 -16.625609) (xy 91.846591 -16.544895) (xy 91.888844 -16.467703) (xy 91.937942 -16.394674)
			(xy 91.993478 -16.326412) (xy 92.05499 -16.263482) (xy 92.121971 -16.206408) (xy 92.193864 -16.15566)
			(xy 92.270073 -16.11166) (xy 92.349968 -16.074773) (xy 92.432887 -16.045304) (xy 92.518142 -16.023497)
			(xy 92.605026 -16.009533) (xy 92.69282 -16.003527) (xy 92.780797 -16.005531) (xy 92.868227 -16.015526)
			(xy 92.954386 -16.03343) (xy 93.03856 -16.059094) (xy 93.120051 -16.092307) (xy 93.198185 -16.132793)
			(xy 93.272313 -16.180215) (xy 93.341821 -16.234182) (xy 93.406135 -16.294247) (xy 93.464719 -16.359911)
			(xy 93.51709 -16.43063) (xy 93.562813 -16.505818) (xy 93.60151 -16.584853) (xy 93.632859 -16.667079)
			(xy 93.656601 -16.751815) (xy 93.672539 -16.838359) (xy 93.680541 -16.925994) (xy 93.681042 -16.969994)
			(xy 129.848363 -16.969994) (xy 129.852368 -16.882086) (xy 129.864351 -16.794906) (xy 129.884211 -16.709177)
			(xy 129.911786 -16.625609) (xy 129.946845 -16.544895) (xy 129.989098 -16.467703) (xy 130.038196 -16.394674)
			(xy 130.093732 -16.326412) (xy 130.155244 -16.263482) (xy 130.222225 -16.206408) (xy 130.294118 -16.15566)
			(xy 130.370327 -16.11166) (xy 130.450222 -16.074773) (xy 130.533141 -16.045304) (xy 130.618396 -16.023497)
			(xy 130.70528 -16.009533) (xy 130.793074 -16.003527) (xy 130.881051 -16.005531) (xy 130.968481 -16.015526)
			(xy 131.05464 -16.03343) (xy 131.138814 -16.059094) (xy 131.220305 -16.092307) (xy 131.298439 -16.132793)
			(xy 131.372567 -16.180215) (xy 131.442075 -16.234182) (xy 131.506389 -16.294247) (xy 131.564973 -16.359911)
			(xy 131.617344 -16.43063) (xy 131.663067 -16.505818) (xy 131.701764 -16.584853) (xy 131.733113 -16.667079)
			(xy 131.756855 -16.751815) (xy 131.772793 -16.838359) (xy 131.780795 -16.925994) (xy 131.781296 -16.969994)
			(xy 155.848311 -16.969994) (xy 155.852316 -16.882086) (xy 155.864299 -16.794906) (xy 155.884159 -16.709177)
			(xy 155.911734 -16.625609) (xy 155.946793 -16.544895) (xy 155.989046 -16.467703) (xy 156.038144 -16.394674)
			(xy 156.09368 -16.326412) (xy 156.155192 -16.263482) (xy 156.222173 -16.206408) (xy 156.294066 -16.15566)
			(xy 156.370275 -16.11166) (xy 156.45017 -16.074773) (xy 156.533089 -16.045304) (xy 156.618344 -16.023497)
			(xy 156.705228 -16.009533) (xy 156.793022 -16.003527) (xy 156.880999 -16.005531) (xy 156.968429 -16.015526)
			(xy 157.054588 -16.03343) (xy 157.138762 -16.059094) (xy 157.220253 -16.092307) (xy 157.298387 -16.132793)
			(xy 157.372515 -16.180215) (xy 157.442023 -16.234182) (xy 157.506337 -16.294247) (xy 157.564921 -16.359911)
			(xy 157.617292 -16.43063) (xy 157.663015 -16.505818) (xy 157.701712 -16.584853) (xy 157.733061 -16.667079)
			(xy 157.756803 -16.751815) (xy 157.772741 -16.838359) (xy 157.780743 -16.925994) (xy 157.781244 -16.969994)
			(xy 181.848259 -16.969994) (xy 181.852264 -16.882086) (xy 181.864247 -16.794906) (xy 181.884107 -16.709177)
			(xy 181.911682 -16.625609) (xy 181.946741 -16.544895) (xy 181.988994 -16.467703) (xy 182.038092 -16.394674)
			(xy 182.093628 -16.326412) (xy 182.15514 -16.263482) (xy 182.222121 -16.206408) (xy 182.294014 -16.15566)
			(xy 182.370223 -16.11166) (xy 182.450118 -16.074773) (xy 182.533037 -16.045304) (xy 182.618292 -16.023497)
			(xy 182.705176 -16.009533) (xy 182.79297 -16.003527) (xy 182.880947 -16.005531) (xy 182.968377 -16.015526)
			(xy 183.054536 -16.03343) (xy 183.13871 -16.059094) (xy 183.220201 -16.092307) (xy 183.298335 -16.132793)
			(xy 183.372463 -16.180215) (xy 183.441971 -16.234182) (xy 183.506285 -16.294247) (xy 183.564869 -16.359911)
			(xy 183.61724 -16.43063) (xy 183.662963 -16.505818) (xy 183.70166 -16.584853) (xy 183.733009 -16.667079)
			(xy 183.756751 -16.751815) (xy 183.772689 -16.838359) (xy 183.780691 -16.925994) (xy 183.781192 -16.969994)
			(xy 207.848207 -16.969994) (xy 207.852212 -16.882086) (xy 207.864195 -16.794906) (xy 207.884055 -16.709177)
			(xy 207.91163 -16.625609) (xy 207.946689 -16.544895) (xy 207.988942 -16.467703) (xy 208.03804 -16.394674)
			(xy 208.093576 -16.326412) (xy 208.155088 -16.263482) (xy 208.222069 -16.206408) (xy 208.293962 -16.15566)
			(xy 208.370171 -16.11166) (xy 208.450066 -16.074773) (xy 208.532985 -16.045304) (xy 208.61824 -16.023497)
			(xy 208.705124 -16.009533) (xy 208.792918 -16.003527) (xy 208.880895 -16.005531) (xy 208.968325 -16.015526)
			(xy 209.054484 -16.03343) (xy 209.138658 -16.059094) (xy 209.220149 -16.092307) (xy 209.298283 -16.132793)
			(xy 209.372411 -16.180215) (xy 209.441919 -16.234182) (xy 209.506233 -16.294247) (xy 209.564817 -16.359911)
			(xy 209.617188 -16.43063) (xy 209.662911 -16.505818) (xy 209.701608 -16.584853) (xy 209.732957 -16.667079)
			(xy 209.756699 -16.751815) (xy 209.772637 -16.838359) (xy 209.780639 -16.925994) (xy 209.78114 -16.969994)
			(xy 245.948207 -16.969994) (xy 245.952212 -16.882086) (xy 245.964195 -16.794906) (xy 245.984055 -16.709177)
			(xy 246.01163 -16.625609) (xy 246.046689 -16.544895) (xy 246.088942 -16.467703) (xy 246.13804 -16.394674)
			(xy 246.193576 -16.326412) (xy 246.255088 -16.263482) (xy 246.322069 -16.206408) (xy 246.393962 -16.15566)
			(xy 246.470171 -16.11166) (xy 246.550066 -16.074773) (xy 246.632985 -16.045304) (xy 246.71824 -16.023497)
			(xy 246.805124 -16.009533) (xy 246.892918 -16.003527) (xy 246.980895 -16.005531) (xy 247.068325 -16.015526)
			(xy 247.154484 -16.03343) (xy 247.238658 -16.059094) (xy 247.320149 -16.092307) (xy 247.398283 -16.132793)
			(xy 247.472411 -16.180215) (xy 247.541919 -16.234182) (xy 247.606233 -16.294247) (xy 247.664817 -16.359911)
			(xy 247.717188 -16.43063) (xy 247.762911 -16.505818) (xy 247.801608 -16.584853) (xy 247.832957 -16.667079)
			(xy 247.856699 -16.751815) (xy 247.872637 -16.838359) (xy 247.880639 -16.925994) (xy 247.88114 -16.969994)
			(xy 271.948155 -16.969994) (xy 271.95216 -16.882086) (xy 271.964143 -16.794906) (xy 271.984003 -16.709177)
			(xy 272.011578 -16.625609) (xy 272.046637 -16.544895) (xy 272.08889 -16.467703) (xy 272.137988 -16.394674)
			(xy 272.193524 -16.326412) (xy 272.255036 -16.263482) (xy 272.322017 -16.206408) (xy 272.39391 -16.15566)
			(xy 272.470119 -16.11166) (xy 272.550014 -16.074773) (xy 272.632933 -16.045304) (xy 272.718188 -16.023497)
			(xy 272.805072 -16.009533) (xy 272.892866 -16.003527) (xy 272.980843 -16.005531) (xy 273.068273 -16.015526)
			(xy 273.154432 -16.03343) (xy 273.238606 -16.059094) (xy 273.320097 -16.092307) (xy 273.398231 -16.132793)
			(xy 273.472359 -16.180215) (xy 273.541867 -16.234182) (xy 273.606181 -16.294247) (xy 273.664765 -16.359911)
			(xy 273.717136 -16.43063) (xy 273.762859 -16.505818) (xy 273.801556 -16.584853) (xy 273.832905 -16.667079)
			(xy 273.856647 -16.751815) (xy 273.872585 -16.838359) (xy 273.880587 -16.925994) (xy 273.881088 -16.969994)
			(xy 297.948103 -16.969994) (xy 297.952108 -16.882086) (xy 297.964091 -16.794906) (xy 297.983951 -16.709177)
			(xy 298.011526 -16.625609) (xy 298.046585 -16.544895) (xy 298.088838 -16.467703) (xy 298.137936 -16.394674)
			(xy 298.193472 -16.326412) (xy 298.254984 -16.263482) (xy 298.321965 -16.206408) (xy 298.393858 -16.15566)
			(xy 298.470067 -16.11166) (xy 298.549962 -16.074773) (xy 298.632881 -16.045304) (xy 298.718136 -16.023497)
			(xy 298.80502 -16.009533) (xy 298.892814 -16.003527) (xy 298.980791 -16.005531) (xy 299.068221 -16.015526)
			(xy 299.15438 -16.03343) (xy 299.238554 -16.059094) (xy 299.320045 -16.092307) (xy 299.398179 -16.132793)
			(xy 299.472307 -16.180215) (xy 299.541815 -16.234182) (xy 299.606129 -16.294247) (xy 299.664713 -16.359911)
			(xy 299.717084 -16.43063) (xy 299.762807 -16.505818) (xy 299.801504 -16.584853) (xy 299.832853 -16.667079)
			(xy 299.856595 -16.751815) (xy 299.872533 -16.838359) (xy 299.880535 -16.925994) (xy 299.881036 -16.969994)
			(xy 323.948051 -16.969994) (xy 323.952056 -16.882086) (xy 323.964039 -16.794906) (xy 323.983899 -16.709177)
			(xy 324.011474 -16.625609) (xy 324.046533 -16.544895) (xy 324.088786 -16.467703) (xy 324.137884 -16.394674)
			(xy 324.19342 -16.326412) (xy 324.254932 -16.263482) (xy 324.321913 -16.206408) (xy 324.393806 -16.15566)
			(xy 324.470015 -16.11166) (xy 324.54991 -16.074773) (xy 324.632829 -16.045304) (xy 324.718084 -16.023497)
			(xy 324.804968 -16.009533) (xy 324.892762 -16.003527) (xy 324.980739 -16.005531) (xy 325.068169 -16.015526)
			(xy 325.154328 -16.03343) (xy 325.238502 -16.059094) (xy 325.319993 -16.092307) (xy 325.398127 -16.132793)
			(xy 325.472255 -16.180215) (xy 325.541763 -16.234182) (xy 325.606077 -16.294247) (xy 325.664661 -16.359911)
			(xy 325.717032 -16.43063) (xy 325.762755 -16.505818) (xy 325.801452 -16.584853) (xy 325.832801 -16.667079)
			(xy 325.856543 -16.751815) (xy 325.872481 -16.838359) (xy 325.880483 -16.925994) (xy 325.880984 -16.969994)
			(xy 362.048305 -16.969994) (xy 362.05231 -16.882086) (xy 362.064293 -16.794906) (xy 362.084153 -16.709177)
			(xy 362.111728 -16.625609) (xy 362.146787 -16.544895) (xy 362.18904 -16.467703) (xy 362.238138 -16.394674)
			(xy 362.293674 -16.326412) (xy 362.355186 -16.263482) (xy 362.422167 -16.206408) (xy 362.49406 -16.15566)
			(xy 362.570269 -16.11166) (xy 362.650164 -16.074773) (xy 362.733083 -16.045304) (xy 362.818338 -16.023497)
			(xy 362.905222 -16.009533) (xy 362.993016 -16.003527) (xy 363.080993 -16.005531) (xy 363.168423 -16.015526)
			(xy 363.254582 -16.03343) (xy 363.338756 -16.059094) (xy 363.420247 -16.092307) (xy 363.498381 -16.132793)
			(xy 363.572509 -16.180215) (xy 363.642017 -16.234182) (xy 363.706331 -16.294247) (xy 363.764915 -16.359911)
			(xy 363.817286 -16.43063) (xy 363.863009 -16.505818) (xy 363.901706 -16.584853) (xy 363.933055 -16.667079)
			(xy 363.956797 -16.751815) (xy 363.972735 -16.838359) (xy 363.980737 -16.925994) (xy 363.981238 -16.969994)
			(xy 388.048253 -16.969994) (xy 388.052258 -16.882086) (xy 388.064241 -16.794906) (xy 388.084101 -16.709177)
			(xy 388.111676 -16.625609) (xy 388.146735 -16.544895) (xy 388.188988 -16.467703) (xy 388.238086 -16.394674)
			(xy 388.293622 -16.326412) (xy 388.355134 -16.263482) (xy 388.422115 -16.206408) (xy 388.494008 -16.15566)
			(xy 388.570217 -16.11166) (xy 388.650112 -16.074773) (xy 388.733031 -16.045304) (xy 388.818286 -16.023497)
			(xy 388.90517 -16.009533) (xy 388.992964 -16.003527) (xy 389.080941 -16.005531) (xy 389.168371 -16.015526)
			(xy 389.25453 -16.03343) (xy 389.338704 -16.059094) (xy 389.420195 -16.092307) (xy 389.498329 -16.132793)
			(xy 389.572457 -16.180215) (xy 389.641965 -16.234182) (xy 389.706279 -16.294247) (xy 389.764863 -16.359911)
			(xy 389.817234 -16.43063) (xy 389.862957 -16.505818) (xy 389.901654 -16.584853) (xy 389.933003 -16.667079)
			(xy 389.956745 -16.751815) (xy 389.972683 -16.838359) (xy 389.980685 -16.925994) (xy 389.981186 -16.969994)
			(xy 414.048201 -16.969994) (xy 414.052206 -16.882086) (xy 414.064189 -16.794906) (xy 414.084049 -16.709177)
			(xy 414.111624 -16.625609) (xy 414.146683 -16.544895) (xy 414.188936 -16.467703) (xy 414.238034 -16.394674)
			(xy 414.29357 -16.326412) (xy 414.355082 -16.263482) (xy 414.422063 -16.206408) (xy 414.493956 -16.15566)
			(xy 414.570165 -16.11166) (xy 414.65006 -16.074773) (xy 414.732979 -16.045304) (xy 414.818234 -16.023497)
			(xy 414.905118 -16.009533) (xy 414.992912 -16.003527) (xy 415.080889 -16.005531) (xy 415.168319 -16.015526)
			(xy 415.254478 -16.03343) (xy 415.338652 -16.059094) (xy 415.420143 -16.092307) (xy 415.498277 -16.132793)
			(xy 415.572405 -16.180215) (xy 415.641913 -16.234182) (xy 415.706227 -16.294247) (xy 415.764811 -16.359911)
			(xy 415.817182 -16.43063) (xy 415.862905 -16.505818) (xy 415.901602 -16.584853) (xy 415.932951 -16.667079)
			(xy 415.956693 -16.751815) (xy 415.972631 -16.838359) (xy 415.980633 -16.925994) (xy 415.981134 -16.969994)
			(xy 440.048149 -16.969994) (xy 440.052154 -16.882086) (xy 440.064137 -16.794906) (xy 440.083997 -16.709177)
			(xy 440.111572 -16.625609) (xy 440.146631 -16.544895) (xy 440.188884 -16.467703) (xy 440.237982 -16.394674)
			(xy 440.293518 -16.326412) (xy 440.35503 -16.263482) (xy 440.422011 -16.206408) (xy 440.493904 -16.15566)
			(xy 440.570113 -16.11166) (xy 440.650008 -16.074773) (xy 440.732927 -16.045304) (xy 440.818182 -16.023497)
			(xy 440.905066 -16.009533) (xy 440.99286 -16.003527) (xy 441.080837 -16.005531) (xy 441.168267 -16.015526)
			(xy 441.254426 -16.03343) (xy 441.3386 -16.059094) (xy 441.420091 -16.092307) (xy 441.498225 -16.132793)
			(xy 441.572353 -16.180215) (xy 441.641861 -16.234182) (xy 441.706175 -16.294247) (xy 441.764759 -16.359911)
			(xy 441.81713 -16.43063) (xy 441.862853 -16.505818) (xy 441.90155 -16.584853) (xy 441.932899 -16.667079)
			(xy 441.956641 -16.751815) (xy 441.972579 -16.838359) (xy 441.980581 -16.925994) (xy 441.981082 -16.969994)
			(xy 441.980581 -17.013994) (xy 441.972579 -17.101629) (xy 441.956641 -17.188173) (xy 441.932899 -17.272909)
			(xy 441.90155 -17.355135) (xy 441.862853 -17.43417) (xy 441.81713 -17.509358) (xy 441.764759 -17.580077)
			(xy 441.706175 -17.645741) (xy 441.641861 -17.705806) (xy 441.572353 -17.759773) (xy 441.498225 -17.807195)
			(xy 441.420091 -17.847681) (xy 441.3386 -17.880894) (xy 441.254426 -17.906558) (xy 441.168267 -17.924462)
			(xy 441.080837 -17.934457) (xy 440.99286 -17.936461) (xy 440.905066 -17.930455) (xy 440.818182 -17.916491)
			(xy 440.732927 -17.894684) (xy 440.650008 -17.865215) (xy 440.570113 -17.828328) (xy 440.493904 -17.784328)
			(xy 440.422011 -17.73358) (xy 440.35503 -17.676506) (xy 440.293518 -17.613576) (xy 440.237982 -17.545314)
			(xy 440.188884 -17.472285) (xy 440.146631 -17.395093) (xy 440.111572 -17.314379) (xy 440.083997 -17.230811)
			(xy 440.064137 -17.145082) (xy 440.052154 -17.057902) (xy 440.048149 -16.969994) (xy 415.981134 -16.969994)
			(xy 415.980633 -17.013994) (xy 415.972631 -17.101629) (xy 415.956693 -17.188173) (xy 415.932951 -17.272909)
			(xy 415.901602 -17.355135) (xy 415.862905 -17.43417) (xy 415.817182 -17.509358) (xy 415.764811 -17.580077)
			(xy 415.706227 -17.645741) (xy 415.641913 -17.705806) (xy 415.572405 -17.759773) (xy 415.498277 -17.807195)
			(xy 415.420143 -17.847681) (xy 415.338652 -17.880894) (xy 415.254478 -17.906558) (xy 415.168319 -17.924462)
			(xy 415.080889 -17.934457) (xy 414.992912 -17.936461) (xy 414.905118 -17.930455) (xy 414.818234 -17.916491)
			(xy 414.732979 -17.894684) (xy 414.65006 -17.865215) (xy 414.570165 -17.828328) (xy 414.493956 -17.784328)
			(xy 414.422063 -17.73358) (xy 414.355082 -17.676506) (xy 414.29357 -17.613576) (xy 414.238034 -17.545314)
			(xy 414.188936 -17.472285) (xy 414.146683 -17.395093) (xy 414.111624 -17.314379) (xy 414.084049 -17.230811)
			(xy 414.064189 -17.145082) (xy 414.052206 -17.057902) (xy 414.048201 -16.969994) (xy 389.981186 -16.969994)
			(xy 389.980685 -17.013994) (xy 389.972683 -17.101629) (xy 389.956745 -17.188173) (xy 389.933003 -17.272909)
			(xy 389.901654 -17.355135) (xy 389.862957 -17.43417) (xy 389.817234 -17.509358) (xy 389.764863 -17.580077)
			(xy 389.706279 -17.645741) (xy 389.641965 -17.705806) (xy 389.572457 -17.759773) (xy 389.498329 -17.807195)
			(xy 389.420195 -17.847681) (xy 389.338704 -17.880894) (xy 389.25453 -17.906558) (xy 389.168371 -17.924462)
			(xy 389.080941 -17.934457) (xy 388.992964 -17.936461) (xy 388.90517 -17.930455) (xy 388.818286 -17.916491)
			(xy 388.733031 -17.894684) (xy 388.650112 -17.865215) (xy 388.570217 -17.828328) (xy 388.494008 -17.784328)
			(xy 388.422115 -17.73358) (xy 388.355134 -17.676506) (xy 388.293622 -17.613576) (xy 388.238086 -17.545314)
			(xy 388.188988 -17.472285) (xy 388.146735 -17.395093) (xy 388.111676 -17.314379) (xy 388.084101 -17.230811)
			(xy 388.064241 -17.145082) (xy 388.052258 -17.057902) (xy 388.048253 -16.969994) (xy 363.981238 -16.969994)
			(xy 363.980737 -17.013994) (xy 363.972735 -17.101629) (xy 363.956797 -17.188173) (xy 363.933055 -17.272909)
			(xy 363.901706 -17.355135) (xy 363.863009 -17.43417) (xy 363.817286 -17.509358) (xy 363.764915 -17.580077)
			(xy 363.706331 -17.645741) (xy 363.642017 -17.705806) (xy 363.572509 -17.759773) (xy 363.498381 -17.807195)
			(xy 363.420247 -17.847681) (xy 363.338756 -17.880894) (xy 363.254582 -17.906558) (xy 363.168423 -17.924462)
			(xy 363.080993 -17.934457) (xy 362.993016 -17.936461) (xy 362.905222 -17.930455) (xy 362.818338 -17.916491)
			(xy 362.733083 -17.894684) (xy 362.650164 -17.865215) (xy 362.570269 -17.828328) (xy 362.49406 -17.784328)
			(xy 362.422167 -17.73358) (xy 362.355186 -17.676506) (xy 362.293674 -17.613576) (xy 362.238138 -17.545314)
			(xy 362.18904 -17.472285) (xy 362.146787 -17.395093) (xy 362.111728 -17.314379) (xy 362.084153 -17.230811)
			(xy 362.064293 -17.145082) (xy 362.05231 -17.057902) (xy 362.048305 -16.969994) (xy 325.880984 -16.969994)
			(xy 325.880483 -17.013994) (xy 325.872481 -17.101629) (xy 325.856543 -17.188173) (xy 325.832801 -17.272909)
			(xy 325.801452 -17.355135) (xy 325.762755 -17.43417) (xy 325.717032 -17.509358) (xy 325.664661 -17.580077)
			(xy 325.606077 -17.645741) (xy 325.541763 -17.705806) (xy 325.472255 -17.759773) (xy 325.398127 -17.807195)
			(xy 325.319993 -17.847681) (xy 325.238502 -17.880894) (xy 325.154328 -17.906558) (xy 325.068169 -17.924462)
			(xy 324.980739 -17.934457) (xy 324.892762 -17.936461) (xy 324.804968 -17.930455) (xy 324.718084 -17.916491)
			(xy 324.632829 -17.894684) (xy 324.54991 -17.865215) (xy 324.470015 -17.828328) (xy 324.393806 -17.784328)
			(xy 324.321913 -17.73358) (xy 324.254932 -17.676506) (xy 324.19342 -17.613576) (xy 324.137884 -17.545314)
			(xy 324.088786 -17.472285) (xy 324.046533 -17.395093) (xy 324.011474 -17.314379) (xy 323.983899 -17.230811)
			(xy 323.964039 -17.145082) (xy 323.952056 -17.057902) (xy 323.948051 -16.969994) (xy 299.881036 -16.969994)
			(xy 299.880535 -17.013994) (xy 299.872533 -17.101629) (xy 299.856595 -17.188173) (xy 299.832853 -17.272909)
			(xy 299.801504 -17.355135) (xy 299.762807 -17.43417) (xy 299.717084 -17.509358) (xy 299.664713 -17.580077)
			(xy 299.606129 -17.645741) (xy 299.541815 -17.705806) (xy 299.472307 -17.759773) (xy 299.398179 -17.807195)
			(xy 299.320045 -17.847681) (xy 299.238554 -17.880894) (xy 299.15438 -17.906558) (xy 299.068221 -17.924462)
			(xy 298.980791 -17.934457) (xy 298.892814 -17.936461) (xy 298.80502 -17.930455) (xy 298.718136 -17.916491)
			(xy 298.632881 -17.894684) (xy 298.549962 -17.865215) (xy 298.470067 -17.828328) (xy 298.393858 -17.784328)
			(xy 298.321965 -17.73358) (xy 298.254984 -17.676506) (xy 298.193472 -17.613576) (xy 298.137936 -17.545314)
			(xy 298.088838 -17.472285) (xy 298.046585 -17.395093) (xy 298.011526 -17.314379) (xy 297.983951 -17.230811)
			(xy 297.964091 -17.145082) (xy 297.952108 -17.057902) (xy 297.948103 -16.969994) (xy 273.881088 -16.969994)
			(xy 273.880587 -17.013994) (xy 273.872585 -17.101629) (xy 273.856647 -17.188173) (xy 273.832905 -17.272909)
			(xy 273.801556 -17.355135) (xy 273.762859 -17.43417) (xy 273.717136 -17.509358) (xy 273.664765 -17.580077)
			(xy 273.606181 -17.645741) (xy 273.541867 -17.705806) (xy 273.472359 -17.759773) (xy 273.398231 -17.807195)
			(xy 273.320097 -17.847681) (xy 273.238606 -17.880894) (xy 273.154432 -17.906558) (xy 273.068273 -17.924462)
			(xy 272.980843 -17.934457) (xy 272.892866 -17.936461) (xy 272.805072 -17.930455) (xy 272.718188 -17.916491)
			(xy 272.632933 -17.894684) (xy 272.550014 -17.865215) (xy 272.470119 -17.828328) (xy 272.39391 -17.784328)
			(xy 272.322017 -17.73358) (xy 272.255036 -17.676506) (xy 272.193524 -17.613576) (xy 272.137988 -17.545314)
			(xy 272.08889 -17.472285) (xy 272.046637 -17.395093) (xy 272.011578 -17.314379) (xy 271.984003 -17.230811)
			(xy 271.964143 -17.145082) (xy 271.95216 -17.057902) (xy 271.948155 -16.969994) (xy 247.88114 -16.969994)
			(xy 247.880639 -17.013994) (xy 247.872637 -17.101629) (xy 247.856699 -17.188173) (xy 247.832957 -17.272909)
			(xy 247.801608 -17.355135) (xy 247.762911 -17.43417) (xy 247.717188 -17.509358) (xy 247.664817 -17.580077)
			(xy 247.606233 -17.645741) (xy 247.541919 -17.705806) (xy 247.472411 -17.759773) (xy 247.398283 -17.807195)
			(xy 247.320149 -17.847681) (xy 247.238658 -17.880894) (xy 247.154484 -17.906558) (xy 247.068325 -17.924462)
			(xy 246.980895 -17.934457) (xy 246.892918 -17.936461) (xy 246.805124 -17.930455) (xy 246.71824 -17.916491)
			(xy 246.632985 -17.894684) (xy 246.550066 -17.865215) (xy 246.470171 -17.828328) (xy 246.393962 -17.784328)
			(xy 246.322069 -17.73358) (xy 246.255088 -17.676506) (xy 246.193576 -17.613576) (xy 246.13804 -17.545314)
			(xy 246.088942 -17.472285) (xy 246.046689 -17.395093) (xy 246.01163 -17.314379) (xy 245.984055 -17.230811)
			(xy 245.964195 -17.145082) (xy 245.952212 -17.057902) (xy 245.948207 -16.969994) (xy 209.78114 -16.969994)
			(xy 209.780639 -17.013994) (xy 209.772637 -17.101629) (xy 209.756699 -17.188173) (xy 209.732957 -17.272909)
			(xy 209.701608 -17.355135) (xy 209.662911 -17.43417) (xy 209.617188 -17.509358) (xy 209.564817 -17.580077)
			(xy 209.506233 -17.645741) (xy 209.441919 -17.705806) (xy 209.372411 -17.759773) (xy 209.298283 -17.807195)
			(xy 209.220149 -17.847681) (xy 209.138658 -17.880894) (xy 209.054484 -17.906558) (xy 208.968325 -17.924462)
			(xy 208.880895 -17.934457) (xy 208.792918 -17.936461) (xy 208.705124 -17.930455) (xy 208.61824 -17.916491)
			(xy 208.532985 -17.894684) (xy 208.450066 -17.865215) (xy 208.370171 -17.828328) (xy 208.293962 -17.784328)
			(xy 208.222069 -17.73358) (xy 208.155088 -17.676506) (xy 208.093576 -17.613576) (xy 208.03804 -17.545314)
			(xy 207.988942 -17.472285) (xy 207.946689 -17.395093) (xy 207.91163 -17.314379) (xy 207.884055 -17.230811)
			(xy 207.864195 -17.145082) (xy 207.852212 -17.057902) (xy 207.848207 -16.969994) (xy 183.781192 -16.969994)
			(xy 183.780691 -17.013994) (xy 183.772689 -17.101629) (xy 183.756751 -17.188173) (xy 183.733009 -17.272909)
			(xy 183.70166 -17.355135) (xy 183.662963 -17.43417) (xy 183.61724 -17.509358) (xy 183.564869 -17.580077)
			(xy 183.506285 -17.645741) (xy 183.441971 -17.705806) (xy 183.372463 -17.759773) (xy 183.298335 -17.807195)
			(xy 183.220201 -17.847681) (xy 183.13871 -17.880894) (xy 183.054536 -17.906558) (xy 182.968377 -17.924462)
			(xy 182.880947 -17.934457) (xy 182.79297 -17.936461) (xy 182.705176 -17.930455) (xy 182.618292 -17.916491)
			(xy 182.533037 -17.894684) (xy 182.450118 -17.865215) (xy 182.370223 -17.828328) (xy 182.294014 -17.784328)
			(xy 182.222121 -17.73358) (xy 182.15514 -17.676506) (xy 182.093628 -17.613576) (xy 182.038092 -17.545314)
			(xy 181.988994 -17.472285) (xy 181.946741 -17.395093) (xy 181.911682 -17.314379) (xy 181.884107 -17.230811)
			(xy 181.864247 -17.145082) (xy 181.852264 -17.057902) (xy 181.848259 -16.969994) (xy 157.781244 -16.969994)
			(xy 157.780743 -17.013994) (xy 157.772741 -17.101629) (xy 157.756803 -17.188173) (xy 157.733061 -17.272909)
			(xy 157.701712 -17.355135) (xy 157.663015 -17.43417) (xy 157.617292 -17.509358) (xy 157.564921 -17.580077)
			(xy 157.506337 -17.645741) (xy 157.442023 -17.705806) (xy 157.372515 -17.759773) (xy 157.298387 -17.807195)
			(xy 157.220253 -17.847681) (xy 157.138762 -17.880894) (xy 157.054588 -17.906558) (xy 156.968429 -17.924462)
			(xy 156.880999 -17.934457) (xy 156.793022 -17.936461) (xy 156.705228 -17.930455) (xy 156.618344 -17.916491)
			(xy 156.533089 -17.894684) (xy 156.45017 -17.865215) (xy 156.370275 -17.828328) (xy 156.294066 -17.784328)
			(xy 156.222173 -17.73358) (xy 156.155192 -17.676506) (xy 156.09368 -17.613576) (xy 156.038144 -17.545314)
			(xy 155.989046 -17.472285) (xy 155.946793 -17.395093) (xy 155.911734 -17.314379) (xy 155.884159 -17.230811)
			(xy 155.864299 -17.145082) (xy 155.852316 -17.057902) (xy 155.848311 -16.969994) (xy 131.781296 -16.969994)
			(xy 131.780795 -17.013994) (xy 131.772793 -17.101629) (xy 131.756855 -17.188173) (xy 131.733113 -17.272909)
			(xy 131.701764 -17.355135) (xy 131.663067 -17.43417) (xy 131.617344 -17.509358) (xy 131.564973 -17.580077)
			(xy 131.506389 -17.645741) (xy 131.442075 -17.705806) (xy 131.372567 -17.759773) (xy 131.298439 -17.807195)
			(xy 131.220305 -17.847681) (xy 131.138814 -17.880894) (xy 131.05464 -17.906558) (xy 130.968481 -17.924462)
			(xy 130.881051 -17.934457) (xy 130.793074 -17.936461) (xy 130.70528 -17.930455) (xy 130.618396 -17.916491)
			(xy 130.533141 -17.894684) (xy 130.450222 -17.865215) (xy 130.370327 -17.828328) (xy 130.294118 -17.784328)
			(xy 130.222225 -17.73358) (xy 130.155244 -17.676506) (xy 130.093732 -17.613576) (xy 130.038196 -17.545314)
			(xy 129.989098 -17.472285) (xy 129.946845 -17.395093) (xy 129.911786 -17.314379) (xy 129.884211 -17.230811)
			(xy 129.864351 -17.145082) (xy 129.852368 -17.057902) (xy 129.848363 -16.969994) (xy 93.681042 -16.969994)
			(xy 93.680541 -17.013994) (xy 93.672539 -17.101629) (xy 93.656601 -17.188173) (xy 93.632859 -17.272909)
			(xy 93.60151 -17.355135) (xy 93.562813 -17.43417) (xy 93.51709 -17.509358) (xy 93.464719 -17.580077)
			(xy 93.406135 -17.645741) (xy 93.341821 -17.705806) (xy 93.272313 -17.759773) (xy 93.198185 -17.807195)
			(xy 93.120051 -17.847681) (xy 93.03856 -17.880894) (xy 92.954386 -17.906558) (xy 92.868227 -17.924462)
			(xy 92.780797 -17.934457) (xy 92.69282 -17.936461) (xy 92.605026 -17.930455) (xy 92.518142 -17.916491)
			(xy 92.432887 -17.894684) (xy 92.349968 -17.865215) (xy 92.270073 -17.828328) (xy 92.193864 -17.784328)
			(xy 92.121971 -17.73358) (xy 92.05499 -17.676506) (xy 91.993478 -17.613576) (xy 91.937942 -17.545314)
			(xy 91.888844 -17.472285) (xy 91.846591 -17.395093) (xy 91.811532 -17.314379) (xy 91.783957 -17.230811)
			(xy 91.764097 -17.145082) (xy 91.752114 -17.057902) (xy 91.748109 -16.969994) (xy 67.681094 -16.969994)
			(xy 67.680593 -17.013994) (xy 67.672591 -17.101629) (xy 67.656653 -17.188173) (xy 67.632911 -17.272909)
			(xy 67.601562 -17.355135) (xy 67.562865 -17.43417) (xy 67.517142 -17.509358) (xy 67.464771 -17.580077)
			(xy 67.406187 -17.645741) (xy 67.341873 -17.705806) (xy 67.272365 -17.759773) (xy 67.198237 -17.807195)
			(xy 67.120103 -17.847681) (xy 67.038612 -17.880894) (xy 66.954438 -17.906558) (xy 66.868279 -17.924462)
			(xy 66.780849 -17.934457) (xy 66.692872 -17.936461) (xy 66.605078 -17.930455) (xy 66.518194 -17.916491)
			(xy 66.432939 -17.894684) (xy 66.35002 -17.865215) (xy 66.270125 -17.828328) (xy 66.193916 -17.784328)
			(xy 66.122023 -17.73358) (xy 66.055042 -17.676506) (xy 65.99353 -17.613576) (xy 65.937994 -17.545314)
			(xy 65.888896 -17.472285) (xy 65.846643 -17.395093) (xy 65.811584 -17.314379) (xy 65.784009 -17.230811)
			(xy 65.764149 -17.145082) (xy 65.752166 -17.057902) (xy 65.748161 -16.969994) (xy 41.681146 -16.969994)
			(xy 41.680645 -17.013994) (xy 41.672643 -17.101629) (xy 41.656705 -17.188173) (xy 41.632963 -17.272909)
			(xy 41.601614 -17.355135) (xy 41.562917 -17.43417) (xy 41.517194 -17.509358) (xy 41.464823 -17.580077)
			(xy 41.406239 -17.645741) (xy 41.341925 -17.705806) (xy 41.272417 -17.759773) (xy 41.198289 -17.807195)
			(xy 41.120155 -17.847681) (xy 41.038664 -17.880894) (xy 40.95449 -17.906558) (xy 40.868331 -17.924462)
			(xy 40.780901 -17.934457) (xy 40.692924 -17.936461) (xy 40.60513 -17.930455) (xy 40.518246 -17.916491)
			(xy 40.432991 -17.894684) (xy 40.350072 -17.865215) (xy 40.270177 -17.828328) (xy 40.193968 -17.784328)
			(xy 40.122075 -17.73358) (xy 40.055094 -17.676506) (xy 39.993582 -17.613576) (xy 39.938046 -17.545314)
			(xy 39.888948 -17.472285) (xy 39.846695 -17.395093) (xy 39.811636 -17.314379) (xy 39.784061 -17.230811)
			(xy 39.764201 -17.145082) (xy 39.752218 -17.057902) (xy 39.748213 -16.969994) (xy 15.681198 -16.969994)
			(xy 15.680697 -17.013994) (xy 15.672695 -17.101629) (xy 15.656757 -17.188173) (xy 15.633015 -17.272909)
			(xy 15.601666 -17.355135) (xy 15.562969 -17.43417) (xy 15.517246 -17.509358) (xy 15.464875 -17.580077)
			(xy 15.406291 -17.645741) (xy 15.341977 -17.705806) (xy 15.272469 -17.759773) (xy 15.198341 -17.807195)
			(xy 15.120207 -17.847681) (xy 15.038716 -17.880894) (xy 14.954542 -17.906558) (xy 14.868383 -17.924462)
			(xy 14.780953 -17.934457) (xy 14.692976 -17.936461) (xy 14.605182 -17.930455) (xy 14.518298 -17.916491)
			(xy 14.433043 -17.894684) (xy 14.350124 -17.865215) (xy 14.270229 -17.828328) (xy 14.19402 -17.784328)
			(xy 14.122127 -17.73358) (xy 14.055146 -17.676506) (xy 13.993634 -17.613576) (xy 13.938098 -17.545314)
			(xy 13.889 -17.472285) (xy 13.846747 -17.395093) (xy 13.811688 -17.314379) (xy 13.784113 -17.230811)
			(xy 13.764253 -17.145082) (xy 13.75227 -17.057902) (xy 13.748265 -16.969994) (xy 0.508 -16.969994)
			(xy 0.508 -27.342846) (xy 16.523716 -27.342846) (xy 16.523716 -26.479246) (xy 16.524206 -26.449278)
			(xy 16.532029 -26.389856) (xy 16.547542 -26.331963) (xy 16.570478 -26.27659) (xy 16.600445 -26.224684)
			(xy 16.636932 -26.177134) (xy 16.679312 -26.134754) (xy 16.726862 -26.098267) (xy 16.778768 -26.0683)
			(xy 16.834141 -26.045364) (xy 16.892034 -26.029851) (xy 16.951456 -26.022028) (xy 17.011392 -26.022028)
			(xy 17.070814 -26.029851) (xy 17.128707 -26.045364) (xy 17.18408 -26.0683) (xy 17.235986 -26.098267)
			(xy 17.283536 -26.134754) (xy 17.325916 -26.177134) (xy 17.362403 -26.224684) (xy 17.39237 -26.27659)
			(xy 17.415306 -26.331963) (xy 17.430819 -26.389856) (xy 17.438642 -26.449278) (xy 17.439132 -26.479246)
			(xy 17.439132 -27.342846) (xy 42.523664 -27.342846) (xy 42.523664 -26.479246) (xy 42.524154 -26.449278)
			(xy 42.531977 -26.389856) (xy 42.54749 -26.331963) (xy 42.570426 -26.27659) (xy 42.600393 -26.224684)
			(xy 42.63688 -26.177134) (xy 42.67926 -26.134754) (xy 42.72681 -26.098267) (xy 42.778716 -26.0683)
			(xy 42.834089 -26.045364) (xy 42.891982 -26.029851) (xy 42.951404 -26.022028) (xy 43.01134 -26.022028)
			(xy 43.070762 -26.029851) (xy 43.128655 -26.045364) (xy 43.184028 -26.0683) (xy 43.235934 -26.098267)
			(xy 43.283484 -26.134754) (xy 43.325864 -26.177134) (xy 43.362351 -26.224684) (xy 43.392318 -26.27659)
			(xy 43.415254 -26.331963) (xy 43.430767 -26.389856) (xy 43.43859 -26.449278) (xy 43.43908 -26.479246)
			(xy 43.43908 -27.342846) (xy 68.523612 -27.342846) (xy 68.523612 -26.479246) (xy 68.524102 -26.449278)
			(xy 68.531925 -26.389856) (xy 68.547438 -26.331963) (xy 68.570374 -26.27659) (xy 68.600341 -26.224684)
			(xy 68.636828 -26.177134) (xy 68.679208 -26.134754) (xy 68.726758 -26.098267) (xy 68.778664 -26.0683)
			(xy 68.834037 -26.045364) (xy 68.89193 -26.029851) (xy 68.951352 -26.022028) (xy 69.011288 -26.022028)
			(xy 69.07071 -26.029851) (xy 69.128603 -26.045364) (xy 69.183976 -26.0683) (xy 69.235882 -26.098267)
			(xy 69.283432 -26.134754) (xy 69.325812 -26.177134) (xy 69.362299 -26.224684) (xy 69.392266 -26.27659)
			(xy 69.415202 -26.331963) (xy 69.430715 -26.389856) (xy 69.438538 -26.449278) (xy 69.439028 -26.479246)
			(xy 69.439028 -27.342846) (xy 94.52356 -27.342846) (xy 94.52356 -26.479246) (xy 94.52405 -26.449278)
			(xy 94.531873 -26.389856) (xy 94.547386 -26.331963) (xy 94.570322 -26.27659) (xy 94.600289 -26.224684)
			(xy 94.636776 -26.177134) (xy 94.679156 -26.134754) (xy 94.726706 -26.098267) (xy 94.778612 -26.0683)
			(xy 94.833985 -26.045364) (xy 94.891878 -26.029851) (xy 94.9513 -26.022028) (xy 95.011236 -26.022028)
			(xy 95.070658 -26.029851) (xy 95.128551 -26.045364) (xy 95.183924 -26.0683) (xy 95.23583 -26.098267)
			(xy 95.28338 -26.134754) (xy 95.32576 -26.177134) (xy 95.362247 -26.224684) (xy 95.392214 -26.27659)
			(xy 95.41515 -26.331963) (xy 95.430663 -26.389856) (xy 95.438486 -26.449278) (xy 95.438976 -26.479246)
			(xy 95.438976 -27.342846) (xy 132.62356 -27.342846) (xy 132.62356 -26.479246) (xy 132.62405 -26.449262)
			(xy 132.631878 -26.389806) (xy 132.647399 -26.331881) (xy 132.670348 -26.276477) (xy 132.700332 -26.224543)
			(xy 132.736838 -26.176967) (xy 132.779243 -26.134562) (xy 132.826819 -26.098056) (xy 132.878753 -26.068072)
			(xy 132.934157 -26.045123) (xy 132.992082 -26.029602) (xy 133.051538 -26.021774) (xy 133.111506 -26.021774)
			(xy 133.170962 -26.029602) (xy 133.228887 -26.045123) (xy 133.284291 -26.068072) (xy 133.336225 -26.098056)
			(xy 133.383801 -26.134562) (xy 133.426206 -26.176967) (xy 133.462712 -26.224543) (xy 133.492696 -26.276477)
			(xy 133.515645 -26.331881) (xy 133.531166 -26.389806) (xy 133.538994 -26.449262) (xy 133.539484 -26.479246)
			(xy 133.539484 -27.342846) (xy 158.623508 -27.342846) (xy 158.623508 -26.479246) (xy 158.623998 -26.449262)
			(xy 158.631826 -26.389806) (xy 158.647347 -26.331881) (xy 158.670296 -26.276477) (xy 158.70028 -26.224543)
			(xy 158.736786 -26.176967) (xy 158.779191 -26.134562) (xy 158.826767 -26.098056) (xy 158.878701 -26.068072)
			(xy 158.934105 -26.045123) (xy 158.99203 -26.029602) (xy 159.051486 -26.021774) (xy 159.111454 -26.021774)
			(xy 159.17091 -26.029602) (xy 159.228835 -26.045123) (xy 159.284239 -26.068072) (xy 159.336173 -26.098056)
			(xy 159.383749 -26.134562) (xy 159.426154 -26.176967) (xy 159.46266 -26.224543) (xy 159.492644 -26.276477)
			(xy 159.515593 -26.331881) (xy 159.531114 -26.389806) (xy 159.538942 -26.449262) (xy 159.539432 -26.479246)
			(xy 159.539432 -27.342846) (xy 184.623456 -27.342846) (xy 184.623456 -26.479246) (xy 184.623946 -26.449262)
			(xy 184.631774 -26.389806) (xy 184.647295 -26.331881) (xy 184.670244 -26.276477) (xy 184.700228 -26.224543)
			(xy 184.736734 -26.176967) (xy 184.779139 -26.134562) (xy 184.826715 -26.098056) (xy 184.878649 -26.068072)
			(xy 184.934053 -26.045123) (xy 184.991978 -26.029602) (xy 185.051434 -26.021774) (xy 185.111402 -26.021774)
			(xy 185.170858 -26.029602) (xy 185.228783 -26.045123) (xy 185.284187 -26.068072) (xy 185.336121 -26.098056)
			(xy 185.383697 -26.134562) (xy 185.426102 -26.176967) (xy 185.462608 -26.224543) (xy 185.492592 -26.276477)
			(xy 185.515541 -26.331881) (xy 185.531062 -26.389806) (xy 185.53889 -26.449262) (xy 185.53938 -26.479246)
			(xy 185.53938 -27.342846) (xy 210.623404 -27.342846) (xy 210.623404 -26.479246) (xy 210.623894 -26.449262)
			(xy 210.631722 -26.389806) (xy 210.647243 -26.331881) (xy 210.670192 -26.276477) (xy 210.700176 -26.224543)
			(xy 210.736682 -26.176967) (xy 210.779087 -26.134562) (xy 210.826663 -26.098056) (xy 210.878597 -26.068072)
			(xy 210.934001 -26.045123) (xy 210.991926 -26.029602) (xy 211.051382 -26.021774) (xy 211.11135 -26.021774)
			(xy 211.170806 -26.029602) (xy 211.228731 -26.045123) (xy 211.284135 -26.068072) (xy 211.336069 -26.098056)
			(xy 211.383645 -26.134562) (xy 211.42605 -26.176967) (xy 211.462556 -26.224543) (xy 211.49254 -26.276477)
			(xy 211.515489 -26.331881) (xy 211.53101 -26.389806) (xy 211.538838 -26.449262) (xy 211.539328 -26.479246)
			(xy 211.539328 -27.342846) (xy 248.723404 -27.342846) (xy 248.723404 -26.479246) (xy 248.723894 -26.449262)
			(xy 248.731722 -26.389806) (xy 248.747243 -26.331881) (xy 248.770192 -26.276477) (xy 248.800176 -26.224543)
			(xy 248.836682 -26.176967) (xy 248.879087 -26.134562) (xy 248.926663 -26.098056) (xy 248.978597 -26.068072)
			(xy 249.034001 -26.045123) (xy 249.091926 -26.029602) (xy 249.151382 -26.021774) (xy 249.21135 -26.021774)
			(xy 249.270806 -26.029602) (xy 249.328731 -26.045123) (xy 249.384135 -26.068072) (xy 249.436069 -26.098056)
			(xy 249.483645 -26.134562) (xy 249.52605 -26.176967) (xy 249.562556 -26.224543) (xy 249.59254 -26.276477)
			(xy 249.615489 -26.331881) (xy 249.63101 -26.389806) (xy 249.638838 -26.449262) (xy 249.639328 -26.479246)
			(xy 249.639328 -27.342846) (xy 274.723352 -27.342846) (xy 274.723352 -26.479246) (xy 274.723842 -26.449262)
			(xy 274.73167 -26.389806) (xy 274.747191 -26.331881) (xy 274.77014 -26.276477) (xy 274.800124 -26.224543)
			(xy 274.83663 -26.176967) (xy 274.879035 -26.134562) (xy 274.926611 -26.098056) (xy 274.978545 -26.068072)
			(xy 275.033949 -26.045123) (xy 275.091874 -26.029602) (xy 275.15133 -26.021774) (xy 275.211298 -26.021774)
			(xy 275.270754 -26.029602) (xy 275.328679 -26.045123) (xy 275.384083 -26.068072) (xy 275.436017 -26.098056)
			(xy 275.483593 -26.134562) (xy 275.525998 -26.176967) (xy 275.562504 -26.224543) (xy 275.592488 -26.276477)
			(xy 275.615437 -26.331881) (xy 275.630958 -26.389806) (xy 275.638786 -26.449262) (xy 275.639276 -26.479246)
			(xy 275.639276 -27.342846) (xy 300.7233 -27.342846) (xy 300.7233 -26.479246) (xy 300.72379 -26.449262)
			(xy 300.731618 -26.389806) (xy 300.747139 -26.331881) (xy 300.770088 -26.276477) (xy 300.800072 -26.224543)
			(xy 300.836578 -26.176967) (xy 300.878983 -26.134562) (xy 300.926559 -26.098056) (xy 300.978493 -26.068072)
			(xy 301.033897 -26.045123) (xy 301.091822 -26.029602) (xy 301.151278 -26.021774) (xy 301.211246 -26.021774)
			(xy 301.270702 -26.029602) (xy 301.328627 -26.045123) (xy 301.384031 -26.068072) (xy 301.435965 -26.098056)
			(xy 301.483541 -26.134562) (xy 301.525946 -26.176967) (xy 301.562452 -26.224543) (xy 301.592436 -26.276477)
			(xy 301.615385 -26.331881) (xy 301.630906 -26.389806) (xy 301.638734 -26.449262) (xy 301.639224 -26.479246)
			(xy 301.639224 -27.342846) (xy 326.723248 -27.342846) (xy 326.723248 -26.479246) (xy 326.723738 -26.449262)
			(xy 326.731566 -26.389806) (xy 326.747087 -26.331881) (xy 326.770036 -26.276477) (xy 326.80002 -26.224543)
			(xy 326.836526 -26.176967) (xy 326.878931 -26.134562) (xy 326.926507 -26.098056) (xy 326.978441 -26.068072)
			(xy 327.033845 -26.045123) (xy 327.09177 -26.029602) (xy 327.151226 -26.021774) (xy 327.211194 -26.021774)
			(xy 327.27065 -26.029602) (xy 327.328575 -26.045123) (xy 327.383979 -26.068072) (xy 327.435913 -26.098056)
			(xy 327.483489 -26.134562) (xy 327.525894 -26.176967) (xy 327.5624 -26.224543) (xy 327.592384 -26.276477)
			(xy 327.615333 -26.331881) (xy 327.630854 -26.389806) (xy 327.638682 -26.449262) (xy 327.639172 -26.479246)
			(xy 327.639172 -27.342846) (xy 364.823756 -27.342846) (xy 364.823756 -26.479246) (xy 364.824246 -26.449278)
			(xy 364.832069 -26.389856) (xy 364.847582 -26.331963) (xy 364.870518 -26.27659) (xy 364.900485 -26.224684)
			(xy 364.936972 -26.177134) (xy 364.979352 -26.134754) (xy 365.026902 -26.098267) (xy 365.078808 -26.0683)
			(xy 365.134181 -26.045364) (xy 365.192074 -26.029851) (xy 365.251496 -26.022028) (xy 365.311432 -26.022028)
			(xy 365.370854 -26.029851) (xy 365.428747 -26.045364) (xy 365.48412 -26.0683) (xy 365.536026 -26.098267)
			(xy 365.583576 -26.134754) (xy 365.625956 -26.177134) (xy 365.662443 -26.224684) (xy 365.69241 -26.27659)
			(xy 365.715346 -26.331963) (xy 365.730859 -26.389856) (xy 365.738682 -26.449278) (xy 365.739172 -26.479246)
			(xy 365.739172 -27.342846) (xy 390.823704 -27.342846) (xy 390.823704 -26.479246) (xy 390.824194 -26.449278)
			(xy 390.832017 -26.389856) (xy 390.84753 -26.331963) (xy 390.870466 -26.27659) (xy 390.900433 -26.224684)
			(xy 390.93692 -26.177134) (xy 390.9793 -26.134754) (xy 391.02685 -26.098267) (xy 391.078756 -26.0683)
			(xy 391.134129 -26.045364) (xy 391.192022 -26.029851) (xy 391.251444 -26.022028) (xy 391.31138 -26.022028)
			(xy 391.370802 -26.029851) (xy 391.428695 -26.045364) (xy 391.484068 -26.0683) (xy 391.535974 -26.098267)
			(xy 391.583524 -26.134754) (xy 391.625904 -26.177134) (xy 391.662391 -26.224684) (xy 391.692358 -26.27659)
			(xy 391.715294 -26.331963) (xy 391.730807 -26.389856) (xy 391.73863 -26.449278) (xy 391.73912 -26.479246)
			(xy 391.73912 -27.342846) (xy 416.823652 -27.342846) (xy 416.823652 -26.479246) (xy 416.824142 -26.449278)
			(xy 416.831965 -26.389856) (xy 416.847478 -26.331963) (xy 416.870414 -26.27659) (xy 416.900381 -26.224684)
			(xy 416.936868 -26.177134) (xy 416.979248 -26.134754) (xy 417.026798 -26.098267) (xy 417.078704 -26.0683)
			(xy 417.134077 -26.045364) (xy 417.19197 -26.029851) (xy 417.251392 -26.022028) (xy 417.311328 -26.022028)
			(xy 417.37075 -26.029851) (xy 417.428643 -26.045364) (xy 417.484016 -26.0683) (xy 417.535922 -26.098267)
			(xy 417.583472 -26.134754) (xy 417.625852 -26.177134) (xy 417.662339 -26.224684) (xy 417.692306 -26.27659)
			(xy 417.715242 -26.331963) (xy 417.730755 -26.389856) (xy 417.738578 -26.449278) (xy 417.739068 -26.479246)
			(xy 417.739068 -27.342846) (xy 442.8236 -27.342846) (xy 442.8236 -26.479246) (xy 442.82409 -26.449278)
			(xy 442.831913 -26.389856) (xy 442.847426 -26.331963) (xy 442.870362 -26.27659) (xy 442.900329 -26.224684)
			(xy 442.936816 -26.177134) (xy 442.979196 -26.134754) (xy 443.026746 -26.098267) (xy 443.078652 -26.0683)
			(xy 443.134025 -26.045364) (xy 443.191918 -26.029851) (xy 443.25134 -26.022028) (xy 443.311276 -26.022028)
			(xy 443.370698 -26.029851) (xy 443.428591 -26.045364) (xy 443.483964 -26.0683) (xy 443.53587 -26.098267)
			(xy 443.58342 -26.134754) (xy 443.6258 -26.177134) (xy 443.662287 -26.224684) (xy 443.692254 -26.27659)
			(xy 443.71519 -26.331963) (xy 443.730703 -26.389856) (xy 443.738526 -26.449278) (xy 443.739016 -26.479246)
			(xy 443.739016 -27.342846) (xy 443.738526 -27.372814) (xy 443.730703 -27.432236) (xy 443.71519 -27.490129)
			(xy 443.692254 -27.545502) (xy 443.662287 -27.597408) (xy 443.6258 -27.644958) (xy 443.58342 -27.687338)
			(xy 443.53587 -27.723825) (xy 443.483964 -27.753792) (xy 443.428591 -27.776728) (xy 443.370698 -27.792241)
			(xy 443.311276 -27.800064) (xy 443.25134 -27.800064) (xy 443.191918 -27.792241) (xy 443.134025 -27.776728)
			(xy 443.078652 -27.753792) (xy 443.026746 -27.723825) (xy 442.979196 -27.687338) (xy 442.936816 -27.644958)
			(xy 442.900329 -27.597408) (xy 442.870362 -27.545502) (xy 442.847426 -27.490129) (xy 442.831913 -27.432236)
			(xy 442.82409 -27.372814) (xy 442.8236 -27.342846) (xy 417.739068 -27.342846) (xy 417.738578 -27.372814)
			(xy 417.730755 -27.432236) (xy 417.715242 -27.490129) (xy 417.692306 -27.545502) (xy 417.662339 -27.597408)
			(xy 417.625852 -27.644958) (xy 417.583472 -27.687338) (xy 417.535922 -27.723825) (xy 417.484016 -27.753792)
			(xy 417.428643 -27.776728) (xy 417.37075 -27.792241) (xy 417.311328 -27.800064) (xy 417.251392 -27.800064)
			(xy 417.19197 -27.792241) (xy 417.134077 -27.776728) (xy 417.078704 -27.753792) (xy 417.026798 -27.723825)
			(xy 416.979248 -27.687338) (xy 416.936868 -27.644958) (xy 416.900381 -27.597408) (xy 416.870414 -27.545502)
			(xy 416.847478 -27.490129) (xy 416.831965 -27.432236) (xy 416.824142 -27.372814) (xy 416.823652 -27.342846)
			(xy 391.73912 -27.342846) (xy 391.73863 -27.372814) (xy 391.730807 -27.432236) (xy 391.715294 -27.490129)
			(xy 391.692358 -27.545502) (xy 391.662391 -27.597408) (xy 391.625904 -27.644958) (xy 391.583524 -27.687338)
			(xy 391.535974 -27.723825) (xy 391.484068 -27.753792) (xy 391.428695 -27.776728) (xy 391.370802 -27.792241)
			(xy 391.31138 -27.800064) (xy 391.251444 -27.800064) (xy 391.192022 -27.792241) (xy 391.134129 -27.776728)
			(xy 391.078756 -27.753792) (xy 391.02685 -27.723825) (xy 390.9793 -27.687338) (xy 390.93692 -27.644958)
			(xy 390.900433 -27.597408) (xy 390.870466 -27.545502) (xy 390.84753 -27.490129) (xy 390.832017 -27.432236)
			(xy 390.824194 -27.372814) (xy 390.823704 -27.342846) (xy 365.739172 -27.342846) (xy 365.738682 -27.372814)
			(xy 365.730859 -27.432236) (xy 365.715346 -27.490129) (xy 365.69241 -27.545502) (xy 365.662443 -27.597408)
			(xy 365.625956 -27.644958) (xy 365.583576 -27.687338) (xy 365.536026 -27.723825) (xy 365.48412 -27.753792)
			(xy 365.428747 -27.776728) (xy 365.370854 -27.792241) (xy 365.311432 -27.800064) (xy 365.251496 -27.800064)
			(xy 365.192074 -27.792241) (xy 365.134181 -27.776728) (xy 365.078808 -27.753792) (xy 365.026902 -27.723825)
			(xy 364.979352 -27.687338) (xy 364.936972 -27.644958) (xy 364.900485 -27.597408) (xy 364.870518 -27.545502)
			(xy 364.847582 -27.490129) (xy 364.832069 -27.432236) (xy 364.824246 -27.372814) (xy 364.823756 -27.342846)
			(xy 327.639172 -27.342846) (xy 327.638682 -27.37283) (xy 327.630854 -27.432286) (xy 327.615333 -27.490211)
			(xy 327.592384 -27.545615) (xy 327.5624 -27.597549) (xy 327.525894 -27.645125) (xy 327.483489 -27.68753)
			(xy 327.435913 -27.724036) (xy 327.383979 -27.75402) (xy 327.328575 -27.776969) (xy 327.27065 -27.79249)
			(xy 327.211194 -27.800318) (xy 327.151226 -27.800318) (xy 327.09177 -27.79249) (xy 327.033845 -27.776969)
			(xy 326.978441 -27.75402) (xy 326.926507 -27.724036) (xy 326.878931 -27.68753) (xy 326.836526 -27.645125)
			(xy 326.80002 -27.597549) (xy 326.770036 -27.545615) (xy 326.747087 -27.490211) (xy 326.731566 -27.432286)
			(xy 326.723738 -27.37283) (xy 326.723248 -27.342846) (xy 301.639224 -27.342846) (xy 301.638734 -27.37283)
			(xy 301.630906 -27.432286) (xy 301.615385 -27.490211) (xy 301.592436 -27.545615) (xy 301.562452 -27.597549)
			(xy 301.525946 -27.645125) (xy 301.483541 -27.68753) (xy 301.435965 -27.724036) (xy 301.384031 -27.75402)
			(xy 301.328627 -27.776969) (xy 301.270702 -27.79249) (xy 301.211246 -27.800318) (xy 301.151278 -27.800318)
			(xy 301.091822 -27.79249) (xy 301.033897 -27.776969) (xy 300.978493 -27.75402) (xy 300.926559 -27.724036)
			(xy 300.878983 -27.68753) (xy 300.836578 -27.645125) (xy 300.800072 -27.597549) (xy 300.770088 -27.545615)
			(xy 300.747139 -27.490211) (xy 300.731618 -27.432286) (xy 300.72379 -27.37283) (xy 300.7233 -27.342846)
			(xy 275.639276 -27.342846) (xy 275.638786 -27.37283) (xy 275.630958 -27.432286) (xy 275.615437 -27.490211)
			(xy 275.592488 -27.545615) (xy 275.562504 -27.597549) (xy 275.525998 -27.645125) (xy 275.483593 -27.68753)
			(xy 275.436017 -27.724036) (xy 275.384083 -27.75402) (xy 275.328679 -27.776969) (xy 275.270754 -27.79249)
			(xy 275.211298 -27.800318) (xy 275.15133 -27.800318) (xy 275.091874 -27.79249) (xy 275.033949 -27.776969)
			(xy 274.978545 -27.75402) (xy 274.926611 -27.724036) (xy 274.879035 -27.68753) (xy 274.83663 -27.645125)
			(xy 274.800124 -27.597549) (xy 274.77014 -27.545615) (xy 274.747191 -27.490211) (xy 274.73167 -27.432286)
			(xy 274.723842 -27.37283) (xy 274.723352 -27.342846) (xy 249.639328 -27.342846) (xy 249.638838 -27.37283)
			(xy 249.63101 -27.432286) (xy 249.615489 -27.490211) (xy 249.59254 -27.545615) (xy 249.562556 -27.597549)
			(xy 249.52605 -27.645125) (xy 249.483645 -27.68753) (xy 249.436069 -27.724036) (xy 249.384135 -27.75402)
			(xy 249.328731 -27.776969) (xy 249.270806 -27.79249) (xy 249.21135 -27.800318) (xy 249.151382 -27.800318)
			(xy 249.091926 -27.79249) (xy 249.034001 -27.776969) (xy 248.978597 -27.75402) (xy 248.926663 -27.724036)
			(xy 248.879087 -27.68753) (xy 248.836682 -27.645125) (xy 248.800176 -27.597549) (xy 248.770192 -27.545615)
			(xy 248.747243 -27.490211) (xy 248.731722 -27.432286) (xy 248.723894 -27.37283) (xy 248.723404 -27.342846)
			(xy 211.539328 -27.342846) (xy 211.538838 -27.37283) (xy 211.53101 -27.432286) (xy 211.515489 -27.490211)
			(xy 211.49254 -27.545615) (xy 211.462556 -27.597549) (xy 211.42605 -27.645125) (xy 211.383645 -27.68753)
			(xy 211.336069 -27.724036) (xy 211.284135 -27.75402) (xy 211.228731 -27.776969) (xy 211.170806 -27.79249)
			(xy 211.11135 -27.800318) (xy 211.051382 -27.800318) (xy 210.991926 -27.79249) (xy 210.934001 -27.776969)
			(xy 210.878597 -27.75402) (xy 210.826663 -27.724036) (xy 210.779087 -27.68753) (xy 210.736682 -27.645125)
			(xy 210.700176 -27.597549) (xy 210.670192 -27.545615) (xy 210.647243 -27.490211) (xy 210.631722 -27.432286)
			(xy 210.623894 -27.37283) (xy 210.623404 -27.342846) (xy 185.53938 -27.342846) (xy 185.53889 -27.37283)
			(xy 185.531062 -27.432286) (xy 185.515541 -27.490211) (xy 185.492592 -27.545615) (xy 185.462608 -27.597549)
			(xy 185.426102 -27.645125) (xy 185.383697 -27.68753) (xy 185.336121 -27.724036) (xy 185.284187 -27.75402)
			(xy 185.228783 -27.776969) (xy 185.170858 -27.79249) (xy 185.111402 -27.800318) (xy 185.051434 -27.800318)
			(xy 184.991978 -27.79249) (xy 184.934053 -27.776969) (xy 184.878649 -27.75402) (xy 184.826715 -27.724036)
			(xy 184.779139 -27.68753) (xy 184.736734 -27.645125) (xy 184.700228 -27.597549) (xy 184.670244 -27.545615)
			(xy 184.647295 -27.490211) (xy 184.631774 -27.432286) (xy 184.623946 -27.37283) (xy 184.623456 -27.342846)
			(xy 159.539432 -27.342846) (xy 159.538942 -27.37283) (xy 159.531114 -27.432286) (xy 159.515593 -27.490211)
			(xy 159.492644 -27.545615) (xy 159.46266 -27.597549) (xy 159.426154 -27.645125) (xy 159.383749 -27.68753)
			(xy 159.336173 -27.724036) (xy 159.284239 -27.75402) (xy 159.228835 -27.776969) (xy 159.17091 -27.79249)
			(xy 159.111454 -27.800318) (xy 159.051486 -27.800318) (xy 158.99203 -27.79249) (xy 158.934105 -27.776969)
			(xy 158.878701 -27.75402) (xy 158.826767 -27.724036) (xy 158.779191 -27.68753) (xy 158.736786 -27.645125)
			(xy 158.70028 -27.597549) (xy 158.670296 -27.545615) (xy 158.647347 -27.490211) (xy 158.631826 -27.432286)
			(xy 158.623998 -27.37283) (xy 158.623508 -27.342846) (xy 133.539484 -27.342846) (xy 133.538994 -27.37283)
			(xy 133.531166 -27.432286) (xy 133.515645 -27.490211) (xy 133.492696 -27.545615) (xy 133.462712 -27.597549)
			(xy 133.426206 -27.645125) (xy 133.383801 -27.68753) (xy 133.336225 -27.724036) (xy 133.284291 -27.75402)
			(xy 133.228887 -27.776969) (xy 133.170962 -27.79249) (xy 133.111506 -27.800318) (xy 133.051538 -27.800318)
			(xy 132.992082 -27.79249) (xy 132.934157 -27.776969) (xy 132.878753 -27.75402) (xy 132.826819 -27.724036)
			(xy 132.779243 -27.68753) (xy 132.736838 -27.645125) (xy 132.700332 -27.597549) (xy 132.670348 -27.545615)
			(xy 132.647399 -27.490211) (xy 132.631878 -27.432286) (xy 132.62405 -27.37283) (xy 132.62356 -27.342846)
			(xy 95.438976 -27.342846) (xy 95.438486 -27.372814) (xy 95.430663 -27.432236) (xy 95.41515 -27.490129)
			(xy 95.392214 -27.545502) (xy 95.362247 -27.597408) (xy 95.32576 -27.644958) (xy 95.28338 -27.687338)
			(xy 95.23583 -27.723825) (xy 95.183924 -27.753792) (xy 95.128551 -27.776728) (xy 95.070658 -27.792241)
			(xy 95.011236 -27.800064) (xy 94.9513 -27.800064) (xy 94.891878 -27.792241) (xy 94.833985 -27.776728)
			(xy 94.778612 -27.753792) (xy 94.726706 -27.723825) (xy 94.679156 -27.687338) (xy 94.636776 -27.644958)
			(xy 94.600289 -27.597408) (xy 94.570322 -27.545502) (xy 94.547386 -27.490129) (xy 94.531873 -27.432236)
			(xy 94.52405 -27.372814) (xy 94.52356 -27.342846) (xy 69.439028 -27.342846) (xy 69.438538 -27.372814)
			(xy 69.430715 -27.432236) (xy 69.415202 -27.490129) (xy 69.392266 -27.545502) (xy 69.362299 -27.597408)
			(xy 69.325812 -27.644958) (xy 69.283432 -27.687338) (xy 69.235882 -27.723825) (xy 69.183976 -27.753792)
			(xy 69.128603 -27.776728) (xy 69.07071 -27.792241) (xy 69.011288 -27.800064) (xy 68.951352 -27.800064)
			(xy 68.89193 -27.792241) (xy 68.834037 -27.776728) (xy 68.778664 -27.753792) (xy 68.726758 -27.723825)
			(xy 68.679208 -27.687338) (xy 68.636828 -27.644958) (xy 68.600341 -27.597408) (xy 68.570374 -27.545502)
			(xy 68.547438 -27.490129) (xy 68.531925 -27.432236) (xy 68.524102 -27.372814) (xy 68.523612 -27.342846)
			(xy 43.43908 -27.342846) (xy 43.43859 -27.372814) (xy 43.430767 -27.432236) (xy 43.415254 -27.490129)
			(xy 43.392318 -27.545502) (xy 43.362351 -27.597408) (xy 43.325864 -27.644958) (xy 43.283484 -27.687338)
			(xy 43.235934 -27.723825) (xy 43.184028 -27.753792) (xy 43.128655 -27.776728) (xy 43.070762 -27.792241)
			(xy 43.01134 -27.800064) (xy 42.951404 -27.800064) (xy 42.891982 -27.792241) (xy 42.834089 -27.776728)
			(xy 42.778716 -27.753792) (xy 42.72681 -27.723825) (xy 42.67926 -27.687338) (xy 42.63688 -27.644958)
			(xy 42.600393 -27.597408) (xy 42.570426 -27.545502) (xy 42.54749 -27.490129) (xy 42.531977 -27.432236)
			(xy 42.524154 -27.372814) (xy 42.523664 -27.342846) (xy 17.439132 -27.342846) (xy 17.438642 -27.372814)
			(xy 17.430819 -27.432236) (xy 17.415306 -27.490129) (xy 17.39237 -27.545502) (xy 17.362403 -27.597408)
			(xy 17.325916 -27.644958) (xy 17.283536 -27.687338) (xy 17.235986 -27.723825) (xy 17.18408 -27.753792)
			(xy 17.128707 -27.776728) (xy 17.070814 -27.792241) (xy 17.011392 -27.800064) (xy 16.951456 -27.800064)
			(xy 16.892034 -27.792241) (xy 16.834141 -27.776728) (xy 16.778768 -27.753792) (xy 16.726862 -27.723825)
			(xy 16.679312 -27.687338) (xy 16.636932 -27.644958) (xy 16.600445 -27.597408) (xy 16.570478 -27.545502)
			(xy 16.547542 -27.490129) (xy 16.532029 -27.432236) (xy 16.524206 -27.372814) (xy 16.523716 -27.342846)
			(xy 0.508 -27.342846) (xy 0.508 -29.12237) (xy 8.607044 -29.12237) (xy 8.607044 -28.25877) (xy 8.607534 -28.228802)
			(xy 8.615357 -28.16938) (xy 8.63087 -28.111487) (xy 8.653806 -28.056114) (xy 8.683773 -28.004208)
			(xy 8.72026 -27.956658) (xy 8.76264 -27.914278) (xy 8.81019 -27.877791) (xy 8.862096 -27.847824)
			(xy 8.917469 -27.824888) (xy 8.975362 -27.809375) (xy 9.034784 -27.801552) (xy 9.09472 -27.801552)
			(xy 9.154142 -27.809375) (xy 9.212035 -27.824888) (xy 9.267408 -27.847824) (xy 9.319314 -27.877791)
			(xy 9.366864 -27.914278) (xy 9.409244 -27.956658) (xy 9.445731 -28.004208) (xy 9.475698 -28.056114)
			(xy 9.498634 -28.111487) (xy 9.514147 -28.16938) (xy 9.52197 -28.228802) (xy 9.52246 -28.25877) (xy 9.52246 -29.114242)
			(xy 18.847308 -29.114242) (xy 18.847308 -28.250642) (xy 18.847798 -28.220658) (xy 18.855626 -28.161202)
			(xy 18.871147 -28.103277) (xy 18.894096 -28.047873) (xy 18.92408 -27.995939) (xy 18.960586 -27.948363)
			(xy 19.002991 -27.905958) (xy 19.050567 -27.869452) (xy 19.102501 -27.839468) (xy 19.157905 -27.816519)
			(xy 19.21583 -27.800998) (xy 19.275286 -27.79317) (xy 19.335254 -27.79317) (xy 19.39471 -27.800998)
			(xy 19.452635 -27.816519) (xy 19.508039 -27.839468) (xy 19.559973 -27.869452) (xy 19.607549 -27.905958)
			(xy 19.649954 -27.948363) (xy 19.68646 -27.995939) (xy 19.716444 -28.047873) (xy 19.739393 -28.103277)
			(xy 19.754914 -28.161202) (xy 19.762742 -28.220658) (xy 19.763232 -28.250642) (xy 19.763232 -29.114242)
			(xy 19.763099 -29.12237) (xy 34.606992 -29.12237) (xy 34.606992 -28.25877) (xy 34.607482 -28.228802)
			(xy 34.615305 -28.16938) (xy 34.630818 -28.111487) (xy 34.653754 -28.056114) (xy 34.683721 -28.004208)
			(xy 34.720208 -27.956658) (xy 34.762588 -27.914278) (xy 34.810138 -27.877791) (xy 34.862044 -27.847824)
			(xy 34.917417 -27.824888) (xy 34.97531 -27.809375) (xy 35.034732 -27.801552) (xy 35.094668 -27.801552)
			(xy 35.15409 -27.809375) (xy 35.211983 -27.824888) (xy 35.267356 -27.847824) (xy 35.319262 -27.877791)
			(xy 35.366812 -27.914278) (xy 35.409192 -27.956658) (xy 35.445679 -28.004208) (xy 35.475646 -28.056114)
			(xy 35.498582 -28.111487) (xy 35.514095 -28.16938) (xy 35.521918 -28.228802) (xy 35.522408 -28.25877)
			(xy 35.522408 -29.114242) (xy 44.847256 -29.114242) (xy 44.847256 -28.250642) (xy 44.847746 -28.220658)
			(xy 44.855574 -28.161202) (xy 44.871095 -28.103277) (xy 44.894044 -28.047873) (xy 44.924028 -27.995939)
			(xy 44.960534 -27.948363) (xy 45.002939 -27.905958) (xy 45.050515 -27.869452) (xy 45.102449 -27.839468)
			(xy 45.157853 -27.816519) (xy 45.215778 -27.800998) (xy 45.275234 -27.79317) (xy 45.335202 -27.79317)
			(xy 45.394658 -27.800998) (xy 45.452583 -27.816519) (xy 45.507987 -27.839468) (xy 45.559921 -27.869452)
			(xy 45.607497 -27.905958) (xy 45.649902 -27.948363) (xy 45.686408 -27.995939) (xy 45.716392 -28.047873)
			(xy 45.739341 -28.103277) (xy 45.754862 -28.161202) (xy 45.76269 -28.220658) (xy 45.76318 -28.250642)
			(xy 45.76318 -29.114242) (xy 45.763047 -29.12237) (xy 60.60694 -29.12237) (xy 60.60694 -28.25877)
			(xy 60.60743 -28.228802) (xy 60.615253 -28.16938) (xy 60.630766 -28.111487) (xy 60.653702 -28.056114)
			(xy 60.683669 -28.004208) (xy 60.720156 -27.956658) (xy 60.762536 -27.914278) (xy 60.810086 -27.877791)
			(xy 60.861992 -27.847824) (xy 60.917365 -27.824888) (xy 60.975258 -27.809375) (xy 61.03468 -27.801552)
			(xy 61.094616 -27.801552) (xy 61.154038 -27.809375) (xy 61.211931 -27.824888) (xy 61.267304 -27.847824)
			(xy 61.31921 -27.877791) (xy 61.36676 -27.914278) (xy 61.40914 -27.956658) (xy 61.445627 -28.004208)
			(xy 61.475594 -28.056114) (xy 61.49853 -28.111487) (xy 61.514043 -28.16938) (xy 61.521866 -28.228802)
			(xy 61.522356 -28.25877) (xy 61.522356 -29.114242) (xy 70.847204 -29.114242) (xy 70.847204 -28.250642)
			(xy 70.847694 -28.220658) (xy 70.855522 -28.161202) (xy 70.871043 -28.103277) (xy 70.893992 -28.047873)
			(xy 70.923976 -27.995939) (xy 70.960482 -27.948363) (xy 71.002887 -27.905958) (xy 71.050463 -27.869452)
			(xy 71.102397 -27.839468) (xy 71.157801 -27.816519) (xy 71.215726 -27.800998) (xy 71.275182 -27.79317)
			(xy 71.33515 -27.79317) (xy 71.394606 -27.800998) (xy 71.452531 -27.816519) (xy 71.507935 -27.839468)
			(xy 71.559869 -27.869452) (xy 71.607445 -27.905958) (xy 71.64985 -27.948363) (xy 71.686356 -27.995939)
			(xy 71.71634 -28.047873) (xy 71.739289 -28.103277) (xy 71.75481 -28.161202) (xy 71.762638 -28.220658)
			(xy 71.763128 -28.250642) (xy 71.763128 -29.114242) (xy 71.762995 -29.12237) (xy 86.606888 -29.12237)
			(xy 86.606888 -28.25877) (xy 86.607378 -28.228802) (xy 86.615201 -28.16938) (xy 86.630714 -28.111487)
			(xy 86.65365 -28.056114) (xy 86.683617 -28.004208) (xy 86.720104 -27.956658) (xy 86.762484 -27.914278)
			(xy 86.810034 -27.877791) (xy 86.86194 -27.847824) (xy 86.917313 -27.824888) (xy 86.975206 -27.809375)
			(xy 87.034628 -27.801552) (xy 87.094564 -27.801552) (xy 87.153986 -27.809375) (xy 87.211879 -27.824888)
			(xy 87.267252 -27.847824) (xy 87.319158 -27.877791) (xy 87.366708 -27.914278) (xy 87.409088 -27.956658)
			(xy 87.445575 -28.004208) (xy 87.475542 -28.056114) (xy 87.498478 -28.111487) (xy 87.513991 -28.16938)
			(xy 87.521814 -28.228802) (xy 87.522304 -28.25877) (xy 87.522304 -29.114242) (xy 96.847152 -29.114242)
			(xy 96.847152 -28.250642) (xy 96.847642 -28.220658) (xy 96.85547 -28.161202) (xy 96.870991 -28.103277)
			(xy 96.89394 -28.047873) (xy 96.923924 -27.995939) (xy 96.96043 -27.948363) (xy 97.002835 -27.905958)
			(xy 97.050411 -27.869452) (xy 97.102345 -27.839468) (xy 97.157749 -27.816519) (xy 97.215674 -27.800998)
			(xy 97.27513 -27.79317) (xy 97.335098 -27.79317) (xy 97.394554 -27.800998) (xy 97.452479 -27.816519)
			(xy 97.507883 -27.839468) (xy 97.559817 -27.869452) (xy 97.607393 -27.905958) (xy 97.649798 -27.948363)
			(xy 97.686304 -27.995939) (xy 97.716288 -28.047873) (xy 97.739237 -28.103277) (xy 97.754758 -28.161202)
			(xy 97.762586 -28.220658) (xy 97.763076 -28.250642) (xy 97.763076 -29.114242) (xy 97.762943 -29.12237)
			(xy 124.706888 -29.12237) (xy 124.706888 -28.25877) (xy 124.707378 -28.228786) (xy 124.715206 -28.16933)
			(xy 124.730727 -28.111405) (xy 124.753676 -28.056001) (xy 124.78366 -28.004067) (xy 124.820166 -27.956491)
			(xy 124.862571 -27.914086) (xy 124.910147 -27.87758) (xy 124.962081 -27.847596) (xy 125.017485 -27.824647)
			(xy 125.07541 -27.809126) (xy 125.134866 -27.801298) (xy 125.194834 -27.801298) (xy 125.25429 -27.809126)
			(xy 125.312215 -27.824647) (xy 125.367619 -27.847596) (xy 125.419553 -27.87758) (xy 125.467129 -27.914086)
			(xy 125.509534 -27.956491) (xy 125.54604 -28.004067) (xy 125.576024 -28.056001) (xy 125.598973 -28.111405)
			(xy 125.614494 -28.16933) (xy 125.622322 -28.228786) (xy 125.622812 -28.25877) (xy 125.622812 -29.114242)
			(xy 134.94766 -29.114242) (xy 134.94766 -28.250642) (xy 134.94815 -28.220674) (xy 134.955973 -28.161252)
			(xy 134.971486 -28.103359) (xy 134.994422 -28.047986) (xy 135.024389 -27.99608) (xy 135.060876 -27.94853)
			(xy 135.103256 -27.90615) (xy 135.150806 -27.869663) (xy 135.202712 -27.839696) (xy 135.258085 -27.81676)
			(xy 135.315978 -27.801247) (xy 135.3754 -27.793424) (xy 135.435336 -27.793424) (xy 135.494758 -27.801247)
			(xy 135.552651 -27.81676) (xy 135.608024 -27.839696) (xy 135.65993 -27.869663) (xy 135.70748 -27.90615)
			(xy 135.74986 -27.94853) (xy 135.786347 -27.99608) (xy 135.816314 -28.047986) (xy 135.83925 -28.103359)
			(xy 135.854763 -28.161252) (xy 135.862586 -28.220674) (xy 135.863076 -28.250642) (xy 135.863076 -29.114242)
			(xy 135.862943 -29.12237) (xy 150.706836 -29.12237) (xy 150.706836 -28.25877) (xy 150.707326 -28.228786)
			(xy 150.715154 -28.16933) (xy 150.730675 -28.111405) (xy 150.753624 -28.056001) (xy 150.783608 -28.004067)
			(xy 150.820114 -27.956491) (xy 150.862519 -27.914086) (xy 150.910095 -27.87758) (xy 150.962029 -27.847596)
			(xy 151.017433 -27.824647) (xy 151.075358 -27.809126) (xy 151.134814 -27.801298) (xy 151.194782 -27.801298)
			(xy 151.254238 -27.809126) (xy 151.312163 -27.824647) (xy 151.367567 -27.847596) (xy 151.419501 -27.87758)
			(xy 151.467077 -27.914086) (xy 151.509482 -27.956491) (xy 151.545988 -28.004067) (xy 151.575972 -28.056001)
			(xy 151.598921 -28.111405) (xy 151.614442 -28.16933) (xy 151.62227 -28.228786) (xy 151.62276 -28.25877)
			(xy 151.62276 -29.114242) (xy 160.947608 -29.114242) (xy 160.947608 -28.250642) (xy 160.948098 -28.220674)
			(xy 160.955921 -28.161252) (xy 160.971434 -28.103359) (xy 160.99437 -28.047986) (xy 161.024337 -27.99608)
			(xy 161.060824 -27.94853) (xy 161.103204 -27.90615) (xy 161.150754 -27.869663) (xy 161.20266 -27.839696)
			(xy 161.258033 -27.81676) (xy 161.315926 -27.801247) (xy 161.375348 -27.793424) (xy 161.435284 -27.793424)
			(xy 161.494706 -27.801247) (xy 161.552599 -27.81676) (xy 161.607972 -27.839696) (xy 161.659878 -27.869663)
			(xy 161.707428 -27.90615) (xy 161.749808 -27.94853) (xy 161.786295 -27.99608) (xy 161.816262 -28.047986)
			(xy 161.839198 -28.103359) (xy 161.854711 -28.161252) (xy 161.862534 -28.220674) (xy 161.863024 -28.250642)
			(xy 161.863024 -29.114242) (xy 161.862891 -29.12237) (xy 176.706784 -29.12237) (xy 176.706784 -28.25877)
			(xy 176.707274 -28.228786) (xy 176.715102 -28.16933) (xy 176.730623 -28.111405) (xy 176.753572 -28.056001)
			(xy 176.783556 -28.004067) (xy 176.820062 -27.956491) (xy 176.862467 -27.914086) (xy 176.910043 -27.87758)
			(xy 176.961977 -27.847596) (xy 177.017381 -27.824647) (xy 177.075306 -27.809126) (xy 177.134762 -27.801298)
			(xy 177.19473 -27.801298) (xy 177.254186 -27.809126) (xy 177.312111 -27.824647) (xy 177.367515 -27.847596)
			(xy 177.419449 -27.87758) (xy 177.467025 -27.914086) (xy 177.50943 -27.956491) (xy 177.545936 -28.004067)
			(xy 177.57592 -28.056001) (xy 177.598869 -28.111405) (xy 177.61439 -28.16933) (xy 177.622218 -28.228786)
			(xy 177.622708 -28.25877) (xy 177.622708 -29.114242) (xy 186.947556 -29.114242) (xy 186.947556 -28.250642)
			(xy 186.948046 -28.220674) (xy 186.955869 -28.161252) (xy 186.971382 -28.103359) (xy 186.994318 -28.047986)
			(xy 187.024285 -27.99608) (xy 187.060772 -27.94853) (xy 187.103152 -27.90615) (xy 187.150702 -27.869663)
			(xy 187.202608 -27.839696) (xy 187.257981 -27.81676) (xy 187.315874 -27.801247) (xy 187.375296 -27.793424)
			(xy 187.435232 -27.793424) (xy 187.494654 -27.801247) (xy 187.552547 -27.81676) (xy 187.60792 -27.839696)
			(xy 187.659826 -27.869663) (xy 187.707376 -27.90615) (xy 187.749756 -27.94853) (xy 187.786243 -27.99608)
			(xy 187.81621 -28.047986) (xy 187.839146 -28.103359) (xy 187.854659 -28.161252) (xy 187.862482 -28.220674)
			(xy 187.862972 -28.250642) (xy 187.862972 -29.114242) (xy 187.862839 -29.12237) (xy 202.706732 -29.12237)
			(xy 202.706732 -28.25877) (xy 202.707222 -28.228786) (xy 202.71505 -28.16933) (xy 202.730571 -28.111405)
			(xy 202.75352 -28.056001) (xy 202.783504 -28.004067) (xy 202.82001 -27.956491) (xy 202.862415 -27.914086)
			(xy 202.909991 -27.87758) (xy 202.961925 -27.847596) (xy 203.017329 -27.824647) (xy 203.075254 -27.809126)
			(xy 203.13471 -27.801298) (xy 203.194678 -27.801298) (xy 203.254134 -27.809126) (xy 203.312059 -27.824647)
			(xy 203.367463 -27.847596) (xy 203.419397 -27.87758) (xy 203.466973 -27.914086) (xy 203.509378 -27.956491)
			(xy 203.545884 -28.004067) (xy 203.575868 -28.056001) (xy 203.598817 -28.111405) (xy 203.614338 -28.16933)
			(xy 203.622166 -28.228786) (xy 203.622656 -28.25877) (xy 203.622656 -29.114242) (xy 212.947504 -29.114242)
			(xy 212.947504 -28.250642) (xy 212.947994 -28.220674) (xy 212.955817 -28.161252) (xy 212.97133 -28.103359)
			(xy 212.994266 -28.047986) (xy 213.024233 -27.99608) (xy 213.06072 -27.94853) (xy 213.1031 -27.90615)
			(xy 213.15065 -27.869663) (xy 213.202556 -27.839696) (xy 213.257929 -27.81676) (xy 213.315822 -27.801247)
			(xy 213.375244 -27.793424) (xy 213.43518 -27.793424) (xy 213.494602 -27.801247) (xy 213.552495 -27.81676)
			(xy 213.607868 -27.839696) (xy 213.659774 -27.869663) (xy 213.707324 -27.90615) (xy 213.749704 -27.94853)
			(xy 213.786191 -27.99608) (xy 213.816158 -28.047986) (xy 213.839094 -28.103359) (xy 213.854607 -28.161252)
			(xy 213.86243 -28.220674) (xy 213.86292 -28.250642) (xy 213.86292 -29.114242) (xy 213.862787 -29.12237)
			(xy 240.806732 -29.12237) (xy 240.806732 -28.25877) (xy 240.807222 -28.228786) (xy 240.81505 -28.16933)
			(xy 240.830571 -28.111405) (xy 240.85352 -28.056001) (xy 240.883504 -28.004067) (xy 240.92001 -27.956491)
			(xy 240.962415 -27.914086) (xy 241.009991 -27.87758) (xy 241.061925 -27.847596) (xy 241.117329 -27.824647)
			(xy 241.175254 -27.809126) (xy 241.23471 -27.801298) (xy 241.294678 -27.801298) (xy 241.354134 -27.809126)
			(xy 241.412059 -27.824647) (xy 241.467463 -27.847596) (xy 241.519397 -27.87758) (xy 241.566973 -27.914086)
			(xy 241.609378 -27.956491) (xy 241.645884 -28.004067) (xy 241.675868 -28.056001) (xy 241.698817 -28.111405)
			(xy 241.714338 -28.16933) (xy 241.722166 -28.228786) (xy 241.722656 -28.25877) (xy 241.722656 -29.114242)
			(xy 251.047504 -29.114242) (xy 251.047504 -28.250642) (xy 251.047994 -28.220674) (xy 251.055817 -28.161252)
			(xy 251.07133 -28.103359) (xy 251.094266 -28.047986) (xy 251.124233 -27.99608) (xy 251.16072 -27.94853)
			(xy 251.2031 -27.90615) (xy 251.25065 -27.869663) (xy 251.302556 -27.839696) (xy 251.357929 -27.81676)
			(xy 251.415822 -27.801247) (xy 251.475244 -27.793424) (xy 251.53518 -27.793424) (xy 251.594602 -27.801247)
			(xy 251.652495 -27.81676) (xy 251.707868 -27.839696) (xy 251.759774 -27.869663) (xy 251.807324 -27.90615)
			(xy 251.849704 -27.94853) (xy 251.886191 -27.99608) (xy 251.916158 -28.047986) (xy 251.939094 -28.103359)
			(xy 251.954607 -28.161252) (xy 251.96243 -28.220674) (xy 251.96292 -28.250642) (xy 251.96292 -29.114242)
			(xy 251.962787 -29.12237) (xy 266.80668 -29.12237) (xy 266.80668 -28.25877) (xy 266.80717 -28.228786)
			(xy 266.814998 -28.16933) (xy 266.830519 -28.111405) (xy 266.853468 -28.056001) (xy 266.883452 -28.004067)
			(xy 266.919958 -27.956491) (xy 266.962363 -27.914086) (xy 267.009939 -27.87758) (xy 267.061873 -27.847596)
			(xy 267.117277 -27.824647) (xy 267.175202 -27.809126) (xy 267.234658 -27.801298) (xy 267.294626 -27.801298)
			(xy 267.354082 -27.809126) (xy 267.412007 -27.824647) (xy 267.467411 -27.847596) (xy 267.519345 -27.87758)
			(xy 267.566921 -27.914086) (xy 267.609326 -27.956491) (xy 267.645832 -28.004067) (xy 267.675816 -28.056001)
			(xy 267.698765 -28.111405) (xy 267.714286 -28.16933) (xy 267.722114 -28.228786) (xy 267.722604 -28.25877)
			(xy 267.722604 -29.114242) (xy 277.047452 -29.114242) (xy 277.047452 -28.250642) (xy 277.047942 -28.220674)
			(xy 277.055765 -28.161252) (xy 277.071278 -28.103359) (xy 277.094214 -28.047986) (xy 277.124181 -27.99608)
			(xy 277.160668 -27.94853) (xy 277.203048 -27.90615) (xy 277.250598 -27.869663) (xy 277.302504 -27.839696)
			(xy 277.357877 -27.81676) (xy 277.41577 -27.801247) (xy 277.475192 -27.793424) (xy 277.535128 -27.793424)
			(xy 277.59455 -27.801247) (xy 277.652443 -27.81676) (xy 277.707816 -27.839696) (xy 277.759722 -27.869663)
			(xy 277.807272 -27.90615) (xy 277.849652 -27.94853) (xy 277.886139 -27.99608) (xy 277.916106 -28.047986)
			(xy 277.939042 -28.103359) (xy 277.954555 -28.161252) (xy 277.962378 -28.220674) (xy 277.962868 -28.250642)
			(xy 277.962868 -29.114242) (xy 277.962735 -29.12237) (xy 292.806628 -29.12237) (xy 292.806628 -28.25877)
			(xy 292.807118 -28.228786) (xy 292.814946 -28.16933) (xy 292.830467 -28.111405) (xy 292.853416 -28.056001)
			(xy 292.8834 -28.004067) (xy 292.919906 -27.956491) (xy 292.962311 -27.914086) (xy 293.009887 -27.87758)
			(xy 293.061821 -27.847596) (xy 293.117225 -27.824647) (xy 293.17515 -27.809126) (xy 293.234606 -27.801298)
			(xy 293.294574 -27.801298) (xy 293.35403 -27.809126) (xy 293.411955 -27.824647) (xy 293.467359 -27.847596)
			(xy 293.519293 -27.87758) (xy 293.566869 -27.914086) (xy 293.609274 -27.956491) (xy 293.64578 -28.004067)
			(xy 293.675764 -28.056001) (xy 293.698713 -28.111405) (xy 293.714234 -28.16933) (xy 293.722062 -28.228786)
			(xy 293.722552 -28.25877) (xy 293.722552 -29.114242) (xy 303.0474 -29.114242) (xy 303.0474 -28.250642)
			(xy 303.04789 -28.220674) (xy 303.055713 -28.161252) (xy 303.071226 -28.103359) (xy 303.094162 -28.047986)
			(xy 303.124129 -27.99608) (xy 303.160616 -27.94853) (xy 303.202996 -27.90615) (xy 303.250546 -27.869663)
			(xy 303.302452 -27.839696) (xy 303.357825 -27.81676) (xy 303.415718 -27.801247) (xy 303.47514 -27.793424)
			(xy 303.535076 -27.793424) (xy 303.594498 -27.801247) (xy 303.652391 -27.81676) (xy 303.707764 -27.839696)
			(xy 303.75967 -27.869663) (xy 303.80722 -27.90615) (xy 303.8496 -27.94853) (xy 303.886087 -27.99608)
			(xy 303.916054 -28.047986) (xy 303.93899 -28.103359) (xy 303.954503 -28.161252) (xy 303.962326 -28.220674)
			(xy 303.962816 -28.250642) (xy 303.962816 -29.114242) (xy 303.962683 -29.12237) (xy 318.806576 -29.12237)
			(xy 318.806576 -28.25877) (xy 318.807066 -28.228786) (xy 318.814894 -28.16933) (xy 318.830415 -28.111405)
			(xy 318.853364 -28.056001) (xy 318.883348 -28.004067) (xy 318.919854 -27.956491) (xy 318.962259 -27.914086)
			(xy 319.009835 -27.87758) (xy 319.061769 -27.847596) (xy 319.117173 -27.824647) (xy 319.175098 -27.809126)
			(xy 319.234554 -27.801298) (xy 319.294522 -27.801298) (xy 319.353978 -27.809126) (xy 319.411903 -27.824647)
			(xy 319.467307 -27.847596) (xy 319.519241 -27.87758) (xy 319.566817 -27.914086) (xy 319.609222 -27.956491)
			(xy 319.645728 -28.004067) (xy 319.675712 -28.056001) (xy 319.698661 -28.111405) (xy 319.714182 -28.16933)
			(xy 319.72201 -28.228786) (xy 319.7225 -28.25877) (xy 319.7225 -29.114242) (xy 329.047348 -29.114242)
			(xy 329.047348 -28.250642) (xy 329.047838 -28.220674) (xy 329.055661 -28.161252) (xy 329.071174 -28.103359)
			(xy 329.09411 -28.047986) (xy 329.124077 -27.99608) (xy 329.160564 -27.94853) (xy 329.202944 -27.90615)
			(xy 329.250494 -27.869663) (xy 329.3024 -27.839696) (xy 329.357773 -27.81676) (xy 329.415666 -27.801247)
			(xy 329.475088 -27.793424) (xy 329.535024 -27.793424) (xy 329.594446 -27.801247) (xy 329.652339 -27.81676)
			(xy 329.707712 -27.839696) (xy 329.759618 -27.869663) (xy 329.807168 -27.90615) (xy 329.849548 -27.94853)
			(xy 329.886035 -27.99608) (xy 329.916002 -28.047986) (xy 329.938938 -28.103359) (xy 329.954451 -28.161252)
			(xy 329.962274 -28.220674) (xy 329.962764 -28.250642) (xy 329.962764 -29.114242) (xy 329.962631 -29.12237)
			(xy 356.907084 -29.12237) (xy 356.907084 -28.25877) (xy 356.907574 -28.228802) (xy 356.915397 -28.16938)
			(xy 356.93091 -28.111487) (xy 356.953846 -28.056114) (xy 356.983813 -28.004208) (xy 357.0203 -27.956658)
			(xy 357.06268 -27.914278) (xy 357.11023 -27.877791) (xy 357.162136 -27.847824) (xy 357.217509 -27.824888)
			(xy 357.275402 -27.809375) (xy 357.334824 -27.801552) (xy 357.39476 -27.801552) (xy 357.454182 -27.809375)
			(xy 357.512075 -27.824888) (xy 357.567448 -27.847824) (xy 357.619354 -27.877791) (xy 357.666904 -27.914278)
			(xy 357.709284 -27.956658) (xy 357.745771 -28.004208) (xy 357.775738 -28.056114) (xy 357.798674 -28.111487)
			(xy 357.814187 -28.16938) (xy 357.82201 -28.228802) (xy 357.8225 -28.25877) (xy 357.8225 -29.114242)
			(xy 367.147348 -29.114242) (xy 367.147348 -28.250642) (xy 367.147838 -28.220658) (xy 367.155666 -28.161202)
			(xy 367.171187 -28.103277) (xy 367.194136 -28.047873) (xy 367.22412 -27.995939) (xy 367.260626 -27.948363)
			(xy 367.303031 -27.905958) (xy 367.350607 -27.869452) (xy 367.402541 -27.839468) (xy 367.457945 -27.816519)
			(xy 367.51587 -27.800998) (xy 367.575326 -27.79317) (xy 367.635294 -27.79317) (xy 367.69475 -27.800998)
			(xy 367.752675 -27.816519) (xy 367.808079 -27.839468) (xy 367.860013 -27.869452) (xy 367.907589 -27.905958)
			(xy 367.949994 -27.948363) (xy 367.9865 -27.995939) (xy 368.016484 -28.047873) (xy 368.039433 -28.103277)
			(xy 368.054954 -28.161202) (xy 368.062782 -28.220658) (xy 368.063272 -28.250642) (xy 368.063272 -29.114242)
			(xy 368.063139 -29.12237) (xy 382.907032 -29.12237) (xy 382.907032 -28.25877) (xy 382.907522 -28.228802)
			(xy 382.915345 -28.16938) (xy 382.930858 -28.111487) (xy 382.953794 -28.056114) (xy 382.983761 -28.004208)
			(xy 383.020248 -27.956658) (xy 383.062628 -27.914278) (xy 383.110178 -27.877791) (xy 383.162084 -27.847824)
			(xy 383.217457 -27.824888) (xy 383.27535 -27.809375) (xy 383.334772 -27.801552) (xy 383.394708 -27.801552)
			(xy 383.45413 -27.809375) (xy 383.512023 -27.824888) (xy 383.567396 -27.847824) (xy 383.619302 -27.877791)
			(xy 383.666852 -27.914278) (xy 383.709232 -27.956658) (xy 383.745719 -28.004208) (xy 383.775686 -28.056114)
			(xy 383.798622 -28.111487) (xy 383.814135 -28.16938) (xy 383.821958 -28.228802) (xy 383.822448 -28.25877)
			(xy 383.822448 -29.114242) (xy 393.147296 -29.114242) (xy 393.147296 -28.250642) (xy 393.147786 -28.220658)
			(xy 393.155614 -28.161202) (xy 393.171135 -28.103277) (xy 393.194084 -28.047873) (xy 393.224068 -27.995939)
			(xy 393.260574 -27.948363) (xy 393.302979 -27.905958) (xy 393.350555 -27.869452) (xy 393.402489 -27.839468)
			(xy 393.457893 -27.816519) (xy 393.515818 -27.800998) (xy 393.575274 -27.79317) (xy 393.635242 -27.79317)
			(xy 393.694698 -27.800998) (xy 393.752623 -27.816519) (xy 393.808027 -27.839468) (xy 393.859961 -27.869452)
			(xy 393.907537 -27.905958) (xy 393.949942 -27.948363) (xy 393.986448 -27.995939) (xy 394.016432 -28.047873)
			(xy 394.039381 -28.103277) (xy 394.054902 -28.161202) (xy 394.06273 -28.220658) (xy 394.06322 -28.250642)
			(xy 394.06322 -29.114242) (xy 394.063087 -29.12237) (xy 408.90698 -29.12237) (xy 408.90698 -28.25877)
			(xy 408.90747 -28.228802) (xy 408.915293 -28.16938) (xy 408.930806 -28.111487) (xy 408.953742 -28.056114)
			(xy 408.983709 -28.004208) (xy 409.020196 -27.956658) (xy 409.062576 -27.914278) (xy 409.110126 -27.877791)
			(xy 409.162032 -27.847824) (xy 409.217405 -27.824888) (xy 409.275298 -27.809375) (xy 409.33472 -27.801552)
			(xy 409.394656 -27.801552) (xy 409.454078 -27.809375) (xy 409.511971 -27.824888) (xy 409.567344 -27.847824)
			(xy 409.61925 -27.877791) (xy 409.6668 -27.914278) (xy 409.70918 -27.956658) (xy 409.745667 -28.004208)
			(xy 409.775634 -28.056114) (xy 409.79857 -28.111487) (xy 409.814083 -28.16938) (xy 409.821906 -28.228802)
			(xy 409.822396 -28.25877) (xy 409.822396 -29.114242) (xy 419.147244 -29.114242) (xy 419.147244 -28.250642)
			(xy 419.147734 -28.220658) (xy 419.155562 -28.161202) (xy 419.171083 -28.103277) (xy 419.194032 -28.047873)
			(xy 419.224016 -27.995939) (xy 419.260522 -27.948363) (xy 419.302927 -27.905958) (xy 419.350503 -27.869452)
			(xy 419.402437 -27.839468) (xy 419.457841 -27.816519) (xy 419.515766 -27.800998) (xy 419.575222 -27.79317)
			(xy 419.63519 -27.79317) (xy 419.694646 -27.800998) (xy 419.752571 -27.816519) (xy 419.807975 -27.839468)
			(xy 419.859909 -27.869452) (xy 419.907485 -27.905958) (xy 419.94989 -27.948363) (xy 419.986396 -27.995939)
			(xy 420.01638 -28.047873) (xy 420.039329 -28.103277) (xy 420.05485 -28.161202) (xy 420.062678 -28.220658)
			(xy 420.063168 -28.250642) (xy 420.063168 -29.114242) (xy 420.063035 -29.12237) (xy 434.906928 -29.12237)
			(xy 434.906928 -28.25877) (xy 434.907418 -28.228802) (xy 434.915241 -28.16938) (xy 434.930754 -28.111487)
			(xy 434.95369 -28.056114) (xy 434.983657 -28.004208) (xy 435.020144 -27.956658) (xy 435.062524 -27.914278)
			(xy 435.110074 -27.877791) (xy 435.16198 -27.847824) (xy 435.217353 -27.824888) (xy 435.275246 -27.809375)
			(xy 435.334668 -27.801552) (xy 435.394604 -27.801552) (xy 435.454026 -27.809375) (xy 435.511919 -27.824888)
			(xy 435.567292 -27.847824) (xy 435.619198 -27.877791) (xy 435.666748 -27.914278) (xy 435.709128 -27.956658)
			(xy 435.745615 -28.004208) (xy 435.775582 -28.056114) (xy 435.798518 -28.111487) (xy 435.814031 -28.16938)
			(xy 435.821854 -28.228802) (xy 435.822344 -28.25877) (xy 435.822344 -29.114242) (xy 445.147192 -29.114242)
			(xy 445.147192 -28.250642) (xy 445.147682 -28.220658) (xy 445.15551 -28.161202) (xy 445.171031 -28.103277)
			(xy 445.19398 -28.047873) (xy 445.223964 -27.995939) (xy 445.26047 -27.948363) (xy 445.302875 -27.905958)
			(xy 445.350451 -27.869452) (xy 445.402385 -27.839468) (xy 445.457789 -27.816519) (xy 445.515714 -27.800998)
			(xy 445.57517 -27.79317) (xy 445.635138 -27.79317) (xy 445.694594 -27.800998) (xy 445.752519 -27.816519)
			(xy 445.807923 -27.839468) (xy 445.859857 -27.869452) (xy 445.907433 -27.905958) (xy 445.949838 -27.948363)
			(xy 445.986344 -27.995939) (xy 446.016328 -28.047873) (xy 446.039277 -28.103277) (xy 446.054798 -28.161202)
			(xy 446.062626 -28.220658) (xy 446.063116 -28.250642) (xy 446.063116 -29.114242) (xy 446.062626 -29.144226)
			(xy 446.054798 -29.203682) (xy 446.039277 -29.261607) (xy 446.016328 -29.317011) (xy 445.986344 -29.368945)
			(xy 445.949838 -29.416521) (xy 445.907433 -29.458926) (xy 445.859857 -29.495432) (xy 445.807923 -29.525416)
			(xy 445.752519 -29.548365) (xy 445.694594 -29.563886) (xy 445.635138 -29.571714) (xy 445.57517 -29.571714)
			(xy 445.515714 -29.563886) (xy 445.457789 -29.548365) (xy 445.402385 -29.525416) (xy 445.350451 -29.495432)
			(xy 445.302875 -29.458926) (xy 445.26047 -29.416521) (xy 445.223964 -29.368945) (xy 445.19398 -29.317011)
			(xy 445.171031 -29.261607) (xy 445.15551 -29.203682) (xy 445.147682 -29.144226) (xy 445.147192 -29.114242)
			(xy 435.822344 -29.114242) (xy 435.822344 -29.12237) (xy 435.821854 -29.152338) (xy 435.814031 -29.21176)
			(xy 435.798518 -29.269653) (xy 435.775582 -29.325026) (xy 435.745615 -29.376932) (xy 435.709128 -29.424482)
			(xy 435.666748 -29.466862) (xy 435.619198 -29.503349) (xy 435.567292 -29.533316) (xy 435.511919 -29.556252)
			(xy 435.454026 -29.571765) (xy 435.394604 -29.579588) (xy 435.334668 -29.579588) (xy 435.275246 -29.571765)
			(xy 435.217353 -29.556252) (xy 435.16198 -29.533316) (xy 435.110074 -29.503349) (xy 435.062524 -29.466862)
			(xy 435.020144 -29.424482) (xy 434.983657 -29.376932) (xy 434.95369 -29.325026) (xy 434.930754 -29.269653)
			(xy 434.915241 -29.21176) (xy 434.907418 -29.152338) (xy 434.906928 -29.12237) (xy 420.063035 -29.12237)
			(xy 420.062678 -29.144226) (xy 420.05485 -29.203682) (xy 420.039329 -29.261607) (xy 420.01638 -29.317011)
			(xy 419.986396 -29.368945) (xy 419.94989 -29.416521) (xy 419.907485 -29.458926) (xy 419.859909 -29.495432)
			(xy 419.807975 -29.525416) (xy 419.752571 -29.548365) (xy 419.694646 -29.563886) (xy 419.63519 -29.571714)
			(xy 419.575222 -29.571714) (xy 419.515766 -29.563886) (xy 419.457841 -29.548365) (xy 419.402437 -29.525416)
			(xy 419.350503 -29.495432) (xy 419.302927 -29.458926) (xy 419.260522 -29.416521) (xy 419.224016 -29.368945)
			(xy 419.194032 -29.317011) (xy 419.171083 -29.261607) (xy 419.155562 -29.203682) (xy 419.147734 -29.144226)
			(xy 419.147244 -29.114242) (xy 409.822396 -29.114242) (xy 409.822396 -29.12237) (xy 409.821906 -29.152338)
			(xy 409.814083 -29.21176) (xy 409.79857 -29.269653) (xy 409.775634 -29.325026) (xy 409.745667 -29.376932)
			(xy 409.70918 -29.424482) (xy 409.6668 -29.466862) (xy 409.61925 -29.503349) (xy 409.567344 -29.533316)
			(xy 409.511971 -29.556252) (xy 409.454078 -29.571765) (xy 409.394656 -29.579588) (xy 409.33472 -29.579588)
			(xy 409.275298 -29.571765) (xy 409.217405 -29.556252) (xy 409.162032 -29.533316) (xy 409.110126 -29.503349)
			(xy 409.062576 -29.466862) (xy 409.020196 -29.424482) (xy 408.983709 -29.376932) (xy 408.953742 -29.325026)
			(xy 408.930806 -29.269653) (xy 408.915293 -29.21176) (xy 408.90747 -29.152338) (xy 408.90698 -29.12237)
			(xy 394.063087 -29.12237) (xy 394.06273 -29.144226) (xy 394.054902 -29.203682) (xy 394.039381 -29.261607)
			(xy 394.016432 -29.317011) (xy 393.986448 -29.368945) (xy 393.949942 -29.416521) (xy 393.907537 -29.458926)
			(xy 393.859961 -29.495432) (xy 393.808027 -29.525416) (xy 393.752623 -29.548365) (xy 393.694698 -29.563886)
			(xy 393.635242 -29.571714) (xy 393.575274 -29.571714) (xy 393.515818 -29.563886) (xy 393.457893 -29.548365)
			(xy 393.402489 -29.525416) (xy 393.350555 -29.495432) (xy 393.302979 -29.458926) (xy 393.260574 -29.416521)
			(xy 393.224068 -29.368945) (xy 393.194084 -29.317011) (xy 393.171135 -29.261607) (xy 393.155614 -29.203682)
			(xy 393.147786 -29.144226) (xy 393.147296 -29.114242) (xy 383.822448 -29.114242) (xy 383.822448 -29.12237)
			(xy 383.821958 -29.152338) (xy 383.814135 -29.21176) (xy 383.798622 -29.269653) (xy 383.775686 -29.325026)
			(xy 383.745719 -29.376932) (xy 383.709232 -29.424482) (xy 383.666852 -29.466862) (xy 383.619302 -29.503349)
			(xy 383.567396 -29.533316) (xy 383.512023 -29.556252) (xy 383.45413 -29.571765) (xy 383.394708 -29.579588)
			(xy 383.334772 -29.579588) (xy 383.27535 -29.571765) (xy 383.217457 -29.556252) (xy 383.162084 -29.533316)
			(xy 383.110178 -29.503349) (xy 383.062628 -29.466862) (xy 383.020248 -29.424482) (xy 382.983761 -29.376932)
			(xy 382.953794 -29.325026) (xy 382.930858 -29.269653) (xy 382.915345 -29.21176) (xy 382.907522 -29.152338)
			(xy 382.907032 -29.12237) (xy 368.063139 -29.12237) (xy 368.062782 -29.144226) (xy 368.054954 -29.203682)
			(xy 368.039433 -29.261607) (xy 368.016484 -29.317011) (xy 367.9865 -29.368945) (xy 367.949994 -29.416521)
			(xy 367.907589 -29.458926) (xy 367.860013 -29.495432) (xy 367.808079 -29.525416) (xy 367.752675 -29.548365)
			(xy 367.69475 -29.563886) (xy 367.635294 -29.571714) (xy 367.575326 -29.571714) (xy 367.51587 -29.563886)
			(xy 367.457945 -29.548365) (xy 367.402541 -29.525416) (xy 367.350607 -29.495432) (xy 367.303031 -29.458926)
			(xy 367.260626 -29.416521) (xy 367.22412 -29.368945) (xy 367.194136 -29.317011) (xy 367.171187 -29.261607)
			(xy 367.155666 -29.203682) (xy 367.147838 -29.144226) (xy 367.147348 -29.114242) (xy 357.8225 -29.114242)
			(xy 357.8225 -29.12237) (xy 357.82201 -29.152338) (xy 357.814187 -29.21176) (xy 357.798674 -29.269653)
			(xy 357.775738 -29.325026) (xy 357.745771 -29.376932) (xy 357.709284 -29.424482) (xy 357.666904 -29.466862)
			(xy 357.619354 -29.503349) (xy 357.567448 -29.533316) (xy 357.512075 -29.556252) (xy 357.454182 -29.571765)
			(xy 357.39476 -29.579588) (xy 357.334824 -29.579588) (xy 357.275402 -29.571765) (xy 357.217509 -29.556252)
			(xy 357.162136 -29.533316) (xy 357.11023 -29.503349) (xy 357.06268 -29.466862) (xy 357.0203 -29.424482)
			(xy 356.983813 -29.376932) (xy 356.953846 -29.325026) (xy 356.93091 -29.269653) (xy 356.915397 -29.21176)
			(xy 356.907574 -29.152338) (xy 356.907084 -29.12237) (xy 329.962631 -29.12237) (xy 329.962274 -29.14421)
			(xy 329.954451 -29.203632) (xy 329.938938 -29.261525) (xy 329.916002 -29.316898) (xy 329.886035 -29.368804)
			(xy 329.849548 -29.416354) (xy 329.807168 -29.458734) (xy 329.759618 -29.495221) (xy 329.707712 -29.525188)
			(xy 329.652339 -29.548124) (xy 329.594446 -29.563637) (xy 329.535024 -29.57146) (xy 329.475088 -29.57146)
			(xy 329.415666 -29.563637) (xy 329.357773 -29.548124) (xy 329.3024 -29.525188) (xy 329.250494 -29.495221)
			(xy 329.202944 -29.458734) (xy 329.160564 -29.416354) (xy 329.124077 -29.368804) (xy 329.09411 -29.316898)
			(xy 329.071174 -29.261525) (xy 329.055661 -29.203632) (xy 329.047838 -29.14421) (xy 329.047348 -29.114242)
			(xy 319.7225 -29.114242) (xy 319.7225 -29.12237) (xy 319.72201 -29.152354) (xy 319.714182 -29.21181)
			(xy 319.698661 -29.269735) (xy 319.675712 -29.325139) (xy 319.645728 -29.377073) (xy 319.609222 -29.424649)
			(xy 319.566817 -29.467054) (xy 319.519241 -29.50356) (xy 319.467307 -29.533544) (xy 319.411903 -29.556493)
			(xy 319.353978 -29.572014) (xy 319.294522 -29.579842) (xy 319.234554 -29.579842) (xy 319.175098 -29.572014)
			(xy 319.117173 -29.556493) (xy 319.061769 -29.533544) (xy 319.009835 -29.50356) (xy 318.962259 -29.467054)
			(xy 318.919854 -29.424649) (xy 318.883348 -29.377073) (xy 318.853364 -29.325139) (xy 318.830415 -29.269735)
			(xy 318.814894 -29.21181) (xy 318.807066 -29.152354) (xy 318.806576 -29.12237) (xy 303.962683 -29.12237)
			(xy 303.962326 -29.14421) (xy 303.954503 -29.203632) (xy 303.93899 -29.261525) (xy 303.916054 -29.316898)
			(xy 303.886087 -29.368804) (xy 303.8496 -29.416354) (xy 303.80722 -29.458734) (xy 303.75967 -29.495221)
			(xy 303.707764 -29.525188) (xy 303.652391 -29.548124) (xy 303.594498 -29.563637) (xy 303.535076 -29.57146)
			(xy 303.47514 -29.57146) (xy 303.415718 -29.563637) (xy 303.357825 -29.548124) (xy 303.302452 -29.525188)
			(xy 303.250546 -29.495221) (xy 303.202996 -29.458734) (xy 303.160616 -29.416354) (xy 303.124129 -29.368804)
			(xy 303.094162 -29.316898) (xy 303.071226 -29.261525) (xy 303.055713 -29.203632) (xy 303.04789 -29.14421)
			(xy 303.0474 -29.114242) (xy 293.722552 -29.114242) (xy 293.722552 -29.12237) (xy 293.722062 -29.152354)
			(xy 293.714234 -29.21181) (xy 293.698713 -29.269735) (xy 293.675764 -29.325139) (xy 293.64578 -29.377073)
			(xy 293.609274 -29.424649) (xy 293.566869 -29.467054) (xy 293.519293 -29.50356) (xy 293.467359 -29.533544)
			(xy 293.411955 -29.556493) (xy 293.35403 -29.572014) (xy 293.294574 -29.579842) (xy 293.234606 -29.579842)
			(xy 293.17515 -29.572014) (xy 293.117225 -29.556493) (xy 293.061821 -29.533544) (xy 293.009887 -29.50356)
			(xy 292.962311 -29.467054) (xy 292.919906 -29.424649) (xy 292.8834 -29.377073) (xy 292.853416 -29.325139)
			(xy 292.830467 -29.269735) (xy 292.814946 -29.21181) (xy 292.807118 -29.152354) (xy 292.806628 -29.12237)
			(xy 277.962735 -29.12237) (xy 277.962378 -29.14421) (xy 277.954555 -29.203632) (xy 277.939042 -29.261525)
			(xy 277.916106 -29.316898) (xy 277.886139 -29.368804) (xy 277.849652 -29.416354) (xy 277.807272 -29.458734)
			(xy 277.759722 -29.495221) (xy 277.707816 -29.525188) (xy 277.652443 -29.548124) (xy 277.59455 -29.563637)
			(xy 277.535128 -29.57146) (xy 277.475192 -29.57146) (xy 277.41577 -29.563637) (xy 277.357877 -29.548124)
			(xy 277.302504 -29.525188) (xy 277.250598 -29.495221) (xy 277.203048 -29.458734) (xy 277.160668 -29.416354)
			(xy 277.124181 -29.368804) (xy 277.094214 -29.316898) (xy 277.071278 -29.261525) (xy 277.055765 -29.203632)
			(xy 277.047942 -29.14421) (xy 277.047452 -29.114242) (xy 267.722604 -29.114242) (xy 267.722604 -29.12237)
			(xy 267.722114 -29.152354) (xy 267.714286 -29.21181) (xy 267.698765 -29.269735) (xy 267.675816 -29.325139)
			(xy 267.645832 -29.377073) (xy 267.609326 -29.424649) (xy 267.566921 -29.467054) (xy 267.519345 -29.50356)
			(xy 267.467411 -29.533544) (xy 267.412007 -29.556493) (xy 267.354082 -29.572014) (xy 267.294626 -29.579842)
			(xy 267.234658 -29.579842) (xy 267.175202 -29.572014) (xy 267.117277 -29.556493) (xy 267.061873 -29.533544)
			(xy 267.009939 -29.50356) (xy 266.962363 -29.467054) (xy 266.919958 -29.424649) (xy 266.883452 -29.377073)
			(xy 266.853468 -29.325139) (xy 266.830519 -29.269735) (xy 266.814998 -29.21181) (xy 266.80717 -29.152354)
			(xy 266.80668 -29.12237) (xy 251.962787 -29.12237) (xy 251.96243 -29.14421) (xy 251.954607 -29.203632)
			(xy 251.939094 -29.261525) (xy 251.916158 -29.316898) (xy 251.886191 -29.368804) (xy 251.849704 -29.416354)
			(xy 251.807324 -29.458734) (xy 251.759774 -29.495221) (xy 251.707868 -29.525188) (xy 251.652495 -29.548124)
			(xy 251.594602 -29.563637) (xy 251.53518 -29.57146) (xy 251.475244 -29.57146) (xy 251.415822 -29.563637)
			(xy 251.357929 -29.548124) (xy 251.302556 -29.525188) (xy 251.25065 -29.495221) (xy 251.2031 -29.458734)
			(xy 251.16072 -29.416354) (xy 251.124233 -29.368804) (xy 251.094266 -29.316898) (xy 251.07133 -29.261525)
			(xy 251.055817 -29.203632) (xy 251.047994 -29.14421) (xy 251.047504 -29.114242) (xy 241.722656 -29.114242)
			(xy 241.722656 -29.12237) (xy 241.722166 -29.152354) (xy 241.714338 -29.21181) (xy 241.698817 -29.269735)
			(xy 241.675868 -29.325139) (xy 241.645884 -29.377073) (xy 241.609378 -29.424649) (xy 241.566973 -29.467054)
			(xy 241.519397 -29.50356) (xy 241.467463 -29.533544) (xy 241.412059 -29.556493) (xy 241.354134 -29.572014)
			(xy 241.294678 -29.579842) (xy 241.23471 -29.579842) (xy 241.175254 -29.572014) (xy 241.117329 -29.556493)
			(xy 241.061925 -29.533544) (xy 241.009991 -29.50356) (xy 240.962415 -29.467054) (xy 240.92001 -29.424649)
			(xy 240.883504 -29.377073) (xy 240.85352 -29.325139) (xy 240.830571 -29.269735) (xy 240.81505 -29.21181)
			(xy 240.807222 -29.152354) (xy 240.806732 -29.12237) (xy 213.862787 -29.12237) (xy 213.86243 -29.14421)
			(xy 213.854607 -29.203632) (xy 213.839094 -29.261525) (xy 213.816158 -29.316898) (xy 213.786191 -29.368804)
			(xy 213.749704 -29.416354) (xy 213.707324 -29.458734) (xy 213.659774 -29.495221) (xy 213.607868 -29.525188)
			(xy 213.552495 -29.548124) (xy 213.494602 -29.563637) (xy 213.43518 -29.57146) (xy 213.375244 -29.57146)
			(xy 213.315822 -29.563637) (xy 213.257929 -29.548124) (xy 213.202556 -29.525188) (xy 213.15065 -29.495221)
			(xy 213.1031 -29.458734) (xy 213.06072 -29.416354) (xy 213.024233 -29.368804) (xy 212.994266 -29.316898)
			(xy 212.97133 -29.261525) (xy 212.955817 -29.203632) (xy 212.947994 -29.14421) (xy 212.947504 -29.114242)
			(xy 203.622656 -29.114242) (xy 203.622656 -29.12237) (xy 203.622166 -29.152354) (xy 203.614338 -29.21181)
			(xy 203.598817 -29.269735) (xy 203.575868 -29.325139) (xy 203.545884 -29.377073) (xy 203.509378 -29.424649)
			(xy 203.466973 -29.467054) (xy 203.419397 -29.50356) (xy 203.367463 -29.533544) (xy 203.312059 -29.556493)
			(xy 203.254134 -29.572014) (xy 203.194678 -29.579842) (xy 203.13471 -29.579842) (xy 203.075254 -29.572014)
			(xy 203.017329 -29.556493) (xy 202.961925 -29.533544) (xy 202.909991 -29.50356) (xy 202.862415 -29.467054)
			(xy 202.82001 -29.424649) (xy 202.783504 -29.377073) (xy 202.75352 -29.325139) (xy 202.730571 -29.269735)
			(xy 202.71505 -29.21181) (xy 202.707222 -29.152354) (xy 202.706732 -29.12237) (xy 187.862839 -29.12237)
			(xy 187.862482 -29.14421) (xy 187.854659 -29.203632) (xy 187.839146 -29.261525) (xy 187.81621 -29.316898)
			(xy 187.786243 -29.368804) (xy 187.749756 -29.416354) (xy 187.707376 -29.458734) (xy 187.659826 -29.495221)
			(xy 187.60792 -29.525188) (xy 187.552547 -29.548124) (xy 187.494654 -29.563637) (xy 187.435232 -29.57146)
			(xy 187.375296 -29.57146) (xy 187.315874 -29.563637) (xy 187.257981 -29.548124) (xy 187.202608 -29.525188)
			(xy 187.150702 -29.495221) (xy 187.103152 -29.458734) (xy 187.060772 -29.416354) (xy 187.024285 -29.368804)
			(xy 186.994318 -29.316898) (xy 186.971382 -29.261525) (xy 186.955869 -29.203632) (xy 186.948046 -29.14421)
			(xy 186.947556 -29.114242) (xy 177.622708 -29.114242) (xy 177.622708 -29.12237) (xy 177.622218 -29.152354)
			(xy 177.61439 -29.21181) (xy 177.598869 -29.269735) (xy 177.57592 -29.325139) (xy 177.545936 -29.377073)
			(xy 177.50943 -29.424649) (xy 177.467025 -29.467054) (xy 177.419449 -29.50356) (xy 177.367515 -29.533544)
			(xy 177.312111 -29.556493) (xy 177.254186 -29.572014) (xy 177.19473 -29.579842) (xy 177.134762 -29.579842)
			(xy 177.075306 -29.572014) (xy 177.017381 -29.556493) (xy 176.961977 -29.533544) (xy 176.910043 -29.50356)
			(xy 176.862467 -29.467054) (xy 176.820062 -29.424649) (xy 176.783556 -29.377073) (xy 176.753572 -29.325139)
			(xy 176.730623 -29.269735) (xy 176.715102 -29.21181) (xy 176.707274 -29.152354) (xy 176.706784 -29.12237)
			(xy 161.862891 -29.12237) (xy 161.862534 -29.14421) (xy 161.854711 -29.203632) (xy 161.839198 -29.261525)
			(xy 161.816262 -29.316898) (xy 161.786295 -29.368804) (xy 161.749808 -29.416354) (xy 161.707428 -29.458734)
			(xy 161.659878 -29.495221) (xy 161.607972 -29.525188) (xy 161.552599 -29.548124) (xy 161.494706 -29.563637)
			(xy 161.435284 -29.57146) (xy 161.375348 -29.57146) (xy 161.315926 -29.563637) (xy 161.258033 -29.548124)
			(xy 161.20266 -29.525188) (xy 161.150754 -29.495221) (xy 161.103204 -29.458734) (xy 161.060824 -29.416354)
			(xy 161.024337 -29.368804) (xy 160.99437 -29.316898) (xy 160.971434 -29.261525) (xy 160.955921 -29.203632)
			(xy 160.948098 -29.14421) (xy 160.947608 -29.114242) (xy 151.62276 -29.114242) (xy 151.62276 -29.12237)
			(xy 151.62227 -29.152354) (xy 151.614442 -29.21181) (xy 151.598921 -29.269735) (xy 151.575972 -29.325139)
			(xy 151.545988 -29.377073) (xy 151.509482 -29.424649) (xy 151.467077 -29.467054) (xy 151.419501 -29.50356)
			(xy 151.367567 -29.533544) (xy 151.312163 -29.556493) (xy 151.254238 -29.572014) (xy 151.194782 -29.579842)
			(xy 151.134814 -29.579842) (xy 151.075358 -29.572014) (xy 151.017433 -29.556493) (xy 150.962029 -29.533544)
			(xy 150.910095 -29.50356) (xy 150.862519 -29.467054) (xy 150.820114 -29.424649) (xy 150.783608 -29.377073)
			(xy 150.753624 -29.325139) (xy 150.730675 -29.269735) (xy 150.715154 -29.21181) (xy 150.707326 -29.152354)
			(xy 150.706836 -29.12237) (xy 135.862943 -29.12237) (xy 135.862586 -29.14421) (xy 135.854763 -29.203632)
			(xy 135.83925 -29.261525) (xy 135.816314 -29.316898) (xy 135.786347 -29.368804) (xy 135.74986 -29.416354)
			(xy 135.70748 -29.458734) (xy 135.65993 -29.495221) (xy 135.608024 -29.525188) (xy 135.552651 -29.548124)
			(xy 135.494758 -29.563637) (xy 135.435336 -29.57146) (xy 135.3754 -29.57146) (xy 135.315978 -29.563637)
			(xy 135.258085 -29.548124) (xy 135.202712 -29.525188) (xy 135.150806 -29.495221) (xy 135.103256 -29.458734)
			(xy 135.060876 -29.416354) (xy 135.024389 -29.368804) (xy 134.994422 -29.316898) (xy 134.971486 -29.261525)
			(xy 134.955973 -29.203632) (xy 134.94815 -29.14421) (xy 134.94766 -29.114242) (xy 125.622812 -29.114242)
			(xy 125.622812 -29.12237) (xy 125.622322 -29.152354) (xy 125.614494 -29.21181) (xy 125.598973 -29.269735)
			(xy 125.576024 -29.325139) (xy 125.54604 -29.377073) (xy 125.509534 -29.424649) (xy 125.467129 -29.467054)
			(xy 125.419553 -29.50356) (xy 125.367619 -29.533544) (xy 125.312215 -29.556493) (xy 125.25429 -29.572014)
			(xy 125.194834 -29.579842) (xy 125.134866 -29.579842) (xy 125.07541 -29.572014) (xy 125.017485 -29.556493)
			(xy 124.962081 -29.533544) (xy 124.910147 -29.50356) (xy 124.862571 -29.467054) (xy 124.820166 -29.424649)
			(xy 124.78366 -29.377073) (xy 124.753676 -29.325139) (xy 124.730727 -29.269735) (xy 124.715206 -29.21181)
			(xy 124.707378 -29.152354) (xy 124.706888 -29.12237) (xy 97.762943 -29.12237) (xy 97.762586 -29.144226)
			(xy 97.754758 -29.203682) (xy 97.739237 -29.261607) (xy 97.716288 -29.317011) (xy 97.686304 -29.368945)
			(xy 97.649798 -29.416521) (xy 97.607393 -29.458926) (xy 97.559817 -29.495432) (xy 97.507883 -29.525416)
			(xy 97.452479 -29.548365) (xy 97.394554 -29.563886) (xy 97.335098 -29.571714) (xy 97.27513 -29.571714)
			(xy 97.215674 -29.563886) (xy 97.157749 -29.548365) (xy 97.102345 -29.525416) (xy 97.050411 -29.495432)
			(xy 97.002835 -29.458926) (xy 96.96043 -29.416521) (xy 96.923924 -29.368945) (xy 96.89394 -29.317011)
			(xy 96.870991 -29.261607) (xy 96.85547 -29.203682) (xy 96.847642 -29.144226) (xy 96.847152 -29.114242)
			(xy 87.522304 -29.114242) (xy 87.522304 -29.12237) (xy 87.521814 -29.152338) (xy 87.513991 -29.21176)
			(xy 87.498478 -29.269653) (xy 87.475542 -29.325026) (xy 87.445575 -29.376932) (xy 87.409088 -29.424482)
			(xy 87.366708 -29.466862) (xy 87.319158 -29.503349) (xy 87.267252 -29.533316) (xy 87.211879 -29.556252)
			(xy 87.153986 -29.571765) (xy 87.094564 -29.579588) (xy 87.034628 -29.579588) (xy 86.975206 -29.571765)
			(xy 86.917313 -29.556252) (xy 86.86194 -29.533316) (xy 86.810034 -29.503349) (xy 86.762484 -29.466862)
			(xy 86.720104 -29.424482) (xy 86.683617 -29.376932) (xy 86.65365 -29.325026) (xy 86.630714 -29.269653)
			(xy 86.615201 -29.21176) (xy 86.607378 -29.152338) (xy 86.606888 -29.12237) (xy 71.762995 -29.12237)
			(xy 71.762638 -29.144226) (xy 71.75481 -29.203682) (xy 71.739289 -29.261607) (xy 71.71634 -29.317011)
			(xy 71.686356 -29.368945) (xy 71.64985 -29.416521) (xy 71.607445 -29.458926) (xy 71.559869 -29.495432)
			(xy 71.507935 -29.525416) (xy 71.452531 -29.548365) (xy 71.394606 -29.563886) (xy 71.33515 -29.571714)
			(xy 71.275182 -29.571714) (xy 71.215726 -29.563886) (xy 71.157801 -29.548365) (xy 71.102397 -29.525416)
			(xy 71.050463 -29.495432) (xy 71.002887 -29.458926) (xy 70.960482 -29.416521) (xy 70.923976 -29.368945)
			(xy 70.893992 -29.317011) (xy 70.871043 -29.261607) (xy 70.855522 -29.203682) (xy 70.847694 -29.144226)
			(xy 70.847204 -29.114242) (xy 61.522356 -29.114242) (xy 61.522356 -29.12237) (xy 61.521866 -29.152338)
			(xy 61.514043 -29.21176) (xy 61.49853 -29.269653) (xy 61.475594 -29.325026) (xy 61.445627 -29.376932)
			(xy 61.40914 -29.424482) (xy 61.36676 -29.466862) (xy 61.31921 -29.503349) (xy 61.267304 -29.533316)
			(xy 61.211931 -29.556252) (xy 61.154038 -29.571765) (xy 61.094616 -29.579588) (xy 61.03468 -29.579588)
			(xy 60.975258 -29.571765) (xy 60.917365 -29.556252) (xy 60.861992 -29.533316) (xy 60.810086 -29.503349)
			(xy 60.762536 -29.466862) (xy 60.720156 -29.424482) (xy 60.683669 -29.376932) (xy 60.653702 -29.325026)
			(xy 60.630766 -29.269653) (xy 60.615253 -29.21176) (xy 60.60743 -29.152338) (xy 60.60694 -29.12237)
			(xy 45.763047 -29.12237) (xy 45.76269 -29.144226) (xy 45.754862 -29.203682) (xy 45.739341 -29.261607)
			(xy 45.716392 -29.317011) (xy 45.686408 -29.368945) (xy 45.649902 -29.416521) (xy 45.607497 -29.458926)
			(xy 45.559921 -29.495432) (xy 45.507987 -29.525416) (xy 45.452583 -29.548365) (xy 45.394658 -29.563886)
			(xy 45.335202 -29.571714) (xy 45.275234 -29.571714) (xy 45.215778 -29.563886) (xy 45.157853 -29.548365)
			(xy 45.102449 -29.525416) (xy 45.050515 -29.495432) (xy 45.002939 -29.458926) (xy 44.960534 -29.416521)
			(xy 44.924028 -29.368945) (xy 44.894044 -29.317011) (xy 44.871095 -29.261607) (xy 44.855574 -29.203682)
			(xy 44.847746 -29.144226) (xy 44.847256 -29.114242) (xy 35.522408 -29.114242) (xy 35.522408 -29.12237)
			(xy 35.521918 -29.152338) (xy 35.514095 -29.21176) (xy 35.498582 -29.269653) (xy 35.475646 -29.325026)
			(xy 35.445679 -29.376932) (xy 35.409192 -29.424482) (xy 35.366812 -29.466862) (xy 35.319262 -29.503349)
			(xy 35.267356 -29.533316) (xy 35.211983 -29.556252) (xy 35.15409 -29.571765) (xy 35.094668 -29.579588)
			(xy 35.034732 -29.579588) (xy 34.97531 -29.571765) (xy 34.917417 -29.556252) (xy 34.862044 -29.533316)
			(xy 34.810138 -29.503349) (xy 34.762588 -29.466862) (xy 34.720208 -29.424482) (xy 34.683721 -29.376932)
			(xy 34.653754 -29.325026) (xy 34.630818 -29.269653) (xy 34.615305 -29.21176) (xy 34.607482 -29.152338)
			(xy 34.606992 -29.12237) (xy 19.763099 -29.12237) (xy 19.762742 -29.144226) (xy 19.754914 -29.203682)
			(xy 19.739393 -29.261607) (xy 19.716444 -29.317011) (xy 19.68646 -29.368945) (xy 19.649954 -29.416521)
			(xy 19.607549 -29.458926) (xy 19.559973 -29.495432) (xy 19.508039 -29.525416) (xy 19.452635 -29.548365)
			(xy 19.39471 -29.563886) (xy 19.335254 -29.571714) (xy 19.275286 -29.571714) (xy 19.21583 -29.563886)
			(xy 19.157905 -29.548365) (xy 19.102501 -29.525416) (xy 19.050567 -29.495432) (xy 19.002991 -29.458926)
			(xy 18.960586 -29.416521) (xy 18.92408 -29.368945) (xy 18.894096 -29.317011) (xy 18.871147 -29.261607)
			(xy 18.855626 -29.203682) (xy 18.847798 -29.144226) (xy 18.847308 -29.114242) (xy 9.52246 -29.114242)
			(xy 9.52246 -29.12237) (xy 9.52197 -29.152338) (xy 9.514147 -29.21176) (xy 9.498634 -29.269653) (xy 9.475698 -29.325026)
			(xy 9.445731 -29.376932) (xy 9.409244 -29.424482) (xy 9.366864 -29.466862) (xy 9.319314 -29.503349)
			(xy 9.267408 -29.533316) (xy 9.212035 -29.556252) (xy 9.154142 -29.571765) (xy 9.09472 -29.579588)
			(xy 9.034784 -29.579588) (xy 8.975362 -29.571765) (xy 8.917469 -29.556252) (xy 8.862096 -29.533316)
			(xy 8.81019 -29.503349) (xy 8.76264 -29.466862) (xy 8.72026 -29.424482) (xy 8.683773 -29.376932)
			(xy 8.653806 -29.325026) (xy 8.63087 -29.269653) (xy 8.615357 -29.21176) (xy 8.607534 -29.152338)
			(xy 8.607044 -29.12237) (xy 0.508 -29.12237) (xy 0.508 -30.922468) (xy 6.752844 -30.922468) (xy 6.752844 -30.058868)
			(xy 6.753334 -30.0289) (xy 6.761157 -29.969478) (xy 6.77667 -29.911585) (xy 6.799606 -29.856212)
			(xy 6.829573 -29.804306) (xy 6.86606 -29.756756) (xy 6.90844 -29.714376) (xy 6.95599 -29.677889)
			(xy 7.007896 -29.647922) (xy 7.063269 -29.624986) (xy 7.121162 -29.609473) (xy 7.180584 -29.60165)
			(xy 7.24052 -29.60165) (xy 7.299942 -29.609473) (xy 7.357835 -29.624986) (xy 7.413208 -29.647922)
			(xy 7.465114 -29.677889) (xy 7.512664 -29.714376) (xy 7.555044 -29.756756) (xy 7.591531 -29.804306)
			(xy 7.621498 -29.856212) (xy 7.644434 -29.911585) (xy 7.659947 -29.969478) (xy 7.66777 -30.0289)
			(xy 7.66826 -30.058868) (xy 7.66826 -30.92069) (xy 21.489416 -30.92069) (xy 21.489416 -30.05709)
			(xy 21.489906 -30.027106) (xy 21.497734 -29.96765) (xy 21.513255 -29.909725) (xy 21.536204 -29.854321)
			(xy 21.566188 -29.802387) (xy 21.602694 -29.754811) (xy 21.645099 -29.712406) (xy 21.692675 -29.6759)
			(xy 21.744609 -29.645916) (xy 21.800013 -29.622967) (xy 21.857938 -29.607446) (xy 21.917394 -29.599618)
			(xy 21.977362 -29.599618) (xy 22.036818 -29.607446) (xy 22.094743 -29.622967) (xy 22.150147 -29.645916)
			(xy 22.202081 -29.6759) (xy 22.249657 -29.712406) (xy 22.292062 -29.754811) (xy 22.328568 -29.802387)
			(xy 22.358552 -29.854321) (xy 22.381501 -29.909725) (xy 22.397022 -29.96765) (xy 22.40485 -30.027106)
			(xy 22.40534 -30.05709) (xy 22.40534 -30.92069) (xy 22.405311 -30.922468) (xy 32.752792 -30.922468)
			(xy 32.752792 -30.058868) (xy 32.753282 -30.0289) (xy 32.761105 -29.969478) (xy 32.776618 -29.911585)
			(xy 32.799554 -29.856212) (xy 32.829521 -29.804306) (xy 32.866008 -29.756756) (xy 32.908388 -29.714376)
			(xy 32.955938 -29.677889) (xy 33.007844 -29.647922) (xy 33.063217 -29.624986) (xy 33.12111 -29.609473)
			(xy 33.180532 -29.60165) (xy 33.240468 -29.60165) (xy 33.29989 -29.609473) (xy 33.357783 -29.624986)
			(xy 33.413156 -29.647922) (xy 33.465062 -29.677889) (xy 33.512612 -29.714376) (xy 33.554992 -29.756756)
			(xy 33.591479 -29.804306) (xy 33.621446 -29.856212) (xy 33.644382 -29.911585) (xy 33.659895 -29.969478)
			(xy 33.667718 -30.0289) (xy 33.668208 -30.058868) (xy 33.668208 -30.92069) (xy 47.489364 -30.92069)
			(xy 47.489364 -30.05709) (xy 47.489854 -30.027106) (xy 47.497682 -29.96765) (xy 47.513203 -29.909725)
			(xy 47.536152 -29.854321) (xy 47.566136 -29.802387) (xy 47.602642 -29.754811) (xy 47.645047 -29.712406)
			(xy 47.692623 -29.6759) (xy 47.744557 -29.645916) (xy 47.799961 -29.622967) (xy 47.857886 -29.607446)
			(xy 47.917342 -29.599618) (xy 47.97731 -29.599618) (xy 48.036766 -29.607446) (xy 48.094691 -29.622967)
			(xy 48.150095 -29.645916) (xy 48.202029 -29.6759) (xy 48.249605 -29.712406) (xy 48.29201 -29.754811)
			(xy 48.328516 -29.802387) (xy 48.3585 -29.854321) (xy 48.381449 -29.909725) (xy 48.39697 -29.96765)
			(xy 48.404798 -30.027106) (xy 48.405288 -30.05709) (xy 48.405288 -30.92069) (xy 48.405259 -30.922468)
			(xy 58.75274 -30.922468) (xy 58.75274 -30.058868) (xy 58.75323 -30.0289) (xy 58.761053 -29.969478)
			(xy 58.776566 -29.911585) (xy 58.799502 -29.856212) (xy 58.829469 -29.804306) (xy 58.865956 -29.756756)
			(xy 58.908336 -29.714376) (xy 58.955886 -29.677889) (xy 59.007792 -29.647922) (xy 59.063165 -29.624986)
			(xy 59.121058 -29.609473) (xy 59.18048 -29.60165) (xy 59.240416 -29.60165) (xy 59.299838 -29.609473)
			(xy 59.357731 -29.624986) (xy 59.413104 -29.647922) (xy 59.46501 -29.677889) (xy 59.51256 -29.714376)
			(xy 59.55494 -29.756756) (xy 59.591427 -29.804306) (xy 59.621394 -29.856212) (xy 59.64433 -29.911585)
			(xy 59.659843 -29.969478) (xy 59.667666 -30.0289) (xy 59.668156 -30.058868) (xy 59.668156 -30.92069)
			(xy 73.489312 -30.92069) (xy 73.489312 -30.05709) (xy 73.489802 -30.027106) (xy 73.49763 -29.96765)
			(xy 73.513151 -29.909725) (xy 73.5361 -29.854321) (xy 73.566084 -29.802387) (xy 73.60259 -29.754811)
			(xy 73.644995 -29.712406) (xy 73.692571 -29.6759) (xy 73.744505 -29.645916) (xy 73.799909 -29.622967)
			(xy 73.857834 -29.607446) (xy 73.91729 -29.599618) (xy 73.977258 -29.599618) (xy 74.036714 -29.607446)
			(xy 74.094639 -29.622967) (xy 74.150043 -29.645916) (xy 74.201977 -29.6759) (xy 74.249553 -29.712406)
			(xy 74.291958 -29.754811) (xy 74.328464 -29.802387) (xy 74.358448 -29.854321) (xy 74.381397 -29.909725)
			(xy 74.396918 -29.96765) (xy 74.404746 -30.027106) (xy 74.405236 -30.05709) (xy 74.405236 -30.92069)
			(xy 74.405207 -30.922468) (xy 84.752688 -30.922468) (xy 84.752688 -30.058868) (xy 84.753178 -30.0289)
			(xy 84.761001 -29.969478) (xy 84.776514 -29.911585) (xy 84.79945 -29.856212) (xy 84.829417 -29.804306)
			(xy 84.865904 -29.756756) (xy 84.908284 -29.714376) (xy 84.955834 -29.677889) (xy 85.00774 -29.647922)
			(xy 85.063113 -29.624986) (xy 85.121006 -29.609473) (xy 85.180428 -29.60165) (xy 85.240364 -29.60165)
			(xy 85.299786 -29.609473) (xy 85.357679 -29.624986) (xy 85.413052 -29.647922) (xy 85.464958 -29.677889)
			(xy 85.512508 -29.714376) (xy 85.554888 -29.756756) (xy 85.591375 -29.804306) (xy 85.621342 -29.856212)
			(xy 85.644278 -29.911585) (xy 85.659791 -29.969478) (xy 85.667614 -30.0289) (xy 85.668104 -30.058868)
			(xy 85.668104 -30.92069) (xy 99.48926 -30.92069) (xy 99.48926 -30.05709) (xy 99.48975 -30.027106)
			(xy 99.497578 -29.96765) (xy 99.513099 -29.909725) (xy 99.536048 -29.854321) (xy 99.566032 -29.802387)
			(xy 99.602538 -29.754811) (xy 99.644943 -29.712406) (xy 99.692519 -29.6759) (xy 99.744453 -29.645916)
			(xy 99.799857 -29.622967) (xy 99.857782 -29.607446) (xy 99.917238 -29.599618) (xy 99.977206 -29.599618)
			(xy 100.036662 -29.607446) (xy 100.094587 -29.622967) (xy 100.149991 -29.645916) (xy 100.201925 -29.6759)
			(xy 100.249501 -29.712406) (xy 100.291906 -29.754811) (xy 100.328412 -29.802387) (xy 100.358396 -29.854321)
			(xy 100.381345 -29.909725) (xy 100.396866 -29.96765) (xy 100.404694 -30.027106) (xy 100.405184 -30.05709)
			(xy 100.405184 -30.92069) (xy 100.405155 -30.922468) (xy 122.852688 -30.922468) (xy 122.852688 -30.058868)
			(xy 122.853178 -30.028884) (xy 122.861006 -29.969428) (xy 122.876527 -29.911503) (xy 122.899476 -29.856099)
			(xy 122.92946 -29.804165) (xy 122.965966 -29.756589) (xy 123.008371 -29.714184) (xy 123.055947 -29.677678)
			(xy 123.107881 -29.647694) (xy 123.163285 -29.624745) (xy 123.22121 -29.609224) (xy 123.280666 -29.601396)
			(xy 123.340634 -29.601396) (xy 123.40009 -29.609224) (xy 123.458015 -29.624745) (xy 123.513419 -29.647694)
			(xy 123.565353 -29.677678) (xy 123.612929 -29.714184) (xy 123.655334 -29.756589) (xy 123.69184 -29.804165)
			(xy 123.721824 -29.856099) (xy 123.744773 -29.911503) (xy 123.760294 -29.969428) (xy 123.768122 -30.028884)
			(xy 123.768612 -30.058868) (xy 123.768612 -30.92069) (xy 137.589768 -30.92069) (xy 137.589768 -30.05709)
			(xy 137.590258 -30.027122) (xy 137.598081 -29.9677) (xy 137.613594 -29.909807) (xy 137.63653 -29.854434)
			(xy 137.666497 -29.802528) (xy 137.702984 -29.754978) (xy 137.745364 -29.712598) (xy 137.792914 -29.676111)
			(xy 137.84482 -29.646144) (xy 137.900193 -29.623208) (xy 137.958086 -29.607695) (xy 138.017508 -29.599872)
			(xy 138.077444 -29.599872) (xy 138.136866 -29.607695) (xy 138.194759 -29.623208) (xy 138.250132 -29.646144)
			(xy 138.302038 -29.676111) (xy 138.349588 -29.712598) (xy 138.391968 -29.754978) (xy 138.428455 -29.802528)
			(xy 138.458422 -29.854434) (xy 138.481358 -29.909807) (xy 138.496871 -29.9677) (xy 138.504694 -30.027122)
			(xy 138.505184 -30.05709) (xy 138.505184 -30.92069) (xy 138.505155 -30.922468) (xy 148.852636 -30.922468)
			(xy 148.852636 -30.058868) (xy 148.853126 -30.028884) (xy 148.860954 -29.969428) (xy 148.876475 -29.911503)
			(xy 148.899424 -29.856099) (xy 148.929408 -29.804165) (xy 148.965914 -29.756589) (xy 149.008319 -29.714184)
			(xy 149.055895 -29.677678) (xy 149.107829 -29.647694) (xy 149.163233 -29.624745) (xy 149.221158 -29.609224)
			(xy 149.280614 -29.601396) (xy 149.340582 -29.601396) (xy 149.400038 -29.609224) (xy 149.457963 -29.624745)
			(xy 149.513367 -29.647694) (xy 149.565301 -29.677678) (xy 149.612877 -29.714184) (xy 149.655282 -29.756589)
			(xy 149.691788 -29.804165) (xy 149.721772 -29.856099) (xy 149.744721 -29.911503) (xy 149.760242 -29.969428)
			(xy 149.76807 -30.028884) (xy 149.76856 -30.058868) (xy 149.76856 -30.92069) (xy 163.589716 -30.92069)
			(xy 163.589716 -30.05709) (xy 163.590206 -30.027122) (xy 163.598029 -29.9677) (xy 163.613542 -29.909807)
			(xy 163.636478 -29.854434) (xy 163.666445 -29.802528) (xy 163.702932 -29.754978) (xy 163.745312 -29.712598)
			(xy 163.792862 -29.676111) (xy 163.844768 -29.646144) (xy 163.900141 -29.623208) (xy 163.958034 -29.607695)
			(xy 164.017456 -29.599872) (xy 164.077392 -29.599872) (xy 164.136814 -29.607695) (xy 164.194707 -29.623208)
			(xy 164.25008 -29.646144) (xy 164.301986 -29.676111) (xy 164.349536 -29.712598) (xy 164.391916 -29.754978)
			(xy 164.428403 -29.802528) (xy 164.45837 -29.854434) (xy 164.481306 -29.909807) (xy 164.496819 -29.9677)
			(xy 164.504642 -30.027122) (xy 164.505132 -30.05709) (xy 164.505132 -30.92069) (xy 164.505103 -30.922468)
			(xy 174.852584 -30.922468) (xy 174.852584 -30.058868) (xy 174.853074 -30.028884) (xy 174.860902 -29.969428)
			(xy 174.876423 -29.911503) (xy 174.899372 -29.856099) (xy 174.929356 -29.804165) (xy 174.965862 -29.756589)
			(xy 175.008267 -29.714184) (xy 175.055843 -29.677678) (xy 175.107777 -29.647694) (xy 175.163181 -29.624745)
			(xy 175.221106 -29.609224) (xy 175.280562 -29.601396) (xy 175.34053 -29.601396) (xy 175.399986 -29.609224)
			(xy 175.457911 -29.624745) (xy 175.513315 -29.647694) (xy 175.565249 -29.677678) (xy 175.612825 -29.714184)
			(xy 175.65523 -29.756589) (xy 175.691736 -29.804165) (xy 175.72172 -29.856099) (xy 175.744669 -29.911503)
			(xy 175.76019 -29.969428) (xy 175.768018 -30.028884) (xy 175.768508 -30.058868) (xy 175.768508 -30.92069)
			(xy 189.589664 -30.92069) (xy 189.589664 -30.05709) (xy 189.590154 -30.027122) (xy 189.597977 -29.9677)
			(xy 189.61349 -29.909807) (xy 189.636426 -29.854434) (xy 189.666393 -29.802528) (xy 189.70288 -29.754978)
			(xy 189.74526 -29.712598) (xy 189.79281 -29.676111) (xy 189.844716 -29.646144) (xy 189.900089 -29.623208)
			(xy 189.957982 -29.607695) (xy 190.017404 -29.599872) (xy 190.07734 -29.599872) (xy 190.136762 -29.607695)
			(xy 190.194655 -29.623208) (xy 190.250028 -29.646144) (xy 190.301934 -29.676111) (xy 190.349484 -29.712598)
			(xy 190.391864 -29.754978) (xy 190.428351 -29.802528) (xy 190.458318 -29.854434) (xy 190.481254 -29.909807)
			(xy 190.496767 -29.9677) (xy 190.50459 -30.027122) (xy 190.50508 -30.05709) (xy 190.50508 -30.92069)
			(xy 190.505051 -30.922468) (xy 200.852532 -30.922468) (xy 200.852532 -30.058868) (xy 200.853022 -30.028884)
			(xy 200.86085 -29.969428) (xy 200.876371 -29.911503) (xy 200.89932 -29.856099) (xy 200.929304 -29.804165)
			(xy 200.96581 -29.756589) (xy 201.008215 -29.714184) (xy 201.055791 -29.677678) (xy 201.107725 -29.647694)
			(xy 201.163129 -29.624745) (xy 201.221054 -29.609224) (xy 201.28051 -29.601396) (xy 201.340478 -29.601396)
			(xy 201.399934 -29.609224) (xy 201.457859 -29.624745) (xy 201.513263 -29.647694) (xy 201.565197 -29.677678)
			(xy 201.612773 -29.714184) (xy 201.655178 -29.756589) (xy 201.691684 -29.804165) (xy 201.721668 -29.856099)
			(xy 201.744617 -29.911503) (xy 201.760138 -29.969428) (xy 201.767966 -30.028884) (xy 201.768456 -30.058868)
			(xy 201.768456 -30.92069) (xy 215.589612 -30.92069) (xy 215.589612 -30.05709) (xy 215.590102 -30.027122)
			(xy 215.597925 -29.9677) (xy 215.613438 -29.909807) (xy 215.636374 -29.854434) (xy 215.666341 -29.802528)
			(xy 215.702828 -29.754978) (xy 215.745208 -29.712598) (xy 215.792758 -29.676111) (xy 215.844664 -29.646144)
			(xy 215.900037 -29.623208) (xy 215.95793 -29.607695) (xy 216.017352 -29.599872) (xy 216.077288 -29.599872)
			(xy 216.13671 -29.607695) (xy 216.194603 -29.623208) (xy 216.249976 -29.646144) (xy 216.301882 -29.676111)
			(xy 216.349432 -29.712598) (xy 216.391812 -29.754978) (xy 216.428299 -29.802528) (xy 216.458266 -29.854434)
			(xy 216.481202 -29.909807) (xy 216.496715 -29.9677) (xy 216.504538 -30.027122) (xy 216.505028 -30.05709)
			(xy 216.505028 -30.92069) (xy 216.504999 -30.922468) (xy 238.952532 -30.922468) (xy 238.952532 -30.058868)
			(xy 238.953022 -30.028884) (xy 238.96085 -29.969428) (xy 238.976371 -29.911503) (xy 238.99932 -29.856099)
			(xy 239.029304 -29.804165) (xy 239.06581 -29.756589) (xy 239.108215 -29.714184) (xy 239.155791 -29.677678)
			(xy 239.207725 -29.647694) (xy 239.263129 -29.624745) (xy 239.321054 -29.609224) (xy 239.38051 -29.601396)
			(xy 239.440478 -29.601396) (xy 239.499934 -29.609224) (xy 239.557859 -29.624745) (xy 239.613263 -29.647694)
			(xy 239.665197 -29.677678) (xy 239.712773 -29.714184) (xy 239.755178 -29.756589) (xy 239.791684 -29.804165)
			(xy 239.821668 -29.856099) (xy 239.844617 -29.911503) (xy 239.860138 -29.969428) (xy 239.867966 -30.028884)
			(xy 239.868456 -30.058868) (xy 239.868456 -30.92069) (xy 253.689612 -30.92069) (xy 253.689612 -30.05709)
			(xy 253.690102 -30.027122) (xy 253.697925 -29.9677) (xy 253.713438 -29.909807) (xy 253.736374 -29.854434)
			(xy 253.766341 -29.802528) (xy 253.802828 -29.754978) (xy 253.845208 -29.712598) (xy 253.892758 -29.676111)
			(xy 253.944664 -29.646144) (xy 254.000037 -29.623208) (xy 254.05793 -29.607695) (xy 254.117352 -29.599872)
			(xy 254.177288 -29.599872) (xy 254.23671 -29.607695) (xy 254.294603 -29.623208) (xy 254.349976 -29.646144)
			(xy 254.401882 -29.676111) (xy 254.449432 -29.712598) (xy 254.491812 -29.754978) (xy 254.528299 -29.802528)
			(xy 254.558266 -29.854434) (xy 254.581202 -29.909807) (xy 254.596715 -29.9677) (xy 254.604538 -30.027122)
			(xy 254.605028 -30.05709) (xy 254.605028 -30.92069) (xy 254.604999 -30.922468) (xy 264.95248 -30.922468)
			(xy 264.95248 -30.058868) (xy 264.95297 -30.028884) (xy 264.960798 -29.969428) (xy 264.976319 -29.911503)
			(xy 264.999268 -29.856099) (xy 265.029252 -29.804165) (xy 265.065758 -29.756589) (xy 265.108163 -29.714184)
			(xy 265.155739 -29.677678) (xy 265.207673 -29.647694) (xy 265.263077 -29.624745) (xy 265.321002 -29.609224)
			(xy 265.380458 -29.601396) (xy 265.440426 -29.601396) (xy 265.499882 -29.609224) (xy 265.557807 -29.624745)
			(xy 265.613211 -29.647694) (xy 265.665145 -29.677678) (xy 265.712721 -29.714184) (xy 265.755126 -29.756589)
			(xy 265.791632 -29.804165) (xy 265.821616 -29.856099) (xy 265.844565 -29.911503) (xy 265.860086 -29.969428)
			(xy 265.867914 -30.028884) (xy 265.868404 -30.058868) (xy 265.868404 -30.92069) (xy 279.68956 -30.92069)
			(xy 279.68956 -30.05709) (xy 279.69005 -30.027122) (xy 279.697873 -29.9677) (xy 279.713386 -29.909807)
			(xy 279.736322 -29.854434) (xy 279.766289 -29.802528) (xy 279.802776 -29.754978) (xy 279.845156 -29.712598)
			(xy 279.892706 -29.676111) (xy 279.944612 -29.646144) (xy 279.999985 -29.623208) (xy 280.057878 -29.607695)
			(xy 280.1173 -29.599872) (xy 280.177236 -29.599872) (xy 280.236658 -29.607695) (xy 280.294551 -29.623208)
			(xy 280.349924 -29.646144) (xy 280.40183 -29.676111) (xy 280.44938 -29.712598) (xy 280.49176 -29.754978)
			(xy 280.528247 -29.802528) (xy 280.558214 -29.854434) (xy 280.58115 -29.909807) (xy 280.596663 -29.9677)
			(xy 280.604486 -30.027122) (xy 280.604976 -30.05709) (xy 280.604976 -30.92069) (xy 280.604947 -30.922468)
			(xy 290.952428 -30.922468) (xy 290.952428 -30.058868) (xy 290.952918 -30.028884) (xy 290.960746 -29.969428)
			(xy 290.976267 -29.911503) (xy 290.999216 -29.856099) (xy 291.0292 -29.804165) (xy 291.065706 -29.756589)
			(xy 291.108111 -29.714184) (xy 291.155687 -29.677678) (xy 291.207621 -29.647694) (xy 291.263025 -29.624745)
			(xy 291.32095 -29.609224) (xy 291.380406 -29.601396) (xy 291.440374 -29.601396) (xy 291.49983 -29.609224)
			(xy 291.557755 -29.624745) (xy 291.613159 -29.647694) (xy 291.665093 -29.677678) (xy 291.712669 -29.714184)
			(xy 291.755074 -29.756589) (xy 291.79158 -29.804165) (xy 291.821564 -29.856099) (xy 291.844513 -29.911503)
			(xy 291.860034 -29.969428) (xy 291.867862 -30.028884) (xy 291.868352 -30.058868) (xy 291.868352 -30.92069)
			(xy 305.689508 -30.92069) (xy 305.689508 -30.05709) (xy 305.689998 -30.027122) (xy 305.697821 -29.9677)
			(xy 305.713334 -29.909807) (xy 305.73627 -29.854434) (xy 305.766237 -29.802528) (xy 305.802724 -29.754978)
			(xy 305.845104 -29.712598) (xy 305.892654 -29.676111) (xy 305.94456 -29.646144) (xy 305.999933 -29.623208)
			(xy 306.057826 -29.607695) (xy 306.117248 -29.599872) (xy 306.177184 -29.599872) (xy 306.236606 -29.607695)
			(xy 306.294499 -29.623208) (xy 306.349872 -29.646144) (xy 306.401778 -29.676111) (xy 306.449328 -29.712598)
			(xy 306.491708 -29.754978) (xy 306.528195 -29.802528) (xy 306.558162 -29.854434) (xy 306.581098 -29.909807)
			(xy 306.596611 -29.9677) (xy 306.604434 -30.027122) (xy 306.604924 -30.05709) (xy 306.604924 -30.92069)
			(xy 306.604895 -30.922468) (xy 316.952376 -30.922468) (xy 316.952376 -30.058868) (xy 316.952866 -30.028884)
			(xy 316.960694 -29.969428) (xy 316.976215 -29.911503) (xy 316.999164 -29.856099) (xy 317.029148 -29.804165)
			(xy 317.065654 -29.756589) (xy 317.108059 -29.714184) (xy 317.155635 -29.677678) (xy 317.207569 -29.647694)
			(xy 317.262973 -29.624745) (xy 317.320898 -29.609224) (xy 317.380354 -29.601396) (xy 317.440322 -29.601396)
			(xy 317.499778 -29.609224) (xy 317.557703 -29.624745) (xy 317.613107 -29.647694) (xy 317.665041 -29.677678)
			(xy 317.712617 -29.714184) (xy 317.755022 -29.756589) (xy 317.791528 -29.804165) (xy 317.821512 -29.856099)
			(xy 317.844461 -29.911503) (xy 317.859982 -29.969428) (xy 317.86781 -30.028884) (xy 317.8683 -30.058868)
			(xy 317.8683 -30.92069) (xy 331.689456 -30.92069) (xy 331.689456 -30.05709) (xy 331.689946 -30.027122)
			(xy 331.697769 -29.9677) (xy 331.713282 -29.909807) (xy 331.736218 -29.854434) (xy 331.766185 -29.802528)
			(xy 331.802672 -29.754978) (xy 331.845052 -29.712598) (xy 331.892602 -29.676111) (xy 331.944508 -29.646144)
			(xy 331.999881 -29.623208) (xy 332.057774 -29.607695) (xy 332.117196 -29.599872) (xy 332.177132 -29.599872)
			(xy 332.236554 -29.607695) (xy 332.294447 -29.623208) (xy 332.34982 -29.646144) (xy 332.401726 -29.676111)
			(xy 332.449276 -29.712598) (xy 332.491656 -29.754978) (xy 332.528143 -29.802528) (xy 332.55811 -29.854434)
			(xy 332.581046 -29.909807) (xy 332.596559 -29.9677) (xy 332.604382 -30.027122) (xy 332.604872 -30.05709)
			(xy 332.604872 -30.92069) (xy 332.604843 -30.922468) (xy 355.052884 -30.922468) (xy 355.052884 -30.058868)
			(xy 355.053374 -30.0289) (xy 355.061197 -29.969478) (xy 355.07671 -29.911585) (xy 355.099646 -29.856212)
			(xy 355.129613 -29.804306) (xy 355.1661 -29.756756) (xy 355.20848 -29.714376) (xy 355.25603 -29.677889)
			(xy 355.307936 -29.647922) (xy 355.363309 -29.624986) (xy 355.421202 -29.609473) (xy 355.480624 -29.60165)
			(xy 355.54056 -29.60165) (xy 355.599982 -29.609473) (xy 355.657875 -29.624986) (xy 355.713248 -29.647922)
			(xy 355.765154 -29.677889) (xy 355.812704 -29.714376) (xy 355.855084 -29.756756) (xy 355.891571 -29.804306)
			(xy 355.921538 -29.856212) (xy 355.944474 -29.911585) (xy 355.959987 -29.969478) (xy 355.96781 -30.0289)
			(xy 355.9683 -30.058868) (xy 355.9683 -30.92069) (xy 369.789456 -30.92069) (xy 369.789456 -30.05709)
			(xy 369.789946 -30.027106) (xy 369.797774 -29.96765) (xy 369.813295 -29.909725) (xy 369.836244 -29.854321)
			(xy 369.866228 -29.802387) (xy 369.902734 -29.754811) (xy 369.945139 -29.712406) (xy 369.992715 -29.6759)
			(xy 370.044649 -29.645916) (xy 370.100053 -29.622967) (xy 370.157978 -29.607446) (xy 370.217434 -29.599618)
			(xy 370.277402 -29.599618) (xy 370.336858 -29.607446) (xy 370.394783 -29.622967) (xy 370.450187 -29.645916)
			(xy 370.502121 -29.6759) (xy 370.549697 -29.712406) (xy 370.592102 -29.754811) (xy 370.628608 -29.802387)
			(xy 370.658592 -29.854321) (xy 370.681541 -29.909725) (xy 370.697062 -29.96765) (xy 370.70489 -30.027106)
			(xy 370.70538 -30.05709) (xy 370.70538 -30.92069) (xy 370.705351 -30.922468) (xy 381.052832 -30.922468)
			(xy 381.052832 -30.058868) (xy 381.053322 -30.0289) (xy 381.061145 -29.969478) (xy 381.076658 -29.911585)
			(xy 381.099594 -29.856212) (xy 381.129561 -29.804306) (xy 381.166048 -29.756756) (xy 381.208428 -29.714376)
			(xy 381.255978 -29.677889) (xy 381.307884 -29.647922) (xy 381.363257 -29.624986) (xy 381.42115 -29.609473)
			(xy 381.480572 -29.60165) (xy 381.540508 -29.60165) (xy 381.59993 -29.609473) (xy 381.657823 -29.624986)
			(xy 381.713196 -29.647922) (xy 381.765102 -29.677889) (xy 381.812652 -29.714376) (xy 381.855032 -29.756756)
			(xy 381.891519 -29.804306) (xy 381.921486 -29.856212) (xy 381.944422 -29.911585) (xy 381.959935 -29.969478)
			(xy 381.967758 -30.0289) (xy 381.968248 -30.058868) (xy 381.968248 -30.92069) (xy 395.789404 -30.92069)
			(xy 395.789404 -30.05709) (xy 395.789894 -30.027106) (xy 395.797722 -29.96765) (xy 395.813243 -29.909725)
			(xy 395.836192 -29.854321) (xy 395.866176 -29.802387) (xy 395.902682 -29.754811) (xy 395.945087 -29.712406)
			(xy 395.992663 -29.6759) (xy 396.044597 -29.645916) (xy 396.100001 -29.622967) (xy 396.157926 -29.607446)
			(xy 396.217382 -29.599618) (xy 396.27735 -29.599618) (xy 396.336806 -29.607446) (xy 396.394731 -29.622967)
			(xy 396.450135 -29.645916) (xy 396.502069 -29.6759) (xy 396.549645 -29.712406) (xy 396.59205 -29.754811)
			(xy 396.628556 -29.802387) (xy 396.65854 -29.854321) (xy 396.681489 -29.909725) (xy 396.69701 -29.96765)
			(xy 396.704838 -30.027106) (xy 396.705328 -30.05709) (xy 396.705328 -30.92069) (xy 396.705299 -30.922468)
			(xy 407.05278 -30.922468) (xy 407.05278 -30.058868) (xy 407.05327 -30.0289) (xy 407.061093 -29.969478)
			(xy 407.076606 -29.911585) (xy 407.099542 -29.856212) (xy 407.129509 -29.804306) (xy 407.165996 -29.756756)
			(xy 407.208376 -29.714376) (xy 407.255926 -29.677889) (xy 407.307832 -29.647922) (xy 407.363205 -29.624986)
			(xy 407.421098 -29.609473) (xy 407.48052 -29.60165) (xy 407.540456 -29.60165) (xy 407.599878 -29.609473)
			(xy 407.657771 -29.624986) (xy 407.713144 -29.647922) (xy 407.76505 -29.677889) (xy 407.8126 -29.714376)
			(xy 407.85498 -29.756756) (xy 407.891467 -29.804306) (xy 407.921434 -29.856212) (xy 407.94437 -29.911585)
			(xy 407.959883 -29.969478) (xy 407.967706 -30.0289) (xy 407.968196 -30.058868) (xy 407.968196 -30.92069)
			(xy 421.789352 -30.92069) (xy 421.789352 -30.05709) (xy 421.789842 -30.027106) (xy 421.79767 -29.96765)
			(xy 421.813191 -29.909725) (xy 421.83614 -29.854321) (xy 421.866124 -29.802387) (xy 421.90263 -29.754811)
			(xy 421.945035 -29.712406) (xy 421.992611 -29.6759) (xy 422.044545 -29.645916) (xy 422.099949 -29.622967)
			(xy 422.157874 -29.607446) (xy 422.21733 -29.599618) (xy 422.277298 -29.599618) (xy 422.336754 -29.607446)
			(xy 422.394679 -29.622967) (xy 422.450083 -29.645916) (xy 422.502017 -29.6759) (xy 422.549593 -29.712406)
			(xy 422.591998 -29.754811) (xy 422.628504 -29.802387) (xy 422.658488 -29.854321) (xy 422.681437 -29.909725)
			(xy 422.696958 -29.96765) (xy 422.704786 -30.027106) (xy 422.705276 -30.05709) (xy 422.705276 -30.92069)
			(xy 422.705247 -30.922468) (xy 433.052728 -30.922468) (xy 433.052728 -30.058868) (xy 433.053218 -30.0289)
			(xy 433.061041 -29.969478) (xy 433.076554 -29.911585) (xy 433.09949 -29.856212) (xy 433.129457 -29.804306)
			(xy 433.165944 -29.756756) (xy 433.208324 -29.714376) (xy 433.255874 -29.677889) (xy 433.30778 -29.647922)
			(xy 433.363153 -29.624986) (xy 433.421046 -29.609473) (xy 433.480468 -29.60165) (xy 433.540404 -29.60165)
			(xy 433.599826 -29.609473) (xy 433.657719 -29.624986) (xy 433.713092 -29.647922) (xy 433.764998 -29.677889)
			(xy 433.812548 -29.714376) (xy 433.854928 -29.756756) (xy 433.891415 -29.804306) (xy 433.921382 -29.856212)
			(xy 433.944318 -29.911585) (xy 433.959831 -29.969478) (xy 433.967654 -30.0289) (xy 433.968144 -30.058868)
			(xy 433.968144 -30.92069) (xy 447.7893 -30.92069) (xy 447.7893 -30.05709) (xy 447.78979 -30.027106)
			(xy 447.797618 -29.96765) (xy 447.813139 -29.909725) (xy 447.836088 -29.854321) (xy 447.866072 -29.802387)
			(xy 447.902578 -29.754811) (xy 447.944983 -29.712406) (xy 447.992559 -29.6759) (xy 448.044493 -29.645916)
			(xy 448.099897 -29.622967) (xy 448.157822 -29.607446) (xy 448.217278 -29.599618) (xy 448.277246 -29.599618)
			(xy 448.336702 -29.607446) (xy 448.394627 -29.622967) (xy 448.450031 -29.645916) (xy 448.501965 -29.6759)
			(xy 448.549541 -29.712406) (xy 448.591946 -29.754811) (xy 448.628452 -29.802387) (xy 448.658436 -29.854321)
			(xy 448.681385 -29.909725) (xy 448.696906 -29.96765) (xy 448.704734 -30.027106) (xy 448.705224 -30.05709)
			(xy 448.705224 -30.745738) (xy 457.614517 -30.745738) (xy 457.614517 -30.616598) (xy 457.622467 -30.487703)
			(xy 457.638337 -30.359543) (xy 457.662066 -30.232602) (xy 457.693565 -30.107363) (xy 457.732714 -29.9843)
			(xy 457.779365 -29.863881) (xy 457.83334 -29.746562) (xy 457.894435 -29.632788) (xy 457.962418 -29.522991)
			(xy 458.037032 -29.417588) (xy 458.117993 -29.316978) (xy 458.204993 -29.221543) (xy 458.297704 -29.131644)
			(xy 458.395774 -29.047623) (xy 458.498829 -28.969799) (xy 458.60648 -28.898467) (xy 458.718319 -28.833897)
			(xy 458.83392 -28.776335) (xy 458.952845 -28.725998) (xy 459.074644 -28.683078) (xy 459.198854 -28.647737)
			(xy 459.325003 -28.62011) (xy 459.452615 -28.600301) (xy 459.581204 -28.588385) (xy 459.710282 -28.584409)
			(xy 459.83936 -28.588385) (xy 459.967949 -28.600301) (xy 460.095561 -28.62011) (xy 460.22171 -28.647737)
			(xy 460.34592 -28.683078) (xy 460.467719 -28.725998) (xy 460.586644 -28.776335) (xy 460.702245 -28.833897)
			(xy 460.814084 -28.898467) (xy 460.921735 -28.969799) (xy 461.02479 -29.047623) (xy 461.12286 -29.131644)
			(xy 461.215571 -29.221543) (xy 461.302571 -29.316978) (xy 461.383532 -29.417588) (xy 461.458146 -29.522991)
			(xy 461.526129 -29.632788) (xy 461.587224 -29.746562) (xy 461.641199 -29.863881) (xy 461.68785 -29.9843)
			(xy 461.726999 -30.107363) (xy 461.758498 -30.232602) (xy 461.782227 -30.359543) (xy 461.798097 -30.487703)
			(xy 461.806047 -30.616598) (xy 461.806544 -30.681168) (xy 461.806047 -30.745738) (xy 461.798097 -30.874633)
			(xy 461.782227 -31.002793) (xy 461.758498 -31.129734) (xy 461.726999 -31.254973) (xy 461.68785 -31.378036)
			(xy 461.641199 -31.498455) (xy 461.587224 -31.615774) (xy 461.526129 -31.729548) (xy 461.458146 -31.839345)
			(xy 461.383532 -31.944748) (xy 461.302571 -32.045358) (xy 461.215571 -32.140793) (xy 461.12286 -32.230692)
			(xy 461.02479 -32.314713) (xy 460.921735 -32.392537) (xy 460.814084 -32.463869) (xy 460.702245 -32.528439)
			(xy 460.586644 -32.586001) (xy 460.467719 -32.636338) (xy 460.34592 -32.679258) (xy 460.22171 -32.714599)
			(xy 460.095561 -32.742226) (xy 459.967949 -32.762035) (xy 459.83936 -32.773951) (xy 459.710282 -32.777928)
			(xy 459.581204 -32.773951) (xy 459.452615 -32.762035) (xy 459.325003 -32.742226) (xy 459.198854 -32.714599)
			(xy 459.074644 -32.679258) (xy 458.952845 -32.636338) (xy 458.83392 -32.586001) (xy 458.718319 -32.528439)
			(xy 458.60648 -32.463869) (xy 458.498829 -32.392537) (xy 458.395774 -32.314713) (xy 458.297704 -32.230692)
			(xy 458.204993 -32.140793) (xy 458.117993 -32.045358) (xy 458.037032 -31.944748) (xy 457.962418 -31.839345)
			(xy 457.894435 -31.729548) (xy 457.83334 -31.615774) (xy 457.779365 -31.498455) (xy 457.732714 -31.378036)
			(xy 457.693565 -31.254973) (xy 457.662066 -31.129734) (xy 457.638337 -31.002793) (xy 457.622467 -30.874633)
			(xy 457.614517 -30.745738) (xy 448.705224 -30.745738) (xy 448.705224 -30.92069) (xy 448.704734 -30.950674)
			(xy 448.696906 -31.01013) (xy 448.681385 -31.068055) (xy 448.658436 -31.123459) (xy 448.628452 -31.175393)
			(xy 448.591946 -31.222969) (xy 448.549541 -31.265374) (xy 448.501965 -31.30188) (xy 448.450031 -31.331864)
			(xy 448.394627 -31.354813) (xy 448.336702 -31.370334) (xy 448.277246 -31.378162) (xy 448.217278 -31.378162)
			(xy 448.157822 -31.370334) (xy 448.099897 -31.354813) (xy 448.044493 -31.331864) (xy 447.992559 -31.30188)
			(xy 447.944983 -31.265374) (xy 447.902578 -31.222969) (xy 447.866072 -31.175393) (xy 447.836088 -31.123459)
			(xy 447.813139 -31.068055) (xy 447.797618 -31.01013) (xy 447.78979 -30.950674) (xy 447.7893 -30.92069)
			(xy 433.968144 -30.92069) (xy 433.968144 -30.922468) (xy 433.967654 -30.952436) (xy 433.959831 -31.011858)
			(xy 433.944318 -31.069751) (xy 433.921382 -31.125124) (xy 433.891415 -31.17703) (xy 433.854928 -31.22458)
			(xy 433.812548 -31.26696) (xy 433.764998 -31.303447) (xy 433.713092 -31.333414) (xy 433.657719 -31.35635)
			(xy 433.599826 -31.371863) (xy 433.540404 -31.379686) (xy 433.480468 -31.379686) (xy 433.421046 -31.371863)
			(xy 433.363153 -31.35635) (xy 433.30778 -31.333414) (xy 433.255874 -31.303447) (xy 433.208324 -31.26696)
			(xy 433.165944 -31.22458) (xy 433.129457 -31.17703) (xy 433.09949 -31.125124) (xy 433.076554 -31.069751)
			(xy 433.061041 -31.011858) (xy 433.053218 -30.952436) (xy 433.052728 -30.922468) (xy 422.705247 -30.922468)
			(xy 422.704786 -30.950674) (xy 422.696958 -31.01013) (xy 422.681437 -31.068055) (xy 422.658488 -31.123459)
			(xy 422.628504 -31.175393) (xy 422.591998 -31.222969) (xy 422.549593 -31.265374) (xy 422.502017 -31.30188)
			(xy 422.450083 -31.331864) (xy 422.394679 -31.354813) (xy 422.336754 -31.370334) (xy 422.277298 -31.378162)
			(xy 422.21733 -31.378162) (xy 422.157874 -31.370334) (xy 422.099949 -31.354813) (xy 422.044545 -31.331864)
			(xy 421.992611 -31.30188) (xy 421.945035 -31.265374) (xy 421.90263 -31.222969) (xy 421.866124 -31.175393)
			(xy 421.83614 -31.123459) (xy 421.813191 -31.068055) (xy 421.79767 -31.01013) (xy 421.789842 -30.950674)
			(xy 421.789352 -30.92069) (xy 407.968196 -30.92069) (xy 407.968196 -30.922468) (xy 407.967706 -30.952436)
			(xy 407.959883 -31.011858) (xy 407.94437 -31.069751) (xy 407.921434 -31.125124) (xy 407.891467 -31.17703)
			(xy 407.85498 -31.22458) (xy 407.8126 -31.26696) (xy 407.76505 -31.303447) (xy 407.713144 -31.333414)
			(xy 407.657771 -31.35635) (xy 407.599878 -31.371863) (xy 407.540456 -31.379686) (xy 407.48052 -31.379686)
			(xy 407.421098 -31.371863) (xy 407.363205 -31.35635) (xy 407.307832 -31.333414) (xy 407.255926 -31.303447)
			(xy 407.208376 -31.26696) (xy 407.165996 -31.22458) (xy 407.129509 -31.17703) (xy 407.099542 -31.125124)
			(xy 407.076606 -31.069751) (xy 407.061093 -31.011858) (xy 407.05327 -30.952436) (xy 407.05278 -30.922468)
			(xy 396.705299 -30.922468) (xy 396.704838 -30.950674) (xy 396.69701 -31.01013) (xy 396.681489 -31.068055)
			(xy 396.65854 -31.123459) (xy 396.628556 -31.175393) (xy 396.59205 -31.222969) (xy 396.549645 -31.265374)
			(xy 396.502069 -31.30188) (xy 396.450135 -31.331864) (xy 396.394731 -31.354813) (xy 396.336806 -31.370334)
			(xy 396.27735 -31.378162) (xy 396.217382 -31.378162) (xy 396.157926 -31.370334) (xy 396.100001 -31.354813)
			(xy 396.044597 -31.331864) (xy 395.992663 -31.30188) (xy 395.945087 -31.265374) (xy 395.902682 -31.222969)
			(xy 395.866176 -31.175393) (xy 395.836192 -31.123459) (xy 395.813243 -31.068055) (xy 395.797722 -31.01013)
			(xy 395.789894 -30.950674) (xy 395.789404 -30.92069) (xy 381.968248 -30.92069) (xy 381.968248 -30.922468)
			(xy 381.967758 -30.952436) (xy 381.959935 -31.011858) (xy 381.944422 -31.069751) (xy 381.921486 -31.125124)
			(xy 381.891519 -31.17703) (xy 381.855032 -31.22458) (xy 381.812652 -31.26696) (xy 381.765102 -31.303447)
			(xy 381.713196 -31.333414) (xy 381.657823 -31.35635) (xy 381.59993 -31.371863) (xy 381.540508 -31.379686)
			(xy 381.480572 -31.379686) (xy 381.42115 -31.371863) (xy 381.363257 -31.35635) (xy 381.307884 -31.333414)
			(xy 381.255978 -31.303447) (xy 381.208428 -31.26696) (xy 381.166048 -31.22458) (xy 381.129561 -31.17703)
			(xy 381.099594 -31.125124) (xy 381.076658 -31.069751) (xy 381.061145 -31.011858) (xy 381.053322 -30.952436)
			(xy 381.052832 -30.922468) (xy 370.705351 -30.922468) (xy 370.70489 -30.950674) (xy 370.697062 -31.01013)
			(xy 370.681541 -31.068055) (xy 370.658592 -31.123459) (xy 370.628608 -31.175393) (xy 370.592102 -31.222969)
			(xy 370.549697 -31.265374) (xy 370.502121 -31.30188) (xy 370.450187 -31.331864) (xy 370.394783 -31.354813)
			(xy 370.336858 -31.370334) (xy 370.277402 -31.378162) (xy 370.217434 -31.378162) (xy 370.157978 -31.370334)
			(xy 370.100053 -31.354813) (xy 370.044649 -31.331864) (xy 369.992715 -31.30188) (xy 369.945139 -31.265374)
			(xy 369.902734 -31.222969) (xy 369.866228 -31.175393) (xy 369.836244 -31.123459) (xy 369.813295 -31.068055)
			(xy 369.797774 -31.01013) (xy 369.789946 -30.950674) (xy 369.789456 -30.92069) (xy 355.9683 -30.92069)
			(xy 355.9683 -30.922468) (xy 355.96781 -30.952436) (xy 355.959987 -31.011858) (xy 355.944474 -31.069751)
			(xy 355.921538 -31.125124) (xy 355.891571 -31.17703) (xy 355.855084 -31.22458) (xy 355.812704 -31.26696)
			(xy 355.765154 -31.303447) (xy 355.713248 -31.333414) (xy 355.657875 -31.35635) (xy 355.599982 -31.371863)
			(xy 355.54056 -31.379686) (xy 355.480624 -31.379686) (xy 355.421202 -31.371863) (xy 355.363309 -31.35635)
			(xy 355.307936 -31.333414) (xy 355.25603 -31.303447) (xy 355.20848 -31.26696) (xy 355.1661 -31.22458)
			(xy 355.129613 -31.17703) (xy 355.099646 -31.125124) (xy 355.07671 -31.069751) (xy 355.061197 -31.011858)
			(xy 355.053374 -30.952436) (xy 355.052884 -30.922468) (xy 332.604843 -30.922468) (xy 332.604382 -30.950658)
			(xy 332.596559 -31.01008) (xy 332.581046 -31.067973) (xy 332.55811 -31.123346) (xy 332.528143 -31.175252)
			(xy 332.491656 -31.222802) (xy 332.449276 -31.265182) (xy 332.401726 -31.301669) (xy 332.34982 -31.331636)
			(xy 332.294447 -31.354572) (xy 332.236554 -31.370085) (xy 332.177132 -31.377908) (xy 332.117196 -31.377908)
			(xy 332.057774 -31.370085) (xy 331.999881 -31.354572) (xy 331.944508 -31.331636) (xy 331.892602 -31.301669)
			(xy 331.845052 -31.265182) (xy 331.802672 -31.222802) (xy 331.766185 -31.175252) (xy 331.736218 -31.123346)
			(xy 331.713282 -31.067973) (xy 331.697769 -31.01008) (xy 331.689946 -30.950658) (xy 331.689456 -30.92069)
			(xy 317.8683 -30.92069) (xy 317.8683 -30.922468) (xy 317.86781 -30.952452) (xy 317.859982 -31.011908)
			(xy 317.844461 -31.069833) (xy 317.821512 -31.125237) (xy 317.791528 -31.177171) (xy 317.755022 -31.224747)
			(xy 317.712617 -31.267152) (xy 317.665041 -31.303658) (xy 317.613107 -31.333642) (xy 317.557703 -31.356591)
			(xy 317.499778 -31.372112) (xy 317.440322 -31.37994) (xy 317.380354 -31.37994) (xy 317.320898 -31.372112)
			(xy 317.262973 -31.356591) (xy 317.207569 -31.333642) (xy 317.155635 -31.303658) (xy 317.108059 -31.267152)
			(xy 317.065654 -31.224747) (xy 317.029148 -31.177171) (xy 316.999164 -31.125237) (xy 316.976215 -31.069833)
			(xy 316.960694 -31.011908) (xy 316.952866 -30.952452) (xy 316.952376 -30.922468) (xy 306.604895 -30.922468)
			(xy 306.604434 -30.950658) (xy 306.596611 -31.01008) (xy 306.581098 -31.067973) (xy 306.558162 -31.123346)
			(xy 306.528195 -31.175252) (xy 306.491708 -31.222802) (xy 306.449328 -31.265182) (xy 306.401778 -31.301669)
			(xy 306.349872 -31.331636) (xy 306.294499 -31.354572) (xy 306.236606 -31.370085) (xy 306.177184 -31.377908)
			(xy 306.117248 -31.377908) (xy 306.057826 -31.370085) (xy 305.999933 -31.354572) (xy 305.94456 -31.331636)
			(xy 305.892654 -31.301669) (xy 305.845104 -31.265182) (xy 305.802724 -31.222802) (xy 305.766237 -31.175252)
			(xy 305.73627 -31.123346) (xy 305.713334 -31.067973) (xy 305.697821 -31.01008) (xy 305.689998 -30.950658)
			(xy 305.689508 -30.92069) (xy 291.868352 -30.92069) (xy 291.868352 -30.922468) (xy 291.867862 -30.952452)
			(xy 291.860034 -31.011908) (xy 291.844513 -31.069833) (xy 291.821564 -31.125237) (xy 291.79158 -31.177171)
			(xy 291.755074 -31.224747) (xy 291.712669 -31.267152) (xy 291.665093 -31.303658) (xy 291.613159 -31.333642)
			(xy 291.557755 -31.356591) (xy 291.49983 -31.372112) (xy 291.440374 -31.37994) (xy 291.380406 -31.37994)
			(xy 291.32095 -31.372112) (xy 291.263025 -31.356591) (xy 291.207621 -31.333642) (xy 291.155687 -31.303658)
			(xy 291.108111 -31.267152) (xy 291.065706 -31.224747) (xy 291.0292 -31.177171) (xy 290.999216 -31.125237)
			(xy 290.976267 -31.069833) (xy 290.960746 -31.011908) (xy 290.952918 -30.952452) (xy 290.952428 -30.922468)
			(xy 280.604947 -30.922468) (xy 280.604486 -30.950658) (xy 280.596663 -31.01008) (xy 280.58115 -31.067973)
			(xy 280.558214 -31.123346) (xy 280.528247 -31.175252) (xy 280.49176 -31.222802) (xy 280.44938 -31.265182)
			(xy 280.40183 -31.301669) (xy 280.349924 -31.331636) (xy 280.294551 -31.354572) (xy 280.236658 -31.370085)
			(xy 280.177236 -31.377908) (xy 280.1173 -31.377908) (xy 280.057878 -31.370085) (xy 279.999985 -31.354572)
			(xy 279.944612 -31.331636) (xy 279.892706 -31.301669) (xy 279.845156 -31.265182) (xy 279.802776 -31.222802)
			(xy 279.766289 -31.175252) (xy 279.736322 -31.123346) (xy 279.713386 -31.067973) (xy 279.697873 -31.01008)
			(xy 279.69005 -30.950658) (xy 279.68956 -30.92069) (xy 265.868404 -30.92069) (xy 265.868404 -30.922468)
			(xy 265.867914 -30.952452) (xy 265.860086 -31.011908) (xy 265.844565 -31.069833) (xy 265.821616 -31.125237)
			(xy 265.791632 -31.177171) (xy 265.755126 -31.224747) (xy 265.712721 -31.267152) (xy 265.665145 -31.303658)
			(xy 265.613211 -31.333642) (xy 265.557807 -31.356591) (xy 265.499882 -31.372112) (xy 265.440426 -31.37994)
			(xy 265.380458 -31.37994) (xy 265.321002 -31.372112) (xy 265.263077 -31.356591) (xy 265.207673 -31.333642)
			(xy 265.155739 -31.303658) (xy 265.108163 -31.267152) (xy 265.065758 -31.224747) (xy 265.029252 -31.177171)
			(xy 264.999268 -31.125237) (xy 264.976319 -31.069833) (xy 264.960798 -31.011908) (xy 264.95297 -30.952452)
			(xy 264.95248 -30.922468) (xy 254.604999 -30.922468) (xy 254.604538 -30.950658) (xy 254.596715 -31.01008)
			(xy 254.581202 -31.067973) (xy 254.558266 -31.123346) (xy 254.528299 -31.175252) (xy 254.491812 -31.222802)
			(xy 254.449432 -31.265182) (xy 254.401882 -31.301669) (xy 254.349976 -31.331636) (xy 254.294603 -31.354572)
			(xy 254.23671 -31.370085) (xy 254.177288 -31.377908) (xy 254.117352 -31.377908) (xy 254.05793 -31.370085)
			(xy 254.000037 -31.354572) (xy 253.944664 -31.331636) (xy 253.892758 -31.301669) (xy 253.845208 -31.265182)
			(xy 253.802828 -31.222802) (xy 253.766341 -31.175252) (xy 253.736374 -31.123346) (xy 253.713438 -31.067973)
			(xy 253.697925 -31.01008) (xy 253.690102 -30.950658) (xy 253.689612 -30.92069) (xy 239.868456 -30.92069)
			(xy 239.868456 -30.922468) (xy 239.867966 -30.952452) (xy 239.860138 -31.011908) (xy 239.844617 -31.069833)
			(xy 239.821668 -31.125237) (xy 239.791684 -31.177171) (xy 239.755178 -31.224747) (xy 239.712773 -31.267152)
			(xy 239.665197 -31.303658) (xy 239.613263 -31.333642) (xy 239.557859 -31.356591) (xy 239.499934 -31.372112)
			(xy 239.440478 -31.37994) (xy 239.38051 -31.37994) (xy 239.321054 -31.372112) (xy 239.263129 -31.356591)
			(xy 239.207725 -31.333642) (xy 239.155791 -31.303658) (xy 239.108215 -31.267152) (xy 239.06581 -31.224747)
			(xy 239.029304 -31.177171) (xy 238.99932 -31.125237) (xy 238.976371 -31.069833) (xy 238.96085 -31.011908)
			(xy 238.953022 -30.952452) (xy 238.952532 -30.922468) (xy 216.504999 -30.922468) (xy 216.504538 -30.950658)
			(xy 216.496715 -31.01008) (xy 216.481202 -31.067973) (xy 216.458266 -31.123346) (xy 216.428299 -31.175252)
			(xy 216.391812 -31.222802) (xy 216.349432 -31.265182) (xy 216.301882 -31.301669) (xy 216.249976 -31.331636)
			(xy 216.194603 -31.354572) (xy 216.13671 -31.370085) (xy 216.077288 -31.377908) (xy 216.017352 -31.377908)
			(xy 215.95793 -31.370085) (xy 215.900037 -31.354572) (xy 215.844664 -31.331636) (xy 215.792758 -31.301669)
			(xy 215.745208 -31.265182) (xy 215.702828 -31.222802) (xy 215.666341 -31.175252) (xy 215.636374 -31.123346)
			(xy 215.613438 -31.067973) (xy 215.597925 -31.01008) (xy 215.590102 -30.950658) (xy 215.589612 -30.92069)
			(xy 201.768456 -30.92069) (xy 201.768456 -30.922468) (xy 201.767966 -30.952452) (xy 201.760138 -31.011908)
			(xy 201.744617 -31.069833) (xy 201.721668 -31.125237) (xy 201.691684 -31.177171) (xy 201.655178 -31.224747)
			(xy 201.612773 -31.267152) (xy 201.565197 -31.303658) (xy 201.513263 -31.333642) (xy 201.457859 -31.356591)
			(xy 201.399934 -31.372112) (xy 201.340478 -31.37994) (xy 201.28051 -31.37994) (xy 201.221054 -31.372112)
			(xy 201.163129 -31.356591) (xy 201.107725 -31.333642) (xy 201.055791 -31.303658) (xy 201.008215 -31.267152)
			(xy 200.96581 -31.224747) (xy 200.929304 -31.177171) (xy 200.89932 -31.125237) (xy 200.876371 -31.069833)
			(xy 200.86085 -31.011908) (xy 200.853022 -30.952452) (xy 200.852532 -30.922468) (xy 190.505051 -30.922468)
			(xy 190.50459 -30.950658) (xy 190.496767 -31.01008) (xy 190.481254 -31.067973) (xy 190.458318 -31.123346)
			(xy 190.428351 -31.175252) (xy 190.391864 -31.222802) (xy 190.349484 -31.265182) (xy 190.301934 -31.301669)
			(xy 190.250028 -31.331636) (xy 190.194655 -31.354572) (xy 190.136762 -31.370085) (xy 190.07734 -31.377908)
			(xy 190.017404 -31.377908) (xy 189.957982 -31.370085) (xy 189.900089 -31.354572) (xy 189.844716 -31.331636)
			(xy 189.79281 -31.301669) (xy 189.74526 -31.265182) (xy 189.70288 -31.222802) (xy 189.666393 -31.175252)
			(xy 189.636426 -31.123346) (xy 189.61349 -31.067973) (xy 189.597977 -31.01008) (xy 189.590154 -30.950658)
			(xy 189.589664 -30.92069) (xy 175.768508 -30.92069) (xy 175.768508 -30.922468) (xy 175.768018 -30.952452)
			(xy 175.76019 -31.011908) (xy 175.744669 -31.069833) (xy 175.72172 -31.125237) (xy 175.691736 -31.177171)
			(xy 175.65523 -31.224747) (xy 175.612825 -31.267152) (xy 175.565249 -31.303658) (xy 175.513315 -31.333642)
			(xy 175.457911 -31.356591) (xy 175.399986 -31.372112) (xy 175.34053 -31.37994) (xy 175.280562 -31.37994)
			(xy 175.221106 -31.372112) (xy 175.163181 -31.356591) (xy 175.107777 -31.333642) (xy 175.055843 -31.303658)
			(xy 175.008267 -31.267152) (xy 174.965862 -31.224747) (xy 174.929356 -31.177171) (xy 174.899372 -31.125237)
			(xy 174.876423 -31.069833) (xy 174.860902 -31.011908) (xy 174.853074 -30.952452) (xy 174.852584 -30.922468)
			(xy 164.505103 -30.922468) (xy 164.504642 -30.950658) (xy 164.496819 -31.01008) (xy 164.481306 -31.067973)
			(xy 164.45837 -31.123346) (xy 164.428403 -31.175252) (xy 164.391916 -31.222802) (xy 164.349536 -31.265182)
			(xy 164.301986 -31.301669) (xy 164.25008 -31.331636) (xy 164.194707 -31.354572) (xy 164.136814 -31.370085)
			(xy 164.077392 -31.377908) (xy 164.017456 -31.377908) (xy 163.958034 -31.370085) (xy 163.900141 -31.354572)
			(xy 163.844768 -31.331636) (xy 163.792862 -31.301669) (xy 163.745312 -31.265182) (xy 163.702932 -31.222802)
			(xy 163.666445 -31.175252) (xy 163.636478 -31.123346) (xy 163.613542 -31.067973) (xy 163.598029 -31.01008)
			(xy 163.590206 -30.950658) (xy 163.589716 -30.92069) (xy 149.76856 -30.92069) (xy 149.76856 -30.922468)
			(xy 149.76807 -30.952452) (xy 149.760242 -31.011908) (xy 149.744721 -31.069833) (xy 149.721772 -31.125237)
			(xy 149.691788 -31.177171) (xy 149.655282 -31.224747) (xy 149.612877 -31.267152) (xy 149.565301 -31.303658)
			(xy 149.513367 -31.333642) (xy 149.457963 -31.356591) (xy 149.400038 -31.372112) (xy 149.340582 -31.37994)
			(xy 149.280614 -31.37994) (xy 149.221158 -31.372112) (xy 149.163233 -31.356591) (xy 149.107829 -31.333642)
			(xy 149.055895 -31.303658) (xy 149.008319 -31.267152) (xy 148.965914 -31.224747) (xy 148.929408 -31.177171)
			(xy 148.899424 -31.125237) (xy 148.876475 -31.069833) (xy 148.860954 -31.011908) (xy 148.853126 -30.952452)
			(xy 148.852636 -30.922468) (xy 138.505155 -30.922468) (xy 138.504694 -30.950658) (xy 138.496871 -31.01008)
			(xy 138.481358 -31.067973) (xy 138.458422 -31.123346) (xy 138.428455 -31.175252) (xy 138.391968 -31.222802)
			(xy 138.349588 -31.265182) (xy 138.302038 -31.301669) (xy 138.250132 -31.331636) (xy 138.194759 -31.354572)
			(xy 138.136866 -31.370085) (xy 138.077444 -31.377908) (xy 138.017508 -31.377908) (xy 137.958086 -31.370085)
			(xy 137.900193 -31.354572) (xy 137.84482 -31.331636) (xy 137.792914 -31.301669) (xy 137.745364 -31.265182)
			(xy 137.702984 -31.222802) (xy 137.666497 -31.175252) (xy 137.63653 -31.123346) (xy 137.613594 -31.067973)
			(xy 137.598081 -31.01008) (xy 137.590258 -30.950658) (xy 137.589768 -30.92069) (xy 123.768612 -30.92069)
			(xy 123.768612 -30.922468) (xy 123.768122 -30.952452) (xy 123.760294 -31.011908) (xy 123.744773 -31.069833)
			(xy 123.721824 -31.125237) (xy 123.69184 -31.177171) (xy 123.655334 -31.224747) (xy 123.612929 -31.267152)
			(xy 123.565353 -31.303658) (xy 123.513419 -31.333642) (xy 123.458015 -31.356591) (xy 123.40009 -31.372112)
			(xy 123.340634 -31.37994) (xy 123.280666 -31.37994) (xy 123.22121 -31.372112) (xy 123.163285 -31.356591)
			(xy 123.107881 -31.333642) (xy 123.055947 -31.303658) (xy 123.008371 -31.267152) (xy 122.965966 -31.224747)
			(xy 122.92946 -31.177171) (xy 122.899476 -31.125237) (xy 122.876527 -31.069833) (xy 122.861006 -31.011908)
			(xy 122.853178 -30.952452) (xy 122.852688 -30.922468) (xy 100.405155 -30.922468) (xy 100.404694 -30.950674)
			(xy 100.396866 -31.01013) (xy 100.381345 -31.068055) (xy 100.358396 -31.123459) (xy 100.328412 -31.175393)
			(xy 100.291906 -31.222969) (xy 100.249501 -31.265374) (xy 100.201925 -31.30188) (xy 100.149991 -31.331864)
			(xy 100.094587 -31.354813) (xy 100.036662 -31.370334) (xy 99.977206 -31.378162) (xy 99.917238 -31.378162)
			(xy 99.857782 -31.370334) (xy 99.799857 -31.354813) (xy 99.744453 -31.331864) (xy 99.692519 -31.30188)
			(xy 99.644943 -31.265374) (xy 99.602538 -31.222969) (xy 99.566032 -31.175393) (xy 99.536048 -31.123459)
			(xy 99.513099 -31.068055) (xy 99.497578 -31.01013) (xy 99.48975 -30.950674) (xy 99.48926 -30.92069)
			(xy 85.668104 -30.92069) (xy 85.668104 -30.922468) (xy 85.667614 -30.952436) (xy 85.659791 -31.011858)
			(xy 85.644278 -31.069751) (xy 85.621342 -31.125124) (xy 85.591375 -31.17703) (xy 85.554888 -31.22458)
			(xy 85.512508 -31.26696) (xy 85.464958 -31.303447) (xy 85.413052 -31.333414) (xy 85.357679 -31.35635)
			(xy 85.299786 -31.371863) (xy 85.240364 -31.379686) (xy 85.180428 -31.379686) (xy 85.121006 -31.371863)
			(xy 85.063113 -31.35635) (xy 85.00774 -31.333414) (xy 84.955834 -31.303447) (xy 84.908284 -31.26696)
			(xy 84.865904 -31.22458) (xy 84.829417 -31.17703) (xy 84.79945 -31.125124) (xy 84.776514 -31.069751)
			(xy 84.761001 -31.011858) (xy 84.753178 -30.952436) (xy 84.752688 -30.922468) (xy 74.405207 -30.922468)
			(xy 74.404746 -30.950674) (xy 74.396918 -31.01013) (xy 74.381397 -31.068055) (xy 74.358448 -31.123459)
			(xy 74.328464 -31.175393) (xy 74.291958 -31.222969) (xy 74.249553 -31.265374) (xy 74.201977 -31.30188)
			(xy 74.150043 -31.331864) (xy 74.094639 -31.354813) (xy 74.036714 -31.370334) (xy 73.977258 -31.378162)
			(xy 73.91729 -31.378162) (xy 73.857834 -31.370334) (xy 73.799909 -31.354813) (xy 73.744505 -31.331864)
			(xy 73.692571 -31.30188) (xy 73.644995 -31.265374) (xy 73.60259 -31.222969) (xy 73.566084 -31.175393)
			(xy 73.5361 -31.123459) (xy 73.513151 -31.068055) (xy 73.49763 -31.01013) (xy 73.489802 -30.950674)
			(xy 73.489312 -30.92069) (xy 59.668156 -30.92069) (xy 59.668156 -30.922468) (xy 59.667666 -30.952436)
			(xy 59.659843 -31.011858) (xy 59.64433 -31.069751) (xy 59.621394 -31.125124) (xy 59.591427 -31.17703)
			(xy 59.55494 -31.22458) (xy 59.51256 -31.26696) (xy 59.46501 -31.303447) (xy 59.413104 -31.333414)
			(xy 59.357731 -31.35635) (xy 59.299838 -31.371863) (xy 59.240416 -31.379686) (xy 59.18048 -31.379686)
			(xy 59.121058 -31.371863) (xy 59.063165 -31.35635) (xy 59.007792 -31.333414) (xy 58.955886 -31.303447)
			(xy 58.908336 -31.26696) (xy 58.865956 -31.22458) (xy 58.829469 -31.17703) (xy 58.799502 -31.125124)
			(xy 58.776566 -31.069751) (xy 58.761053 -31.011858) (xy 58.75323 -30.952436) (xy 58.75274 -30.922468)
			(xy 48.405259 -30.922468) (xy 48.404798 -30.950674) (xy 48.39697 -31.01013) (xy 48.381449 -31.068055)
			(xy 48.3585 -31.123459) (xy 48.328516 -31.175393) (xy 48.29201 -31.222969) (xy 48.249605 -31.265374)
			(xy 48.202029 -31.30188) (xy 48.150095 -31.331864) (xy 48.094691 -31.354813) (xy 48.036766 -31.370334)
			(xy 47.97731 -31.378162) (xy 47.917342 -31.378162) (xy 47.857886 -31.370334) (xy 47.799961 -31.354813)
			(xy 47.744557 -31.331864) (xy 47.692623 -31.30188) (xy 47.645047 -31.265374) (xy 47.602642 -31.222969)
			(xy 47.566136 -31.175393) (xy 47.536152 -31.123459) (xy 47.513203 -31.068055) (xy 47.497682 -31.01013)
			(xy 47.489854 -30.950674) (xy 47.489364 -30.92069) (xy 33.668208 -30.92069) (xy 33.668208 -30.922468)
			(xy 33.667718 -30.952436) (xy 33.659895 -31.011858) (xy 33.644382 -31.069751) (xy 33.621446 -31.125124)
			(xy 33.591479 -31.17703) (xy 33.554992 -31.22458) (xy 33.512612 -31.26696) (xy 33.465062 -31.303447)
			(xy 33.413156 -31.333414) (xy 33.357783 -31.35635) (xy 33.29989 -31.371863) (xy 33.240468 -31.379686)
			(xy 33.180532 -31.379686) (xy 33.12111 -31.371863) (xy 33.063217 -31.35635) (xy 33.007844 -31.333414)
			(xy 32.955938 -31.303447) (xy 32.908388 -31.26696) (xy 32.866008 -31.22458) (xy 32.829521 -31.17703)
			(xy 32.799554 -31.125124) (xy 32.776618 -31.069751) (xy 32.761105 -31.011858) (xy 32.753282 -30.952436)
			(xy 32.752792 -30.922468) (xy 22.405311 -30.922468) (xy 22.40485 -30.950674) (xy 22.397022 -31.01013)
			(xy 22.381501 -31.068055) (xy 22.358552 -31.123459) (xy 22.328568 -31.175393) (xy 22.292062 -31.222969)
			(xy 22.249657 -31.265374) (xy 22.202081 -31.30188) (xy 22.150147 -31.331864) (xy 22.094743 -31.354813)
			(xy 22.036818 -31.370334) (xy 21.977362 -31.378162) (xy 21.917394 -31.378162) (xy 21.857938 -31.370334)
			(xy 21.800013 -31.354813) (xy 21.744609 -31.331864) (xy 21.692675 -31.30188) (xy 21.645099 -31.265374)
			(xy 21.602694 -31.222969) (xy 21.566188 -31.175393) (xy 21.536204 -31.123459) (xy 21.513255 -31.068055)
			(xy 21.497734 -31.01013) (xy 21.489906 -30.950674) (xy 21.489416 -30.92069) (xy 7.66826 -30.92069)
			(xy 7.66826 -30.922468) (xy 7.66777 -30.952436) (xy 7.659947 -31.011858) (xy 7.644434 -31.069751)
			(xy 7.621498 -31.125124) (xy 7.591531 -31.17703) (xy 7.555044 -31.22458) (xy 7.512664 -31.26696)
			(xy 7.465114 -31.303447) (xy 7.413208 -31.333414) (xy 7.357835 -31.35635) (xy 7.299942 -31.371863)
			(xy 7.24052 -31.379686) (xy 7.180584 -31.379686) (xy 7.121162 -31.371863) (xy 7.063269 -31.35635)
			(xy 7.007896 -31.333414) (xy 6.95599 -31.303447) (xy 6.90844 -31.26696) (xy 6.86606 -31.22458) (xy 6.829573 -31.17703)
			(xy 6.799606 -31.125124) (xy 6.77667 -31.069751) (xy 6.761157 -31.011858) (xy 6.753334 -30.952436)
			(xy 6.752844 -30.922468) (xy 0.508 -30.922468) (xy 0.508 -32.722312) (xy 8.607044 -32.722312) (xy 8.607044 -31.858712)
			(xy 8.607534 -31.828744) (xy 8.615357 -31.769322) (xy 8.63087 -31.711429) (xy 8.653806 -31.656056)
			(xy 8.683773 -31.60415) (xy 8.72026 -31.5566) (xy 8.76264 -31.51422) (xy 8.81019 -31.477733) (xy 8.862096 -31.447766)
			(xy 8.917469 -31.42483) (xy 8.975362 -31.409317) (xy 9.034784 -31.401494) (xy 9.09472 -31.401494)
			(xy 9.154142 -31.409317) (xy 9.212035 -31.42483) (xy 9.267408 -31.447766) (xy 9.319314 -31.477733)
			(xy 9.366864 -31.51422) (xy 9.409244 -31.5566) (xy 9.445731 -31.60415) (xy 9.475698 -31.656056) (xy 9.498634 -31.711429)
			(xy 9.514147 -31.769322) (xy 9.52197 -31.828744) (xy 9.52246 -31.858712) (xy 9.52246 -32.714184)
			(xy 18.847308 -32.714184) (xy 18.847308 -31.850584) (xy 18.847798 -31.8206) (xy 18.855626 -31.761144)
			(xy 18.871147 -31.703219) (xy 18.894096 -31.647815) (xy 18.92408 -31.595881) (xy 18.960586 -31.548305)
			(xy 19.002991 -31.5059) (xy 19.050567 -31.469394) (xy 19.102501 -31.43941) (xy 19.157905 -31.416461)
			(xy 19.21583 -31.40094) (xy 19.275286 -31.393112) (xy 19.335254 -31.393112) (xy 19.39471 -31.40094)
			(xy 19.452635 -31.416461) (xy 19.508039 -31.43941) (xy 19.559973 -31.469394) (xy 19.607549 -31.5059)
			(xy 19.649954 -31.548305) (xy 19.68646 -31.595881) (xy 19.716444 -31.647815) (xy 19.739393 -31.703219)
			(xy 19.754914 -31.761144) (xy 19.762742 -31.8206) (xy 19.763232 -31.850584) (xy 19.763232 -32.714184)
			(xy 19.763099 -32.722312) (xy 34.606992 -32.722312) (xy 34.606992 -31.858712) (xy 34.607482 -31.828744)
			(xy 34.615305 -31.769322) (xy 34.630818 -31.711429) (xy 34.653754 -31.656056) (xy 34.683721 -31.60415)
			(xy 34.720208 -31.5566) (xy 34.762588 -31.51422) (xy 34.810138 -31.477733) (xy 34.862044 -31.447766)
			(xy 34.917417 -31.42483) (xy 34.97531 -31.409317) (xy 35.034732 -31.401494) (xy 35.094668 -31.401494)
			(xy 35.15409 -31.409317) (xy 35.211983 -31.42483) (xy 35.267356 -31.447766) (xy 35.319262 -31.477733)
			(xy 35.366812 -31.51422) (xy 35.409192 -31.5566) (xy 35.445679 -31.60415) (xy 35.475646 -31.656056)
			(xy 35.498582 -31.711429) (xy 35.514095 -31.769322) (xy 35.521918 -31.828744) (xy 35.522408 -31.858712)
			(xy 35.522408 -32.714184) (xy 44.847256 -32.714184) (xy 44.847256 -31.850584) (xy 44.847746 -31.8206)
			(xy 44.855574 -31.761144) (xy 44.871095 -31.703219) (xy 44.894044 -31.647815) (xy 44.924028 -31.595881)
			(xy 44.960534 -31.548305) (xy 45.002939 -31.5059) (xy 45.050515 -31.469394) (xy 45.102449 -31.43941)
			(xy 45.157853 -31.416461) (xy 45.215778 -31.40094) (xy 45.275234 -31.393112) (xy 45.335202 -31.393112)
			(xy 45.394658 -31.40094) (xy 45.452583 -31.416461) (xy 45.507987 -31.43941) (xy 45.559921 -31.469394)
			(xy 45.607497 -31.5059) (xy 45.649902 -31.548305) (xy 45.686408 -31.595881) (xy 45.716392 -31.647815)
			(xy 45.739341 -31.703219) (xy 45.754862 -31.761144) (xy 45.76269 -31.8206) (xy 45.76318 -31.850584)
			(xy 45.76318 -32.714184) (xy 45.763047 -32.722312) (xy 60.60694 -32.722312) (xy 60.60694 -31.858712)
			(xy 60.60743 -31.828744) (xy 60.615253 -31.769322) (xy 60.630766 -31.711429) (xy 60.653702 -31.656056)
			(xy 60.683669 -31.60415) (xy 60.720156 -31.5566) (xy 60.762536 -31.51422) (xy 60.810086 -31.477733)
			(xy 60.861992 -31.447766) (xy 60.917365 -31.42483) (xy 60.975258 -31.409317) (xy 61.03468 -31.401494)
			(xy 61.094616 -31.401494) (xy 61.154038 -31.409317) (xy 61.211931 -31.42483) (xy 61.267304 -31.447766)
			(xy 61.31921 -31.477733) (xy 61.36676 -31.51422) (xy 61.40914 -31.5566) (xy 61.445627 -31.60415)
			(xy 61.475594 -31.656056) (xy 61.49853 -31.711429) (xy 61.514043 -31.769322) (xy 61.521866 -31.828744)
			(xy 61.522356 -31.858712) (xy 61.522356 -32.714184) (xy 70.847204 -32.714184) (xy 70.847204 -31.850584)
			(xy 70.847694 -31.8206) (xy 70.855522 -31.761144) (xy 70.871043 -31.703219) (xy 70.893992 -31.647815)
			(xy 70.923976 -31.595881) (xy 70.960482 -31.548305) (xy 71.002887 -31.5059) (xy 71.050463 -31.469394)
			(xy 71.102397 -31.43941) (xy 71.157801 -31.416461) (xy 71.215726 -31.40094) (xy 71.275182 -31.393112)
			(xy 71.33515 -31.393112) (xy 71.394606 -31.40094) (xy 71.452531 -31.416461) (xy 71.507935 -31.43941)
			(xy 71.559869 -31.469394) (xy 71.607445 -31.5059) (xy 71.64985 -31.548305) (xy 71.686356 -31.595881)
			(xy 71.71634 -31.647815) (xy 71.739289 -31.703219) (xy 71.75481 -31.761144) (xy 71.762638 -31.8206)
			(xy 71.763128 -31.850584) (xy 71.763128 -32.714184) (xy 71.762995 -32.722312) (xy 86.606888 -32.722312)
			(xy 86.606888 -31.858712) (xy 86.607378 -31.828744) (xy 86.615201 -31.769322) (xy 86.630714 -31.711429)
			(xy 86.65365 -31.656056) (xy 86.683617 -31.60415) (xy 86.720104 -31.5566) (xy 86.762484 -31.51422)
			(xy 86.810034 -31.477733) (xy 86.86194 -31.447766) (xy 86.917313 -31.42483) (xy 86.975206 -31.409317)
			(xy 87.034628 -31.401494) (xy 87.094564 -31.401494) (xy 87.153986 -31.409317) (xy 87.211879 -31.42483)
			(xy 87.267252 -31.447766) (xy 87.319158 -31.477733) (xy 87.366708 -31.51422) (xy 87.409088 -31.5566)
			(xy 87.445575 -31.60415) (xy 87.475542 -31.656056) (xy 87.498478 -31.711429) (xy 87.513991 -31.769322)
			(xy 87.521814 -31.828744) (xy 87.522304 -31.858712) (xy 87.522304 -32.714184) (xy 96.847152 -32.714184)
			(xy 96.847152 -31.850584) (xy 96.847642 -31.8206) (xy 96.85547 -31.761144) (xy 96.870991 -31.703219)
			(xy 96.89394 -31.647815) (xy 96.923924 -31.595881) (xy 96.96043 -31.548305) (xy 97.002835 -31.5059)
			(xy 97.050411 -31.469394) (xy 97.102345 -31.43941) (xy 97.157749 -31.416461) (xy 97.215674 -31.40094)
			(xy 97.27513 -31.393112) (xy 97.335098 -31.393112) (xy 97.394554 -31.40094) (xy 97.452479 -31.416461)
			(xy 97.507883 -31.43941) (xy 97.559817 -31.469394) (xy 97.607393 -31.5059) (xy 97.649798 -31.548305)
			(xy 97.686304 -31.595881) (xy 97.716288 -31.647815) (xy 97.739237 -31.703219) (xy 97.754758 -31.761144)
			(xy 97.762586 -31.8206) (xy 97.763076 -31.850584) (xy 97.763076 -32.714184) (xy 97.762943 -32.722312)
			(xy 124.706888 -32.722312) (xy 124.706888 -31.858712) (xy 124.707378 -31.828728) (xy 124.715206 -31.769272)
			(xy 124.730727 -31.711347) (xy 124.753676 -31.655943) (xy 124.78366 -31.604009) (xy 124.820166 -31.556433)
			(xy 124.862571 -31.514028) (xy 124.910147 -31.477522) (xy 124.962081 -31.447538) (xy 125.017485 -31.424589)
			(xy 125.07541 -31.409068) (xy 125.134866 -31.40124) (xy 125.194834 -31.40124) (xy 125.25429 -31.409068)
			(xy 125.312215 -31.424589) (xy 125.367619 -31.447538) (xy 125.419553 -31.477522) (xy 125.467129 -31.514028)
			(xy 125.509534 -31.556433) (xy 125.54604 -31.604009) (xy 125.576024 -31.655943) (xy 125.598973 -31.711347)
			(xy 125.614494 -31.769272) (xy 125.622322 -31.828728) (xy 125.622812 -31.858712) (xy 125.622812 -32.714184)
			(xy 134.94766 -32.714184) (xy 134.94766 -31.850584) (xy 134.94815 -31.820616) (xy 134.955973 -31.761194)
			(xy 134.971486 -31.703301) (xy 134.994422 -31.647928) (xy 135.024389 -31.596022) (xy 135.060876 -31.548472)
			(xy 135.103256 -31.506092) (xy 135.150806 -31.469605) (xy 135.202712 -31.439638) (xy 135.258085 -31.416702)
			(xy 135.315978 -31.401189) (xy 135.3754 -31.393366) (xy 135.435336 -31.393366) (xy 135.494758 -31.401189)
			(xy 135.552651 -31.416702) (xy 135.608024 -31.439638) (xy 135.65993 -31.469605) (xy 135.70748 -31.506092)
			(xy 135.74986 -31.548472) (xy 135.786347 -31.596022) (xy 135.816314 -31.647928) (xy 135.83925 -31.703301)
			(xy 135.854763 -31.761194) (xy 135.862586 -31.820616) (xy 135.863076 -31.850584) (xy 135.863076 -32.714184)
			(xy 135.862943 -32.722312) (xy 150.706836 -32.722312) (xy 150.706836 -31.858712) (xy 150.707326 -31.828728)
			(xy 150.715154 -31.769272) (xy 150.730675 -31.711347) (xy 150.753624 -31.655943) (xy 150.783608 -31.604009)
			(xy 150.820114 -31.556433) (xy 150.862519 -31.514028) (xy 150.910095 -31.477522) (xy 150.962029 -31.447538)
			(xy 151.017433 -31.424589) (xy 151.075358 -31.409068) (xy 151.134814 -31.40124) (xy 151.194782 -31.40124)
			(xy 151.254238 -31.409068) (xy 151.312163 -31.424589) (xy 151.367567 -31.447538) (xy 151.419501 -31.477522)
			(xy 151.467077 -31.514028) (xy 151.509482 -31.556433) (xy 151.545988 -31.604009) (xy 151.575972 -31.655943)
			(xy 151.598921 -31.711347) (xy 151.614442 -31.769272) (xy 151.62227 -31.828728) (xy 151.62276 -31.858712)
			(xy 151.62276 -32.714184) (xy 160.947608 -32.714184) (xy 160.947608 -31.850584) (xy 160.948098 -31.820616)
			(xy 160.955921 -31.761194) (xy 160.971434 -31.703301) (xy 160.99437 -31.647928) (xy 161.024337 -31.596022)
			(xy 161.060824 -31.548472) (xy 161.103204 -31.506092) (xy 161.150754 -31.469605) (xy 161.20266 -31.439638)
			(xy 161.258033 -31.416702) (xy 161.315926 -31.401189) (xy 161.375348 -31.393366) (xy 161.435284 -31.393366)
			(xy 161.494706 -31.401189) (xy 161.552599 -31.416702) (xy 161.607972 -31.439638) (xy 161.659878 -31.469605)
			(xy 161.707428 -31.506092) (xy 161.749808 -31.548472) (xy 161.786295 -31.596022) (xy 161.816262 -31.647928)
			(xy 161.839198 -31.703301) (xy 161.854711 -31.761194) (xy 161.862534 -31.820616) (xy 161.863024 -31.850584)
			(xy 161.863024 -32.714184) (xy 161.862891 -32.722312) (xy 176.706784 -32.722312) (xy 176.706784 -31.858712)
			(xy 176.707274 -31.828728) (xy 176.715102 -31.769272) (xy 176.730623 -31.711347) (xy 176.753572 -31.655943)
			(xy 176.783556 -31.604009) (xy 176.820062 -31.556433) (xy 176.862467 -31.514028) (xy 176.910043 -31.477522)
			(xy 176.961977 -31.447538) (xy 177.017381 -31.424589) (xy 177.075306 -31.409068) (xy 177.134762 -31.40124)
			(xy 177.19473 -31.40124) (xy 177.254186 -31.409068) (xy 177.312111 -31.424589) (xy 177.367515 -31.447538)
			(xy 177.419449 -31.477522) (xy 177.467025 -31.514028) (xy 177.50943 -31.556433) (xy 177.545936 -31.604009)
			(xy 177.57592 -31.655943) (xy 177.598869 -31.711347) (xy 177.61439 -31.769272) (xy 177.622218 -31.828728)
			(xy 177.622708 -31.858712) (xy 177.622708 -32.714184) (xy 186.947556 -32.714184) (xy 186.947556 -31.850584)
			(xy 186.948046 -31.820616) (xy 186.955869 -31.761194) (xy 186.971382 -31.703301) (xy 186.994318 -31.647928)
			(xy 187.024285 -31.596022) (xy 187.060772 -31.548472) (xy 187.103152 -31.506092) (xy 187.150702 -31.469605)
			(xy 187.202608 -31.439638) (xy 187.257981 -31.416702) (xy 187.315874 -31.401189) (xy 187.375296 -31.393366)
			(xy 187.435232 -31.393366) (xy 187.494654 -31.401189) (xy 187.552547 -31.416702) (xy 187.60792 -31.439638)
			(xy 187.659826 -31.469605) (xy 187.707376 -31.506092) (xy 187.749756 -31.548472) (xy 187.786243 -31.596022)
			(xy 187.81621 -31.647928) (xy 187.839146 -31.703301) (xy 187.854659 -31.761194) (xy 187.862482 -31.820616)
			(xy 187.862972 -31.850584) (xy 187.862972 -32.714184) (xy 187.862839 -32.722312) (xy 202.706732 -32.722312)
			(xy 202.706732 -31.858712) (xy 202.707222 -31.828728) (xy 202.71505 -31.769272) (xy 202.730571 -31.711347)
			(xy 202.75352 -31.655943) (xy 202.783504 -31.604009) (xy 202.82001 -31.556433) (xy 202.862415 -31.514028)
			(xy 202.909991 -31.477522) (xy 202.961925 -31.447538) (xy 203.017329 -31.424589) (xy 203.075254 -31.409068)
			(xy 203.13471 -31.40124) (xy 203.194678 -31.40124) (xy 203.254134 -31.409068) (xy 203.312059 -31.424589)
			(xy 203.367463 -31.447538) (xy 203.419397 -31.477522) (xy 203.466973 -31.514028) (xy 203.509378 -31.556433)
			(xy 203.545884 -31.604009) (xy 203.575868 -31.655943) (xy 203.598817 -31.711347) (xy 203.614338 -31.769272)
			(xy 203.622166 -31.828728) (xy 203.622656 -31.858712) (xy 203.622656 -32.714184) (xy 212.947504 -32.714184)
			(xy 212.947504 -31.850584) (xy 212.947994 -31.820616) (xy 212.955817 -31.761194) (xy 212.97133 -31.703301)
			(xy 212.994266 -31.647928) (xy 213.024233 -31.596022) (xy 213.06072 -31.548472) (xy 213.1031 -31.506092)
			(xy 213.15065 -31.469605) (xy 213.202556 -31.439638) (xy 213.257929 -31.416702) (xy 213.315822 -31.401189)
			(xy 213.375244 -31.393366) (xy 213.43518 -31.393366) (xy 213.494602 -31.401189) (xy 213.552495 -31.416702)
			(xy 213.607868 -31.439638) (xy 213.659774 -31.469605) (xy 213.707324 -31.506092) (xy 213.749704 -31.548472)
			(xy 213.786191 -31.596022) (xy 213.816158 -31.647928) (xy 213.839094 -31.703301) (xy 213.854607 -31.761194)
			(xy 213.86243 -31.820616) (xy 213.86292 -31.850584) (xy 213.86292 -32.714184) (xy 213.862787 -32.722312)
			(xy 240.806732 -32.722312) (xy 240.806732 -31.858712) (xy 240.807222 -31.828728) (xy 240.81505 -31.769272)
			(xy 240.830571 -31.711347) (xy 240.85352 -31.655943) (xy 240.883504 -31.604009) (xy 240.92001 -31.556433)
			(xy 240.962415 -31.514028) (xy 241.009991 -31.477522) (xy 241.061925 -31.447538) (xy 241.117329 -31.424589)
			(xy 241.175254 -31.409068) (xy 241.23471 -31.40124) (xy 241.294678 -31.40124) (xy 241.354134 -31.409068)
			(xy 241.412059 -31.424589) (xy 241.467463 -31.447538) (xy 241.519397 -31.477522) (xy 241.566973 -31.514028)
			(xy 241.609378 -31.556433) (xy 241.645884 -31.604009) (xy 241.675868 -31.655943) (xy 241.698817 -31.711347)
			(xy 241.714338 -31.769272) (xy 241.722166 -31.828728) (xy 241.722656 -31.858712) (xy 241.722656 -32.714184)
			(xy 251.047504 -32.714184) (xy 251.047504 -31.850584) (xy 251.047994 -31.820616) (xy 251.055817 -31.761194)
			(xy 251.07133 -31.703301) (xy 251.094266 -31.647928) (xy 251.124233 -31.596022) (xy 251.16072 -31.548472)
			(xy 251.2031 -31.506092) (xy 251.25065 -31.469605) (xy 251.302556 -31.439638) (xy 251.357929 -31.416702)
			(xy 251.415822 -31.401189) (xy 251.475244 -31.393366) (xy 251.53518 -31.393366) (xy 251.594602 -31.401189)
			(xy 251.652495 -31.416702) (xy 251.707868 -31.439638) (xy 251.759774 -31.469605) (xy 251.807324 -31.506092)
			(xy 251.849704 -31.548472) (xy 251.886191 -31.596022) (xy 251.916158 -31.647928) (xy 251.939094 -31.703301)
			(xy 251.954607 -31.761194) (xy 251.96243 -31.820616) (xy 251.96292 -31.850584) (xy 251.96292 -32.714184)
			(xy 251.962787 -32.722312) (xy 266.80668 -32.722312) (xy 266.80668 -31.858712) (xy 266.80717 -31.828728)
			(xy 266.814998 -31.769272) (xy 266.830519 -31.711347) (xy 266.853468 -31.655943) (xy 266.883452 -31.604009)
			(xy 266.919958 -31.556433) (xy 266.962363 -31.514028) (xy 267.009939 -31.477522) (xy 267.061873 -31.447538)
			(xy 267.117277 -31.424589) (xy 267.175202 -31.409068) (xy 267.234658 -31.40124) (xy 267.294626 -31.40124)
			(xy 267.354082 -31.409068) (xy 267.412007 -31.424589) (xy 267.467411 -31.447538) (xy 267.519345 -31.477522)
			(xy 267.566921 -31.514028) (xy 267.609326 -31.556433) (xy 267.645832 -31.604009) (xy 267.675816 -31.655943)
			(xy 267.698765 -31.711347) (xy 267.714286 -31.769272) (xy 267.722114 -31.828728) (xy 267.722604 -31.858712)
			(xy 267.722604 -32.714184) (xy 277.047452 -32.714184) (xy 277.047452 -31.850584) (xy 277.047942 -31.820616)
			(xy 277.055765 -31.761194) (xy 277.071278 -31.703301) (xy 277.094214 -31.647928) (xy 277.124181 -31.596022)
			(xy 277.160668 -31.548472) (xy 277.203048 -31.506092) (xy 277.250598 -31.469605) (xy 277.302504 -31.439638)
			(xy 277.357877 -31.416702) (xy 277.41577 -31.401189) (xy 277.475192 -31.393366) (xy 277.535128 -31.393366)
			(xy 277.59455 -31.401189) (xy 277.652443 -31.416702) (xy 277.707816 -31.439638) (xy 277.759722 -31.469605)
			(xy 277.807272 -31.506092) (xy 277.849652 -31.548472) (xy 277.886139 -31.596022) (xy 277.916106 -31.647928)
			(xy 277.939042 -31.703301) (xy 277.954555 -31.761194) (xy 277.962378 -31.820616) (xy 277.962868 -31.850584)
			(xy 277.962868 -32.714184) (xy 277.962735 -32.722312) (xy 292.806628 -32.722312) (xy 292.806628 -31.858712)
			(xy 292.807118 -31.828728) (xy 292.814946 -31.769272) (xy 292.830467 -31.711347) (xy 292.853416 -31.655943)
			(xy 292.8834 -31.604009) (xy 292.919906 -31.556433) (xy 292.962311 -31.514028) (xy 293.009887 -31.477522)
			(xy 293.061821 -31.447538) (xy 293.117225 -31.424589) (xy 293.17515 -31.409068) (xy 293.234606 -31.40124)
			(xy 293.294574 -31.40124) (xy 293.35403 -31.409068) (xy 293.411955 -31.424589) (xy 293.467359 -31.447538)
			(xy 293.519293 -31.477522) (xy 293.566869 -31.514028) (xy 293.609274 -31.556433) (xy 293.64578 -31.604009)
			(xy 293.675764 -31.655943) (xy 293.698713 -31.711347) (xy 293.714234 -31.769272) (xy 293.722062 -31.828728)
			(xy 293.722552 -31.858712) (xy 293.722552 -32.714184) (xy 303.0474 -32.714184) (xy 303.0474 -31.850584)
			(xy 303.04789 -31.820616) (xy 303.055713 -31.761194) (xy 303.071226 -31.703301) (xy 303.094162 -31.647928)
			(xy 303.124129 -31.596022) (xy 303.160616 -31.548472) (xy 303.202996 -31.506092) (xy 303.250546 -31.469605)
			(xy 303.302452 -31.439638) (xy 303.357825 -31.416702) (xy 303.415718 -31.401189) (xy 303.47514 -31.393366)
			(xy 303.535076 -31.393366) (xy 303.594498 -31.401189) (xy 303.652391 -31.416702) (xy 303.707764 -31.439638)
			(xy 303.75967 -31.469605) (xy 303.80722 -31.506092) (xy 303.8496 -31.548472) (xy 303.886087 -31.596022)
			(xy 303.916054 -31.647928) (xy 303.93899 -31.703301) (xy 303.954503 -31.761194) (xy 303.962326 -31.820616)
			(xy 303.962816 -31.850584) (xy 303.962816 -32.714184) (xy 303.962683 -32.722312) (xy 318.806576 -32.722312)
			(xy 318.806576 -31.858712) (xy 318.807066 -31.828728) (xy 318.814894 -31.769272) (xy 318.830415 -31.711347)
			(xy 318.853364 -31.655943) (xy 318.883348 -31.604009) (xy 318.919854 -31.556433) (xy 318.962259 -31.514028)
			(xy 319.009835 -31.477522) (xy 319.061769 -31.447538) (xy 319.117173 -31.424589) (xy 319.175098 -31.409068)
			(xy 319.234554 -31.40124) (xy 319.294522 -31.40124) (xy 319.353978 -31.409068) (xy 319.411903 -31.424589)
			(xy 319.467307 -31.447538) (xy 319.519241 -31.477522) (xy 319.566817 -31.514028) (xy 319.609222 -31.556433)
			(xy 319.645728 -31.604009) (xy 319.675712 -31.655943) (xy 319.698661 -31.711347) (xy 319.714182 -31.769272)
			(xy 319.72201 -31.828728) (xy 319.7225 -31.858712) (xy 319.7225 -32.714184) (xy 329.047348 -32.714184)
			(xy 329.047348 -31.850584) (xy 329.047838 -31.820616) (xy 329.055661 -31.761194) (xy 329.071174 -31.703301)
			(xy 329.09411 -31.647928) (xy 329.124077 -31.596022) (xy 329.160564 -31.548472) (xy 329.202944 -31.506092)
			(xy 329.250494 -31.469605) (xy 329.3024 -31.439638) (xy 329.357773 -31.416702) (xy 329.415666 -31.401189)
			(xy 329.475088 -31.393366) (xy 329.535024 -31.393366) (xy 329.594446 -31.401189) (xy 329.652339 -31.416702)
			(xy 329.707712 -31.439638) (xy 329.759618 -31.469605) (xy 329.807168 -31.506092) (xy 329.849548 -31.548472)
			(xy 329.886035 -31.596022) (xy 329.916002 -31.647928) (xy 329.938938 -31.703301) (xy 329.954451 -31.761194)
			(xy 329.962274 -31.820616) (xy 329.962764 -31.850584) (xy 329.962764 -32.714184) (xy 329.962631 -32.722312)
			(xy 356.907084 -32.722312) (xy 356.907084 -31.858712) (xy 356.907574 -31.828744) (xy 356.915397 -31.769322)
			(xy 356.93091 -31.711429) (xy 356.953846 -31.656056) (xy 356.983813 -31.60415) (xy 357.0203 -31.5566)
			(xy 357.06268 -31.51422) (xy 357.11023 -31.477733) (xy 357.162136 -31.447766) (xy 357.217509 -31.42483)
			(xy 357.275402 -31.409317) (xy 357.334824 -31.401494) (xy 357.39476 -31.401494) (xy 357.454182 -31.409317)
			(xy 357.512075 -31.42483) (xy 357.567448 -31.447766) (xy 357.619354 -31.477733) (xy 357.666904 -31.51422)
			(xy 357.709284 -31.5566) (xy 357.745771 -31.60415) (xy 357.775738 -31.656056) (xy 357.798674 -31.711429)
			(xy 357.814187 -31.769322) (xy 357.82201 -31.828744) (xy 357.8225 -31.858712) (xy 357.8225 -32.714184)
			(xy 367.147348 -32.714184) (xy 367.147348 -31.850584) (xy 367.147838 -31.8206) (xy 367.155666 -31.761144)
			(xy 367.171187 -31.703219) (xy 367.194136 -31.647815) (xy 367.22412 -31.595881) (xy 367.260626 -31.548305)
			(xy 367.303031 -31.5059) (xy 367.350607 -31.469394) (xy 367.402541 -31.43941) (xy 367.457945 -31.416461)
			(xy 367.51587 -31.40094) (xy 367.575326 -31.393112) (xy 367.635294 -31.393112) (xy 367.69475 -31.40094)
			(xy 367.752675 -31.416461) (xy 367.808079 -31.43941) (xy 367.860013 -31.469394) (xy 367.907589 -31.5059)
			(xy 367.949994 -31.548305) (xy 367.9865 -31.595881) (xy 368.016484 -31.647815) (xy 368.039433 -31.703219)
			(xy 368.054954 -31.761144) (xy 368.062782 -31.8206) (xy 368.063272 -31.850584) (xy 368.063272 -32.714184)
			(xy 368.063139 -32.722312) (xy 382.907032 -32.722312) (xy 382.907032 -31.858712) (xy 382.907522 -31.828744)
			(xy 382.915345 -31.769322) (xy 382.930858 -31.711429) (xy 382.953794 -31.656056) (xy 382.983761 -31.60415)
			(xy 383.020248 -31.5566) (xy 383.062628 -31.51422) (xy 383.110178 -31.477733) (xy 383.162084 -31.447766)
			(xy 383.217457 -31.42483) (xy 383.27535 -31.409317) (xy 383.334772 -31.401494) (xy 383.394708 -31.401494)
			(xy 383.45413 -31.409317) (xy 383.512023 -31.42483) (xy 383.567396 -31.447766) (xy 383.619302 -31.477733)
			(xy 383.666852 -31.51422) (xy 383.709232 -31.5566) (xy 383.745719 -31.60415) (xy 383.775686 -31.656056)
			(xy 383.798622 -31.711429) (xy 383.814135 -31.769322) (xy 383.821958 -31.828744) (xy 383.822448 -31.858712)
			(xy 383.822448 -32.714184) (xy 393.147296 -32.714184) (xy 393.147296 -31.850584) (xy 393.147786 -31.8206)
			(xy 393.155614 -31.761144) (xy 393.171135 -31.703219) (xy 393.194084 -31.647815) (xy 393.224068 -31.595881)
			(xy 393.260574 -31.548305) (xy 393.302979 -31.5059) (xy 393.350555 -31.469394) (xy 393.402489 -31.43941)
			(xy 393.457893 -31.416461) (xy 393.515818 -31.40094) (xy 393.575274 -31.393112) (xy 393.635242 -31.393112)
			(xy 393.694698 -31.40094) (xy 393.752623 -31.416461) (xy 393.808027 -31.43941) (xy 393.859961 -31.469394)
			(xy 393.907537 -31.5059) (xy 393.949942 -31.548305) (xy 393.986448 -31.595881) (xy 394.016432 -31.647815)
			(xy 394.039381 -31.703219) (xy 394.054902 -31.761144) (xy 394.06273 -31.8206) (xy 394.06322 -31.850584)
			(xy 394.06322 -32.714184) (xy 394.063087 -32.722312) (xy 408.90698 -32.722312) (xy 408.90698 -31.858712)
			(xy 408.90747 -31.828744) (xy 408.915293 -31.769322) (xy 408.930806 -31.711429) (xy 408.953742 -31.656056)
			(xy 408.983709 -31.60415) (xy 409.020196 -31.5566) (xy 409.062576 -31.51422) (xy 409.110126 -31.477733)
			(xy 409.162032 -31.447766) (xy 409.217405 -31.42483) (xy 409.275298 -31.409317) (xy 409.33472 -31.401494)
			(xy 409.394656 -31.401494) (xy 409.454078 -31.409317) (xy 409.511971 -31.42483) (xy 409.567344 -31.447766)
			(xy 409.61925 -31.477733) (xy 409.6668 -31.51422) (xy 409.70918 -31.5566) (xy 409.745667 -31.60415)
			(xy 409.775634 -31.656056) (xy 409.79857 -31.711429) (xy 409.814083 -31.769322) (xy 409.821906 -31.828744)
			(xy 409.822396 -31.858712) (xy 409.822396 -32.714184) (xy 419.147244 -32.714184) (xy 419.147244 -31.850584)
			(xy 419.147734 -31.8206) (xy 419.155562 -31.761144) (xy 419.171083 -31.703219) (xy 419.194032 -31.647815)
			(xy 419.224016 -31.595881) (xy 419.260522 -31.548305) (xy 419.302927 -31.5059) (xy 419.350503 -31.469394)
			(xy 419.402437 -31.43941) (xy 419.457841 -31.416461) (xy 419.515766 -31.40094) (xy 419.575222 -31.393112)
			(xy 419.63519 -31.393112) (xy 419.694646 -31.40094) (xy 419.752571 -31.416461) (xy 419.807975 -31.43941)
			(xy 419.859909 -31.469394) (xy 419.907485 -31.5059) (xy 419.94989 -31.548305) (xy 419.986396 -31.595881)
			(xy 420.01638 -31.647815) (xy 420.039329 -31.703219) (xy 420.05485 -31.761144) (xy 420.062678 -31.8206)
			(xy 420.063168 -31.850584) (xy 420.063168 -32.714184) (xy 420.063035 -32.722312) (xy 434.906928 -32.722312)
			(xy 434.906928 -31.858712) (xy 434.907418 -31.828744) (xy 434.915241 -31.769322) (xy 434.930754 -31.711429)
			(xy 434.95369 -31.656056) (xy 434.983657 -31.60415) (xy 435.020144 -31.5566) (xy 435.062524 -31.51422)
			(xy 435.110074 -31.477733) (xy 435.16198 -31.447766) (xy 435.217353 -31.42483) (xy 435.275246 -31.409317)
			(xy 435.334668 -31.401494) (xy 435.394604 -31.401494) (xy 435.454026 -31.409317) (xy 435.511919 -31.42483)
			(xy 435.567292 -31.447766) (xy 435.619198 -31.477733) (xy 435.666748 -31.51422) (xy 435.709128 -31.5566)
			(xy 435.745615 -31.60415) (xy 435.775582 -31.656056) (xy 435.798518 -31.711429) (xy 435.814031 -31.769322)
			(xy 435.821854 -31.828744) (xy 435.822344 -31.858712) (xy 435.822344 -32.714184) (xy 445.147192 -32.714184)
			(xy 445.147192 -31.850584) (xy 445.147682 -31.8206) (xy 445.15551 -31.761144) (xy 445.171031 -31.703219)
			(xy 445.19398 -31.647815) (xy 445.223964 -31.595881) (xy 445.26047 -31.548305) (xy 445.302875 -31.5059)
			(xy 445.350451 -31.469394) (xy 445.402385 -31.43941) (xy 445.457789 -31.416461) (xy 445.515714 -31.40094)
			(xy 445.57517 -31.393112) (xy 445.635138 -31.393112) (xy 445.694594 -31.40094) (xy 445.752519 -31.416461)
			(xy 445.807923 -31.43941) (xy 445.859857 -31.469394) (xy 445.907433 -31.5059) (xy 445.949838 -31.548305)
			(xy 445.986344 -31.595881) (xy 446.016328 -31.647815) (xy 446.039277 -31.703219) (xy 446.054798 -31.761144)
			(xy 446.062626 -31.8206) (xy 446.063116 -31.850584) (xy 446.063116 -32.714184) (xy 446.062626 -32.744168)
			(xy 446.054798 -32.803624) (xy 446.039277 -32.861549) (xy 446.016328 -32.916953) (xy 445.986344 -32.968887)
			(xy 445.949838 -33.016463) (xy 445.907433 -33.058868) (xy 445.859857 -33.095374) (xy 445.807923 -33.125358)
			(xy 445.752519 -33.148307) (xy 445.694594 -33.163828) (xy 445.635138 -33.171656) (xy 445.57517 -33.171656)
			(xy 445.515714 -33.163828) (xy 445.457789 -33.148307) (xy 445.402385 -33.125358) (xy 445.350451 -33.095374)
			(xy 445.302875 -33.058868) (xy 445.26047 -33.016463) (xy 445.223964 -32.968887) (xy 445.19398 -32.916953)
			(xy 445.171031 -32.861549) (xy 445.15551 -32.803624) (xy 445.147682 -32.744168) (xy 445.147192 -32.714184)
			(xy 435.822344 -32.714184) (xy 435.822344 -32.722312) (xy 435.821854 -32.75228) (xy 435.814031 -32.811702)
			(xy 435.798518 -32.869595) (xy 435.775582 -32.924968) (xy 435.745615 -32.976874) (xy 435.709128 -33.024424)
			(xy 435.666748 -33.066804) (xy 435.619198 -33.103291) (xy 435.567292 -33.133258) (xy 435.511919 -33.156194)
			(xy 435.454026 -33.171707) (xy 435.394604 -33.17953) (xy 435.334668 -33.17953) (xy 435.275246 -33.171707)
			(xy 435.217353 -33.156194) (xy 435.16198 -33.133258) (xy 435.110074 -33.103291) (xy 435.062524 -33.066804)
			(xy 435.020144 -33.024424) (xy 434.983657 -32.976874) (xy 434.95369 -32.924968) (xy 434.930754 -32.869595)
			(xy 434.915241 -32.811702) (xy 434.907418 -32.75228) (xy 434.906928 -32.722312) (xy 420.063035 -32.722312)
			(xy 420.062678 -32.744168) (xy 420.05485 -32.803624) (xy 420.039329 -32.861549) (xy 420.01638 -32.916953)
			(xy 419.986396 -32.968887) (xy 419.94989 -33.016463) (xy 419.907485 -33.058868) (xy 419.859909 -33.095374)
			(xy 419.807975 -33.125358) (xy 419.752571 -33.148307) (xy 419.694646 -33.163828) (xy 419.63519 -33.171656)
			(xy 419.575222 -33.171656) (xy 419.515766 -33.163828) (xy 419.457841 -33.148307) (xy 419.402437 -33.125358)
			(xy 419.350503 -33.095374) (xy 419.302927 -33.058868) (xy 419.260522 -33.016463) (xy 419.224016 -32.968887)
			(xy 419.194032 -32.916953) (xy 419.171083 -32.861549) (xy 419.155562 -32.803624) (xy 419.147734 -32.744168)
			(xy 419.147244 -32.714184) (xy 409.822396 -32.714184) (xy 409.822396 -32.722312) (xy 409.821906 -32.75228)
			(xy 409.814083 -32.811702) (xy 409.79857 -32.869595) (xy 409.775634 -32.924968) (xy 409.745667 -32.976874)
			(xy 409.70918 -33.024424) (xy 409.6668 -33.066804) (xy 409.61925 -33.103291) (xy 409.567344 -33.133258)
			(xy 409.511971 -33.156194) (xy 409.454078 -33.171707) (xy 409.394656 -33.17953) (xy 409.33472 -33.17953)
			(xy 409.275298 -33.171707) (xy 409.217405 -33.156194) (xy 409.162032 -33.133258) (xy 409.110126 -33.103291)
			(xy 409.062576 -33.066804) (xy 409.020196 -33.024424) (xy 408.983709 -32.976874) (xy 408.953742 -32.924968)
			(xy 408.930806 -32.869595) (xy 408.915293 -32.811702) (xy 408.90747 -32.75228) (xy 408.90698 -32.722312)
			(xy 394.063087 -32.722312) (xy 394.06273 -32.744168) (xy 394.054902 -32.803624) (xy 394.039381 -32.861549)
			(xy 394.016432 -32.916953) (xy 393.986448 -32.968887) (xy 393.949942 -33.016463) (xy 393.907537 -33.058868)
			(xy 393.859961 -33.095374) (xy 393.808027 -33.125358) (xy 393.752623 -33.148307) (xy 393.694698 -33.163828)
			(xy 393.635242 -33.171656) (xy 393.575274 -33.171656) (xy 393.515818 -33.163828) (xy 393.457893 -33.148307)
			(xy 393.402489 -33.125358) (xy 393.350555 -33.095374) (xy 393.302979 -33.058868) (xy 393.260574 -33.016463)
			(xy 393.224068 -32.968887) (xy 393.194084 -32.916953) (xy 393.171135 -32.861549) (xy 393.155614 -32.803624)
			(xy 393.147786 -32.744168) (xy 393.147296 -32.714184) (xy 383.822448 -32.714184) (xy 383.822448 -32.722312)
			(xy 383.821958 -32.75228) (xy 383.814135 -32.811702) (xy 383.798622 -32.869595) (xy 383.775686 -32.924968)
			(xy 383.745719 -32.976874) (xy 383.709232 -33.024424) (xy 383.666852 -33.066804) (xy 383.619302 -33.103291)
			(xy 383.567396 -33.133258) (xy 383.512023 -33.156194) (xy 383.45413 -33.171707) (xy 383.394708 -33.17953)
			(xy 383.334772 -33.17953) (xy 383.27535 -33.171707) (xy 383.217457 -33.156194) (xy 383.162084 -33.133258)
			(xy 383.110178 -33.103291) (xy 383.062628 -33.066804) (xy 383.020248 -33.024424) (xy 382.983761 -32.976874)
			(xy 382.953794 -32.924968) (xy 382.930858 -32.869595) (xy 382.915345 -32.811702) (xy 382.907522 -32.75228)
			(xy 382.907032 -32.722312) (xy 368.063139 -32.722312) (xy 368.062782 -32.744168) (xy 368.054954 -32.803624)
			(xy 368.039433 -32.861549) (xy 368.016484 -32.916953) (xy 367.9865 -32.968887) (xy 367.949994 -33.016463)
			(xy 367.907589 -33.058868) (xy 367.860013 -33.095374) (xy 367.808079 -33.125358) (xy 367.752675 -33.148307)
			(xy 367.69475 -33.163828) (xy 367.635294 -33.171656) (xy 367.575326 -33.171656) (xy 367.51587 -33.163828)
			(xy 367.457945 -33.148307) (xy 367.402541 -33.125358) (xy 367.350607 -33.095374) (xy 367.303031 -33.058868)
			(xy 367.260626 -33.016463) (xy 367.22412 -32.968887) (xy 367.194136 -32.916953) (xy 367.171187 -32.861549)
			(xy 367.155666 -32.803624) (xy 367.147838 -32.744168) (xy 367.147348 -32.714184) (xy 357.8225 -32.714184)
			(xy 357.8225 -32.722312) (xy 357.82201 -32.75228) (xy 357.814187 -32.811702) (xy 357.798674 -32.869595)
			(xy 357.775738 -32.924968) (xy 357.745771 -32.976874) (xy 357.709284 -33.024424) (xy 357.666904 -33.066804)
			(xy 357.619354 -33.103291) (xy 357.567448 -33.133258) (xy 357.512075 -33.156194) (xy 357.454182 -33.171707)
			(xy 357.39476 -33.17953) (xy 357.334824 -33.17953) (xy 357.275402 -33.171707) (xy 357.217509 -33.156194)
			(xy 357.162136 -33.133258) (xy 357.11023 -33.103291) (xy 357.06268 -33.066804) (xy 357.0203 -33.024424)
			(xy 356.983813 -32.976874) (xy 356.953846 -32.924968) (xy 356.93091 -32.869595) (xy 356.915397 -32.811702)
			(xy 356.907574 -32.75228) (xy 356.907084 -32.722312) (xy 329.962631 -32.722312) (xy 329.962274 -32.744152)
			(xy 329.954451 -32.803574) (xy 329.938938 -32.861467) (xy 329.916002 -32.91684) (xy 329.886035 -32.968746)
			(xy 329.849548 -33.016296) (xy 329.807168 -33.058676) (xy 329.759618 -33.095163) (xy 329.707712 -33.12513)
			(xy 329.652339 -33.148066) (xy 329.594446 -33.163579) (xy 329.535024 -33.171402) (xy 329.475088 -33.171402)
			(xy 329.415666 -33.163579) (xy 329.357773 -33.148066) (xy 329.3024 -33.12513) (xy 329.250494 -33.095163)
			(xy 329.202944 -33.058676) (xy 329.160564 -33.016296) (xy 329.124077 -32.968746) (xy 329.09411 -32.91684)
			(xy 329.071174 -32.861467) (xy 329.055661 -32.803574) (xy 329.047838 -32.744152) (xy 329.047348 -32.714184)
			(xy 319.7225 -32.714184) (xy 319.7225 -32.722312) (xy 319.72201 -32.752296) (xy 319.714182 -32.811752)
			(xy 319.698661 -32.869677) (xy 319.675712 -32.925081) (xy 319.645728 -32.977015) (xy 319.609222 -33.024591)
			(xy 319.566817 -33.066996) (xy 319.519241 -33.103502) (xy 319.467307 -33.133486) (xy 319.411903 -33.156435)
			(xy 319.353978 -33.171956) (xy 319.294522 -33.179784) (xy 319.234554 -33.179784) (xy 319.175098 -33.171956)
			(xy 319.117173 -33.156435) (xy 319.061769 -33.133486) (xy 319.009835 -33.103502) (xy 318.962259 -33.066996)
			(xy 318.919854 -33.024591) (xy 318.883348 -32.977015) (xy 318.853364 -32.925081) (xy 318.830415 -32.869677)
			(xy 318.814894 -32.811752) (xy 318.807066 -32.752296) (xy 318.806576 -32.722312) (xy 303.962683 -32.722312)
			(xy 303.962326 -32.744152) (xy 303.954503 -32.803574) (xy 303.93899 -32.861467) (xy 303.916054 -32.91684)
			(xy 303.886087 -32.968746) (xy 303.8496 -33.016296) (xy 303.80722 -33.058676) (xy 303.75967 -33.095163)
			(xy 303.707764 -33.12513) (xy 303.652391 -33.148066) (xy 303.594498 -33.163579) (xy 303.535076 -33.171402)
			(xy 303.47514 -33.171402) (xy 303.415718 -33.163579) (xy 303.357825 -33.148066) (xy 303.302452 -33.12513)
			(xy 303.250546 -33.095163) (xy 303.202996 -33.058676) (xy 303.160616 -33.016296) (xy 303.124129 -32.968746)
			(xy 303.094162 -32.91684) (xy 303.071226 -32.861467) (xy 303.055713 -32.803574) (xy 303.04789 -32.744152)
			(xy 303.0474 -32.714184) (xy 293.722552 -32.714184) (xy 293.722552 -32.722312) (xy 293.722062 -32.752296)
			(xy 293.714234 -32.811752) (xy 293.698713 -32.869677) (xy 293.675764 -32.925081) (xy 293.64578 -32.977015)
			(xy 293.609274 -33.024591) (xy 293.566869 -33.066996) (xy 293.519293 -33.103502) (xy 293.467359 -33.133486)
			(xy 293.411955 -33.156435) (xy 293.35403 -33.171956) (xy 293.294574 -33.179784) (xy 293.234606 -33.179784)
			(xy 293.17515 -33.171956) (xy 293.117225 -33.156435) (xy 293.061821 -33.133486) (xy 293.009887 -33.103502)
			(xy 292.962311 -33.066996) (xy 292.919906 -33.024591) (xy 292.8834 -32.977015) (xy 292.853416 -32.925081)
			(xy 292.830467 -32.869677) (xy 292.814946 -32.811752) (xy 292.807118 -32.752296) (xy 292.806628 -32.722312)
			(xy 277.962735 -32.722312) (xy 277.962378 -32.744152) (xy 277.954555 -32.803574) (xy 277.939042 -32.861467)
			(xy 277.916106 -32.91684) (xy 277.886139 -32.968746) (xy 277.849652 -33.016296) (xy 277.807272 -33.058676)
			(xy 277.759722 -33.095163) (xy 277.707816 -33.12513) (xy 277.652443 -33.148066) (xy 277.59455 -33.163579)
			(xy 277.535128 -33.171402) (xy 277.475192 -33.171402) (xy 277.41577 -33.163579) (xy 277.357877 -33.148066)
			(xy 277.302504 -33.12513) (xy 277.250598 -33.095163) (xy 277.203048 -33.058676) (xy 277.160668 -33.016296)
			(xy 277.124181 -32.968746) (xy 277.094214 -32.91684) (xy 277.071278 -32.861467) (xy 277.055765 -32.803574)
			(xy 277.047942 -32.744152) (xy 277.047452 -32.714184) (xy 267.722604 -32.714184) (xy 267.722604 -32.722312)
			(xy 267.722114 -32.752296) (xy 267.714286 -32.811752) (xy 267.698765 -32.869677) (xy 267.675816 -32.925081)
			(xy 267.645832 -32.977015) (xy 267.609326 -33.024591) (xy 267.566921 -33.066996) (xy 267.519345 -33.103502)
			(xy 267.467411 -33.133486) (xy 267.412007 -33.156435) (xy 267.354082 -33.171956) (xy 267.294626 -33.179784)
			(xy 267.234658 -33.179784) (xy 267.175202 -33.171956) (xy 267.117277 -33.156435) (xy 267.061873 -33.133486)
			(xy 267.009939 -33.103502) (xy 266.962363 -33.066996) (xy 266.919958 -33.024591) (xy 266.883452 -32.977015)
			(xy 266.853468 -32.925081) (xy 266.830519 -32.869677) (xy 266.814998 -32.811752) (xy 266.80717 -32.752296)
			(xy 266.80668 -32.722312) (xy 251.962787 -32.722312) (xy 251.96243 -32.744152) (xy 251.954607 -32.803574)
			(xy 251.939094 -32.861467) (xy 251.916158 -32.91684) (xy 251.886191 -32.968746) (xy 251.849704 -33.016296)
			(xy 251.807324 -33.058676) (xy 251.759774 -33.095163) (xy 251.707868 -33.12513) (xy 251.652495 -33.148066)
			(xy 251.594602 -33.163579) (xy 251.53518 -33.171402) (xy 251.475244 -33.171402) (xy 251.415822 -33.163579)
			(xy 251.357929 -33.148066) (xy 251.302556 -33.12513) (xy 251.25065 -33.095163) (xy 251.2031 -33.058676)
			(xy 251.16072 -33.016296) (xy 251.124233 -32.968746) (xy 251.094266 -32.91684) (xy 251.07133 -32.861467)
			(xy 251.055817 -32.803574) (xy 251.047994 -32.744152) (xy 251.047504 -32.714184) (xy 241.722656 -32.714184)
			(xy 241.722656 -32.722312) (xy 241.722166 -32.752296) (xy 241.714338 -32.811752) (xy 241.698817 -32.869677)
			(xy 241.675868 -32.925081) (xy 241.645884 -32.977015) (xy 241.609378 -33.024591) (xy 241.566973 -33.066996)
			(xy 241.519397 -33.103502) (xy 241.467463 -33.133486) (xy 241.412059 -33.156435) (xy 241.354134 -33.171956)
			(xy 241.294678 -33.179784) (xy 241.23471 -33.179784) (xy 241.175254 -33.171956) (xy 241.117329 -33.156435)
			(xy 241.061925 -33.133486) (xy 241.009991 -33.103502) (xy 240.962415 -33.066996) (xy 240.92001 -33.024591)
			(xy 240.883504 -32.977015) (xy 240.85352 -32.925081) (xy 240.830571 -32.869677) (xy 240.81505 -32.811752)
			(xy 240.807222 -32.752296) (xy 240.806732 -32.722312) (xy 213.862787 -32.722312) (xy 213.86243 -32.744152)
			(xy 213.854607 -32.803574) (xy 213.839094 -32.861467) (xy 213.816158 -32.91684) (xy 213.786191 -32.968746)
			(xy 213.749704 -33.016296) (xy 213.707324 -33.058676) (xy 213.659774 -33.095163) (xy 213.607868 -33.12513)
			(xy 213.552495 -33.148066) (xy 213.494602 -33.163579) (xy 213.43518 -33.171402) (xy 213.375244 -33.171402)
			(xy 213.315822 -33.163579) (xy 213.257929 -33.148066) (xy 213.202556 -33.12513) (xy 213.15065 -33.095163)
			(xy 213.1031 -33.058676) (xy 213.06072 -33.016296) (xy 213.024233 -32.968746) (xy 212.994266 -32.91684)
			(xy 212.97133 -32.861467) (xy 212.955817 -32.803574) (xy 212.947994 -32.744152) (xy 212.947504 -32.714184)
			(xy 203.622656 -32.714184) (xy 203.622656 -32.722312) (xy 203.622166 -32.752296) (xy 203.614338 -32.811752)
			(xy 203.598817 -32.869677) (xy 203.575868 -32.925081) (xy 203.545884 -32.977015) (xy 203.509378 -33.024591)
			(xy 203.466973 -33.066996) (xy 203.419397 -33.103502) (xy 203.367463 -33.133486) (xy 203.312059 -33.156435)
			(xy 203.254134 -33.171956) (xy 203.194678 -33.179784) (xy 203.13471 -33.179784) (xy 203.075254 -33.171956)
			(xy 203.017329 -33.156435) (xy 202.961925 -33.133486) (xy 202.909991 -33.103502) (xy 202.862415 -33.066996)
			(xy 202.82001 -33.024591) (xy 202.783504 -32.977015) (xy 202.75352 -32.925081) (xy 202.730571 -32.869677)
			(xy 202.71505 -32.811752) (xy 202.707222 -32.752296) (xy 202.706732 -32.722312) (xy 187.862839 -32.722312)
			(xy 187.862482 -32.744152) (xy 187.854659 -32.803574) (xy 187.839146 -32.861467) (xy 187.81621 -32.91684)
			(xy 187.786243 -32.968746) (xy 187.749756 -33.016296) (xy 187.707376 -33.058676) (xy 187.659826 -33.095163)
			(xy 187.60792 -33.12513) (xy 187.552547 -33.148066) (xy 187.494654 -33.163579) (xy 187.435232 -33.171402)
			(xy 187.375296 -33.171402) (xy 187.315874 -33.163579) (xy 187.257981 -33.148066) (xy 187.202608 -33.12513)
			(xy 187.150702 -33.095163) (xy 187.103152 -33.058676) (xy 187.060772 -33.016296) (xy 187.024285 -32.968746)
			(xy 186.994318 -32.91684) (xy 186.971382 -32.861467) (xy 186.955869 -32.803574) (xy 186.948046 -32.744152)
			(xy 186.947556 -32.714184) (xy 177.622708 -32.714184) (xy 177.622708 -32.722312) (xy 177.622218 -32.752296)
			(xy 177.61439 -32.811752) (xy 177.598869 -32.869677) (xy 177.57592 -32.925081) (xy 177.545936 -32.977015)
			(xy 177.50943 -33.024591) (xy 177.467025 -33.066996) (xy 177.419449 -33.103502) (xy 177.367515 -33.133486)
			(xy 177.312111 -33.156435) (xy 177.254186 -33.171956) (xy 177.19473 -33.179784) (xy 177.134762 -33.179784)
			(xy 177.075306 -33.171956) (xy 177.017381 -33.156435) (xy 176.961977 -33.133486) (xy 176.910043 -33.103502)
			(xy 176.862467 -33.066996) (xy 176.820062 -33.024591) (xy 176.783556 -32.977015) (xy 176.753572 -32.925081)
			(xy 176.730623 -32.869677) (xy 176.715102 -32.811752) (xy 176.707274 -32.752296) (xy 176.706784 -32.722312)
			(xy 161.862891 -32.722312) (xy 161.862534 -32.744152) (xy 161.854711 -32.803574) (xy 161.839198 -32.861467)
			(xy 161.816262 -32.91684) (xy 161.786295 -32.968746) (xy 161.749808 -33.016296) (xy 161.707428 -33.058676)
			(xy 161.659878 -33.095163) (xy 161.607972 -33.12513) (xy 161.552599 -33.148066) (xy 161.494706 -33.163579)
			(xy 161.435284 -33.171402) (xy 161.375348 -33.171402) (xy 161.315926 -33.163579) (xy 161.258033 -33.148066)
			(xy 161.20266 -33.12513) (xy 161.150754 -33.095163) (xy 161.103204 -33.058676) (xy 161.060824 -33.016296)
			(xy 161.024337 -32.968746) (xy 160.99437 -32.91684) (xy 160.971434 -32.861467) (xy 160.955921 -32.803574)
			(xy 160.948098 -32.744152) (xy 160.947608 -32.714184) (xy 151.62276 -32.714184) (xy 151.62276 -32.722312)
			(xy 151.62227 -32.752296) (xy 151.614442 -32.811752) (xy 151.598921 -32.869677) (xy 151.575972 -32.925081)
			(xy 151.545988 -32.977015) (xy 151.509482 -33.024591) (xy 151.467077 -33.066996) (xy 151.419501 -33.103502)
			(xy 151.367567 -33.133486) (xy 151.312163 -33.156435) (xy 151.254238 -33.171956) (xy 151.194782 -33.179784)
			(xy 151.134814 -33.179784) (xy 151.075358 -33.171956) (xy 151.017433 -33.156435) (xy 150.962029 -33.133486)
			(xy 150.910095 -33.103502) (xy 150.862519 -33.066996) (xy 150.820114 -33.024591) (xy 150.783608 -32.977015)
			(xy 150.753624 -32.925081) (xy 150.730675 -32.869677) (xy 150.715154 -32.811752) (xy 150.707326 -32.752296)
			(xy 150.706836 -32.722312) (xy 135.862943 -32.722312) (xy 135.862586 -32.744152) (xy 135.854763 -32.803574)
			(xy 135.83925 -32.861467) (xy 135.816314 -32.91684) (xy 135.786347 -32.968746) (xy 135.74986 -33.016296)
			(xy 135.70748 -33.058676) (xy 135.65993 -33.095163) (xy 135.608024 -33.12513) (xy 135.552651 -33.148066)
			(xy 135.494758 -33.163579) (xy 135.435336 -33.171402) (xy 135.3754 -33.171402) (xy 135.315978 -33.163579)
			(xy 135.258085 -33.148066) (xy 135.202712 -33.12513) (xy 135.150806 -33.095163) (xy 135.103256 -33.058676)
			(xy 135.060876 -33.016296) (xy 135.024389 -32.968746) (xy 134.994422 -32.91684) (xy 134.971486 -32.861467)
			(xy 134.955973 -32.803574) (xy 134.94815 -32.744152) (xy 134.94766 -32.714184) (xy 125.622812 -32.714184)
			(xy 125.622812 -32.722312) (xy 125.622322 -32.752296) (xy 125.614494 -32.811752) (xy 125.598973 -32.869677)
			(xy 125.576024 -32.925081) (xy 125.54604 -32.977015) (xy 125.509534 -33.024591) (xy 125.467129 -33.066996)
			(xy 125.419553 -33.103502) (xy 125.367619 -33.133486) (xy 125.312215 -33.156435) (xy 125.25429 -33.171956)
			(xy 125.194834 -33.179784) (xy 125.134866 -33.179784) (xy 125.07541 -33.171956) (xy 125.017485 -33.156435)
			(xy 124.962081 -33.133486) (xy 124.910147 -33.103502) (xy 124.862571 -33.066996) (xy 124.820166 -33.024591)
			(xy 124.78366 -32.977015) (xy 124.753676 -32.925081) (xy 124.730727 -32.869677) (xy 124.715206 -32.811752)
			(xy 124.707378 -32.752296) (xy 124.706888 -32.722312) (xy 97.762943 -32.722312) (xy 97.762586 -32.744168)
			(xy 97.754758 -32.803624) (xy 97.739237 -32.861549) (xy 97.716288 -32.916953) (xy 97.686304 -32.968887)
			(xy 97.649798 -33.016463) (xy 97.607393 -33.058868) (xy 97.559817 -33.095374) (xy 97.507883 -33.125358)
			(xy 97.452479 -33.148307) (xy 97.394554 -33.163828) (xy 97.335098 -33.171656) (xy 97.27513 -33.171656)
			(xy 97.215674 -33.163828) (xy 97.157749 -33.148307) (xy 97.102345 -33.125358) (xy 97.050411 -33.095374)
			(xy 97.002835 -33.058868) (xy 96.96043 -33.016463) (xy 96.923924 -32.968887) (xy 96.89394 -32.916953)
			(xy 96.870991 -32.861549) (xy 96.85547 -32.803624) (xy 96.847642 -32.744168) (xy 96.847152 -32.714184)
			(xy 87.522304 -32.714184) (xy 87.522304 -32.722312) (xy 87.521814 -32.75228) (xy 87.513991 -32.811702)
			(xy 87.498478 -32.869595) (xy 87.475542 -32.924968) (xy 87.445575 -32.976874) (xy 87.409088 -33.024424)
			(xy 87.366708 -33.066804) (xy 87.319158 -33.103291) (xy 87.267252 -33.133258) (xy 87.211879 -33.156194)
			(xy 87.153986 -33.171707) (xy 87.094564 -33.17953) (xy 87.034628 -33.17953) (xy 86.975206 -33.171707)
			(xy 86.917313 -33.156194) (xy 86.86194 -33.133258) (xy 86.810034 -33.103291) (xy 86.762484 -33.066804)
			(xy 86.720104 -33.024424) (xy 86.683617 -32.976874) (xy 86.65365 -32.924968) (xy 86.630714 -32.869595)
			(xy 86.615201 -32.811702) (xy 86.607378 -32.75228) (xy 86.606888 -32.722312) (xy 71.762995 -32.722312)
			(xy 71.762638 -32.744168) (xy 71.75481 -32.803624) (xy 71.739289 -32.861549) (xy 71.71634 -32.916953)
			(xy 71.686356 -32.968887) (xy 71.64985 -33.016463) (xy 71.607445 -33.058868) (xy 71.559869 -33.095374)
			(xy 71.507935 -33.125358) (xy 71.452531 -33.148307) (xy 71.394606 -33.163828) (xy 71.33515 -33.171656)
			(xy 71.275182 -33.171656) (xy 71.215726 -33.163828) (xy 71.157801 -33.148307) (xy 71.102397 -33.125358)
			(xy 71.050463 -33.095374) (xy 71.002887 -33.058868) (xy 70.960482 -33.016463) (xy 70.923976 -32.968887)
			(xy 70.893992 -32.916953) (xy 70.871043 -32.861549) (xy 70.855522 -32.803624) (xy 70.847694 -32.744168)
			(xy 70.847204 -32.714184) (xy 61.522356 -32.714184) (xy 61.522356 -32.722312) (xy 61.521866 -32.75228)
			(xy 61.514043 -32.811702) (xy 61.49853 -32.869595) (xy 61.475594 -32.924968) (xy 61.445627 -32.976874)
			(xy 61.40914 -33.024424) (xy 61.36676 -33.066804) (xy 61.31921 -33.103291) (xy 61.267304 -33.133258)
			(xy 61.211931 -33.156194) (xy 61.154038 -33.171707) (xy 61.094616 -33.17953) (xy 61.03468 -33.17953)
			(xy 60.975258 -33.171707) (xy 60.917365 -33.156194) (xy 60.861992 -33.133258) (xy 60.810086 -33.103291)
			(xy 60.762536 -33.066804) (xy 60.720156 -33.024424) (xy 60.683669 -32.976874) (xy 60.653702 -32.924968)
			(xy 60.630766 -32.869595) (xy 60.615253 -32.811702) (xy 60.60743 -32.75228) (xy 60.60694 -32.722312)
			(xy 45.763047 -32.722312) (xy 45.76269 -32.744168) (xy 45.754862 -32.803624) (xy 45.739341 -32.861549)
			(xy 45.716392 -32.916953) (xy 45.686408 -32.968887) (xy 45.649902 -33.016463) (xy 45.607497 -33.058868)
			(xy 45.559921 -33.095374) (xy 45.507987 -33.125358) (xy 45.452583 -33.148307) (xy 45.394658 -33.163828)
			(xy 45.335202 -33.171656) (xy 45.275234 -33.171656) (xy 45.215778 -33.163828) (xy 45.157853 -33.148307)
			(xy 45.102449 -33.125358) (xy 45.050515 -33.095374) (xy 45.002939 -33.058868) (xy 44.960534 -33.016463)
			(xy 44.924028 -32.968887) (xy 44.894044 -32.916953) (xy 44.871095 -32.861549) (xy 44.855574 -32.803624)
			(xy 44.847746 -32.744168) (xy 44.847256 -32.714184) (xy 35.522408 -32.714184) (xy 35.522408 -32.722312)
			(xy 35.521918 -32.75228) (xy 35.514095 -32.811702) (xy 35.498582 -32.869595) (xy 35.475646 -32.924968)
			(xy 35.445679 -32.976874) (xy 35.409192 -33.024424) (xy 35.366812 -33.066804) (xy 35.319262 -33.103291)
			(xy 35.267356 -33.133258) (xy 35.211983 -33.156194) (xy 35.15409 -33.171707) (xy 35.094668 -33.17953)
			(xy 35.034732 -33.17953) (xy 34.97531 -33.171707) (xy 34.917417 -33.156194) (xy 34.862044 -33.133258)
			(xy 34.810138 -33.103291) (xy 34.762588 -33.066804) (xy 34.720208 -33.024424) (xy 34.683721 -32.976874)
			(xy 34.653754 -32.924968) (xy 34.630818 -32.869595) (xy 34.615305 -32.811702) (xy 34.607482 -32.75228)
			(xy 34.606992 -32.722312) (xy 19.763099 -32.722312) (xy 19.762742 -32.744168) (xy 19.754914 -32.803624)
			(xy 19.739393 -32.861549) (xy 19.716444 -32.916953) (xy 19.68646 -32.968887) (xy 19.649954 -33.016463)
			(xy 19.607549 -33.058868) (xy 19.559973 -33.095374) (xy 19.508039 -33.125358) (xy 19.452635 -33.148307)
			(xy 19.39471 -33.163828) (xy 19.335254 -33.171656) (xy 19.275286 -33.171656) (xy 19.21583 -33.163828)
			(xy 19.157905 -33.148307) (xy 19.102501 -33.125358) (xy 19.050567 -33.095374) (xy 19.002991 -33.058868)
			(xy 18.960586 -33.016463) (xy 18.92408 -32.968887) (xy 18.894096 -32.916953) (xy 18.871147 -32.861549)
			(xy 18.855626 -32.803624) (xy 18.847798 -32.744168) (xy 18.847308 -32.714184) (xy 9.52246 -32.714184)
			(xy 9.52246 -32.722312) (xy 9.52197 -32.75228) (xy 9.514147 -32.811702) (xy 9.498634 -32.869595)
			(xy 9.475698 -32.924968) (xy 9.445731 -32.976874) (xy 9.409244 -33.024424) (xy 9.366864 -33.066804)
			(xy 9.319314 -33.103291) (xy 9.267408 -33.133258) (xy 9.212035 -33.156194) (xy 9.154142 -33.171707)
			(xy 9.09472 -33.17953) (xy 9.034784 -33.17953) (xy 8.975362 -33.171707) (xy 8.917469 -33.156194)
			(xy 8.862096 -33.133258) (xy 8.81019 -33.103291) (xy 8.76264 -33.066804) (xy 8.72026 -33.024424)
			(xy 8.683773 -32.976874) (xy 8.653806 -32.924968) (xy 8.63087 -32.869595) (xy 8.615357 -32.811702)
			(xy 8.607534 -32.75228) (xy 8.607044 -32.722312) (xy 0.508 -32.722312) (xy 0.508 -34.52241) (xy 6.752844 -34.52241)
			(xy 6.752844 -33.65881) (xy 6.753334 -33.628842) (xy 6.761157 -33.56942) (xy 6.77667 -33.511527)
			(xy 6.799606 -33.456154) (xy 6.829573 -33.404248) (xy 6.86606 -33.356698) (xy 6.90844 -33.314318)
			(xy 6.95599 -33.277831) (xy 7.007896 -33.247864) (xy 7.063269 -33.224928) (xy 7.121162 -33.209415)
			(xy 7.180584 -33.201592) (xy 7.24052 -33.201592) (xy 7.299942 -33.209415) (xy 7.357835 -33.224928)
			(xy 7.413208 -33.247864) (xy 7.465114 -33.277831) (xy 7.512664 -33.314318) (xy 7.555044 -33.356698)
			(xy 7.591531 -33.404248) (xy 7.621498 -33.456154) (xy 7.644434 -33.511527) (xy 7.659947 -33.56942)
			(xy 7.66777 -33.628842) (xy 7.66826 -33.65881) (xy 7.66826 -34.520886) (xy 21.489416 -34.520886)
			(xy 21.489416 -33.657286) (xy 21.489906 -33.627302) (xy 21.497734 -33.567846) (xy 21.513255 -33.509921)
			(xy 21.536204 -33.454517) (xy 21.566188 -33.402583) (xy 21.602694 -33.355007) (xy 21.645099 -33.312602)
			(xy 21.692675 -33.276096) (xy 21.744609 -33.246112) (xy 21.800013 -33.223163) (xy 21.857938 -33.207642)
			(xy 21.917394 -33.199814) (xy 21.977362 -33.199814) (xy 22.036818 -33.207642) (xy 22.094743 -33.223163)
			(xy 22.150147 -33.246112) (xy 22.202081 -33.276096) (xy 22.249657 -33.312602) (xy 22.292062 -33.355007)
			(xy 22.328568 -33.402583) (xy 22.358552 -33.454517) (xy 22.381501 -33.509921) (xy 22.397022 -33.567846)
			(xy 22.40485 -33.627302) (xy 22.40534 -33.657286) (xy 22.40534 -34.520886) (xy 22.405315 -34.52241)
			(xy 32.752792 -34.52241) (xy 32.752792 -33.65881) (xy 32.753282 -33.628842) (xy 32.761105 -33.56942)
			(xy 32.776618 -33.511527) (xy 32.799554 -33.456154) (xy 32.829521 -33.404248) (xy 32.866008 -33.356698)
			(xy 32.908388 -33.314318) (xy 32.955938 -33.277831) (xy 33.007844 -33.247864) (xy 33.063217 -33.224928)
			(xy 33.12111 -33.209415) (xy 33.180532 -33.201592) (xy 33.240468 -33.201592) (xy 33.29989 -33.209415)
			(xy 33.357783 -33.224928) (xy 33.413156 -33.247864) (xy 33.465062 -33.277831) (xy 33.512612 -33.314318)
			(xy 33.554992 -33.356698) (xy 33.591479 -33.404248) (xy 33.621446 -33.456154) (xy 33.644382 -33.511527)
			(xy 33.659895 -33.56942) (xy 33.667718 -33.628842) (xy 33.668208 -33.65881) (xy 33.668208 -34.520886)
			(xy 47.489364 -34.520886) (xy 47.489364 -33.657286) (xy 47.489854 -33.627302) (xy 47.497682 -33.567846)
			(xy 47.513203 -33.509921) (xy 47.536152 -33.454517) (xy 47.566136 -33.402583) (xy 47.602642 -33.355007)
			(xy 47.645047 -33.312602) (xy 47.692623 -33.276096) (xy 47.744557 -33.246112) (xy 47.799961 -33.223163)
			(xy 47.857886 -33.207642) (xy 47.917342 -33.199814) (xy 47.97731 -33.199814) (xy 48.036766 -33.207642)
			(xy 48.094691 -33.223163) (xy 48.150095 -33.246112) (xy 48.202029 -33.276096) (xy 48.249605 -33.312602)
			(xy 48.29201 -33.355007) (xy 48.328516 -33.402583) (xy 48.3585 -33.454517) (xy 48.381449 -33.509921)
			(xy 48.39697 -33.567846) (xy 48.404798 -33.627302) (xy 48.405288 -33.657286) (xy 48.405288 -34.520886)
			(xy 48.405263 -34.52241) (xy 58.75274 -34.52241) (xy 58.75274 -33.65881) (xy 58.75323 -33.628842)
			(xy 58.761053 -33.56942) (xy 58.776566 -33.511527) (xy 58.799502 -33.456154) (xy 58.829469 -33.404248)
			(xy 58.865956 -33.356698) (xy 58.908336 -33.314318) (xy 58.955886 -33.277831) (xy 59.007792 -33.247864)
			(xy 59.063165 -33.224928) (xy 59.121058 -33.209415) (xy 59.18048 -33.201592) (xy 59.240416 -33.201592)
			(xy 59.299838 -33.209415) (xy 59.357731 -33.224928) (xy 59.413104 -33.247864) (xy 59.46501 -33.277831)
			(xy 59.51256 -33.314318) (xy 59.55494 -33.356698) (xy 59.591427 -33.404248) (xy 59.621394 -33.456154)
			(xy 59.64433 -33.511527) (xy 59.659843 -33.56942) (xy 59.667666 -33.628842) (xy 59.668156 -33.65881)
			(xy 59.668156 -34.520886) (xy 73.489312 -34.520886) (xy 73.489312 -33.657286) (xy 73.489802 -33.627302)
			(xy 73.49763 -33.567846) (xy 73.513151 -33.509921) (xy 73.5361 -33.454517) (xy 73.566084 -33.402583)
			(xy 73.60259 -33.355007) (xy 73.644995 -33.312602) (xy 73.692571 -33.276096) (xy 73.744505 -33.246112)
			(xy 73.799909 -33.223163) (xy 73.857834 -33.207642) (xy 73.91729 -33.199814) (xy 73.977258 -33.199814)
			(xy 74.036714 -33.207642) (xy 74.094639 -33.223163) (xy 74.150043 -33.246112) (xy 74.201977 -33.276096)
			(xy 74.249553 -33.312602) (xy 74.291958 -33.355007) (xy 74.328464 -33.402583) (xy 74.358448 -33.454517)
			(xy 74.381397 -33.509921) (xy 74.396918 -33.567846) (xy 74.404746 -33.627302) (xy 74.405236 -33.657286)
			(xy 74.405236 -34.520886) (xy 74.405211 -34.52241) (xy 84.752688 -34.52241) (xy 84.752688 -33.65881)
			(xy 84.753178 -33.628842) (xy 84.761001 -33.56942) (xy 84.776514 -33.511527) (xy 84.79945 -33.456154)
			(xy 84.829417 -33.404248) (xy 84.865904 -33.356698) (xy 84.908284 -33.314318) (xy 84.955834 -33.277831)
			(xy 85.00774 -33.247864) (xy 85.063113 -33.224928) (xy 85.121006 -33.209415) (xy 85.180428 -33.201592)
			(xy 85.240364 -33.201592) (xy 85.299786 -33.209415) (xy 85.357679 -33.224928) (xy 85.413052 -33.247864)
			(xy 85.464958 -33.277831) (xy 85.512508 -33.314318) (xy 85.554888 -33.356698) (xy 85.591375 -33.404248)
			(xy 85.621342 -33.456154) (xy 85.644278 -33.511527) (xy 85.659791 -33.56942) (xy 85.667614 -33.628842)
			(xy 85.668104 -33.65881) (xy 85.668104 -34.520886) (xy 99.48926 -34.520886) (xy 99.48926 -33.657286)
			(xy 99.48975 -33.627302) (xy 99.497578 -33.567846) (xy 99.513099 -33.509921) (xy 99.536048 -33.454517)
			(xy 99.566032 -33.402583) (xy 99.602538 -33.355007) (xy 99.644943 -33.312602) (xy 99.692519 -33.276096)
			(xy 99.744453 -33.246112) (xy 99.799857 -33.223163) (xy 99.857782 -33.207642) (xy 99.917238 -33.199814)
			(xy 99.977206 -33.199814) (xy 100.036662 -33.207642) (xy 100.094587 -33.223163) (xy 100.149991 -33.246112)
			(xy 100.201925 -33.276096) (xy 100.249501 -33.312602) (xy 100.291906 -33.355007) (xy 100.328412 -33.402583)
			(xy 100.358396 -33.454517) (xy 100.381345 -33.509921) (xy 100.396866 -33.567846) (xy 100.404694 -33.627302)
			(xy 100.405184 -33.657286) (xy 100.405184 -34.520886) (xy 100.405159 -34.52241) (xy 122.852688 -34.52241)
			(xy 122.852688 -33.65881) (xy 122.853178 -33.628826) (xy 122.861006 -33.56937) (xy 122.876527 -33.511445)
			(xy 122.899476 -33.456041) (xy 122.92946 -33.404107) (xy 122.965966 -33.356531) (xy 123.008371 -33.314126)
			(xy 123.055947 -33.27762) (xy 123.107881 -33.247636) (xy 123.163285 -33.224687) (xy 123.22121 -33.209166)
			(xy 123.280666 -33.201338) (xy 123.340634 -33.201338) (xy 123.40009 -33.209166) (xy 123.458015 -33.224687)
			(xy 123.513419 -33.247636) (xy 123.565353 -33.27762) (xy 123.612929 -33.314126) (xy 123.655334 -33.356531)
			(xy 123.69184 -33.404107) (xy 123.721824 -33.456041) (xy 123.744773 -33.511445) (xy 123.760294 -33.56937)
			(xy 123.768122 -33.628826) (xy 123.768612 -33.65881) (xy 123.768612 -34.520886) (xy 137.589768 -34.520886)
			(xy 137.589768 -33.657286) (xy 137.590258 -33.627318) (xy 137.598081 -33.567896) (xy 137.613594 -33.510003)
			(xy 137.63653 -33.45463) (xy 137.666497 -33.402724) (xy 137.702984 -33.355174) (xy 137.745364 -33.312794)
			(xy 137.792914 -33.276307) (xy 137.84482 -33.24634) (xy 137.900193 -33.223404) (xy 137.958086 -33.207891)
			(xy 138.017508 -33.200068) (xy 138.077444 -33.200068) (xy 138.136866 -33.207891) (xy 138.194759 -33.223404)
			(xy 138.250132 -33.24634) (xy 138.302038 -33.276307) (xy 138.349588 -33.312794) (xy 138.391968 -33.355174)
			(xy 138.428455 -33.402724) (xy 138.458422 -33.45463) (xy 138.481358 -33.510003) (xy 138.496871 -33.567896)
			(xy 138.504694 -33.627318) (xy 138.505184 -33.657286) (xy 138.505184 -34.520886) (xy 138.505159 -34.52241)
			(xy 148.852636 -34.52241) (xy 148.852636 -33.65881) (xy 148.853126 -33.628826) (xy 148.860954 -33.56937)
			(xy 148.876475 -33.511445) (xy 148.899424 -33.456041) (xy 148.929408 -33.404107) (xy 148.965914 -33.356531)
			(xy 149.008319 -33.314126) (xy 149.055895 -33.27762) (xy 149.107829 -33.247636) (xy 149.163233 -33.224687)
			(xy 149.221158 -33.209166) (xy 149.280614 -33.201338) (xy 149.340582 -33.201338) (xy 149.400038 -33.209166)
			(xy 149.457963 -33.224687) (xy 149.513367 -33.247636) (xy 149.565301 -33.27762) (xy 149.612877 -33.314126)
			(xy 149.655282 -33.356531) (xy 149.691788 -33.404107) (xy 149.721772 -33.456041) (xy 149.744721 -33.511445)
			(xy 149.760242 -33.56937) (xy 149.76807 -33.628826) (xy 149.76856 -33.65881) (xy 149.76856 -34.520886)
			(xy 163.589716 -34.520886) (xy 163.589716 -33.657286) (xy 163.590206 -33.627318) (xy 163.598029 -33.567896)
			(xy 163.613542 -33.510003) (xy 163.636478 -33.45463) (xy 163.666445 -33.402724) (xy 163.702932 -33.355174)
			(xy 163.745312 -33.312794) (xy 163.792862 -33.276307) (xy 163.844768 -33.24634) (xy 163.900141 -33.223404)
			(xy 163.958034 -33.207891) (xy 164.017456 -33.200068) (xy 164.077392 -33.200068) (xy 164.136814 -33.207891)
			(xy 164.194707 -33.223404) (xy 164.25008 -33.24634) (xy 164.301986 -33.276307) (xy 164.349536 -33.312794)
			(xy 164.391916 -33.355174) (xy 164.428403 -33.402724) (xy 164.45837 -33.45463) (xy 164.481306 -33.510003)
			(xy 164.496819 -33.567896) (xy 164.504642 -33.627318) (xy 164.505132 -33.657286) (xy 164.505132 -34.520886)
			(xy 164.505107 -34.52241) (xy 174.852584 -34.52241) (xy 174.852584 -33.65881) (xy 174.853074 -33.628826)
			(xy 174.860902 -33.56937) (xy 174.876423 -33.511445) (xy 174.899372 -33.456041) (xy 174.929356 -33.404107)
			(xy 174.965862 -33.356531) (xy 175.008267 -33.314126) (xy 175.055843 -33.27762) (xy 175.107777 -33.247636)
			(xy 175.163181 -33.224687) (xy 175.221106 -33.209166) (xy 175.280562 -33.201338) (xy 175.34053 -33.201338)
			(xy 175.399986 -33.209166) (xy 175.457911 -33.224687) (xy 175.513315 -33.247636) (xy 175.565249 -33.27762)
			(xy 175.612825 -33.314126) (xy 175.65523 -33.356531) (xy 175.691736 -33.404107) (xy 175.72172 -33.456041)
			(xy 175.744669 -33.511445) (xy 175.76019 -33.56937) (xy 175.768018 -33.628826) (xy 175.768508 -33.65881)
			(xy 175.768508 -34.520886) (xy 189.589664 -34.520886) (xy 189.589664 -33.657286) (xy 189.590154 -33.627318)
			(xy 189.597977 -33.567896) (xy 189.61349 -33.510003) (xy 189.636426 -33.45463) (xy 189.666393 -33.402724)
			(xy 189.70288 -33.355174) (xy 189.74526 -33.312794) (xy 189.79281 -33.276307) (xy 189.844716 -33.24634)
			(xy 189.900089 -33.223404) (xy 189.957982 -33.207891) (xy 190.017404 -33.200068) (xy 190.07734 -33.200068)
			(xy 190.136762 -33.207891) (xy 190.194655 -33.223404) (xy 190.250028 -33.24634) (xy 190.301934 -33.276307)
			(xy 190.349484 -33.312794) (xy 190.391864 -33.355174) (xy 190.428351 -33.402724) (xy 190.458318 -33.45463)
			(xy 190.481254 -33.510003) (xy 190.496767 -33.567896) (xy 190.50459 -33.627318) (xy 190.50508 -33.657286)
			(xy 190.50508 -34.520886) (xy 190.505055 -34.52241) (xy 200.852532 -34.52241) (xy 200.852532 -33.65881)
			(xy 200.853022 -33.628826) (xy 200.86085 -33.56937) (xy 200.876371 -33.511445) (xy 200.89932 -33.456041)
			(xy 200.929304 -33.404107) (xy 200.96581 -33.356531) (xy 201.008215 -33.314126) (xy 201.055791 -33.27762)
			(xy 201.107725 -33.247636) (xy 201.163129 -33.224687) (xy 201.221054 -33.209166) (xy 201.28051 -33.201338)
			(xy 201.340478 -33.201338) (xy 201.399934 -33.209166) (xy 201.457859 -33.224687) (xy 201.513263 -33.247636)
			(xy 201.565197 -33.27762) (xy 201.612773 -33.314126) (xy 201.655178 -33.356531) (xy 201.691684 -33.404107)
			(xy 201.721668 -33.456041) (xy 201.744617 -33.511445) (xy 201.760138 -33.56937) (xy 201.767966 -33.628826)
			(xy 201.768456 -33.65881) (xy 201.768456 -34.520886) (xy 215.589612 -34.520886) (xy 215.589612 -33.657286)
			(xy 215.590102 -33.627318) (xy 215.597925 -33.567896) (xy 215.613438 -33.510003) (xy 215.636374 -33.45463)
			(xy 215.666341 -33.402724) (xy 215.702828 -33.355174) (xy 215.745208 -33.312794) (xy 215.792758 -33.276307)
			(xy 215.844664 -33.24634) (xy 215.900037 -33.223404) (xy 215.95793 -33.207891) (xy 216.017352 -33.200068)
			(xy 216.077288 -33.200068) (xy 216.13671 -33.207891) (xy 216.194603 -33.223404) (xy 216.249976 -33.24634)
			(xy 216.301882 -33.276307) (xy 216.349432 -33.312794) (xy 216.391812 -33.355174) (xy 216.428299 -33.402724)
			(xy 216.458266 -33.45463) (xy 216.481202 -33.510003) (xy 216.496715 -33.567896) (xy 216.504538 -33.627318)
			(xy 216.505028 -33.657286) (xy 216.505028 -34.520886) (xy 216.505003 -34.52241) (xy 238.952532 -34.52241)
			(xy 238.952532 -33.65881) (xy 238.953022 -33.628826) (xy 238.96085 -33.56937) (xy 238.976371 -33.511445)
			(xy 238.99932 -33.456041) (xy 239.029304 -33.404107) (xy 239.06581 -33.356531) (xy 239.108215 -33.314126)
			(xy 239.155791 -33.27762) (xy 239.207725 -33.247636) (xy 239.263129 -33.224687) (xy 239.321054 -33.209166)
			(xy 239.38051 -33.201338) (xy 239.440478 -33.201338) (xy 239.499934 -33.209166) (xy 239.557859 -33.224687)
			(xy 239.613263 -33.247636) (xy 239.665197 -33.27762) (xy 239.712773 -33.314126) (xy 239.755178 -33.356531)
			(xy 239.791684 -33.404107) (xy 239.821668 -33.456041) (xy 239.844617 -33.511445) (xy 239.860138 -33.56937)
			(xy 239.867966 -33.628826) (xy 239.868456 -33.65881) (xy 239.868456 -34.520886) (xy 253.689612 -34.520886)
			(xy 253.689612 -33.657286) (xy 253.690102 -33.627318) (xy 253.697925 -33.567896) (xy 253.713438 -33.510003)
			(xy 253.736374 -33.45463) (xy 253.766341 -33.402724) (xy 253.802828 -33.355174) (xy 253.845208 -33.312794)
			(xy 253.892758 -33.276307) (xy 253.944664 -33.24634) (xy 254.000037 -33.223404) (xy 254.05793 -33.207891)
			(xy 254.117352 -33.200068) (xy 254.177288 -33.200068) (xy 254.23671 -33.207891) (xy 254.294603 -33.223404)
			(xy 254.349976 -33.24634) (xy 254.401882 -33.276307) (xy 254.449432 -33.312794) (xy 254.491812 -33.355174)
			(xy 254.528299 -33.402724) (xy 254.558266 -33.45463) (xy 254.581202 -33.510003) (xy 254.596715 -33.567896)
			(xy 254.604538 -33.627318) (xy 254.605028 -33.657286) (xy 254.605028 -34.520886) (xy 254.605003 -34.52241)
			(xy 264.95248 -34.52241) (xy 264.95248 -33.65881) (xy 264.95297 -33.628826) (xy 264.960798 -33.56937)
			(xy 264.976319 -33.511445) (xy 264.999268 -33.456041) (xy 265.029252 -33.404107) (xy 265.065758 -33.356531)
			(xy 265.108163 -33.314126) (xy 265.155739 -33.27762) (xy 265.207673 -33.247636) (xy 265.263077 -33.224687)
			(xy 265.321002 -33.209166) (xy 265.380458 -33.201338) (xy 265.440426 -33.201338) (xy 265.499882 -33.209166)
			(xy 265.557807 -33.224687) (xy 265.613211 -33.247636) (xy 265.665145 -33.27762) (xy 265.712721 -33.314126)
			(xy 265.755126 -33.356531) (xy 265.791632 -33.404107) (xy 265.821616 -33.456041) (xy 265.844565 -33.511445)
			(xy 265.860086 -33.56937) (xy 265.867914 -33.628826) (xy 265.868404 -33.65881) (xy 265.868404 -34.520886)
			(xy 279.68956 -34.520886) (xy 279.68956 -33.657286) (xy 279.69005 -33.627318) (xy 279.697873 -33.567896)
			(xy 279.713386 -33.510003) (xy 279.736322 -33.45463) (xy 279.766289 -33.402724) (xy 279.802776 -33.355174)
			(xy 279.845156 -33.312794) (xy 279.892706 -33.276307) (xy 279.944612 -33.24634) (xy 279.999985 -33.223404)
			(xy 280.057878 -33.207891) (xy 280.1173 -33.200068) (xy 280.177236 -33.200068) (xy 280.236658 -33.207891)
			(xy 280.294551 -33.223404) (xy 280.349924 -33.24634) (xy 280.40183 -33.276307) (xy 280.44938 -33.312794)
			(xy 280.49176 -33.355174) (xy 280.528247 -33.402724) (xy 280.558214 -33.45463) (xy 280.58115 -33.510003)
			(xy 280.596663 -33.567896) (xy 280.604486 -33.627318) (xy 280.604976 -33.657286) (xy 280.604976 -34.520886)
			(xy 280.604951 -34.52241) (xy 290.952428 -34.52241) (xy 290.952428 -33.65881) (xy 290.952918 -33.628826)
			(xy 290.960746 -33.56937) (xy 290.976267 -33.511445) (xy 290.999216 -33.456041) (xy 291.0292 -33.404107)
			(xy 291.065706 -33.356531) (xy 291.108111 -33.314126) (xy 291.155687 -33.27762) (xy 291.207621 -33.247636)
			(xy 291.263025 -33.224687) (xy 291.32095 -33.209166) (xy 291.380406 -33.201338) (xy 291.440374 -33.201338)
			(xy 291.49983 -33.209166) (xy 291.557755 -33.224687) (xy 291.613159 -33.247636) (xy 291.665093 -33.27762)
			(xy 291.712669 -33.314126) (xy 291.755074 -33.356531) (xy 291.79158 -33.404107) (xy 291.821564 -33.456041)
			(xy 291.844513 -33.511445) (xy 291.860034 -33.56937) (xy 291.867862 -33.628826) (xy 291.868352 -33.65881)
			(xy 291.868352 -34.520886) (xy 305.689508 -34.520886) (xy 305.689508 -33.657286) (xy 305.689998 -33.627318)
			(xy 305.697821 -33.567896) (xy 305.713334 -33.510003) (xy 305.73627 -33.45463) (xy 305.766237 -33.402724)
			(xy 305.802724 -33.355174) (xy 305.845104 -33.312794) (xy 305.892654 -33.276307) (xy 305.94456 -33.24634)
			(xy 305.999933 -33.223404) (xy 306.057826 -33.207891) (xy 306.117248 -33.200068) (xy 306.177184 -33.200068)
			(xy 306.236606 -33.207891) (xy 306.294499 -33.223404) (xy 306.349872 -33.24634) (xy 306.401778 -33.276307)
			(xy 306.449328 -33.312794) (xy 306.491708 -33.355174) (xy 306.528195 -33.402724) (xy 306.558162 -33.45463)
			(xy 306.581098 -33.510003) (xy 306.596611 -33.567896) (xy 306.604434 -33.627318) (xy 306.604924 -33.657286)
			(xy 306.604924 -34.520886) (xy 306.604899 -34.52241) (xy 316.952376 -34.52241) (xy 316.952376 -33.65881)
			(xy 316.952866 -33.628826) (xy 316.960694 -33.56937) (xy 316.976215 -33.511445) (xy 316.999164 -33.456041)
			(xy 317.029148 -33.404107) (xy 317.065654 -33.356531) (xy 317.108059 -33.314126) (xy 317.155635 -33.27762)
			(xy 317.207569 -33.247636) (xy 317.262973 -33.224687) (xy 317.320898 -33.209166) (xy 317.380354 -33.201338)
			(xy 317.440322 -33.201338) (xy 317.499778 -33.209166) (xy 317.557703 -33.224687) (xy 317.613107 -33.247636)
			(xy 317.665041 -33.27762) (xy 317.712617 -33.314126) (xy 317.755022 -33.356531) (xy 317.791528 -33.404107)
			(xy 317.821512 -33.456041) (xy 317.844461 -33.511445) (xy 317.859982 -33.56937) (xy 317.86781 -33.628826)
			(xy 317.8683 -33.65881) (xy 317.8683 -34.520886) (xy 331.689456 -34.520886) (xy 331.689456 -33.657286)
			(xy 331.689946 -33.627318) (xy 331.697769 -33.567896) (xy 331.713282 -33.510003) (xy 331.736218 -33.45463)
			(xy 331.766185 -33.402724) (xy 331.802672 -33.355174) (xy 331.845052 -33.312794) (xy 331.892602 -33.276307)
			(xy 331.944508 -33.24634) (xy 331.999881 -33.223404) (xy 332.057774 -33.207891) (xy 332.117196 -33.200068)
			(xy 332.177132 -33.200068) (xy 332.236554 -33.207891) (xy 332.294447 -33.223404) (xy 332.34982 -33.24634)
			(xy 332.401726 -33.276307) (xy 332.449276 -33.312794) (xy 332.491656 -33.355174) (xy 332.528143 -33.402724)
			(xy 332.55811 -33.45463) (xy 332.581046 -33.510003) (xy 332.596559 -33.567896) (xy 332.604382 -33.627318)
			(xy 332.604872 -33.657286) (xy 332.604872 -34.520886) (xy 332.604847 -34.52241) (xy 355.052884 -34.52241)
			(xy 355.052884 -33.65881) (xy 355.053374 -33.628842) (xy 355.061197 -33.56942) (xy 355.07671 -33.511527)
			(xy 355.099646 -33.456154) (xy 355.129613 -33.404248) (xy 355.1661 -33.356698) (xy 355.20848 -33.314318)
			(xy 355.25603 -33.277831) (xy 355.307936 -33.247864) (xy 355.363309 -33.224928) (xy 355.421202 -33.209415)
			(xy 355.480624 -33.201592) (xy 355.54056 -33.201592) (xy 355.599982 -33.209415) (xy 355.657875 -33.224928)
			(xy 355.713248 -33.247864) (xy 355.765154 -33.277831) (xy 355.812704 -33.314318) (xy 355.855084 -33.356698)
			(xy 355.891571 -33.404248) (xy 355.921538 -33.456154) (xy 355.944474 -33.511527) (xy 355.959987 -33.56942)
			(xy 355.96781 -33.628842) (xy 355.9683 -33.65881) (xy 355.9683 -34.520886) (xy 369.789456 -34.520886)
			(xy 369.789456 -33.657286) (xy 369.789946 -33.627302) (xy 369.797774 -33.567846) (xy 369.813295 -33.509921)
			(xy 369.836244 -33.454517) (xy 369.866228 -33.402583) (xy 369.902734 -33.355007) (xy 369.945139 -33.312602)
			(xy 369.992715 -33.276096) (xy 370.044649 -33.246112) (xy 370.100053 -33.223163) (xy 370.157978 -33.207642)
			(xy 370.217434 -33.199814) (xy 370.277402 -33.199814) (xy 370.336858 -33.207642) (xy 370.394783 -33.223163)
			(xy 370.450187 -33.246112) (xy 370.502121 -33.276096) (xy 370.549697 -33.312602) (xy 370.592102 -33.355007)
			(xy 370.628608 -33.402583) (xy 370.658592 -33.454517) (xy 370.681541 -33.509921) (xy 370.697062 -33.567846)
			(xy 370.70489 -33.627302) (xy 370.70538 -33.657286) (xy 370.70538 -34.520886) (xy 370.705355 -34.52241)
			(xy 381.052832 -34.52241) (xy 381.052832 -33.65881) (xy 381.053322 -33.628842) (xy 381.061145 -33.56942)
			(xy 381.076658 -33.511527) (xy 381.099594 -33.456154) (xy 381.129561 -33.404248) (xy 381.166048 -33.356698)
			(xy 381.208428 -33.314318) (xy 381.255978 -33.277831) (xy 381.307884 -33.247864) (xy 381.363257 -33.224928)
			(xy 381.42115 -33.209415) (xy 381.480572 -33.201592) (xy 381.540508 -33.201592) (xy 381.59993 -33.209415)
			(xy 381.657823 -33.224928) (xy 381.713196 -33.247864) (xy 381.765102 -33.277831) (xy 381.812652 -33.314318)
			(xy 381.855032 -33.356698) (xy 381.891519 -33.404248) (xy 381.921486 -33.456154) (xy 381.944422 -33.511527)
			(xy 381.959935 -33.56942) (xy 381.967758 -33.628842) (xy 381.968248 -33.65881) (xy 381.968248 -34.520886)
			(xy 395.789404 -34.520886) (xy 395.789404 -33.657286) (xy 395.789894 -33.627302) (xy 395.797722 -33.567846)
			(xy 395.813243 -33.509921) (xy 395.836192 -33.454517) (xy 395.866176 -33.402583) (xy 395.902682 -33.355007)
			(xy 395.945087 -33.312602) (xy 395.992663 -33.276096) (xy 396.044597 -33.246112) (xy 396.100001 -33.223163)
			(xy 396.157926 -33.207642) (xy 396.217382 -33.199814) (xy 396.27735 -33.199814) (xy 396.336806 -33.207642)
			(xy 396.394731 -33.223163) (xy 396.450135 -33.246112) (xy 396.502069 -33.276096) (xy 396.549645 -33.312602)
			(xy 396.59205 -33.355007) (xy 396.628556 -33.402583) (xy 396.65854 -33.454517) (xy 396.681489 -33.509921)
			(xy 396.69701 -33.567846) (xy 396.704838 -33.627302) (xy 396.705328 -33.657286) (xy 396.705328 -34.520886)
			(xy 396.705303 -34.52241) (xy 407.05278 -34.52241) (xy 407.05278 -33.65881) (xy 407.05327 -33.628842)
			(xy 407.061093 -33.56942) (xy 407.076606 -33.511527) (xy 407.099542 -33.456154) (xy 407.129509 -33.404248)
			(xy 407.165996 -33.356698) (xy 407.208376 -33.314318) (xy 407.255926 -33.277831) (xy 407.307832 -33.247864)
			(xy 407.363205 -33.224928) (xy 407.421098 -33.209415) (xy 407.48052 -33.201592) (xy 407.540456 -33.201592)
			(xy 407.599878 -33.209415) (xy 407.657771 -33.224928) (xy 407.713144 -33.247864) (xy 407.76505 -33.277831)
			(xy 407.8126 -33.314318) (xy 407.85498 -33.356698) (xy 407.891467 -33.404248) (xy 407.921434 -33.456154)
			(xy 407.94437 -33.511527) (xy 407.959883 -33.56942) (xy 407.967706 -33.628842) (xy 407.968196 -33.65881)
			(xy 407.968196 -34.520886) (xy 421.789352 -34.520886) (xy 421.789352 -33.657286) (xy 421.789842 -33.627302)
			(xy 421.79767 -33.567846) (xy 421.813191 -33.509921) (xy 421.83614 -33.454517) (xy 421.866124 -33.402583)
			(xy 421.90263 -33.355007) (xy 421.945035 -33.312602) (xy 421.992611 -33.276096) (xy 422.044545 -33.246112)
			(xy 422.099949 -33.223163) (xy 422.157874 -33.207642) (xy 422.21733 -33.199814) (xy 422.277298 -33.199814)
			(xy 422.336754 -33.207642) (xy 422.394679 -33.223163) (xy 422.450083 -33.246112) (xy 422.502017 -33.276096)
			(xy 422.549593 -33.312602) (xy 422.591998 -33.355007) (xy 422.628504 -33.402583) (xy 422.658488 -33.454517)
			(xy 422.681437 -33.509921) (xy 422.696958 -33.567846) (xy 422.704786 -33.627302) (xy 422.705276 -33.657286)
			(xy 422.705276 -34.520886) (xy 422.705251 -34.52241) (xy 433.052728 -34.52241) (xy 433.052728 -33.65881)
			(xy 433.053218 -33.628842) (xy 433.061041 -33.56942) (xy 433.076554 -33.511527) (xy 433.09949 -33.456154)
			(xy 433.129457 -33.404248) (xy 433.165944 -33.356698) (xy 433.208324 -33.314318) (xy 433.255874 -33.277831)
			(xy 433.30778 -33.247864) (xy 433.363153 -33.224928) (xy 433.421046 -33.209415) (xy 433.480468 -33.201592)
			(xy 433.540404 -33.201592) (xy 433.599826 -33.209415) (xy 433.657719 -33.224928) (xy 433.713092 -33.247864)
			(xy 433.764998 -33.277831) (xy 433.812548 -33.314318) (xy 433.854928 -33.356698) (xy 433.891415 -33.404248)
			(xy 433.921382 -33.456154) (xy 433.944318 -33.511527) (xy 433.959831 -33.56942) (xy 433.967654 -33.628842)
			(xy 433.968144 -33.65881) (xy 433.968144 -34.520886) (xy 447.7893 -34.520886) (xy 447.7893 -33.657286)
			(xy 447.78979 -33.627302) (xy 447.797618 -33.567846) (xy 447.813139 -33.509921) (xy 447.836088 -33.454517)
			(xy 447.866072 -33.402583) (xy 447.902578 -33.355007) (xy 447.944983 -33.312602) (xy 447.992559 -33.276096)
			(xy 448.044493 -33.246112) (xy 448.099897 -33.223163) (xy 448.157822 -33.207642) (xy 448.217278 -33.199814)
			(xy 448.277246 -33.199814) (xy 448.336702 -33.207642) (xy 448.394627 -33.223163) (xy 448.450031 -33.246112)
			(xy 448.501965 -33.276096) (xy 448.549541 -33.312602) (xy 448.591946 -33.355007) (xy 448.628452 -33.402583)
			(xy 448.658436 -33.454517) (xy 448.681385 -33.509921) (xy 448.696906 -33.567846) (xy 448.704734 -33.627302)
			(xy 448.705224 -33.657286) (xy 448.705224 -34.520886) (xy 448.704734 -34.55087) (xy 448.696906 -34.610326)
			(xy 448.681385 -34.668251) (xy 448.658436 -34.723655) (xy 448.628452 -34.775589) (xy 448.591946 -34.823165)
			(xy 448.549541 -34.86557) (xy 448.501965 -34.902076) (xy 448.450031 -34.93206) (xy 448.394627 -34.955009)
			(xy 448.336702 -34.97053) (xy 448.277246 -34.978358) (xy 448.217278 -34.978358) (xy 448.157822 -34.97053)
			(xy 448.099897 -34.955009) (xy 448.044493 -34.93206) (xy 447.992559 -34.902076) (xy 447.944983 -34.86557)
			(xy 447.902578 -34.823165) (xy 447.866072 -34.775589) (xy 447.836088 -34.723655) (xy 447.813139 -34.668251)
			(xy 447.797618 -34.610326) (xy 447.78979 -34.55087) (xy 447.7893 -34.520886) (xy 433.968144 -34.520886)
			(xy 433.968144 -34.52241) (xy 433.967654 -34.552378) (xy 433.959831 -34.6118) (xy 433.944318 -34.669693)
			(xy 433.921382 -34.725066) (xy 433.891415 -34.776972) (xy 433.854928 -34.824522) (xy 433.812548 -34.866902)
			(xy 433.764998 -34.903389) (xy 433.713092 -34.933356) (xy 433.657719 -34.956292) (xy 433.599826 -34.971805)
			(xy 433.540404 -34.979628) (xy 433.480468 -34.979628) (xy 433.421046 -34.971805) (xy 433.363153 -34.956292)
			(xy 433.30778 -34.933356) (xy 433.255874 -34.903389) (xy 433.208324 -34.866902) (xy 433.165944 -34.824522)
			(xy 433.129457 -34.776972) (xy 433.09949 -34.725066) (xy 433.076554 -34.669693) (xy 433.061041 -34.6118)
			(xy 433.053218 -34.552378) (xy 433.052728 -34.52241) (xy 422.705251 -34.52241) (xy 422.704786 -34.55087)
			(xy 422.696958 -34.610326) (xy 422.681437 -34.668251) (xy 422.658488 -34.723655) (xy 422.628504 -34.775589)
			(xy 422.591998 -34.823165) (xy 422.549593 -34.86557) (xy 422.502017 -34.902076) (xy 422.450083 -34.93206)
			(xy 422.394679 -34.955009) (xy 422.336754 -34.97053) (xy 422.277298 -34.978358) (xy 422.21733 -34.978358)
			(xy 422.157874 -34.97053) (xy 422.099949 -34.955009) (xy 422.044545 -34.93206) (xy 421.992611 -34.902076)
			(xy 421.945035 -34.86557) (xy 421.90263 -34.823165) (xy 421.866124 -34.775589) (xy 421.83614 -34.723655)
			(xy 421.813191 -34.668251) (xy 421.79767 -34.610326) (xy 421.789842 -34.55087) (xy 421.789352 -34.520886)
			(xy 407.968196 -34.520886) (xy 407.968196 -34.52241) (xy 407.967706 -34.552378) (xy 407.959883 -34.6118)
			(xy 407.94437 -34.669693) (xy 407.921434 -34.725066) (xy 407.891467 -34.776972) (xy 407.85498 -34.824522)
			(xy 407.8126 -34.866902) (xy 407.76505 -34.903389) (xy 407.713144 -34.933356) (xy 407.657771 -34.956292)
			(xy 407.599878 -34.971805) (xy 407.540456 -34.979628) (xy 407.48052 -34.979628) (xy 407.421098 -34.971805)
			(xy 407.363205 -34.956292) (xy 407.307832 -34.933356) (xy 407.255926 -34.903389) (xy 407.208376 -34.866902)
			(xy 407.165996 -34.824522) (xy 407.129509 -34.776972) (xy 407.099542 -34.725066) (xy 407.076606 -34.669693)
			(xy 407.061093 -34.6118) (xy 407.05327 -34.552378) (xy 407.05278 -34.52241) (xy 396.705303 -34.52241)
			(xy 396.704838 -34.55087) (xy 396.69701 -34.610326) (xy 396.681489 -34.668251) (xy 396.65854 -34.723655)
			(xy 396.628556 -34.775589) (xy 396.59205 -34.823165) (xy 396.549645 -34.86557) (xy 396.502069 -34.902076)
			(xy 396.450135 -34.93206) (xy 396.394731 -34.955009) (xy 396.336806 -34.97053) (xy 396.27735 -34.978358)
			(xy 396.217382 -34.978358) (xy 396.157926 -34.97053) (xy 396.100001 -34.955009) (xy 396.044597 -34.93206)
			(xy 395.992663 -34.902076) (xy 395.945087 -34.86557) (xy 395.902682 -34.823165) (xy 395.866176 -34.775589)
			(xy 395.836192 -34.723655) (xy 395.813243 -34.668251) (xy 395.797722 -34.610326) (xy 395.789894 -34.55087)
			(xy 395.789404 -34.520886) (xy 381.968248 -34.520886) (xy 381.968248 -34.52241) (xy 381.967758 -34.552378)
			(xy 381.959935 -34.6118) (xy 381.944422 -34.669693) (xy 381.921486 -34.725066) (xy 381.891519 -34.776972)
			(xy 381.855032 -34.824522) (xy 381.812652 -34.866902) (xy 381.765102 -34.903389) (xy 381.713196 -34.933356)
			(xy 381.657823 -34.956292) (xy 381.59993 -34.971805) (xy 381.540508 -34.979628) (xy 381.480572 -34.979628)
			(xy 381.42115 -34.971805) (xy 381.363257 -34.956292) (xy 381.307884 -34.933356) (xy 381.255978 -34.903389)
			(xy 381.208428 -34.866902) (xy 381.166048 -34.824522) (xy 381.129561 -34.776972) (xy 381.099594 -34.725066)
			(xy 381.076658 -34.669693) (xy 381.061145 -34.6118) (xy 381.053322 -34.552378) (xy 381.052832 -34.52241)
			(xy 370.705355 -34.52241) (xy 370.70489 -34.55087) (xy 370.697062 -34.610326) (xy 370.681541 -34.668251)
			(xy 370.658592 -34.723655) (xy 370.628608 -34.775589) (xy 370.592102 -34.823165) (xy 370.549697 -34.86557)
			(xy 370.502121 -34.902076) (xy 370.450187 -34.93206) (xy 370.394783 -34.955009) (xy 370.336858 -34.97053)
			(xy 370.277402 -34.978358) (xy 370.217434 -34.978358) (xy 370.157978 -34.97053) (xy 370.100053 -34.955009)
			(xy 370.044649 -34.93206) (xy 369.992715 -34.902076) (xy 369.945139 -34.86557) (xy 369.902734 -34.823165)
			(xy 369.866228 -34.775589) (xy 369.836244 -34.723655) (xy 369.813295 -34.668251) (xy 369.797774 -34.610326)
			(xy 369.789946 -34.55087) (xy 369.789456 -34.520886) (xy 355.9683 -34.520886) (xy 355.9683 -34.52241)
			(xy 355.96781 -34.552378) (xy 355.959987 -34.6118) (xy 355.944474 -34.669693) (xy 355.921538 -34.725066)
			(xy 355.891571 -34.776972) (xy 355.855084 -34.824522) (xy 355.812704 -34.866902) (xy 355.765154 -34.903389)
			(xy 355.713248 -34.933356) (xy 355.657875 -34.956292) (xy 355.599982 -34.971805) (xy 355.54056 -34.979628)
			(xy 355.480624 -34.979628) (xy 355.421202 -34.971805) (xy 355.363309 -34.956292) (xy 355.307936 -34.933356)
			(xy 355.25603 -34.903389) (xy 355.20848 -34.866902) (xy 355.1661 -34.824522) (xy 355.129613 -34.776972)
			(xy 355.099646 -34.725066) (xy 355.07671 -34.669693) (xy 355.061197 -34.6118) (xy 355.053374 -34.552378)
			(xy 355.052884 -34.52241) (xy 332.604847 -34.52241) (xy 332.604382 -34.550854) (xy 332.596559 -34.610276)
			(xy 332.581046 -34.668169) (xy 332.55811 -34.723542) (xy 332.528143 -34.775448) (xy 332.491656 -34.822998)
			(xy 332.449276 -34.865378) (xy 332.401726 -34.901865) (xy 332.34982 -34.931832) (xy 332.294447 -34.954768)
			(xy 332.236554 -34.970281) (xy 332.177132 -34.978104) (xy 332.117196 -34.978104) (xy 332.057774 -34.970281)
			(xy 331.999881 -34.954768) (xy 331.944508 -34.931832) (xy 331.892602 -34.901865) (xy 331.845052 -34.865378)
			(xy 331.802672 -34.822998) (xy 331.766185 -34.775448) (xy 331.736218 -34.723542) (xy 331.713282 -34.668169)
			(xy 331.697769 -34.610276) (xy 331.689946 -34.550854) (xy 331.689456 -34.520886) (xy 317.8683 -34.520886)
			(xy 317.8683 -34.52241) (xy 317.86781 -34.552394) (xy 317.859982 -34.61185) (xy 317.844461 -34.669775)
			(xy 317.821512 -34.725179) (xy 317.791528 -34.777113) (xy 317.755022 -34.824689) (xy 317.712617 -34.867094)
			(xy 317.665041 -34.9036) (xy 317.613107 -34.933584) (xy 317.557703 -34.956533) (xy 317.499778 -34.972054)
			(xy 317.440322 -34.979882) (xy 317.380354 -34.979882) (xy 317.320898 -34.972054) (xy 317.262973 -34.956533)
			(xy 317.207569 -34.933584) (xy 317.155635 -34.9036) (xy 317.108059 -34.867094) (xy 317.065654 -34.824689)
			(xy 317.029148 -34.777113) (xy 316.999164 -34.725179) (xy 316.976215 -34.669775) (xy 316.960694 -34.61185)
			(xy 316.952866 -34.552394) (xy 316.952376 -34.52241) (xy 306.604899 -34.52241) (xy 306.604434 -34.550854)
			(xy 306.596611 -34.610276) (xy 306.581098 -34.668169) (xy 306.558162 -34.723542) (xy 306.528195 -34.775448)
			(xy 306.491708 -34.822998) (xy 306.449328 -34.865378) (xy 306.401778 -34.901865) (xy 306.349872 -34.931832)
			(xy 306.294499 -34.954768) (xy 306.236606 -34.970281) (xy 306.177184 -34.978104) (xy 306.117248 -34.978104)
			(xy 306.057826 -34.970281) (xy 305.999933 -34.954768) (xy 305.94456 -34.931832) (xy 305.892654 -34.901865)
			(xy 305.845104 -34.865378) (xy 305.802724 -34.822998) (xy 305.766237 -34.775448) (xy 305.73627 -34.723542)
			(xy 305.713334 -34.668169) (xy 305.697821 -34.610276) (xy 305.689998 -34.550854) (xy 305.689508 -34.520886)
			(xy 291.868352 -34.520886) (xy 291.868352 -34.52241) (xy 291.867862 -34.552394) (xy 291.860034 -34.61185)
			(xy 291.844513 -34.669775) (xy 291.821564 -34.725179) (xy 291.79158 -34.777113) (xy 291.755074 -34.824689)
			(xy 291.712669 -34.867094) (xy 291.665093 -34.9036) (xy 291.613159 -34.933584) (xy 291.557755 -34.956533)
			(xy 291.49983 -34.972054) (xy 291.440374 -34.979882) (xy 291.380406 -34.979882) (xy 291.32095 -34.972054)
			(xy 291.263025 -34.956533) (xy 291.207621 -34.933584) (xy 291.155687 -34.9036) (xy 291.108111 -34.867094)
			(xy 291.065706 -34.824689) (xy 291.0292 -34.777113) (xy 290.999216 -34.725179) (xy 290.976267 -34.669775)
			(xy 290.960746 -34.61185) (xy 290.952918 -34.552394) (xy 290.952428 -34.52241) (xy 280.604951 -34.52241)
			(xy 280.604486 -34.550854) (xy 280.596663 -34.610276) (xy 280.58115 -34.668169) (xy 280.558214 -34.723542)
			(xy 280.528247 -34.775448) (xy 280.49176 -34.822998) (xy 280.44938 -34.865378) (xy 280.40183 -34.901865)
			(xy 280.349924 -34.931832) (xy 280.294551 -34.954768) (xy 280.236658 -34.970281) (xy 280.177236 -34.978104)
			(xy 280.1173 -34.978104) (xy 280.057878 -34.970281) (xy 279.999985 -34.954768) (xy 279.944612 -34.931832)
			(xy 279.892706 -34.901865) (xy 279.845156 -34.865378) (xy 279.802776 -34.822998) (xy 279.766289 -34.775448)
			(xy 279.736322 -34.723542) (xy 279.713386 -34.668169) (xy 279.697873 -34.610276) (xy 279.69005 -34.550854)
			(xy 279.68956 -34.520886) (xy 265.868404 -34.520886) (xy 265.868404 -34.52241) (xy 265.867914 -34.552394)
			(xy 265.860086 -34.61185) (xy 265.844565 -34.669775) (xy 265.821616 -34.725179) (xy 265.791632 -34.777113)
			(xy 265.755126 -34.824689) (xy 265.712721 -34.867094) (xy 265.665145 -34.9036) (xy 265.613211 -34.933584)
			(xy 265.557807 -34.956533) (xy 265.499882 -34.972054) (xy 265.440426 -34.979882) (xy 265.380458 -34.979882)
			(xy 265.321002 -34.972054) (xy 265.263077 -34.956533) (xy 265.207673 -34.933584) (xy 265.155739 -34.9036)
			(xy 265.108163 -34.867094) (xy 265.065758 -34.824689) (xy 265.029252 -34.777113) (xy 264.999268 -34.725179)
			(xy 264.976319 -34.669775) (xy 264.960798 -34.61185) (xy 264.95297 -34.552394) (xy 264.95248 -34.52241)
			(xy 254.605003 -34.52241) (xy 254.604538 -34.550854) (xy 254.596715 -34.610276) (xy 254.581202 -34.668169)
			(xy 254.558266 -34.723542) (xy 254.528299 -34.775448) (xy 254.491812 -34.822998) (xy 254.449432 -34.865378)
			(xy 254.401882 -34.901865) (xy 254.349976 -34.931832) (xy 254.294603 -34.954768) (xy 254.23671 -34.970281)
			(xy 254.177288 -34.978104) (xy 254.117352 -34.978104) (xy 254.05793 -34.970281) (xy 254.000037 -34.954768)
			(xy 253.944664 -34.931832) (xy 253.892758 -34.901865) (xy 253.845208 -34.865378) (xy 253.802828 -34.822998)
			(xy 253.766341 -34.775448) (xy 253.736374 -34.723542) (xy 253.713438 -34.668169) (xy 253.697925 -34.610276)
			(xy 253.690102 -34.550854) (xy 253.689612 -34.520886) (xy 239.868456 -34.520886) (xy 239.868456 -34.52241)
			(xy 239.867966 -34.552394) (xy 239.860138 -34.61185) (xy 239.844617 -34.669775) (xy 239.821668 -34.725179)
			(xy 239.791684 -34.777113) (xy 239.755178 -34.824689) (xy 239.712773 -34.867094) (xy 239.665197 -34.9036)
			(xy 239.613263 -34.933584) (xy 239.557859 -34.956533) (xy 239.499934 -34.972054) (xy 239.440478 -34.979882)
			(xy 239.38051 -34.979882) (xy 239.321054 -34.972054) (xy 239.263129 -34.956533) (xy 239.207725 -34.933584)
			(xy 239.155791 -34.9036) (xy 239.108215 -34.867094) (xy 239.06581 -34.824689) (xy 239.029304 -34.777113)
			(xy 238.99932 -34.725179) (xy 238.976371 -34.669775) (xy 238.96085 -34.61185) (xy 238.953022 -34.552394)
			(xy 238.952532 -34.52241) (xy 216.505003 -34.52241) (xy 216.504538 -34.550854) (xy 216.496715 -34.610276)
			(xy 216.481202 -34.668169) (xy 216.458266 -34.723542) (xy 216.428299 -34.775448) (xy 216.391812 -34.822998)
			(xy 216.349432 -34.865378) (xy 216.301882 -34.901865) (xy 216.249976 -34.931832) (xy 216.194603 -34.954768)
			(xy 216.13671 -34.970281) (xy 216.077288 -34.978104) (xy 216.017352 -34.978104) (xy 215.95793 -34.970281)
			(xy 215.900037 -34.954768) (xy 215.844664 -34.931832) (xy 215.792758 -34.901865) (xy 215.745208 -34.865378)
			(xy 215.702828 -34.822998) (xy 215.666341 -34.775448) (xy 215.636374 -34.723542) (xy 215.613438 -34.668169)
			(xy 215.597925 -34.610276) (xy 215.590102 -34.550854) (xy 215.589612 -34.520886) (xy 201.768456 -34.520886)
			(xy 201.768456 -34.52241) (xy 201.767966 -34.552394) (xy 201.760138 -34.61185) (xy 201.744617 -34.669775)
			(xy 201.721668 -34.725179) (xy 201.691684 -34.777113) (xy 201.655178 -34.824689) (xy 201.612773 -34.867094)
			(xy 201.565197 -34.9036) (xy 201.513263 -34.933584) (xy 201.457859 -34.956533) (xy 201.399934 -34.972054)
			(xy 201.340478 -34.979882) (xy 201.28051 -34.979882) (xy 201.221054 -34.972054) (xy 201.163129 -34.956533)
			(xy 201.107725 -34.933584) (xy 201.055791 -34.9036) (xy 201.008215 -34.867094) (xy 200.96581 -34.824689)
			(xy 200.929304 -34.777113) (xy 200.89932 -34.725179) (xy 200.876371 -34.669775) (xy 200.86085 -34.61185)
			(xy 200.853022 -34.552394) (xy 200.852532 -34.52241) (xy 190.505055 -34.52241) (xy 190.50459 -34.550854)
			(xy 190.496767 -34.610276) (xy 190.481254 -34.668169) (xy 190.458318 -34.723542) (xy 190.428351 -34.775448)
			(xy 190.391864 -34.822998) (xy 190.349484 -34.865378) (xy 190.301934 -34.901865) (xy 190.250028 -34.931832)
			(xy 190.194655 -34.954768) (xy 190.136762 -34.970281) (xy 190.07734 -34.978104) (xy 190.017404 -34.978104)
			(xy 189.957982 -34.970281) (xy 189.900089 -34.954768) (xy 189.844716 -34.931832) (xy 189.79281 -34.901865)
			(xy 189.74526 -34.865378) (xy 189.70288 -34.822998) (xy 189.666393 -34.775448) (xy 189.636426 -34.723542)
			(xy 189.61349 -34.668169) (xy 189.597977 -34.610276) (xy 189.590154 -34.550854) (xy 189.589664 -34.520886)
			(xy 175.768508 -34.520886) (xy 175.768508 -34.52241) (xy 175.768018 -34.552394) (xy 175.76019 -34.61185)
			(xy 175.744669 -34.669775) (xy 175.72172 -34.725179) (xy 175.691736 -34.777113) (xy 175.65523 -34.824689)
			(xy 175.612825 -34.867094) (xy 175.565249 -34.9036) (xy 175.513315 -34.933584) (xy 175.457911 -34.956533)
			(xy 175.399986 -34.972054) (xy 175.34053 -34.979882) (xy 175.280562 -34.979882) (xy 175.221106 -34.972054)
			(xy 175.163181 -34.956533) (xy 175.107777 -34.933584) (xy 175.055843 -34.9036) (xy 175.008267 -34.867094)
			(xy 174.965862 -34.824689) (xy 174.929356 -34.777113) (xy 174.899372 -34.725179) (xy 174.876423 -34.669775)
			(xy 174.860902 -34.61185) (xy 174.853074 -34.552394) (xy 174.852584 -34.52241) (xy 164.505107 -34.52241)
			(xy 164.504642 -34.550854) (xy 164.496819 -34.610276) (xy 164.481306 -34.668169) (xy 164.45837 -34.723542)
			(xy 164.428403 -34.775448) (xy 164.391916 -34.822998) (xy 164.349536 -34.865378) (xy 164.301986 -34.901865)
			(xy 164.25008 -34.931832) (xy 164.194707 -34.954768) (xy 164.136814 -34.970281) (xy 164.077392 -34.978104)
			(xy 164.017456 -34.978104) (xy 163.958034 -34.970281) (xy 163.900141 -34.954768) (xy 163.844768 -34.931832)
			(xy 163.792862 -34.901865) (xy 163.745312 -34.865378) (xy 163.702932 -34.822998) (xy 163.666445 -34.775448)
			(xy 163.636478 -34.723542) (xy 163.613542 -34.668169) (xy 163.598029 -34.610276) (xy 163.590206 -34.550854)
			(xy 163.589716 -34.520886) (xy 149.76856 -34.520886) (xy 149.76856 -34.52241) (xy 149.76807 -34.552394)
			(xy 149.760242 -34.61185) (xy 149.744721 -34.669775) (xy 149.721772 -34.725179) (xy 149.691788 -34.777113)
			(xy 149.655282 -34.824689) (xy 149.612877 -34.867094) (xy 149.565301 -34.9036) (xy 149.513367 -34.933584)
			(xy 149.457963 -34.956533) (xy 149.400038 -34.972054) (xy 149.340582 -34.979882) (xy 149.280614 -34.979882)
			(xy 149.221158 -34.972054) (xy 149.163233 -34.956533) (xy 149.107829 -34.933584) (xy 149.055895 -34.9036)
			(xy 149.008319 -34.867094) (xy 148.965914 -34.824689) (xy 148.929408 -34.777113) (xy 148.899424 -34.725179)
			(xy 148.876475 -34.669775) (xy 148.860954 -34.61185) (xy 148.853126 -34.552394) (xy 148.852636 -34.52241)
			(xy 138.505159 -34.52241) (xy 138.504694 -34.550854) (xy 138.496871 -34.610276) (xy 138.481358 -34.668169)
			(xy 138.458422 -34.723542) (xy 138.428455 -34.775448) (xy 138.391968 -34.822998) (xy 138.349588 -34.865378)
			(xy 138.302038 -34.901865) (xy 138.250132 -34.931832) (xy 138.194759 -34.954768) (xy 138.136866 -34.970281)
			(xy 138.077444 -34.978104) (xy 138.017508 -34.978104) (xy 137.958086 -34.970281) (xy 137.900193 -34.954768)
			(xy 137.84482 -34.931832) (xy 137.792914 -34.901865) (xy 137.745364 -34.865378) (xy 137.702984 -34.822998)
			(xy 137.666497 -34.775448) (xy 137.63653 -34.723542) (xy 137.613594 -34.668169) (xy 137.598081 -34.610276)
			(xy 137.590258 -34.550854) (xy 137.589768 -34.520886) (xy 123.768612 -34.520886) (xy 123.768612 -34.52241)
			(xy 123.768122 -34.552394) (xy 123.760294 -34.61185) (xy 123.744773 -34.669775) (xy 123.721824 -34.725179)
			(xy 123.69184 -34.777113) (xy 123.655334 -34.824689) (xy 123.612929 -34.867094) (xy 123.565353 -34.9036)
			(xy 123.513419 -34.933584) (xy 123.458015 -34.956533) (xy 123.40009 -34.972054) (xy 123.340634 -34.979882)
			(xy 123.280666 -34.979882) (xy 123.22121 -34.972054) (xy 123.163285 -34.956533) (xy 123.107881 -34.933584)
			(xy 123.055947 -34.9036) (xy 123.008371 -34.867094) (xy 122.965966 -34.824689) (xy 122.92946 -34.777113)
			(xy 122.899476 -34.725179) (xy 122.876527 -34.669775) (xy 122.861006 -34.61185) (xy 122.853178 -34.552394)
			(xy 122.852688 -34.52241) (xy 100.405159 -34.52241) (xy 100.404694 -34.55087) (xy 100.396866 -34.610326)
			(xy 100.381345 -34.668251) (xy 100.358396 -34.723655) (xy 100.328412 -34.775589) (xy 100.291906 -34.823165)
			(xy 100.249501 -34.86557) (xy 100.201925 -34.902076) (xy 100.149991 -34.93206) (xy 100.094587 -34.955009)
			(xy 100.036662 -34.97053) (xy 99.977206 -34.978358) (xy 99.917238 -34.978358) (xy 99.857782 -34.97053)
			(xy 99.799857 -34.955009) (xy 99.744453 -34.93206) (xy 99.692519 -34.902076) (xy 99.644943 -34.86557)
			(xy 99.602538 -34.823165) (xy 99.566032 -34.775589) (xy 99.536048 -34.723655) (xy 99.513099 -34.668251)
			(xy 99.497578 -34.610326) (xy 99.48975 -34.55087) (xy 99.48926 -34.520886) (xy 85.668104 -34.520886)
			(xy 85.668104 -34.52241) (xy 85.667614 -34.552378) (xy 85.659791 -34.6118) (xy 85.644278 -34.669693)
			(xy 85.621342 -34.725066) (xy 85.591375 -34.776972) (xy 85.554888 -34.824522) (xy 85.512508 -34.866902)
			(xy 85.464958 -34.903389) (xy 85.413052 -34.933356) (xy 85.357679 -34.956292) (xy 85.299786 -34.971805)
			(xy 85.240364 -34.979628) (xy 85.180428 -34.979628) (xy 85.121006 -34.971805) (xy 85.063113 -34.956292)
			(xy 85.00774 -34.933356) (xy 84.955834 -34.903389) (xy 84.908284 -34.866902) (xy 84.865904 -34.824522)
			(xy 84.829417 -34.776972) (xy 84.79945 -34.725066) (xy 84.776514 -34.669693) (xy 84.761001 -34.6118)
			(xy 84.753178 -34.552378) (xy 84.752688 -34.52241) (xy 74.405211 -34.52241) (xy 74.404746 -34.55087)
			(xy 74.396918 -34.610326) (xy 74.381397 -34.668251) (xy 74.358448 -34.723655) (xy 74.328464 -34.775589)
			(xy 74.291958 -34.823165) (xy 74.249553 -34.86557) (xy 74.201977 -34.902076) (xy 74.150043 -34.93206)
			(xy 74.094639 -34.955009) (xy 74.036714 -34.97053) (xy 73.977258 -34.978358) (xy 73.91729 -34.978358)
			(xy 73.857834 -34.97053) (xy 73.799909 -34.955009) (xy 73.744505 -34.93206) (xy 73.692571 -34.902076)
			(xy 73.644995 -34.86557) (xy 73.60259 -34.823165) (xy 73.566084 -34.775589) (xy 73.5361 -34.723655)
			(xy 73.513151 -34.668251) (xy 73.49763 -34.610326) (xy 73.489802 -34.55087) (xy 73.489312 -34.520886)
			(xy 59.668156 -34.520886) (xy 59.668156 -34.52241) (xy 59.667666 -34.552378) (xy 59.659843 -34.6118)
			(xy 59.64433 -34.669693) (xy 59.621394 -34.725066) (xy 59.591427 -34.776972) (xy 59.55494 -34.824522)
			(xy 59.51256 -34.866902) (xy 59.46501 -34.903389) (xy 59.413104 -34.933356) (xy 59.357731 -34.956292)
			(xy 59.299838 -34.971805) (xy 59.240416 -34.979628) (xy 59.18048 -34.979628) (xy 59.121058 -34.971805)
			(xy 59.063165 -34.956292) (xy 59.007792 -34.933356) (xy 58.955886 -34.903389) (xy 58.908336 -34.866902)
			(xy 58.865956 -34.824522) (xy 58.829469 -34.776972) (xy 58.799502 -34.725066) (xy 58.776566 -34.669693)
			(xy 58.761053 -34.6118) (xy 58.75323 -34.552378) (xy 58.75274 -34.52241) (xy 48.405263 -34.52241)
			(xy 48.404798 -34.55087) (xy 48.39697 -34.610326) (xy 48.381449 -34.668251) (xy 48.3585 -34.723655)
			(xy 48.328516 -34.775589) (xy 48.29201 -34.823165) (xy 48.249605 -34.86557) (xy 48.202029 -34.902076)
			(xy 48.150095 -34.93206) (xy 48.094691 -34.955009) (xy 48.036766 -34.97053) (xy 47.97731 -34.978358)
			(xy 47.917342 -34.978358) (xy 47.857886 -34.97053) (xy 47.799961 -34.955009) (xy 47.744557 -34.93206)
			(xy 47.692623 -34.902076) (xy 47.645047 -34.86557) (xy 47.602642 -34.823165) (xy 47.566136 -34.775589)
			(xy 47.536152 -34.723655) (xy 47.513203 -34.668251) (xy 47.497682 -34.610326) (xy 47.489854 -34.55087)
			(xy 47.489364 -34.520886) (xy 33.668208 -34.520886) (xy 33.668208 -34.52241) (xy 33.667718 -34.552378)
			(xy 33.659895 -34.6118) (xy 33.644382 -34.669693) (xy 33.621446 -34.725066) (xy 33.591479 -34.776972)
			(xy 33.554992 -34.824522) (xy 33.512612 -34.866902) (xy 33.465062 -34.903389) (xy 33.413156 -34.933356)
			(xy 33.357783 -34.956292) (xy 33.29989 -34.971805) (xy 33.240468 -34.979628) (xy 33.180532 -34.979628)
			(xy 33.12111 -34.971805) (xy 33.063217 -34.956292) (xy 33.007844 -34.933356) (xy 32.955938 -34.903389)
			(xy 32.908388 -34.866902) (xy 32.866008 -34.824522) (xy 32.829521 -34.776972) (xy 32.799554 -34.725066)
			(xy 32.776618 -34.669693) (xy 32.761105 -34.6118) (xy 32.753282 -34.552378) (xy 32.752792 -34.52241)
			(xy 22.405315 -34.52241) (xy 22.40485 -34.55087) (xy 22.397022 -34.610326) (xy 22.381501 -34.668251)
			(xy 22.358552 -34.723655) (xy 22.328568 -34.775589) (xy 22.292062 -34.823165) (xy 22.249657 -34.86557)
			(xy 22.202081 -34.902076) (xy 22.150147 -34.93206) (xy 22.094743 -34.955009) (xy 22.036818 -34.97053)
			(xy 21.977362 -34.978358) (xy 21.917394 -34.978358) (xy 21.857938 -34.97053) (xy 21.800013 -34.955009)
			(xy 21.744609 -34.93206) (xy 21.692675 -34.902076) (xy 21.645099 -34.86557) (xy 21.602694 -34.823165)
			(xy 21.566188 -34.775589) (xy 21.536204 -34.723655) (xy 21.513255 -34.668251) (xy 21.497734 -34.610326)
			(xy 21.489906 -34.55087) (xy 21.489416 -34.520886) (xy 7.66826 -34.520886) (xy 7.66826 -34.52241)
			(xy 7.66777 -34.552378) (xy 7.659947 -34.6118) (xy 7.644434 -34.669693) (xy 7.621498 -34.725066)
			(xy 7.591531 -34.776972) (xy 7.555044 -34.824522) (xy 7.512664 -34.866902) (xy 7.465114 -34.903389)
			(xy 7.413208 -34.933356) (xy 7.357835 -34.956292) (xy 7.299942 -34.971805) (xy 7.24052 -34.979628)
			(xy 7.180584 -34.979628) (xy 7.121162 -34.971805) (xy 7.063269 -34.956292) (xy 7.007896 -34.933356)
			(xy 6.95599 -34.903389) (xy 6.90844 -34.866902) (xy 6.86606 -34.824522) (xy 6.829573 -34.776972)
			(xy 6.799606 -34.725066) (xy 6.77667 -34.669693) (xy 6.761157 -34.6118) (xy 6.753334 -34.552378)
			(xy 6.752844 -34.52241) (xy 0.508 -34.52241) (xy 0.508 -36.60013) (xy 11.998205 -36.60013) (xy 12.00221 -36.512222)
			(xy 12.014193 -36.425042) (xy 12.034053 -36.339313) (xy 12.061628 -36.255745) (xy 12.096687 -36.175031)
			(xy 12.13894 -36.097839) (xy 12.188038 -36.02481) (xy 12.243574 -35.956548) (xy 12.305086 -35.893618)
			(xy 12.372067 -35.836544) (xy 12.44396 -35.785796) (xy 12.520169 -35.741796) (xy 12.600064 -35.704909)
			(xy 12.682983 -35.67544) (xy 12.768238 -35.653633) (xy 12.855122 -35.639669) (xy 12.942916 -35.633663)
			(xy 13.030893 -35.635667) (xy 13.118323 -35.645662) (xy 13.204482 -35.663566) (xy 13.288656 -35.68923)
			(xy 13.370147 -35.722443) (xy 13.448281 -35.762929) (xy 13.522409 -35.810351) (xy 13.591917 -35.864318)
			(xy 13.656231 -35.924383) (xy 13.714815 -35.990047) (xy 13.767186 -36.060766) (xy 13.812909 -36.135954)
			(xy 13.851606 -36.214989) (xy 13.882955 -36.297215) (xy 13.906697 -36.381951) (xy 13.922635 -36.468495)
			(xy 13.930637 -36.55613) (xy 13.931138 -36.60013) (xy 37.998153 -36.60013) (xy 38.002158 -36.512222)
			(xy 38.014141 -36.425042) (xy 38.034001 -36.339313) (xy 38.061576 -36.255745) (xy 38.096635 -36.175031)
			(xy 38.138888 -36.097839) (xy 38.187986 -36.02481) (xy 38.243522 -35.956548) (xy 38.305034 -35.893618)
			(xy 38.372015 -35.836544) (xy 38.443908 -35.785796) (xy 38.520117 -35.741796) (xy 38.600012 -35.704909)
			(xy 38.682931 -35.67544) (xy 38.768186 -35.653633) (xy 38.85507 -35.639669) (xy 38.942864 -35.633663)
			(xy 39.030841 -35.635667) (xy 39.118271 -35.645662) (xy 39.20443 -35.663566) (xy 39.288604 -35.68923)
			(xy 39.370095 -35.722443) (xy 39.448229 -35.762929) (xy 39.522357 -35.810351) (xy 39.591865 -35.864318)
			(xy 39.656179 -35.924383) (xy 39.714763 -35.990047) (xy 39.767134 -36.060766) (xy 39.812857 -36.135954)
			(xy 39.851554 -36.214989) (xy 39.882903 -36.297215) (xy 39.906645 -36.381951) (xy 39.922583 -36.468495)
			(xy 39.930585 -36.55613) (xy 39.931086 -36.60013) (xy 63.998101 -36.60013) (xy 64.002106 -36.512222)
			(xy 64.014089 -36.425042) (xy 64.033949 -36.339313) (xy 64.061524 -36.255745) (xy 64.096583 -36.175031)
			(xy 64.138836 -36.097839) (xy 64.187934 -36.02481) (xy 64.24347 -35.956548) (xy 64.304982 -35.893618)
			(xy 64.371963 -35.836544) (xy 64.443856 -35.785796) (xy 64.520065 -35.741796) (xy 64.59996 -35.704909)
			(xy 64.682879 -35.67544) (xy 64.768134 -35.653633) (xy 64.855018 -35.639669) (xy 64.942812 -35.633663)
			(xy 65.030789 -35.635667) (xy 65.118219 -35.645662) (xy 65.204378 -35.663566) (xy 65.288552 -35.68923)
			(xy 65.370043 -35.722443) (xy 65.448177 -35.762929) (xy 65.522305 -35.810351) (xy 65.591813 -35.864318)
			(xy 65.656127 -35.924383) (xy 65.714711 -35.990047) (xy 65.767082 -36.060766) (xy 65.812805 -36.135954)
			(xy 65.851502 -36.214989) (xy 65.882851 -36.297215) (xy 65.906593 -36.381951) (xy 65.922531 -36.468495)
			(xy 65.930533 -36.55613) (xy 65.931034 -36.60013) (xy 89.998049 -36.60013) (xy 90.002054 -36.512222)
			(xy 90.014037 -36.425042) (xy 90.033897 -36.339313) (xy 90.061472 -36.255745) (xy 90.096531 -36.175031)
			(xy 90.138784 -36.097839) (xy 90.187882 -36.02481) (xy 90.243418 -35.956548) (xy 90.30493 -35.893618)
			(xy 90.371911 -35.836544) (xy 90.443804 -35.785796) (xy 90.520013 -35.741796) (xy 90.599908 -35.704909)
			(xy 90.682827 -35.67544) (xy 90.768082 -35.653633) (xy 90.854966 -35.639669) (xy 90.94276 -35.633663)
			(xy 91.030737 -35.635667) (xy 91.118167 -35.645662) (xy 91.204326 -35.663566) (xy 91.2885 -35.68923)
			(xy 91.369991 -35.722443) (xy 91.448125 -35.762929) (xy 91.522253 -35.810351) (xy 91.591761 -35.864318)
			(xy 91.656075 -35.924383) (xy 91.714659 -35.990047) (xy 91.76703 -36.060766) (xy 91.812753 -36.135954)
			(xy 91.85145 -36.214989) (xy 91.882799 -36.297215) (xy 91.906541 -36.381951) (xy 91.922479 -36.468495)
			(xy 91.930481 -36.55613) (xy 91.930982 -36.60013) (xy 128.098303 -36.60013) (xy 128.102308 -36.512222)
			(xy 128.114291 -36.425042) (xy 128.134151 -36.339313) (xy 128.161726 -36.255745) (xy 128.196785 -36.175031)
			(xy 128.239038 -36.097839) (xy 128.288136 -36.02481) (xy 128.343672 -35.956548) (xy 128.405184 -35.893618)
			(xy 128.472165 -35.836544) (xy 128.544058 -35.785796) (xy 128.620267 -35.741796) (xy 128.700162 -35.704909)
			(xy 128.783081 -35.67544) (xy 128.868336 -35.653633) (xy 128.95522 -35.639669) (xy 129.043014 -35.633663)
			(xy 129.130991 -35.635667) (xy 129.218421 -35.645662) (xy 129.30458 -35.663566) (xy 129.388754 -35.68923)
			(xy 129.470245 -35.722443) (xy 129.548379 -35.762929) (xy 129.622507 -35.810351) (xy 129.692015 -35.864318)
			(xy 129.756329 -35.924383) (xy 129.814913 -35.990047) (xy 129.867284 -36.060766) (xy 129.913007 -36.135954)
			(xy 129.951704 -36.214989) (xy 129.983053 -36.297215) (xy 130.006795 -36.381951) (xy 130.022733 -36.468495)
			(xy 130.030735 -36.55613) (xy 130.031236 -36.60013) (xy 154.098251 -36.60013) (xy 154.102256 -36.512222)
			(xy 154.114239 -36.425042) (xy 154.134099 -36.339313) (xy 154.161674 -36.255745) (xy 154.196733 -36.175031)
			(xy 154.238986 -36.097839) (xy 154.288084 -36.02481) (xy 154.34362 -35.956548) (xy 154.405132 -35.893618)
			(xy 154.472113 -35.836544) (xy 154.544006 -35.785796) (xy 154.620215 -35.741796) (xy 154.70011 -35.704909)
			(xy 154.783029 -35.67544) (xy 154.868284 -35.653633) (xy 154.955168 -35.639669) (xy 155.042962 -35.633663)
			(xy 155.130939 -35.635667) (xy 155.218369 -35.645662) (xy 155.304528 -35.663566) (xy 155.388702 -35.68923)
			(xy 155.470193 -35.722443) (xy 155.548327 -35.762929) (xy 155.622455 -35.810351) (xy 155.691963 -35.864318)
			(xy 155.756277 -35.924383) (xy 155.814861 -35.990047) (xy 155.867232 -36.060766) (xy 155.912955 -36.135954)
			(xy 155.951652 -36.214989) (xy 155.983001 -36.297215) (xy 156.006743 -36.381951) (xy 156.022681 -36.468495)
			(xy 156.030683 -36.55613) (xy 156.031184 -36.60013) (xy 180.098199 -36.60013) (xy 180.102204 -36.512222)
			(xy 180.114187 -36.425042) (xy 180.134047 -36.339313) (xy 180.161622 -36.255745) (xy 180.196681 -36.175031)
			(xy 180.238934 -36.097839) (xy 180.288032 -36.02481) (xy 180.343568 -35.956548) (xy 180.40508 -35.893618)
			(xy 180.472061 -35.836544) (xy 180.543954 -35.785796) (xy 180.620163 -35.741796) (xy 180.700058 -35.704909)
			(xy 180.782977 -35.67544) (xy 180.868232 -35.653633) (xy 180.955116 -35.639669) (xy 181.04291 -35.633663)
			(xy 181.130887 -35.635667) (xy 181.218317 -35.645662) (xy 181.304476 -35.663566) (xy 181.38865 -35.68923)
			(xy 181.470141 -35.722443) (xy 181.548275 -35.762929) (xy 181.622403 -35.810351) (xy 181.691911 -35.864318)
			(xy 181.756225 -35.924383) (xy 181.814809 -35.990047) (xy 181.86718 -36.060766) (xy 181.912903 -36.135954)
			(xy 181.9516 -36.214989) (xy 181.982949 -36.297215) (xy 182.006691 -36.381951) (xy 182.022629 -36.468495)
			(xy 182.030631 -36.55613) (xy 182.031132 -36.60013) (xy 206.098655 -36.60013) (xy 206.102659 -36.512245)
			(xy 206.114639 -36.425088) (xy 206.134494 -36.339381) (xy 206.162061 -36.255836) (xy 206.197111 -36.175143)
			(xy 206.239353 -36.097971) (xy 206.288438 -36.024961) (xy 206.343959 -35.956717) (xy 206.405456 -35.893804)
			(xy 206.472418 -35.836744) (xy 206.544292 -35.78601) (xy 206.620482 -35.742022) (xy 206.700356 -35.705144)
			(xy 206.783253 -35.675683) (xy 206.868485 -35.653881) (xy 206.955347 -35.639921) (xy 207.043118 -35.633917)
			(xy 207.131072 -35.63592) (xy 207.218479 -35.645912) (xy 207.304615 -35.663812) (xy 207.388767 -35.68947)
			(xy 207.470237 -35.722674) (xy 207.54835 -35.763148) (xy 207.622458 -35.810559) (xy 207.691949 -35.864512)
			(xy 207.756245 -35.92456) (xy 207.814814 -35.990207) (xy 207.867171 -36.060907) (xy 207.912883 -36.136076)
			(xy 207.951569 -36.21509) (xy 207.98291 -36.297295) (xy 208.006645 -36.382009) (xy 208.022579 -36.46853)
			(xy 208.030579 -36.556142) (xy 208.03108 -36.60013) (xy 244.198655 -36.60013) (xy 244.202659 -36.512245)
			(xy 244.214639 -36.425088) (xy 244.234494 -36.339381) (xy 244.262061 -36.255836) (xy 244.297111 -36.175143)
			(xy 244.339353 -36.097971) (xy 244.388438 -36.024961) (xy 244.443959 -35.956717) (xy 244.505456 -35.893804)
			(xy 244.572418 -35.836744) (xy 244.644292 -35.78601) (xy 244.720482 -35.742022) (xy 244.800356 -35.705144)
			(xy 244.883253 -35.675683) (xy 244.968485 -35.653881) (xy 245.055347 -35.639921) (xy 245.143118 -35.633917)
			(xy 245.231072 -35.63592) (xy 245.318479 -35.645912) (xy 245.404615 -35.663812) (xy 245.488767 -35.68947)
			(xy 245.570237 -35.722674) (xy 245.64835 -35.763148) (xy 245.722458 -35.810559) (xy 245.791949 -35.864512)
			(xy 245.856245 -35.92456) (xy 245.914814 -35.990207) (xy 245.967171 -36.060907) (xy 246.012883 -36.136076)
			(xy 246.051569 -36.21509) (xy 246.08291 -36.297295) (xy 246.106645 -36.382009) (xy 246.122579 -36.46853)
			(xy 246.130579 -36.556142) (xy 246.13108 -36.60013) (xy 270.198603 -36.60013) (xy 270.202607 -36.512245)
			(xy 270.214587 -36.425088) (xy 270.234442 -36.339381) (xy 270.262009 -36.255836) (xy 270.297059 -36.175143)
			(xy 270.339301 -36.097971) (xy 270.388386 -36.024961) (xy 270.443907 -35.956717) (xy 270.505404 -35.893804)
			(xy 270.572366 -35.836744) (xy 270.64424 -35.78601) (xy 270.72043 -35.742022) (xy 270.800304 -35.705144)
			(xy 270.883201 -35.675683) (xy 270.968433 -35.653881) (xy 271.055295 -35.639921) (xy 271.143066 -35.633917)
			(xy 271.23102 -35.63592) (xy 271.318427 -35.645912) (xy 271.404563 -35.663812) (xy 271.488715 -35.68947)
			(xy 271.570185 -35.722674) (xy 271.648298 -35.763148) (xy 271.722406 -35.810559) (xy 271.791897 -35.864512)
			(xy 271.856193 -35.92456) (xy 271.914762 -35.990207) (xy 271.967119 -36.060907) (xy 272.012831 -36.136076)
			(xy 272.051517 -36.21509) (xy 272.082858 -36.297295) (xy 272.106593 -36.382009) (xy 272.122527 -36.46853)
			(xy 272.130527 -36.556142) (xy 272.131028 -36.60013) (xy 296.198551 -36.60013) (xy 296.202555 -36.512245)
			(xy 296.214535 -36.425088) (xy 296.23439 -36.339381) (xy 296.261957 -36.255836) (xy 296.297007 -36.175143)
			(xy 296.339249 -36.097971) (xy 296.388334 -36.024961) (xy 296.443855 -35.956717) (xy 296.505352 -35.893804)
			(xy 296.572314 -35.836744) (xy 296.644188 -35.78601) (xy 296.720378 -35.742022) (xy 296.800252 -35.705144)
			(xy 296.883149 -35.675683) (xy 296.968381 -35.653881) (xy 297.055243 -35.639921) (xy 297.143014 -35.633917)
			(xy 297.230968 -35.63592) (xy 297.318375 -35.645912) (xy 297.404511 -35.663812) (xy 297.488663 -35.68947)
			(xy 297.570133 -35.722674) (xy 297.648246 -35.763148) (xy 297.722354 -35.810559) (xy 297.791845 -35.864512)
			(xy 297.856141 -35.92456) (xy 297.91471 -35.990207) (xy 297.967067 -36.060907) (xy 298.012779 -36.136076)
			(xy 298.051465 -36.21509) (xy 298.082806 -36.297295) (xy 298.106541 -36.382009) (xy 298.122475 -36.46853)
			(xy 298.130475 -36.556142) (xy 298.130976 -36.60013) (xy 322.197991 -36.60013) (xy 322.201996 -36.512222)
			(xy 322.213979 -36.425042) (xy 322.233839 -36.339313) (xy 322.261414 -36.255745) (xy 322.296473 -36.175031)
			(xy 322.338726 -36.097839) (xy 322.387824 -36.02481) (xy 322.44336 -35.956548) (xy 322.504872 -35.893618)
			(xy 322.571853 -35.836544) (xy 322.643746 -35.785796) (xy 322.719955 -35.741796) (xy 322.79985 -35.704909)
			(xy 322.882769 -35.67544) (xy 322.968024 -35.653633) (xy 323.054908 -35.639669) (xy 323.142702 -35.633663)
			(xy 323.230679 -35.635667) (xy 323.318109 -35.645662) (xy 323.404268 -35.663566) (xy 323.488442 -35.68923)
			(xy 323.569933 -35.722443) (xy 323.648067 -35.762929) (xy 323.722195 -35.810351) (xy 323.791703 -35.864318)
			(xy 323.856017 -35.924383) (xy 323.914601 -35.990047) (xy 323.966972 -36.060766) (xy 324.012695 -36.135954)
			(xy 324.051392 -36.214989) (xy 324.082741 -36.297215) (xy 324.106483 -36.381951) (xy 324.122421 -36.468495)
			(xy 324.130423 -36.55613) (xy 324.130924 -36.60013) (xy 360.298245 -36.60013) (xy 360.30225 -36.512222)
			(xy 360.314233 -36.425042) (xy 360.334093 -36.339313) (xy 360.361668 -36.255745) (xy 360.396727 -36.175031)
			(xy 360.43898 -36.097839) (xy 360.488078 -36.02481) (xy 360.543614 -35.956548) (xy 360.605126 -35.893618)
			(xy 360.672107 -35.836544) (xy 360.744 -35.785796) (xy 360.820209 -35.741796) (xy 360.900104 -35.704909)
			(xy 360.983023 -35.67544) (xy 361.068278 -35.653633) (xy 361.155162 -35.639669) (xy 361.242956 -35.633663)
			(xy 361.330933 -35.635667) (xy 361.418363 -35.645662) (xy 361.504522 -35.663566) (xy 361.588696 -35.68923)
			(xy 361.670187 -35.722443) (xy 361.748321 -35.762929) (xy 361.822449 -35.810351) (xy 361.891957 -35.864318)
			(xy 361.956271 -35.924383) (xy 362.014855 -35.990047) (xy 362.067226 -36.060766) (xy 362.112949 -36.135954)
			(xy 362.151646 -36.214989) (xy 362.182995 -36.297215) (xy 362.206737 -36.381951) (xy 362.222675 -36.468495)
			(xy 362.230677 -36.55613) (xy 362.231178 -36.60013) (xy 386.298193 -36.60013) (xy 386.302198 -36.512222)
			(xy 386.314181 -36.425042) (xy 386.334041 -36.339313) (xy 386.361616 -36.255745) (xy 386.396675 -36.175031)
			(xy 386.438928 -36.097839) (xy 386.488026 -36.02481) (xy 386.543562 -35.956548) (xy 386.605074 -35.893618)
			(xy 386.672055 -35.836544) (xy 386.743948 -35.785796) (xy 386.820157 -35.741796) (xy 386.900052 -35.704909)
			(xy 386.982971 -35.67544) (xy 387.068226 -35.653633) (xy 387.15511 -35.639669) (xy 387.242904 -35.633663)
			(xy 387.330881 -35.635667) (xy 387.418311 -35.645662) (xy 387.50447 -35.663566) (xy 387.588644 -35.68923)
			(xy 387.670135 -35.722443) (xy 387.748269 -35.762929) (xy 387.822397 -35.810351) (xy 387.891905 -35.864318)
			(xy 387.956219 -35.924383) (xy 388.014803 -35.990047) (xy 388.067174 -36.060766) (xy 388.112897 -36.135954)
			(xy 388.151594 -36.214989) (xy 388.182943 -36.297215) (xy 388.206685 -36.381951) (xy 388.222623 -36.468495)
			(xy 388.230625 -36.55613) (xy 388.231126 -36.60013) (xy 412.298649 -36.60013) (xy 412.302653 -36.512245)
			(xy 412.314633 -36.425088) (xy 412.334488 -36.339381) (xy 412.362055 -36.255836) (xy 412.397105 -36.175143)
			(xy 412.439347 -36.097971) (xy 412.488432 -36.024961) (xy 412.543953 -35.956717) (xy 412.60545 -35.893804)
			(xy 412.672412 -35.836744) (xy 412.744286 -35.78601) (xy 412.820476 -35.742022) (xy 412.90035 -35.705144)
			(xy 412.983247 -35.675683) (xy 413.068479 -35.653881) (xy 413.155341 -35.639921) (xy 413.243112 -35.633917)
			(xy 413.331066 -35.63592) (xy 413.418473 -35.645912) (xy 413.504609 -35.663812) (xy 413.588761 -35.68947)
			(xy 413.670231 -35.722674) (xy 413.748344 -35.763148) (xy 413.822452 -35.810559) (xy 413.891943 -35.864512)
			(xy 413.956239 -35.92456) (xy 414.014808 -35.990207) (xy 414.067165 -36.060907) (xy 414.112877 -36.136076)
			(xy 414.151563 -36.21509) (xy 414.182904 -36.297295) (xy 414.206639 -36.382009) (xy 414.222573 -36.46853)
			(xy 414.230573 -36.556142) (xy 414.231074 -36.60013) (xy 438.298597 -36.60013) (xy 438.302601 -36.512245)
			(xy 438.314581 -36.425088) (xy 438.334436 -36.339381) (xy 438.362003 -36.255836) (xy 438.397053 -36.175143)
			(xy 438.439295 -36.097971) (xy 438.48838 -36.024961) (xy 438.543901 -35.956717) (xy 438.605398 -35.893804)
			(xy 438.67236 -35.836744) (xy 438.744234 -35.78601) (xy 438.820424 -35.742022) (xy 438.900298 -35.705144)
			(xy 438.983195 -35.675683) (xy 439.068427 -35.653881) (xy 439.155289 -35.639921) (xy 439.24306 -35.633917)
			(xy 439.331014 -35.63592) (xy 439.418421 -35.645912) (xy 439.504557 -35.663812) (xy 439.588709 -35.68947)
			(xy 439.670179 -35.722674) (xy 439.748292 -35.763148) (xy 439.8224 -35.810559) (xy 439.891891 -35.864512)
			(xy 439.956187 -35.92456) (xy 440.014756 -35.990207) (xy 440.067113 -36.060907) (xy 440.112825 -36.136076)
			(xy 440.151511 -36.21509) (xy 440.182852 -36.297295) (xy 440.206587 -36.382009) (xy 440.222521 -36.46853)
			(xy 440.230521 -36.556142) (xy 440.231022 -36.60013) (xy 440.230521 -36.644118) (xy 440.222521 -36.73173)
			(xy 440.206587 -36.818251) (xy 440.182852 -36.902965) (xy 440.151511 -36.98517) (xy 440.112825 -37.064184)
			(xy 440.067113 -37.139353) (xy 440.014756 -37.210053) (xy 439.956187 -37.2757) (xy 439.891891 -37.335748)
			(xy 439.8224 -37.389701) (xy 439.748292 -37.437112) (xy 439.670179 -37.477586) (xy 439.588709 -37.51079)
			(xy 439.504557 -37.536448) (xy 439.418421 -37.554348) (xy 439.331014 -37.56434) (xy 439.24306 -37.566343)
			(xy 439.155289 -37.560339) (xy 439.068427 -37.546379) (xy 438.983195 -37.524577) (xy 438.900298 -37.495116)
			(xy 438.820424 -37.458238) (xy 438.744234 -37.41425) (xy 438.67236 -37.363516) (xy 438.605398 -37.306456)
			(xy 438.543901 -37.243543) (xy 438.48838 -37.175299) (xy 438.439295 -37.102289) (xy 438.397053 -37.025117)
			(xy 438.362003 -36.944424) (xy 438.334436 -36.860879) (xy 438.314581 -36.775172) (xy 438.302601 -36.688015)
			(xy 438.298597 -36.60013) (xy 414.231074 -36.60013) (xy 414.230573 -36.644118) (xy 414.222573 -36.73173)
			(xy 414.206639 -36.818251) (xy 414.182904 -36.902965) (xy 414.151563 -36.98517) (xy 414.112877 -37.064184)
			(xy 414.067165 -37.139353) (xy 414.014808 -37.210053) (xy 413.956239 -37.2757) (xy 413.891943 -37.335748)
			(xy 413.822452 -37.389701) (xy 413.748344 -37.437112) (xy 413.670231 -37.477586) (xy 413.588761 -37.51079)
			(xy 413.504609 -37.536448) (xy 413.418473 -37.554348) (xy 413.331066 -37.56434) (xy 413.243112 -37.566343)
			(xy 413.155341 -37.560339) (xy 413.068479 -37.546379) (xy 412.983247 -37.524577) (xy 412.90035 -37.495116)
			(xy 412.820476 -37.458238) (xy 412.744286 -37.41425) (xy 412.672412 -37.363516) (xy 412.60545 -37.306456)
			(xy 412.543953 -37.243543) (xy 412.488432 -37.175299) (xy 412.439347 -37.102289) (xy 412.397105 -37.025117)
			(xy 412.362055 -36.944424) (xy 412.334488 -36.860879) (xy 412.314633 -36.775172) (xy 412.302653 -36.688015)
			(xy 412.298649 -36.60013) (xy 388.231126 -36.60013) (xy 388.230625 -36.64413) (xy 388.222623 -36.731765)
			(xy 388.206685 -36.818309) (xy 388.182943 -36.903045) (xy 388.151594 -36.985271) (xy 388.112897 -37.064306)
			(xy 388.067174 -37.139494) (xy 388.014803 -37.210213) (xy 387.956219 -37.275877) (xy 387.891905 -37.335942)
			(xy 387.822397 -37.389909) (xy 387.748269 -37.437331) (xy 387.670135 -37.477817) (xy 387.588644 -37.51103)
			(xy 387.50447 -37.536694) (xy 387.418311 -37.554598) (xy 387.330881 -37.564593) (xy 387.242904 -37.566597)
			(xy 387.15511 -37.560591) (xy 387.068226 -37.546627) (xy 386.982971 -37.52482) (xy 386.900052 -37.495351)
			(xy 386.820157 -37.458464) (xy 386.743948 -37.414464) (xy 386.672055 -37.363716) (xy 386.605074 -37.306642)
			(xy 386.543562 -37.243712) (xy 386.488026 -37.17545) (xy 386.438928 -37.102421) (xy 386.396675 -37.025229)
			(xy 386.361616 -36.944515) (xy 386.334041 -36.860947) (xy 386.314181 -36.775218) (xy 386.302198 -36.688038)
			(xy 386.298193 -36.60013) (xy 362.231178 -36.60013) (xy 362.230677 -36.64413) (xy 362.222675 -36.731765)
			(xy 362.206737 -36.818309) (xy 362.182995 -36.903045) (xy 362.151646 -36.985271) (xy 362.112949 -37.064306)
			(xy 362.067226 -37.139494) (xy 362.014855 -37.210213) (xy 361.956271 -37.275877) (xy 361.891957 -37.335942)
			(xy 361.822449 -37.389909) (xy 361.748321 -37.437331) (xy 361.670187 -37.477817) (xy 361.588696 -37.51103)
			(xy 361.504522 -37.536694) (xy 361.418363 -37.554598) (xy 361.330933 -37.564593) (xy 361.242956 -37.566597)
			(xy 361.155162 -37.560591) (xy 361.068278 -37.546627) (xy 360.983023 -37.52482) (xy 360.900104 -37.495351)
			(xy 360.820209 -37.458464) (xy 360.744 -37.414464) (xy 360.672107 -37.363716) (xy 360.605126 -37.306642)
			(xy 360.543614 -37.243712) (xy 360.488078 -37.17545) (xy 360.43898 -37.102421) (xy 360.396727 -37.025229)
			(xy 360.361668 -36.944515) (xy 360.334093 -36.860947) (xy 360.314233 -36.775218) (xy 360.30225 -36.688038)
			(xy 360.298245 -36.60013) (xy 324.130924 -36.60013) (xy 324.130423 -36.64413) (xy 324.122421 -36.731765)
			(xy 324.106483 -36.818309) (xy 324.082741 -36.903045) (xy 324.051392 -36.985271) (xy 324.012695 -37.064306)
			(xy 323.966972 -37.139494) (xy 323.914601 -37.210213) (xy 323.856017 -37.275877) (xy 323.791703 -37.335942)
			(xy 323.722195 -37.389909) (xy 323.648067 -37.437331) (xy 323.569933 -37.477817) (xy 323.488442 -37.51103)
			(xy 323.404268 -37.536694) (xy 323.318109 -37.554598) (xy 323.230679 -37.564593) (xy 323.142702 -37.566597)
			(xy 323.054908 -37.560591) (xy 322.968024 -37.546627) (xy 322.882769 -37.52482) (xy 322.79985 -37.495351)
			(xy 322.719955 -37.458464) (xy 322.643746 -37.414464) (xy 322.571853 -37.363716) (xy 322.504872 -37.306642)
			(xy 322.44336 -37.243712) (xy 322.387824 -37.17545) (xy 322.338726 -37.102421) (xy 322.296473 -37.025229)
			(xy 322.261414 -36.944515) (xy 322.233839 -36.860947) (xy 322.213979 -36.775218) (xy 322.201996 -36.688038)
			(xy 322.197991 -36.60013) (xy 298.130976 -36.60013) (xy 298.130475 -36.644118) (xy 298.122475 -36.73173)
			(xy 298.106541 -36.818251) (xy 298.082806 -36.902965) (xy 298.051465 -36.98517) (xy 298.012779 -37.064184)
			(xy 297.967067 -37.139353) (xy 297.91471 -37.210053) (xy 297.856141 -37.2757) (xy 297.791845 -37.335748)
			(xy 297.722354 -37.389701) (xy 297.648246 -37.437112) (xy 297.570133 -37.477586) (xy 297.488663 -37.51079)
			(xy 297.404511 -37.536448) (xy 297.318375 -37.554348) (xy 297.230968 -37.56434) (xy 297.143014 -37.566343)
			(xy 297.055243 -37.560339) (xy 296.968381 -37.546379) (xy 296.883149 -37.524577) (xy 296.800252 -37.495116)
			(xy 296.720378 -37.458238) (xy 296.644188 -37.41425) (xy 296.572314 -37.363516) (xy 296.505352 -37.306456)
			(xy 296.443855 -37.243543) (xy 296.388334 -37.175299) (xy 296.339249 -37.102289) (xy 296.297007 -37.025117)
			(xy 296.261957 -36.944424) (xy 296.23439 -36.860879) (xy 296.214535 -36.775172) (xy 296.202555 -36.688015)
			(xy 296.198551 -36.60013) (xy 272.131028 -36.60013) (xy 272.130527 -36.644118) (xy 272.122527 -36.73173)
			(xy 272.106593 -36.818251) (xy 272.082858 -36.902965) (xy 272.051517 -36.98517) (xy 272.012831 -37.064184)
			(xy 271.967119 -37.139353) (xy 271.914762 -37.210053) (xy 271.856193 -37.2757) (xy 271.791897 -37.335748)
			(xy 271.722406 -37.389701) (xy 271.648298 -37.437112) (xy 271.570185 -37.477586) (xy 271.488715 -37.51079)
			(xy 271.404563 -37.536448) (xy 271.318427 -37.554348) (xy 271.23102 -37.56434) (xy 271.143066 -37.566343)
			(xy 271.055295 -37.560339) (xy 270.968433 -37.546379) (xy 270.883201 -37.524577) (xy 270.800304 -37.495116)
			(xy 270.72043 -37.458238) (xy 270.64424 -37.41425) (xy 270.572366 -37.363516) (xy 270.505404 -37.306456)
			(xy 270.443907 -37.243543) (xy 270.388386 -37.175299) (xy 270.339301 -37.102289) (xy 270.297059 -37.025117)
			(xy 270.262009 -36.944424) (xy 270.234442 -36.860879) (xy 270.214587 -36.775172) (xy 270.202607 -36.688015)
			(xy 270.198603 -36.60013) (xy 246.13108 -36.60013) (xy 246.130579 -36.644118) (xy 246.122579 -36.73173)
			(xy 246.106645 -36.818251) (xy 246.08291 -36.902965) (xy 246.051569 -36.98517) (xy 246.012883 -37.064184)
			(xy 245.967171 -37.139353) (xy 245.914814 -37.210053) (xy 245.856245 -37.2757) (xy 245.791949 -37.335748)
			(xy 245.722458 -37.389701) (xy 245.64835 -37.437112) (xy 245.570237 -37.477586) (xy 245.488767 -37.51079)
			(xy 245.404615 -37.536448) (xy 245.318479 -37.554348) (xy 245.231072 -37.56434) (xy 245.143118 -37.566343)
			(xy 245.055347 -37.560339) (xy 244.968485 -37.546379) (xy 244.883253 -37.524577) (xy 244.800356 -37.495116)
			(xy 244.720482 -37.458238) (xy 244.644292 -37.41425) (xy 244.572418 -37.363516) (xy 244.505456 -37.306456)
			(xy 244.443959 -37.243543) (xy 244.388438 -37.175299) (xy 244.339353 -37.102289) (xy 244.297111 -37.025117)
			(xy 244.262061 -36.944424) (xy 244.234494 -36.860879) (xy 244.214639 -36.775172) (xy 244.202659 -36.688015)
			(xy 244.198655 -36.60013) (xy 208.03108 -36.60013) (xy 208.030579 -36.644118) (xy 208.022579 -36.73173)
			(xy 208.006645 -36.818251) (xy 207.98291 -36.902965) (xy 207.951569 -36.98517) (xy 207.912883 -37.064184)
			(xy 207.867171 -37.139353) (xy 207.814814 -37.210053) (xy 207.756245 -37.2757) (xy 207.691949 -37.335748)
			(xy 207.622458 -37.389701) (xy 207.54835 -37.437112) (xy 207.470237 -37.477586) (xy 207.388767 -37.51079)
			(xy 207.304615 -37.536448) (xy 207.218479 -37.554348) (xy 207.131072 -37.56434) (xy 207.043118 -37.566343)
			(xy 206.955347 -37.560339) (xy 206.868485 -37.546379) (xy 206.783253 -37.524577) (xy 206.700356 -37.495116)
			(xy 206.620482 -37.458238) (xy 206.544292 -37.41425) (xy 206.472418 -37.363516) (xy 206.405456 -37.306456)
			(xy 206.343959 -37.243543) (xy 206.288438 -37.175299) (xy 206.239353 -37.102289) (xy 206.197111 -37.025117)
			(xy 206.162061 -36.944424) (xy 206.134494 -36.860879) (xy 206.114639 -36.775172) (xy 206.102659 -36.688015)
			(xy 206.098655 -36.60013) (xy 182.031132 -36.60013) (xy 182.030631 -36.64413) (xy 182.022629 -36.731765)
			(xy 182.006691 -36.818309) (xy 181.982949 -36.903045) (xy 181.9516 -36.985271) (xy 181.912903 -37.064306)
			(xy 181.86718 -37.139494) (xy 181.814809 -37.210213) (xy 181.756225 -37.275877) (xy 181.691911 -37.335942)
			(xy 181.622403 -37.389909) (xy 181.548275 -37.437331) (xy 181.470141 -37.477817) (xy 181.38865 -37.51103)
			(xy 181.304476 -37.536694) (xy 181.218317 -37.554598) (xy 181.130887 -37.564593) (xy 181.04291 -37.566597)
			(xy 180.955116 -37.560591) (xy 180.868232 -37.546627) (xy 180.782977 -37.52482) (xy 180.700058 -37.495351)
			(xy 180.620163 -37.458464) (xy 180.543954 -37.414464) (xy 180.472061 -37.363716) (xy 180.40508 -37.306642)
			(xy 180.343568 -37.243712) (xy 180.288032 -37.17545) (xy 180.238934 -37.102421) (xy 180.196681 -37.025229)
			(xy 180.161622 -36.944515) (xy 180.134047 -36.860947) (xy 180.114187 -36.775218) (xy 180.102204 -36.688038)
			(xy 180.098199 -36.60013) (xy 156.031184 -36.60013) (xy 156.030683 -36.64413) (xy 156.022681 -36.731765)
			(xy 156.006743 -36.818309) (xy 155.983001 -36.903045) (xy 155.951652 -36.985271) (xy 155.912955 -37.064306)
			(xy 155.867232 -37.139494) (xy 155.814861 -37.210213) (xy 155.756277 -37.275877) (xy 155.691963 -37.335942)
			(xy 155.622455 -37.389909) (xy 155.548327 -37.437331) (xy 155.470193 -37.477817) (xy 155.388702 -37.51103)
			(xy 155.304528 -37.536694) (xy 155.218369 -37.554598) (xy 155.130939 -37.564593) (xy 155.042962 -37.566597)
			(xy 154.955168 -37.560591) (xy 154.868284 -37.546627) (xy 154.783029 -37.52482) (xy 154.70011 -37.495351)
			(xy 154.620215 -37.458464) (xy 154.544006 -37.414464) (xy 154.472113 -37.363716) (xy 154.405132 -37.306642)
			(xy 154.34362 -37.243712) (xy 154.288084 -37.17545) (xy 154.238986 -37.102421) (xy 154.196733 -37.025229)
			(xy 154.161674 -36.944515) (xy 154.134099 -36.860947) (xy 154.114239 -36.775218) (xy 154.102256 -36.688038)
			(xy 154.098251 -36.60013) (xy 130.031236 -36.60013) (xy 130.030735 -36.64413) (xy 130.022733 -36.731765)
			(xy 130.006795 -36.818309) (xy 129.983053 -36.903045) (xy 129.951704 -36.985271) (xy 129.913007 -37.064306)
			(xy 129.867284 -37.139494) (xy 129.814913 -37.210213) (xy 129.756329 -37.275877) (xy 129.692015 -37.335942)
			(xy 129.622507 -37.389909) (xy 129.548379 -37.437331) (xy 129.470245 -37.477817) (xy 129.388754 -37.51103)
			(xy 129.30458 -37.536694) (xy 129.218421 -37.554598) (xy 129.130991 -37.564593) (xy 129.043014 -37.566597)
			(xy 128.95522 -37.560591) (xy 128.868336 -37.546627) (xy 128.783081 -37.52482) (xy 128.700162 -37.495351)
			(xy 128.620267 -37.458464) (xy 128.544058 -37.414464) (xy 128.472165 -37.363716) (xy 128.405184 -37.306642)
			(xy 128.343672 -37.243712) (xy 128.288136 -37.17545) (xy 128.239038 -37.102421) (xy 128.196785 -37.025229)
			(xy 128.161726 -36.944515) (xy 128.134151 -36.860947) (xy 128.114291 -36.775218) (xy 128.102308 -36.688038)
			(xy 128.098303 -36.60013) (xy 91.930982 -36.60013) (xy 91.930481 -36.64413) (xy 91.922479 -36.731765)
			(xy 91.906541 -36.818309) (xy 91.882799 -36.903045) (xy 91.85145 -36.985271) (xy 91.812753 -37.064306)
			(xy 91.76703 -37.139494) (xy 91.714659 -37.210213) (xy 91.656075 -37.275877) (xy 91.591761 -37.335942)
			(xy 91.522253 -37.389909) (xy 91.448125 -37.437331) (xy 91.369991 -37.477817) (xy 91.2885 -37.51103)
			(xy 91.204326 -37.536694) (xy 91.118167 -37.554598) (xy 91.030737 -37.564593) (xy 90.94276 -37.566597)
			(xy 90.854966 -37.560591) (xy 90.768082 -37.546627) (xy 90.682827 -37.52482) (xy 90.599908 -37.495351)
			(xy 90.520013 -37.458464) (xy 90.443804 -37.414464) (xy 90.371911 -37.363716) (xy 90.30493 -37.306642)
			(xy 90.243418 -37.243712) (xy 90.187882 -37.17545) (xy 90.138784 -37.102421) (xy 90.096531 -37.025229)
			(xy 90.061472 -36.944515) (xy 90.033897 -36.860947) (xy 90.014037 -36.775218) (xy 90.002054 -36.688038)
			(xy 89.998049 -36.60013) (xy 65.931034 -36.60013) (xy 65.930533 -36.64413) (xy 65.922531 -36.731765)
			(xy 65.906593 -36.818309) (xy 65.882851 -36.903045) (xy 65.851502 -36.985271) (xy 65.812805 -37.064306)
			(xy 65.767082 -37.139494) (xy 65.714711 -37.210213) (xy 65.656127 -37.275877) (xy 65.591813 -37.335942)
			(xy 65.522305 -37.389909) (xy 65.448177 -37.437331) (xy 65.370043 -37.477817) (xy 65.288552 -37.51103)
			(xy 65.204378 -37.536694) (xy 65.118219 -37.554598) (xy 65.030789 -37.564593) (xy 64.942812 -37.566597)
			(xy 64.855018 -37.560591) (xy 64.768134 -37.546627) (xy 64.682879 -37.52482) (xy 64.59996 -37.495351)
			(xy 64.520065 -37.458464) (xy 64.443856 -37.414464) (xy 64.371963 -37.363716) (xy 64.304982 -37.306642)
			(xy 64.24347 -37.243712) (xy 64.187934 -37.17545) (xy 64.138836 -37.102421) (xy 64.096583 -37.025229)
			(xy 64.061524 -36.944515) (xy 64.033949 -36.860947) (xy 64.014089 -36.775218) (xy 64.002106 -36.688038)
			(xy 63.998101 -36.60013) (xy 39.931086 -36.60013) (xy 39.930585 -36.64413) (xy 39.922583 -36.731765)
			(xy 39.906645 -36.818309) (xy 39.882903 -36.903045) (xy 39.851554 -36.985271) (xy 39.812857 -37.064306)
			(xy 39.767134 -37.139494) (xy 39.714763 -37.210213) (xy 39.656179 -37.275877) (xy 39.591865 -37.335942)
			(xy 39.522357 -37.389909) (xy 39.448229 -37.437331) (xy 39.370095 -37.477817) (xy 39.288604 -37.51103)
			(xy 39.20443 -37.536694) (xy 39.118271 -37.554598) (xy 39.030841 -37.564593) (xy 38.942864 -37.566597)
			(xy 38.85507 -37.560591) (xy 38.768186 -37.546627) (xy 38.682931 -37.52482) (xy 38.600012 -37.495351)
			(xy 38.520117 -37.458464) (xy 38.443908 -37.414464) (xy 38.372015 -37.363716) (xy 38.305034 -37.306642)
			(xy 38.243522 -37.243712) (xy 38.187986 -37.17545) (xy 38.138888 -37.102421) (xy 38.096635 -37.025229)
			(xy 38.061576 -36.944515) (xy 38.034001 -36.860947) (xy 38.014141 -36.775218) (xy 38.002158 -36.688038)
			(xy 37.998153 -36.60013) (xy 13.931138 -36.60013) (xy 13.930637 -36.64413) (xy 13.922635 -36.731765)
			(xy 13.906697 -36.818309) (xy 13.882955 -36.903045) (xy 13.851606 -36.985271) (xy 13.812909 -37.064306)
			(xy 13.767186 -37.139494) (xy 13.714815 -37.210213) (xy 13.656231 -37.275877) (xy 13.591917 -37.335942)
			(xy 13.522409 -37.389909) (xy 13.448281 -37.437331) (xy 13.370147 -37.477817) (xy 13.288656 -37.51103)
			(xy 13.204482 -37.536694) (xy 13.118323 -37.554598) (xy 13.030893 -37.564593) (xy 12.942916 -37.566597)
			(xy 12.855122 -37.560591) (xy 12.768238 -37.546627) (xy 12.682983 -37.52482) (xy 12.600064 -37.495351)
			(xy 12.520169 -37.458464) (xy 12.44396 -37.414464) (xy 12.372067 -37.363716) (xy 12.305086 -37.306642)
			(xy 12.243574 -37.243712) (xy 12.188038 -37.17545) (xy 12.13894 -37.102421) (xy 12.096687 -37.025229)
			(xy 12.061628 -36.944515) (xy 12.034053 -36.860947) (xy 12.014193 -36.775218) (xy 12.00221 -36.688038)
			(xy 11.998205 -36.60013) (xy 0.508 -36.60013) (xy 0.508 -58.698471) (xy 229.808523 -58.698471) (xy 229.808523 -58.601777)
			(xy 229.816508 -58.505414) (xy 229.832424 -58.410039) (xy 229.85616 -58.316305) (xy 229.887557 -58.22485)
			(xy 229.926398 -58.136301) (xy 229.972419 -58.051261) (xy 230.025305 -57.970313) (xy 230.084696 -57.894008)
			(xy 230.150184 -57.822868) (xy 230.221324 -57.75738) (xy 230.297629 -57.697989) (xy 230.378577 -57.645103)
			(xy 230.463617 -57.599082) (xy 230.552166 -57.560241) (xy 230.643621 -57.528844) (xy 230.737355 -57.505108)
			(xy 230.83273 -57.489192) (xy 230.929093 -57.481207) (xy 231.025787 -57.481207) (xy 231.12215 -57.489192)
			(xy 231.217525 -57.505108) (xy 231.311259 -57.528844) (xy 231.402714 -57.560241) (xy 231.491263 -57.599082)
			(xy 231.576303 -57.645103) (xy 231.657251 -57.697989) (xy 231.733556 -57.75738) (xy 231.804696 -57.822868)
			(xy 231.870184 -57.894008) (xy 231.929575 -57.970313) (xy 231.982461 -58.051261) (xy 232.028482 -58.136301)
			(xy 232.067323 -58.22485) (xy 232.09872 -58.316305) (xy 232.122456 -58.410039) (xy 232.138372 -58.505414)
			(xy 232.146357 -58.601777) (xy 232.146856 -58.650124) (xy 232.146357 -58.698471) (xy 232.138372 -58.794834)
			(xy 232.122456 -58.890209) (xy 232.09872 -58.983943) (xy 232.067323 -59.075398) (xy 232.028482 -59.163947)
			(xy 231.982461 -59.248987) (xy 231.929575 -59.329935) (xy 231.870184 -59.40624) (xy 231.804696 -59.47738)
			(xy 231.733556 -59.542868) (xy 231.657251 -59.602259) (xy 231.576303 -59.655145) (xy 231.491263 -59.701166)
			(xy 231.402714 -59.740007) (xy 231.311259 -59.771404) (xy 231.217525 -59.79514) (xy 231.12215 -59.811056)
			(xy 231.025787 -59.819041) (xy 230.929093 -59.819041) (xy 230.83273 -59.811056) (xy 230.737355 -59.79514)
			(xy 230.643621 -59.771404) (xy 230.552166 -59.740007) (xy 230.463617 -59.701166) (xy 230.378577 -59.655145)
			(xy 230.297629 -59.602259) (xy 230.221324 -59.542868) (xy 230.150184 -59.47738) (xy 230.084696 -59.40624)
			(xy 230.025305 -59.329935) (xy 229.972419 -59.248987) (xy 229.926398 -59.163947) (xy 229.887557 -59.075398)
			(xy 229.85616 -58.983943) (xy 229.832424 -58.890209) (xy 229.816508 -58.794834) (xy 229.808523 -58.698471)
			(xy 0.508 -58.698471) (xy 0.508 -60.13196) (xy 226.436428 -60.13196) (xy 226.436428 -59.26836) (xy 226.436918 -59.238392)
			(xy 226.444741 -59.17897) (xy 226.460254 -59.121077) (xy 226.48319 -59.065704) (xy 226.513157 -59.013798)
			(xy 226.549644 -58.966248) (xy 226.592024 -58.923868) (xy 226.639574 -58.887381) (xy 226.69148 -58.857414)
			(xy 226.746853 -58.834478) (xy 226.804746 -58.818965) (xy 226.864168 -58.811142) (xy 226.924104 -58.811142)
			(xy 226.983526 -58.818965) (xy 227.041419 -58.834478) (xy 227.096792 -58.857414) (xy 227.148698 -58.887381)
			(xy 227.196248 -58.923868) (xy 227.238628 -58.966248) (xy 227.275115 -59.013798) (xy 227.305082 -59.065704)
			(xy 227.328018 -59.121077) (xy 227.343531 -59.17897) (xy 227.351354 -59.238392) (xy 227.351844 -59.26836)
			(xy 227.351844 -60.13196) (xy 227.351354 -60.161928) (xy 227.343531 -60.22135) (xy 227.328018 -60.279243)
			(xy 227.305082 -60.334616) (xy 227.275115 -60.386522) (xy 227.238628 -60.434072) (xy 227.196248 -60.476452)
			(xy 227.148698 -60.512939) (xy 227.096792 -60.542906) (xy 227.041419 -60.565842) (xy 226.983526 -60.581355)
			(xy 226.924104 -60.589178) (xy 226.864168 -60.589178) (xy 226.804746 -60.581355) (xy 226.746853 -60.565842)
			(xy 226.69148 -60.542906) (xy 226.639574 -60.512939) (xy 226.592024 -60.476452) (xy 226.549644 -60.434072)
			(xy 226.513157 -60.386522) (xy 226.48319 -60.334616) (xy 226.460254 -60.279243) (xy 226.444741 -60.22135)
			(xy 226.436918 -60.161928) (xy 226.436428 -60.13196) (xy 0.508 -60.13196) (xy 0.508 -69.798271) (xy 229.808523 -69.798271)
			(xy 229.808523 -69.701577) (xy 229.816508 -69.605214) (xy 229.832424 -69.509839) (xy 229.85616 -69.416105)
			(xy 229.887557 -69.32465) (xy 229.926398 -69.236101) (xy 229.972419 -69.151061) (xy 230.025305 -69.070113)
			(xy 230.084696 -68.993808) (xy 230.150184 -68.922668) (xy 230.221324 -68.85718) (xy 230.297629 -68.797789)
			(xy 230.378577 -68.744903) (xy 230.463617 -68.698882) (xy 230.552166 -68.660041) (xy 230.643621 -68.628644)
			(xy 230.737355 -68.604908) (xy 230.83273 -68.588992) (xy 230.929093 -68.581007) (xy 231.025787 -68.581007)
			(xy 231.12215 -68.588992) (xy 231.217525 -68.604908) (xy 231.311259 -68.628644) (xy 231.402714 -68.660041)
			(xy 231.491263 -68.698882) (xy 231.576303 -68.744903) (xy 231.657251 -68.797789) (xy 231.733556 -68.85718)
			(xy 231.804696 -68.922668) (xy 231.870184 -68.993808) (xy 231.929575 -69.070113) (xy 231.982461 -69.151061)
			(xy 232.028482 -69.236101) (xy 232.067323 -69.32465) (xy 232.09872 -69.416105) (xy 232.122456 -69.509839)
			(xy 232.138372 -69.605214) (xy 232.146357 -69.701577) (xy 232.146856 -69.749924) (xy 232.146357 -69.798271)
			(xy 232.138372 -69.894634) (xy 232.122456 -69.990009) (xy 232.09872 -70.083743) (xy 232.067323 -70.175198)
			(xy 232.028482 -70.263747) (xy 231.982461 -70.348787) (xy 231.929575 -70.429735) (xy 231.870184 -70.50604)
			(xy 231.804696 -70.57718) (xy 231.733556 -70.642668) (xy 231.657251 -70.702059) (xy 231.576303 -70.754945)
			(xy 231.491263 -70.800966) (xy 231.402714 -70.839807) (xy 231.311259 -70.871204) (xy 231.217525 -70.89494)
			(xy 231.12215 -70.910856) (xy 231.025787 -70.918841) (xy 230.929093 -70.918841) (xy 230.83273 -70.910856)
			(xy 230.737355 -70.89494) (xy 230.643621 -70.871204) (xy 230.552166 -70.839807) (xy 230.463617 -70.800966)
			(xy 230.378577 -70.754945) (xy 230.297629 -70.702059) (xy 230.221324 -70.642668) (xy 230.150184 -70.57718)
			(xy 230.084696 -70.50604) (xy 230.025305 -70.429735) (xy 229.972419 -70.348787) (xy 229.926398 -70.263747)
			(xy 229.887557 -70.175198) (xy 229.85616 -70.083743) (xy 229.832424 -69.990009) (xy 229.816508 -69.894634)
			(xy 229.808523 -69.798271) (xy 0.508 -69.798271) (xy 0.508 -75.288385) (xy 262.150829 -75.288385)
			(xy 262.150829 -75.228415) (xy 262.158657 -75.168959) (xy 262.174178 -75.111033) (xy 262.197128 -75.055628)
			(xy 262.227114 -75.003693) (xy 262.263621 -74.956116) (xy 262.306027 -74.913712) (xy 262.353605 -74.877206)
			(xy 262.405541 -74.847222) (xy 262.460946 -74.824274) (xy 262.518872 -74.808754) (xy 262.578329 -74.800928)
			(xy 262.608314 -74.80046) (xy 263.471914 -74.80046) (xy 263.501899 -74.800907) (xy 263.561356 -74.808736)
			(xy 263.619283 -74.824259) (xy 263.674687 -74.84721) (xy 263.726623 -74.877196) (xy 263.7742 -74.913705)
			(xy 263.816604 -74.956111) (xy 263.853111 -75.003689) (xy 263.883096 -75.055625) (xy 263.906045 -75.111031)
			(xy 263.921566 -75.168958) (xy 263.929394 -75.228415) (xy 263.929394 -75.288385) (xy 263.921566 -75.347842)
			(xy 263.906045 -75.405769) (xy 263.883096 -75.461175) (xy 263.853111 -75.513111) (xy 263.816604 -75.560689)
			(xy 263.7742 -75.603095) (xy 263.726623 -75.639604) (xy 263.674687 -75.66959) (xy 263.619283 -75.692541)
			(xy 263.561356 -75.708064) (xy 263.501899 -75.715893) (xy 263.471914 -75.716384) (xy 262.608314 -75.716384)
			(xy 262.578329 -75.715872) (xy 262.518872 -75.708046) (xy 262.460946 -75.692526) (xy 262.405541 -75.669578)
			(xy 262.353605 -75.639594) (xy 262.306027 -75.603088) (xy 262.263621 -75.560684) (xy 262.227114 -75.513107)
			(xy 262.197128 -75.461172) (xy 262.174178 -75.405767) (xy 262.158657 -75.347841) (xy 262.150829 -75.288385)
			(xy 0.508 -75.288385) (xy 0.508 -76.826085) (xy 229.640845 -76.826085) (xy 229.640845 -76.766115)
			(xy 229.648673 -76.706658) (xy 229.664196 -76.648731) (xy 229.687147 -76.593327) (xy 229.717134 -76.541392)
			(xy 229.753643 -76.493816) (xy 229.796051 -76.451413) (xy 229.84363 -76.414908) (xy 229.895568 -76.384926)
			(xy 229.950975 -76.361981) (xy 230.008903 -76.346464) (xy 230.068361 -76.338642) (xy 230.098346 -76.338176)
			(xy 230.961946 -76.338176) (xy 230.991931 -76.338593) (xy 231.051387 -76.346426) (xy 231.109312 -76.361952)
			(xy 231.164715 -76.384906) (xy 231.216648 -76.414894) (xy 231.264223 -76.451404) (xy 231.306626 -76.493811)
			(xy 231.343131 -76.54139) (xy 231.373114 -76.593326) (xy 231.396063 -76.648732) (xy 231.411583 -76.706658)
			(xy 231.41941 -76.766115) (xy 231.41941 -76.826085) (xy 231.411583 -76.885542) (xy 231.396063 -76.943468)
			(xy 231.373114 -76.998874) (xy 231.343131 -77.05081) (xy 231.306626 -77.098389) (xy 231.264223 -77.140796)
			(xy 231.216648 -77.177306) (xy 231.164715 -77.207294) (xy 231.109312 -77.230248) (xy 231.051387 -77.245774)
			(xy 230.991931 -77.253607) (xy 230.961946 -77.2541) (xy 230.098346 -77.2541) (xy 230.068361 -77.253558)
			(xy 230.008903 -77.245736) (xy 229.950975 -77.230219) (xy 229.895568 -77.207274) (xy 229.84363 -77.177292)
			(xy 229.796051 -77.140787) (xy 229.753643 -77.098384) (xy 229.717134 -77.050808) (xy 229.687147 -76.998873)
			(xy 229.664196 -76.943469) (xy 229.648673 -76.885542) (xy 229.640845 -76.826085) (xy 0.508 -76.826085)
			(xy 0.508 -77.365367) (xy 105.150162 -77.365367) (xy 105.150162 -77.305433) (xy 105.157985 -77.246011)
			(xy 105.173496 -77.188119) (xy 105.19643 -77.132746) (xy 105.226396 -77.08084) (xy 105.26288 -77.03329)
			(xy 105.305258 -76.990908) (xy 105.352805 -76.954419) (xy 105.404708 -76.924449) (xy 105.460079 -76.901509)
			(xy 105.51797 -76.885993) (xy 105.577391 -76.878165) (xy 105.607358 -76.877672) (xy 106.470958 -76.877672)
			(xy 106.500928 -76.878178) (xy 106.560354 -76.885997) (xy 106.618252 -76.901506) (xy 106.67363 -76.92444)
			(xy 106.72554 -76.954406) (xy 106.773095 -76.990892) (xy 106.81548 -77.033273) (xy 106.851971 -77.080825)
			(xy 106.881942 -77.132732) (xy 106.904881 -77.188108) (xy 106.920395 -77.246004) (xy 106.928219 -77.305431)
			(xy 106.928219 -77.365367) (xy 109.150162 -77.365367) (xy 109.150162 -77.305433) (xy 109.157984 -77.246012)
			(xy 109.173495 -77.18812) (xy 109.196429 -77.132748) (xy 109.226394 -77.080843) (xy 109.262878 -77.033292)
			(xy 109.305255 -76.990911) (xy 109.352801 -76.954422) (xy 109.404703 -76.924452) (xy 109.460073 -76.901511)
			(xy 109.517963 -76.885994) (xy 109.577383 -76.878165) (xy 109.60735 -76.877672) (xy 110.47095 -76.877672)
			(xy 110.50092 -76.878178) (xy 110.560347 -76.885996) (xy 110.618246 -76.901504) (xy 110.673625 -76.924437)
			(xy 110.725536 -76.954403) (xy 110.773092 -76.990889) (xy 110.815478 -77.03327) (xy 110.851969 -77.080822)
			(xy 110.881941 -77.13273) (xy 110.90488 -77.188107) (xy 110.920395 -77.246003) (xy 110.928219 -77.30543)
			(xy 110.928219 -77.36537) (xy 110.920395 -77.424797) (xy 110.90488 -77.482693) (xy 110.881941 -77.53807)
			(xy 110.851969 -77.589978) (xy 110.815478 -77.63753) (xy 110.773092 -77.679911) (xy 110.725536 -77.716397)
			(xy 110.673625 -77.746363) (xy 110.618246 -77.769296) (xy 110.560347 -77.784804) (xy 110.50092 -77.792622)
			(xy 110.47095 -77.793088) (xy 109.60735 -77.793088) (xy 109.577383 -77.792635) (xy 109.517963 -77.784806)
			(xy 109.460073 -77.769289) (xy 109.404703 -77.746348) (xy 109.352801 -77.716378) (xy 109.305255 -77.679889)
			(xy 109.262878 -77.637508) (xy 109.226394 -77.589957) (xy 109.196429 -77.538052) (xy 109.173495 -77.48268)
			(xy 109.157984 -77.424788) (xy 109.150162 -77.365367) (xy 106.928219 -77.365367) (xy 106.928219 -77.365369)
			(xy 106.920395 -77.424796) (xy 106.904881 -77.482692) (xy 106.881942 -77.538068) (xy 106.851971 -77.589975)
			(xy 106.81548 -77.637527) (xy 106.773095 -77.679908) (xy 106.72554 -77.716394) (xy 106.67363 -77.74636)
			(xy 106.618252 -77.769294) (xy 106.560354 -77.784803) (xy 106.500928 -77.792622) (xy 106.470958 -77.793088)
			(xy 105.607358 -77.793088) (xy 105.577391 -77.792635) (xy 105.51797 -77.784807) (xy 105.460079 -77.769291)
			(xy 105.404708 -77.746351) (xy 105.352805 -77.716381) (xy 105.305258 -77.679892) (xy 105.26288 -77.63751)
			(xy 105.226396 -77.58996) (xy 105.19643 -77.538054) (xy 105.173496 -77.482681) (xy 105.157985 -77.424789)
			(xy 105.150162 -77.365367) (xy 0.508 -77.365367) (xy 0.508 -78.127367) (xy 107.150162 -78.127367)
			(xy 107.150162 -78.067433) (xy 107.157984 -78.008012) (xy 107.173496 -77.950119) (xy 107.19643 -77.894747)
			(xy 107.226395 -77.842842) (xy 107.262879 -77.795291) (xy 107.305256 -77.752909) (xy 107.352803 -77.716421)
			(xy 107.404706 -77.68645) (xy 107.460076 -77.66351) (xy 107.517966 -77.647993) (xy 107.577387 -77.640165)
			(xy 107.607354 -77.639672) (xy 108.470954 -77.639672) (xy 108.500924 -77.640178) (xy 108.560351 -77.647996)
			(xy 108.618249 -77.663505) (xy 108.673627 -77.686438) (xy 108.725538 -77.716405) (xy 108.773094 -77.752891)
			(xy 108.815479 -77.795272) (xy 108.85197 -77.842823) (xy 108.881941 -77.894731) (xy 108.90488 -77.950107)
			(xy 108.920395 -78.008004) (xy 108.928219 -78.06743) (xy 108.928219 -78.12737) (xy 108.920395 -78.186796)
			(xy 108.90488 -78.244693) (xy 108.881941 -78.300069) (xy 108.85197 -78.351977) (xy 108.815479 -78.399528)
			(xy 108.773093 -78.441909) (xy 108.725538 -78.478395) (xy 108.673627 -78.508362) (xy 108.618249 -78.531295)
			(xy 108.560351 -78.546804) (xy 108.500924 -78.554622) (xy 108.470954 -78.555088) (xy 107.607354 -78.555088)
			(xy 107.577387 -78.554635) (xy 107.517966 -78.546807) (xy 107.460076 -78.53129) (xy 107.404706 -78.50835)
			(xy 107.352803 -78.478379) (xy 107.305256 -78.441891) (xy 107.262879 -78.399509) (xy 107.226395 -78.351958)
			(xy 107.19643 -78.300053) (xy 107.173496 -78.244681) (xy 107.157984 -78.186788) (xy 107.150162 -78.127367)
			(xy 0.508 -78.127367) (xy 0.508 -79.238094) (xy 227.9777 -79.238094) (xy 227.9777 -78.374494) (xy 227.97819 -78.344526)
			(xy 227.986013 -78.285104) (xy 228.001526 -78.227211) (xy 228.024462 -78.171838) (xy 228.054429 -78.119932)
			(xy 228.090916 -78.072382) (xy 228.133296 -78.030002) (xy 228.180846 -77.993515) (xy 228.232752 -77.963548)
			(xy 228.288125 -77.940612) (xy 228.346018 -77.925099) (xy 228.40544 -77.917276) (xy 228.465376 -77.917276)
			(xy 228.524798 -77.925099) (xy 228.582691 -77.940612) (xy 228.638064 -77.963548) (xy 228.68997 -77.993515)
			(xy 228.73752 -78.030002) (xy 228.7799 -78.072382) (xy 228.816387 -78.119932) (xy 228.83413 -78.150664)
			(xy 336.40703 -78.150664) (xy 336.40703 -78.090736) (xy 336.414852 -78.031319) (xy 336.430363 -77.973433)
			(xy 336.453297 -77.918066) (xy 336.483261 -77.866166) (xy 336.519743 -77.818621) (xy 336.562119 -77.776245)
			(xy 336.609664 -77.739762) (xy 336.661564 -77.709797) (xy 336.716931 -77.686864) (xy 336.774817 -77.671353)
			(xy 336.834234 -77.66353) (xy 336.864198 -77.66304) (xy 337.727798 -77.66304) (xy 337.75777 -77.663413)
			(xy 337.817202 -77.671237) (xy 337.875104 -77.686751) (xy 337.930486 -77.709691) (xy 337.982399 -77.739663)
			(xy 338.029957 -77.776155) (xy 338.072344 -77.818542) (xy 338.108836 -77.866099) (xy 338.138808 -77.918013)
			(xy 338.161748 -77.973394) (xy 338.177263 -78.031296) (xy 338.185087 -78.090728) (xy 338.185087 -78.150672)
			(xy 338.177263 -78.210104) (xy 338.161748 -78.268006) (xy 338.138808 -78.323387) (xy 338.108836 -78.375301)
			(xy 338.072344 -78.422858) (xy 338.029957 -78.465245) (xy 337.982399 -78.501737) (xy 337.930486 -78.531709)
			(xy 337.875104 -78.554649) (xy 337.817202 -78.570163) (xy 337.75777 -78.577987) (xy 337.727798 -78.578456)
			(xy 336.864198 -78.578456) (xy 336.834234 -78.57787) (xy 336.774817 -78.570047) (xy 336.716931 -78.554536)
			(xy 336.661564 -78.531603) (xy 336.609664 -78.501638) (xy 336.562119 -78.465155) (xy 336.519743 -78.422779)
			(xy 336.483261 -78.375234) (xy 336.453297 -78.323334) (xy 336.430363 -78.267967) (xy 336.414852 -78.210081)
			(xy 336.40703 -78.150664) (xy 228.83413 -78.150664) (xy 228.846354 -78.171838) (xy 228.86929 -78.227211)
			(xy 228.884803 -78.285104) (xy 228.892626 -78.344526) (xy 228.893116 -78.374494) (xy 228.893116 -79.238094)
			(xy 228.892626 -79.268062) (xy 228.884803 -79.327484) (xy 228.86929 -79.385377) (xy 228.846354 -79.44075)
			(xy 228.816387 -79.492656) (xy 228.7799 -79.540206) (xy 228.73752 -79.582586) (xy 228.68997 -79.619073)
			(xy 228.638064 -79.64904) (xy 228.582691 -79.671976) (xy 228.524798 -79.687489) (xy 228.465376 -79.695312)
			(xy 228.40544 -79.695312) (xy 228.346018 -79.687489) (xy 228.288125 -79.671976) (xy 228.232752 -79.64904)
			(xy 228.180846 -79.619073) (xy 228.133296 -79.582586) (xy 228.090916 -79.540206) (xy 228.054429 -79.492656)
			(xy 228.024462 -79.44075) (xy 228.001526 -79.385377) (xy 227.986013 -79.327484) (xy 227.97819 -79.268062)
			(xy 227.9777 -79.238094) (xy 0.508 -79.238094) (xy 0.508 -80.183482) (xy 237.540292 -80.183482) (xy 237.540292 -79.319882)
			(xy 237.540782 -79.289914) (xy 237.548605 -79.230492) (xy 237.564118 -79.172599) (xy 237.587054 -79.117226)
			(xy 237.617021 -79.06532) (xy 237.653508 -79.01777) (xy 237.695888 -78.97539) (xy 237.743438 -78.938903)
			(xy 237.795344 -78.908936) (xy 237.850717 -78.886) (xy 237.90861 -78.870487) (xy 237.968032 -78.862664)
			(xy 238.027968 -78.862664) (xy 238.08739 -78.870487) (xy 238.145283 -78.886) (xy 238.200656 -78.908936)
			(xy 238.207117 -78.912666) (xy 334.407009 -78.912666) (xy 334.407009 -78.852734) (xy 334.414832 -78.793315)
			(xy 334.430343 -78.735425) (xy 334.453278 -78.680055) (xy 334.483244 -78.628153) (xy 334.519729 -78.580606)
			(xy 334.562107 -78.538227) (xy 334.609654 -78.501743) (xy 334.661557 -78.471777) (xy 334.716927 -78.448843)
			(xy 334.774817 -78.433331) (xy 334.834236 -78.425509) (xy 334.864202 -78.42504) (xy 335.727802 -78.42504)
			(xy 335.757773 -78.425434) (xy 335.817201 -78.433258) (xy 335.8751 -78.448773) (xy 335.930479 -78.471711)
			(xy 335.982389 -78.501682) (xy 336.029944 -78.538172) (xy 336.072329 -78.580557) (xy 336.108819 -78.628112)
			(xy 336.13879 -78.680023) (xy 336.161728 -78.735402) (xy 336.177242 -78.793301) (xy 336.185066 -78.852729)
			(xy 336.185066 -78.912664) (xy 338.40703 -78.912664) (xy 338.40703 -78.852736) (xy 338.414852 -78.79332)
			(xy 338.430363 -78.735433) (xy 338.453296 -78.680067) (xy 338.48326 -78.628167) (xy 338.519742 -78.580622)
			(xy 338.562118 -78.538246) (xy 338.609662 -78.501763) (xy 338.661561 -78.471799) (xy 338.716928 -78.448865)
			(xy 338.774814 -78.433353) (xy 338.83423 -78.42553) (xy 338.864194 -78.42504) (xy 339.727794 -78.42504)
			(xy 339.757766 -78.425412) (xy 339.817199 -78.433236) (xy 339.875101 -78.44875) (xy 339.930483 -78.47169)
			(xy 339.982397 -78.501662) (xy 340.029955 -78.538153) (xy 340.072343 -78.580541) (xy 340.108835 -78.628098)
			(xy 340.138808 -78.680011) (xy 340.161748 -78.735393) (xy 340.177263 -78.793296) (xy 340.185087 -78.852728)
			(xy 340.185087 -78.912672) (xy 340.177263 -78.972104) (xy 340.161748 -79.030007) (xy 340.138808 -79.085389)
			(xy 340.108835 -79.137302) (xy 340.072343 -79.184859) (xy 340.029955 -79.227247) (xy 339.982397 -79.263738)
			(xy 339.930483 -79.29371) (xy 339.875101 -79.31665) (xy 339.817199 -79.332164) (xy 339.757766 -79.339988)
			(xy 339.727794 -79.340456) (xy 338.864194 -79.340456) (xy 338.83423 -79.33987) (xy 338.774814 -79.332047)
			(xy 338.716928 -79.316535) (xy 338.661561 -79.293601) (xy 338.609662 -79.263637) (xy 338.562118 -79.227154)
			(xy 338.519742 -79.184778) (xy 338.48326 -79.137233) (xy 338.453296 -79.085333) (xy 338.430363 -79.029967)
			(xy 338.414852 -78.97208) (xy 338.40703 -78.912664) (xy 336.185066 -78.912664) (xy 336.185066 -78.912671)
			(xy 336.177242 -78.972099) (xy 336.161728 -79.029998) (xy 336.13879 -79.085377) (xy 336.108819 -79.137288)
			(xy 336.072329 -79.184843) (xy 336.029944 -79.227228) (xy 335.982389 -79.263718) (xy 335.930479 -79.293689)
			(xy 335.8751 -79.316627) (xy 335.817201 -79.332142) (xy 335.757773 -79.339966) (xy 335.727802 -79.340456)
			(xy 334.864202 -79.340456) (xy 334.834236 -79.339891) (xy 334.774817 -79.332069) (xy 334.716927 -79.316557)
			(xy 334.661557 -79.293623) (xy 334.609654 -79.263657) (xy 334.562107 -79.227173) (xy 334.519729 -79.184794)
			(xy 334.483244 -79.137247) (xy 334.453278 -79.085345) (xy 334.430343 -79.029975) (xy 334.414832 -78.972085)
			(xy 334.407009 -78.912666) (xy 238.207117 -78.912666) (xy 238.252562 -78.938903) (xy 238.300112 -78.97539)
			(xy 238.342492 -79.01777) (xy 238.378979 -79.06532) (xy 238.408946 -79.117226) (xy 238.431882 -79.172599)
			(xy 238.447395 -79.230492) (xy 238.455218 -79.289914) (xy 238.455708 -79.319882) (xy 238.455708 -80.183482)
			(xy 238.455218 -80.21345) (xy 238.447395 -80.272872) (xy 238.431882 -80.330765) (xy 238.408946 -80.386138)
			(xy 238.378979 -80.438044) (xy 238.342492 -80.485594) (xy 238.300112 -80.527974) (xy 238.252562 -80.564461)
			(xy 238.200656 -80.594428) (xy 238.145283 -80.617364) (xy 238.08739 -80.632877) (xy 238.027968 -80.6407)
			(xy 237.968032 -80.6407) (xy 237.90861 -80.632877) (xy 237.850717 -80.617364) (xy 237.795344 -80.594428)
			(xy 237.743438 -80.564461) (xy 237.695888 -80.527974) (xy 237.653508 -80.485594) (xy 237.617021 -80.438044)
			(xy 237.587054 -80.386138) (xy 237.564118 -80.330765) (xy 237.548605 -80.272872) (xy 237.540782 -80.21345)
			(xy 237.540292 -80.183482) (xy 0.508 -80.183482) (xy 0.508 -82.131916) (xy 0.508487 -82.185165) (xy 0.516104 -82.291392)
			(xy 0.531277 -82.396804) (xy 0.553928 -82.500867) (xy 0.583941 -82.603049) (xy 0.621164 -82.702831)
			(xy 0.665407 -82.799705) (xy 0.716446 -82.893178) (xy 0.774019 -82.982773) (xy 0.837835 -83.068035)
			(xy 0.907568 -83.14853) (xy 0.94488 -83.186524) (xy 2.783716 -85.025538) (xy 44.856389 -85.025538)
			(xy 44.856389 -84.896398) (xy 44.864339 -84.767503) (xy 44.880209 -84.639343) (xy 44.903938 -84.512402)
			(xy 44.935437 -84.387163) (xy 44.974586 -84.2641) (xy 45.021237 -84.143681) (xy 45.075212 -84.026362)
			(xy 45.136307 -83.912588) (xy 45.20429 -83.802791) (xy 45.278904 -83.697388) (xy 45.359865 -83.596778)
			(xy 45.446865 -83.501343) (xy 45.539576 -83.411444) (xy 45.637646 -83.327423) (xy 45.740701 -83.249599)
			(xy 45.848352 -83.178267) (xy 45.960191 -83.113697) (xy 46.075792 -83.056135) (xy 46.194717 -83.005798)
			(xy 46.316516 -82.962878) (xy 46.440726 -82.927537) (xy 46.566875 -82.89991) (xy 46.694487 -82.880101)
			(xy 46.823076 -82.868185) (xy 46.952154 -82.864209) (xy 47.081232 -82.868185) (xy 47.209821 -82.880101)
			(xy 47.337433 -82.89991) (xy 47.463582 -82.927537) (xy 47.587792 -82.962878) (xy 47.709591 -83.005798)
			(xy 47.828516 -83.056135) (xy 47.944117 -83.113697) (xy 48.055956 -83.178267) (xy 48.163607 -83.249599)
			(xy 48.266662 -83.327423) (xy 48.303507 -83.35899) (xy 116.623592 -83.35899) (xy 116.623592 -82.49539)
			(xy 116.624082 -82.465422) (xy 116.631905 -82.406) (xy 116.647418 -82.348107) (xy 116.670354 -82.292734)
			(xy 116.700321 -82.240828) (xy 116.736808 -82.193278) (xy 116.779188 -82.150898) (xy 116.826738 -82.114411)
			(xy 116.878644 -82.084444) (xy 116.934017 -82.061508) (xy 116.99191 -82.045995) (xy 117.051332 -82.038172)
			(xy 117.111268 -82.038172) (xy 117.17069 -82.045995) (xy 117.228583 -82.061508) (xy 117.283956 -82.084444)
			(xy 117.335862 -82.114411) (xy 117.383412 -82.150898) (xy 117.425792 -82.193278) (xy 117.462279 -82.240828)
			(xy 117.492246 -82.292734) (xy 117.515182 -82.348107) (xy 117.530695 -82.406) (xy 117.538518 -82.465422)
			(xy 117.539008 -82.49539) (xy 117.539008 -83.35899) (xy 117.538875 -83.367118) (xy 232.68432 -83.367118)
			(xy 232.68432 -82.503518) (xy 232.68481 -82.47355) (xy 232.692633 -82.414128) (xy 232.708146 -82.356235)
			(xy 232.731082 -82.300862) (xy 232.761049 -82.248956) (xy 232.797536 -82.201406) (xy 232.839916 -82.159026)
			(xy 232.887466 -82.122539) (xy 232.939372 -82.092572) (xy 232.994745 -82.069636) (xy 233.052638 -82.054123)
			(xy 233.11206 -82.0463) (xy 233.171996 -82.0463) (xy 233.231418 -82.054123) (xy 233.289311 -82.069636)
			(xy 233.344684 -82.092572) (xy 233.39659 -82.122539) (xy 233.44414 -82.159026) (xy 233.48652 -82.201406)
			(xy 233.523007 -82.248956) (xy 233.552974 -82.300862) (xy 233.568014 -82.337171) (xy 238.132537 -82.337171)
			(xy 238.132537 -82.277229) (xy 238.140362 -82.217799) (xy 238.155876 -82.159898) (xy 238.178816 -82.104519)
			(xy 238.208788 -82.052607) (xy 238.24528 -82.005052) (xy 238.287667 -81.962667) (xy 238.335224 -81.926177)
			(xy 238.387137 -81.896207) (xy 238.442517 -81.87327) (xy 238.500418 -81.857758) (xy 238.559849 -81.849936)
			(xy 238.58982 -81.849468) (xy 239.45342 -81.849468) (xy 239.483385 -81.850007) (xy 239.542803 -81.857832)
			(xy 239.600691 -81.873345) (xy 239.656058 -81.896282) (xy 239.707959 -81.926248) (xy 239.755504 -81.962733)
			(xy 239.769238 -81.976468) (xy 273.798284 -81.976468) (xy 273.798284 -81.112868) (xy 273.798774 -81.0829)
			(xy 273.806597 -81.023478) (xy 273.82211 -80.965585) (xy 273.845046 -80.910212) (xy 273.875013 -80.858306)
			(xy 273.9115 -80.810756) (xy 273.95388 -80.768376) (xy 274.00143 -80.731889) (xy 274.053336 -80.701922)
			(xy 274.108709 -80.678986) (xy 274.166602 -80.663473) (xy 274.226024 -80.65565) (xy 274.28596 -80.65565)
			(xy 274.345382 -80.663473) (xy 274.403275 -80.678986) (xy 274.458648 -80.701922) (xy 274.510554 -80.731889)
			(xy 274.558104 -80.768376) (xy 274.600484 -80.810756) (xy 274.636971 -80.858306) (xy 274.666938 -80.910212)
			(xy 274.689874 -80.965585) (xy 274.705387 -81.023478) (xy 274.71321 -81.0829) (xy 274.7137 -81.112868)
			(xy 274.7137 -81.976468) (xy 274.71321 -82.006436) (xy 274.705387 -82.065858) (xy 274.689874 -82.123751)
			(xy 274.666938 -82.179124) (xy 274.636971 -82.23103) (xy 274.600484 -82.27858) (xy 274.558104 -82.32096)
			(xy 274.510554 -82.357447) (xy 274.458648 -82.387414) (xy 274.403275 -82.41035) (xy 274.345382 -82.425863)
			(xy 274.28596 -82.433686) (xy 274.226024 -82.433686) (xy 274.166602 -82.425863) (xy 274.108709 -82.41035)
			(xy 274.053336 -82.387414) (xy 274.00143 -82.357447) (xy 273.95388 -82.32096) (xy 273.9115 -82.27858)
			(xy 273.875013 -82.23103) (xy 273.845046 -82.179124) (xy 273.82211 -82.123751) (xy 273.806597 -82.065858)
			(xy 273.798774 -82.006436) (xy 273.798284 -81.976468) (xy 239.769238 -81.976468) (xy 239.79788 -82.005111)
			(xy 239.834363 -82.052658) (xy 239.864327 -82.10456) (xy 239.887261 -82.159928) (xy 239.902772 -82.217817)
			(xy 239.910594 -82.277235) (xy 239.910594 -82.337165) (xy 239.902772 -82.396583) (xy 239.887261 -82.454472)
			(xy 239.864327 -82.50984) (xy 239.834363 -82.561742) (xy 239.79788 -82.609289) (xy 239.755504 -82.651667)
			(xy 239.707959 -82.688152) (xy 239.656058 -82.718118) (xy 239.600691 -82.741055) (xy 239.542803 -82.756568)
			(xy 239.483385 -82.764393) (xy 239.45342 -82.764884) (xy 238.58982 -82.764884) (xy 238.559849 -82.764464)
			(xy 238.500418 -82.756642) (xy 238.442517 -82.74113) (xy 238.387137 -82.718193) (xy 238.335224 -82.688223)
			(xy 238.287667 -82.651733) (xy 238.24528 -82.609348) (xy 238.208788 -82.561793) (xy 238.178816 -82.509881)
			(xy 238.155876 -82.454502) (xy 238.140362 -82.396601) (xy 238.132537 -82.337171) (xy 233.568014 -82.337171)
			(xy 233.57591 -82.356235) (xy 233.591423 -82.414128) (xy 233.599246 -82.47355) (xy 233.599736 -82.503518)
			(xy 233.599736 -83.367118) (xy 233.599246 -83.397086) (xy 233.591423 -83.456508) (xy 233.57591 -83.514401)
			(xy 233.552974 -83.569774) (xy 233.523007 -83.62168) (xy 233.48652 -83.66923) (xy 233.44414 -83.71161)
			(xy 233.39659 -83.748097) (xy 233.344684 -83.778064) (xy 233.289311 -83.801) (xy 233.231418 -83.816513)
			(xy 233.171996 -83.824336) (xy 233.11206 -83.824336) (xy 233.052638 -83.816513) (xy 232.994745 -83.801)
			(xy 232.939372 -83.778064) (xy 232.887466 -83.748097) (xy 232.839916 -83.71161) (xy 232.797536 -83.66923)
			(xy 232.761049 -83.62168) (xy 232.731082 -83.569774) (xy 232.708146 -83.514401) (xy 232.692633 -83.456508)
			(xy 232.68481 -83.397086) (xy 232.68432 -83.367118) (xy 117.538875 -83.367118) (xy 117.538518 -83.388958)
			(xy 117.530695 -83.44838) (xy 117.515182 -83.506273) (xy 117.492246 -83.561646) (xy 117.462279 -83.613552)
			(xy 117.425792 -83.661102) (xy 117.383412 -83.703482) (xy 117.335862 -83.739969) (xy 117.283956 -83.769936)
			(xy 117.228583 -83.792872) (xy 117.17069 -83.808385) (xy 117.111268 -83.816208) (xy 117.051332 -83.816208)
			(xy 116.99191 -83.808385) (xy 116.934017 -83.792872) (xy 116.878644 -83.769936) (xy 116.826738 -83.739969)
			(xy 116.779188 -83.703482) (xy 116.736808 -83.661102) (xy 116.700321 -83.613552) (xy 116.670354 -83.561646)
			(xy 116.647418 -83.506273) (xy 116.631905 -83.44838) (xy 116.624082 -83.388958) (xy 116.623592 -83.35899)
			(xy 48.303507 -83.35899) (xy 48.364732 -83.411444) (xy 48.457443 -83.501343) (xy 48.544443 -83.596778)
			(xy 48.625404 -83.697388) (xy 48.700018 -83.802791) (xy 48.768001 -83.912588) (xy 48.829096 -84.026362)
			(xy 48.883071 -84.143681) (xy 48.929722 -84.2641) (xy 48.968871 -84.387163) (xy 49.00037 -84.512402)
			(xy 49.024099 -84.639343) (xy 49.039969 -84.767503) (xy 49.047919 -84.896398) (xy 49.048416 -84.960968)
			(xy 49.047919 -85.025538) (xy 49.039969 -85.154433) (xy 49.024099 -85.282593) (xy 49.009819 -85.358986)
			(xy 117.385592 -85.358986) (xy 117.385592 -84.495386) (xy 117.386082 -84.465418) (xy 117.393905 -84.405996)
			(xy 117.409418 -84.348103) (xy 117.432354 -84.29273) (xy 117.462321 -84.240824) (xy 117.498808 -84.193274)
			(xy 117.541188 -84.150894) (xy 117.588738 -84.114407) (xy 117.640644 -84.08444) (xy 117.696017 -84.061504)
			(xy 117.75391 -84.045991) (xy 117.813332 -84.038168) (xy 117.873268 -84.038168) (xy 117.93269 -84.045991)
			(xy 117.990583 -84.061504) (xy 118.045956 -84.08444) (xy 118.097862 -84.114407) (xy 118.145412 -84.150894)
			(xy 118.187792 -84.193274) (xy 118.224279 -84.240824) (xy 118.254246 -84.29273) (xy 118.277182 -84.348103)
			(xy 118.292695 -84.405996) (xy 118.300518 -84.465418) (xy 118.301008 -84.495386) (xy 118.301008 -85.358986)
			(xy 118.300518 -85.388954) (xy 118.292695 -85.448376) (xy 118.289959 -85.458587) (xy 232.264389 -85.458587)
			(xy 232.264389 -85.398613) (xy 232.272218 -85.339151) (xy 232.28774 -85.28122) (xy 232.310692 -85.225811)
			(xy 232.34068 -85.173871) (xy 232.377191 -85.126291) (xy 232.4196 -85.083883) (xy 232.467181 -85.047373)
			(xy 232.519122 -85.017387) (xy 232.574531 -84.994437) (xy 232.632463 -84.978915) (xy 232.691925 -84.971088)
			(xy 232.721912 -84.97062) (xy 233.585512 -84.97062) (xy 233.615495 -84.971147) (xy 233.674947 -84.978975)
			(xy 233.732868 -84.994497) (xy 233.788268 -85.017445) (xy 233.840199 -85.047429) (xy 233.887772 -85.083934)
			(xy 233.930174 -85.126337) (xy 233.963295 -85.169502) (xy 238.555276 -85.169502) (xy 238.555276 -84.305902)
			(xy 238.555766 -84.275918) (xy 238.563594 -84.216462) (xy 238.579115 -84.158537) (xy 238.602064 -84.103133)
			(xy 238.632048 -84.051199) (xy 238.668554 -84.003623) (xy 238.710959 -83.961218) (xy 238.758535 -83.924712)
			(xy 238.810469 -83.894728) (xy 238.865873 -83.871779) (xy 238.923798 -83.856258) (xy 238.983254 -83.84843)
			(xy 239.043222 -83.84843) (xy 239.102678 -83.856258) (xy 239.160603 -83.871779) (xy 239.216007 -83.894728)
			(xy 239.267941 -83.924712) (xy 239.315517 -83.961218) (xy 239.357922 -84.003623) (xy 239.394428 -84.051199)
			(xy 239.424412 -84.103133) (xy 239.447361 -84.158537) (xy 239.462882 -84.216462) (xy 239.46603 -84.24037)
			(xy 273.951192 -84.24037) (xy 273.951192 -83.37677) (xy 273.951682 -83.346786) (xy 273.95951 -83.28733)
			(xy 273.975031 -83.229405) (xy 273.99798 -83.174001) (xy 274.027964 -83.122067) (xy 274.06447 -83.074491)
			(xy 274.106875 -83.032086) (xy 274.154451 -82.99558) (xy 274.206385 -82.965596) (xy 274.261789 -82.942647)
			(xy 274.319714 -82.927126) (xy 274.37917 -82.919298) (xy 274.439138 -82.919298) (xy 274.498594 -82.927126)
			(xy 274.556519 -82.942647) (xy 274.611923 -82.965596) (xy 274.663857 -82.99558) (xy 274.711433 -83.032086)
			(xy 274.753838 -83.074491) (xy 274.790344 -83.122067) (xy 274.820328 -83.174001) (xy 274.843277 -83.229405)
			(xy 274.858798 -83.28733) (xy 274.866626 -83.346786) (xy 274.867116 -83.37677) (xy 274.867116 -84.144612)
			(xy 345.879928 -84.144612) (xy 345.879928 -83.281012) (xy 345.880418 -83.251028) (xy 345.888246 -83.191572)
			(xy 345.903767 -83.133647) (xy 345.926716 -83.078243) (xy 345.9567 -83.026309) (xy 345.993206 -82.978733)
			(xy 346.035611 -82.936328) (xy 346.083187 -82.899822) (xy 346.135121 -82.869838) (xy 346.190525 -82.846889)
			(xy 346.24845 -82.831368) (xy 346.307906 -82.82354) (xy 346.367874 -82.82354) (xy 346.42733 -82.831368)
			(xy 346.485255 -82.846889) (xy 346.540659 -82.869838) (xy 346.592593 -82.899822) (xy 346.640169 -82.936328)
			(xy 346.682574 -82.978733) (xy 346.71908 -83.026309) (xy 346.749064 -83.078243) (xy 346.772013 -83.133647)
			(xy 346.787534 -83.191572) (xy 346.795362 -83.251028) (xy 346.795852 -83.281012) (xy 346.795852 -84.144612)
			(xy 346.795362 -84.174596) (xy 346.787534 -84.234052) (xy 346.772013 -84.291977) (xy 346.749064 -84.347381)
			(xy 346.71908 -84.399315) (xy 346.682574 -84.446891) (xy 346.640169 -84.489296) (xy 346.592593 -84.525802)
			(xy 346.540659 -84.555786) (xy 346.485255 -84.578735) (xy 346.42733 -84.594256) (xy 346.367874 -84.602084)
			(xy 346.307906 -84.602084) (xy 346.24845 -84.594256) (xy 346.190525 -84.578735) (xy 346.135121 -84.555786)
			(xy 346.083187 -84.525802) (xy 346.035611 -84.489296) (xy 345.993206 -84.446891) (xy 345.9567 -84.399315)
			(xy 345.926716 -84.347381) (xy 345.903767 -84.291977) (xy 345.888246 -84.234052) (xy 345.880418 -84.174596)
			(xy 345.879928 -84.144612) (xy 274.867116 -84.144612) (xy 274.867116 -84.24037) (xy 274.866626 -84.270354)
			(xy 274.858798 -84.32981) (xy 274.843277 -84.387735) (xy 274.820328 -84.443139) (xy 274.790344 -84.495073)
			(xy 274.753838 -84.542649) (xy 274.711433 -84.585054) (xy 274.663857 -84.62156) (xy 274.611923 -84.651544)
			(xy 274.556519 -84.674493) (xy 274.498594 -84.690014) (xy 274.439138 -84.697842) (xy 274.37917 -84.697842)
			(xy 274.319714 -84.690014) (xy 274.261789 -84.674493) (xy 274.206385 -84.651544) (xy 274.154451 -84.62156)
			(xy 274.106875 -84.585054) (xy 274.06447 -84.542649) (xy 274.027964 -84.495073) (xy 273.99798 -84.443139)
			(xy 273.975031 -84.387735) (xy 273.95951 -84.32981) (xy 273.951682 -84.270354) (xy 273.951192 -84.24037)
			(xy 239.46603 -84.24037) (xy 239.47071 -84.275918) (xy 239.4712 -84.305902) (xy 239.4712 -85.169502)
			(xy 239.47071 -85.199486) (xy 239.462882 -85.258942) (xy 239.447361 -85.316867) (xy 239.424412 -85.372271)
			(xy 239.394428 -85.424205) (xy 239.357922 -85.471781) (xy 239.315517 -85.514186) (xy 239.267941 -85.550692)
			(xy 239.216007 -85.580676) (xy 239.160603 -85.603625) (xy 239.102678 -85.619146) (xy 239.043222 -85.626974)
			(xy 238.983254 -85.626974) (xy 238.923798 -85.619146) (xy 238.865873 -85.603625) (xy 238.810469 -85.580676)
			(xy 238.758535 -85.550692) (xy 238.710959 -85.514186) (xy 238.668554 -85.471781) (xy 238.632048 -85.424205)
			(xy 238.602064 -85.372271) (xy 238.579115 -85.316867) (xy 238.563594 -85.258942) (xy 238.555766 -85.199486)
			(xy 238.555276 -85.169502) (xy 233.963295 -85.169502) (xy 233.966678 -85.173911) (xy 233.99666 -85.225842)
			(xy 234.019607 -85.281243) (xy 234.035127 -85.339165) (xy 234.042954 -85.398617) (xy 234.042954 -85.458583)
			(xy 234.035127 -85.518035) (xy 234.019607 -85.575957) (xy 233.99666 -85.631358) (xy 233.966678 -85.683289)
			(xy 233.930174 -85.730863) (xy 233.887772 -85.773266) (xy 233.840199 -85.809771) (xy 233.788268 -85.839755)
			(xy 233.732868 -85.862703) (xy 233.674947 -85.878225) (xy 233.615495 -85.886053) (xy 233.585512 -85.886544)
			(xy 232.721912 -85.886544) (xy 232.691925 -85.886112) (xy 232.632463 -85.878285) (xy 232.574531 -85.862763)
			(xy 232.519122 -85.839813) (xy 232.467181 -85.809827) (xy 232.4196 -85.773317) (xy 232.377191 -85.730909)
			(xy 232.34068 -85.683329) (xy 232.310692 -85.631389) (xy 232.28774 -85.57598) (xy 232.272218 -85.518049)
			(xy 232.264389 -85.458587) (xy 118.289959 -85.458587) (xy 118.277182 -85.506269) (xy 118.254246 -85.561642)
			(xy 118.224279 -85.613548) (xy 118.187792 -85.661098) (xy 118.145412 -85.703478) (xy 118.097862 -85.739965)
			(xy 118.045956 -85.769932) (xy 117.990583 -85.792868) (xy 117.93269 -85.808381) (xy 117.873268 -85.816204)
			(xy 117.813332 -85.816204) (xy 117.75391 -85.808381) (xy 117.696017 -85.792868) (xy 117.640644 -85.769932)
			(xy 117.588738 -85.739965) (xy 117.541188 -85.703478) (xy 117.498808 -85.661098) (xy 117.462321 -85.613548)
			(xy 117.432354 -85.561642) (xy 117.409418 -85.506269) (xy 117.393905 -85.448376) (xy 117.386082 -85.388954)
			(xy 117.385592 -85.358986) (xy 49.009819 -85.358986) (xy 49.00037 -85.409534) (xy 48.968871 -85.534773)
			(xy 48.929722 -85.657836) (xy 48.883071 -85.778255) (xy 48.829096 -85.895574) (xy 48.768001 -86.009348)
			(xy 48.700018 -86.119145) (xy 48.625404 -86.224548) (xy 48.544443 -86.325158) (xy 48.457443 -86.420593)
			(xy 48.364732 -86.510492) (xy 48.266662 -86.594513) (xy 48.163607 -86.672337) (xy 48.055956 -86.743669)
			(xy 47.944117 -86.808239) (xy 47.937853 -86.811358) (xy 99.84232 -86.811358) (xy 99.84232 -85.947758)
			(xy 99.84281 -85.917774) (xy 99.850638 -85.858318) (xy 99.866159 -85.800393) (xy 99.889108 -85.744989)
			(xy 99.919092 -85.693055) (xy 99.955598 -85.645479) (xy 99.998003 -85.603074) (xy 100.045579 -85.566568)
			(xy 100.097513 -85.536584) (xy 100.152917 -85.513635) (xy 100.210842 -85.498114) (xy 100.270298 -85.490286)
			(xy 100.330266 -85.490286) (xy 100.389722 -85.498114) (xy 100.447647 -85.513635) (xy 100.503051 -85.536584)
			(xy 100.554985 -85.566568) (xy 100.602561 -85.603074) (xy 100.644966 -85.645479) (xy 100.681472 -85.693055)
			(xy 100.711456 -85.744989) (xy 100.734405 -85.800393) (xy 100.749926 -85.858318) (xy 100.757754 -85.917774)
			(xy 100.758244 -85.947758) (xy 100.758244 -86.811358) (xy 100.757754 -86.841342) (xy 100.749926 -86.900798)
			(xy 100.734405 -86.958723) (xy 100.711456 -87.014127) (xy 100.681472 -87.066061) (xy 100.644966 -87.113637)
			(xy 100.602561 -87.156042) (xy 100.554985 -87.192548) (xy 100.503051 -87.222532) (xy 100.447647 -87.245481)
			(xy 100.389722 -87.261002) (xy 100.330266 -87.26883) (xy 100.270298 -87.26883) (xy 100.210842 -87.261002)
			(xy 100.152917 -87.245481) (xy 100.097513 -87.222532) (xy 100.045579 -87.192548) (xy 99.998003 -87.156042)
			(xy 99.955598 -87.113637) (xy 99.919092 -87.066061) (xy 99.889108 -87.014127) (xy 99.866159 -86.958723)
			(xy 99.850638 -86.900798) (xy 99.84281 -86.841342) (xy 99.84232 -86.811358) (xy 47.937853 -86.811358)
			(xy 47.828516 -86.865801) (xy 47.709591 -86.916138) (xy 47.587792 -86.959058) (xy 47.463582 -86.994399)
			(xy 47.337433 -87.022026) (xy 47.209821 -87.041835) (xy 47.081232 -87.053751) (xy 46.952154 -87.057728)
			(xy 46.823076 -87.053751) (xy 46.694487 -87.041835) (xy 46.566875 -87.022026) (xy 46.440726 -86.994399)
			(xy 46.316516 -86.959058) (xy 46.194717 -86.916138) (xy 46.075792 -86.865801) (xy 45.960191 -86.808239)
			(xy 45.848352 -86.743669) (xy 45.740701 -86.672337) (xy 45.637646 -86.594513) (xy 45.539576 -86.510492)
			(xy 45.446865 -86.420593) (xy 45.359865 -86.325158) (xy 45.278904 -86.224548) (xy 45.20429 -86.119145)
			(xy 45.136307 -86.009348) (xy 45.075212 -85.895574) (xy 45.021237 -85.778255) (xy 44.974586 -85.657836)
			(xy 44.935437 -85.534773) (xy 44.903938 -85.409534) (xy 44.880209 -85.282593) (xy 44.864339 -85.154433)
			(xy 44.856389 -85.025538) (xy 2.783716 -85.025538) (xy 3.573272 -85.81517) (xy 3.622687 -85.865245)
			(xy 3.716468 -85.970133) (xy 3.804219 -86.080117) (xy 3.885663 -86.194848) (xy 3.960544 -86.313966)
			(xy 4.028628 -86.437097) (xy 4.089698 -86.563852) (xy 4.143563 -86.693833) (xy 4.190054 -86.82663)
			(xy 4.229024 -86.961825) (xy 4.260351 -87.098994) (xy 4.283935 -87.237703) (xy 4.297613 -87.358982)
			(xy 116.623592 -87.358982) (xy 116.623592 -86.495382) (xy 116.624082 -86.465414) (xy 116.631905 -86.405992)
			(xy 116.647418 -86.348099) (xy 116.670354 -86.292726) (xy 116.700321 -86.24082) (xy 116.736808 -86.19327)
			(xy 116.779188 -86.15089) (xy 116.826738 -86.114403) (xy 116.878644 -86.084436) (xy 116.934017 -86.0615)
			(xy 116.99191 -86.045987) (xy 117.051332 -86.038164) (xy 117.111268 -86.038164) (xy 117.17069 -86.045987)
			(xy 117.228583 -86.0615) (xy 117.283956 -86.084436) (xy 117.335862 -86.114403) (xy 117.383412 -86.15089)
			(xy 117.425792 -86.19327) (xy 117.462279 -86.24082) (xy 117.492246 -86.292726) (xy 117.515182 -86.348099)
			(xy 117.530695 -86.405992) (xy 117.538518 -86.465414) (xy 117.539008 -86.495382) (xy 117.539008 -87.358982)
			(xy 117.538518 -87.38895) (xy 117.531262 -87.444066) (xy 232.194882 -87.444066) (xy 232.194882 -87.384134)
			(xy 232.202704 -87.324714) (xy 232.218215 -87.266824) (xy 232.241149 -87.211454) (xy 232.271114 -87.15955)
			(xy 232.307596 -87.112002) (xy 232.349973 -87.069621) (xy 232.397519 -87.033135) (xy 232.44942 -87.003166)
			(xy 232.504788 -86.980227) (xy 232.562677 -86.964712) (xy 232.622096 -86.956884) (xy 232.652062 -86.956392)
			(xy 233.515662 -86.956392) (xy 233.545633 -86.956859) (xy 233.605062 -86.964678) (xy 233.662961 -86.980188)
			(xy 233.718341 -87.003123) (xy 233.770254 -87.033091) (xy 233.81781 -87.069578) (xy 233.860197 -87.111961)
			(xy 233.896688 -87.159515) (xy 233.92666 -87.211425) (xy 233.9496 -87.266803) (xy 233.965115 -87.324701)
			(xy 233.972939 -87.384129) (xy 233.972939 -87.416385) (xy 234.381521 -87.416385) (xy 234.381521 -87.356415)
			(xy 234.389349 -87.296959) (xy 234.40487 -87.239032) (xy 234.42782 -87.183628) (xy 234.457804 -87.131692)
			(xy 234.494312 -87.084115) (xy 234.536717 -87.04171) (xy 234.584294 -87.005203) (xy 234.636229 -86.975219)
			(xy 234.691634 -86.952269) (xy 234.749561 -86.936748) (xy 234.809017 -86.928921) (xy 234.839002 -86.928452)
			(xy 235.702602 -86.928452) (xy 235.732587 -86.928914) (xy 235.792044 -86.936742) (xy 235.849971 -86.952264)
			(xy 235.905376 -86.975214) (xy 235.957312 -87.005199) (xy 236.004889 -87.041707) (xy 236.047295 -87.084112)
			(xy 236.083802 -87.13169) (xy 236.113787 -87.183626) (xy 236.136737 -87.239031) (xy 236.152258 -87.296958)
			(xy 236.155843 -87.324184) (xy 330.477876 -87.324184) (xy 330.477876 -86.460584) (xy 330.478366 -86.430616)
			(xy 330.486189 -86.371194) (xy 330.501702 -86.313301) (xy 330.524638 -86.257928) (xy 330.554605 -86.206022)
			(xy 330.591092 -86.158472) (xy 330.633472 -86.116092) (xy 330.681022 -86.079605) (xy 330.732928 -86.049638)
			(xy 330.788301 -86.026702) (xy 330.846194 -86.011189) (xy 330.905616 -86.003366) (xy 330.965552 -86.003366)
			(xy 331.024974 -86.011189) (xy 331.082867 -86.026702) (xy 331.13824 -86.049638) (xy 331.190146 -86.079605)
			(xy 331.237696 -86.116092) (xy 331.266212 -86.144608) (xy 346.641928 -86.144608) (xy 346.641928 -85.281008)
			(xy 346.642418 -85.251024) (xy 346.650246 -85.191568) (xy 346.665767 -85.133643) (xy 346.688716 -85.078239)
			(xy 346.7187 -85.026305) (xy 346.755206 -84.978729) (xy 346.797611 -84.936324) (xy 346.845187 -84.899818)
			(xy 346.897121 -84.869834) (xy 346.952525 -84.846885) (xy 347.01045 -84.831364) (xy 347.069906 -84.823536)
			(xy 347.129874 -84.823536) (xy 347.18933 -84.831364) (xy 347.247255 -84.846885) (xy 347.302659 -84.869834)
			(xy 347.354593 -84.899818) (xy 347.402169 -84.936324) (xy 347.444574 -84.978729) (xy 347.48108 -85.026305)
			(xy 347.511064 -85.078239) (xy 347.534013 -85.133643) (xy 347.549534 -85.191568) (xy 347.557362 -85.251024)
			(xy 347.557852 -85.281008) (xy 347.557852 -86.144608) (xy 347.557362 -86.174592) (xy 347.549534 -86.234048)
			(xy 347.534013 -86.291973) (xy 347.511064 -86.347377) (xy 347.48108 -86.399311) (xy 347.444574 -86.446887)
			(xy 347.402169 -86.489292) (xy 347.354593 -86.525798) (xy 347.302659 -86.555782) (xy 347.247255 -86.578731)
			(xy 347.18933 -86.594252) (xy 347.129874 -86.60208) (xy 347.069906 -86.60208) (xy 347.01045 -86.594252)
			(xy 346.952525 -86.578731) (xy 346.897121 -86.555782) (xy 346.845187 -86.525798) (xy 346.797611 -86.489292)
			(xy 346.755206 -86.446887) (xy 346.7187 -86.399311) (xy 346.688716 -86.347377) (xy 346.665767 -86.291973)
			(xy 346.650246 -86.234048) (xy 346.642418 -86.174592) (xy 346.641928 -86.144608) (xy 331.266212 -86.144608)
			(xy 331.280076 -86.158472) (xy 331.316563 -86.206022) (xy 331.34653 -86.257928) (xy 331.369466 -86.313301)
			(xy 331.384979 -86.371194) (xy 331.392802 -86.430616) (xy 331.393292 -86.460584) (xy 331.393292 -87.324184)
			(xy 331.392802 -87.354152) (xy 331.384979 -87.413574) (xy 331.369466 -87.471467) (xy 331.34653 -87.52684)
			(xy 331.316563 -87.578746) (xy 331.280076 -87.626296) (xy 331.237696 -87.668676) (xy 331.190146 -87.705163)
			(xy 331.13824 -87.73513) (xy 331.082867 -87.758066) (xy 331.024974 -87.773579) (xy 330.965552 -87.781402)
			(xy 330.905616 -87.781402) (xy 330.846194 -87.773579) (xy 330.788301 -87.758066) (xy 330.732928 -87.73513)
			(xy 330.681022 -87.705163) (xy 330.633472 -87.668676) (xy 330.591092 -87.626296) (xy 330.554605 -87.578746)
			(xy 330.524638 -87.52684) (xy 330.501702 -87.471467) (xy 330.486189 -87.413574) (xy 330.478366 -87.354152)
			(xy 330.477876 -87.324184) (xy 236.155843 -87.324184) (xy 236.160086 -87.356415) (xy 236.160086 -87.416385)
			(xy 236.152258 -87.475842) (xy 236.136737 -87.533769) (xy 236.113787 -87.589174) (xy 236.083802 -87.64111)
			(xy 236.047295 -87.688688) (xy 236.004889 -87.731093) (xy 235.957312 -87.767601) (xy 235.905376 -87.797586)
			(xy 235.849971 -87.820536) (xy 235.792044 -87.836058) (xy 235.732587 -87.843886) (xy 235.702602 -87.844376)
			(xy 234.839002 -87.844376) (xy 234.809017 -87.843879) (xy 234.749561 -87.836052) (xy 234.691634 -87.820531)
			(xy 234.636229 -87.797581) (xy 234.584294 -87.767597) (xy 234.536717 -87.73109) (xy 234.494312 -87.688685)
			(xy 234.457804 -87.641108) (xy 234.42782 -87.589172) (xy 234.40487 -87.533768) (xy 234.389349 -87.475841)
			(xy 234.381521 -87.416385) (xy 233.972939 -87.416385) (xy 233.972939 -87.444071) (xy 233.965115 -87.503499)
			(xy 233.9496 -87.561397) (xy 233.92666 -87.616775) (xy 233.896688 -87.668685) (xy 233.860197 -87.716239)
			(xy 233.81781 -87.758622) (xy 233.770254 -87.795109) (xy 233.718341 -87.825077) (xy 233.662961 -87.848012)
			(xy 233.605062 -87.863522) (xy 233.545633 -87.871341) (xy 233.515662 -87.871808) (xy 232.652062 -87.871808)
			(xy 232.622096 -87.871316) (xy 232.562677 -87.863488) (xy 232.504788 -87.847973) (xy 232.44942 -87.825034)
			(xy 232.397519 -87.795065) (xy 232.349973 -87.758579) (xy 232.307596 -87.716198) (xy 232.271114 -87.66865)
			(xy 232.241149 -87.616746) (xy 232.218215 -87.561376) (xy 232.202704 -87.503486) (xy 232.194882 -87.444066)
			(xy 117.531262 -87.444066) (xy 117.530695 -87.448372) (xy 117.515182 -87.506265) (xy 117.492246 -87.561638)
			(xy 117.462279 -87.613544) (xy 117.425792 -87.661094) (xy 117.383412 -87.703474) (xy 117.335862 -87.739961)
			(xy 117.283956 -87.769928) (xy 117.228583 -87.792864) (xy 117.17069 -87.808377) (xy 117.111268 -87.8162)
			(xy 117.051332 -87.8162) (xy 116.99191 -87.808377) (xy 116.934017 -87.792864) (xy 116.878644 -87.769928)
			(xy 116.826738 -87.739961) (xy 116.779188 -87.703474) (xy 116.736808 -87.661094) (xy 116.700321 -87.613544)
			(xy 116.670354 -87.561638) (xy 116.647418 -87.506265) (xy 116.631905 -87.448372) (xy 116.624082 -87.38895)
			(xy 116.623592 -87.358982) (xy 4.297613 -87.358982) (xy 4.299703 -87.377516) (xy 4.307605 -87.517994)
			(xy 4.308094 -87.588344) (xy 4.308094 -88.006187) (xy 238.124409 -88.006187) (xy 238.124409 -87.946213)
			(xy 238.132238 -87.886751) (xy 238.147762 -87.82882) (xy 238.170714 -87.773411) (xy 238.200704 -87.721472)
			(xy 238.237216 -87.673892) (xy 238.279627 -87.631486) (xy 238.32721 -87.594978) (xy 238.379152 -87.564994)
			(xy 238.434563 -87.542047) (xy 238.492496 -87.526529) (xy 238.551959 -87.518706) (xy 238.581946 -87.51824)
			(xy 239.445546 -87.51824) (xy 239.475528 -87.518729) (xy 239.53498 -87.526561) (xy 239.5929 -87.542086)
			(xy 239.648299 -87.565038) (xy 239.700228 -87.595024) (xy 239.747799 -87.631531) (xy 239.790199 -87.673935)
			(xy 239.826701 -87.72151) (xy 239.856682 -87.773442) (xy 239.879628 -87.828843) (xy 239.895148 -87.886765)
			(xy 239.902974 -87.946217) (xy 239.902974 -88.006183) (xy 239.895148 -88.065635) (xy 239.879628 -88.123557)
			(xy 239.870911 -88.144604) (xy 345.879928 -88.144604) (xy 345.879928 -87.281004) (xy 345.880418 -87.25102)
			(xy 345.888246 -87.191564) (xy 345.903767 -87.133639) (xy 345.926716 -87.078235) (xy 345.9567 -87.026301)
			(xy 345.993206 -86.978725) (xy 346.035611 -86.93632) (xy 346.083187 -86.899814) (xy 346.135121 -86.86983)
			(xy 346.190525 -86.846881) (xy 346.24845 -86.83136) (xy 346.307906 -86.823532) (xy 346.367874 -86.823532)
			(xy 346.42733 -86.83136) (xy 346.485255 -86.846881) (xy 346.540659 -86.86983) (xy 346.592593 -86.899814)
			(xy 346.640169 -86.93632) (xy 346.682574 -86.978725) (xy 346.71908 -87.026301) (xy 346.749064 -87.078235)
			(xy 346.772013 -87.133639) (xy 346.787534 -87.191564) (xy 346.795362 -87.25102) (xy 346.795852 -87.281004)
			(xy 346.795852 -88.144604) (xy 346.795362 -88.174588) (xy 346.787534 -88.234044) (xy 346.772013 -88.291969)
			(xy 346.749064 -88.347373) (xy 346.71908 -88.399307) (xy 346.682574 -88.446883) (xy 346.640169 -88.489288)
			(xy 346.592593 -88.525794) (xy 346.540659 -88.555778) (xy 346.485255 -88.578727) (xy 346.42733 -88.594248)
			(xy 346.367874 -88.602076) (xy 346.307906 -88.602076) (xy 346.24845 -88.594248) (xy 346.190525 -88.578727)
			(xy 346.135121 -88.555778) (xy 346.083187 -88.525794) (xy 346.035611 -88.489288) (xy 345.993206 -88.446883)
			(xy 345.9567 -88.399307) (xy 345.926716 -88.347373) (xy 345.903767 -88.291969) (xy 345.888246 -88.234044)
			(xy 345.880418 -88.174588) (xy 345.879928 -88.144604) (xy 239.870911 -88.144604) (xy 239.856682 -88.178958)
			(xy 239.826701 -88.23089) (xy 239.790199 -88.278465) (xy 239.747799 -88.320869) (xy 239.700228 -88.357376)
			(xy 239.648299 -88.387362) (xy 239.5929 -88.410314) (xy 239.53498 -88.425839) (xy 239.475528 -88.433671)
			(xy 239.445546 -88.434164) (xy 238.581946 -88.434164) (xy 238.551959 -88.433694) (xy 238.492496 -88.425871)
			(xy 238.434563 -88.410353) (xy 238.379152 -88.387406) (xy 238.32721 -88.357422) (xy 238.279627 -88.320914)
			(xy 238.237216 -88.278508) (xy 238.200704 -88.230928) (xy 238.170714 -88.178989) (xy 238.147762 -88.12358)
			(xy 238.132238 -88.065649) (xy 238.124409 -88.006187) (xy 4.308094 -88.006187) (xy 4.308094 -89.358978)
			(xy 117.385592 -89.358978) (xy 117.385592 -88.495378) (xy 117.386082 -88.46541) (xy 117.393905 -88.405988)
			(xy 117.409418 -88.348095) (xy 117.432354 -88.292722) (xy 117.462321 -88.240816) (xy 117.498808 -88.193266)
			(xy 117.541188 -88.150886) (xy 117.588738 -88.114399) (xy 117.640644 -88.084432) (xy 117.696017 -88.061496)
			(xy 117.75391 -88.045983) (xy 117.813332 -88.03816) (xy 117.873268 -88.03816) (xy 117.93269 -88.045983)
			(xy 117.990583 -88.061496) (xy 118.045956 -88.084432) (xy 118.097862 -88.114399) (xy 118.145412 -88.150886)
			(xy 118.187792 -88.193266) (xy 118.224279 -88.240816) (xy 118.254246 -88.292722) (xy 118.277182 -88.348095)
			(xy 118.292695 -88.405988) (xy 118.300518 -88.46541) (xy 118.301008 -88.495378) (xy 118.301008 -89.358978)
			(xy 118.300518 -89.388946) (xy 118.292695 -89.448368) (xy 118.277182 -89.506261) (xy 118.254246 -89.561634)
			(xy 118.224279 -89.61354) (xy 118.187792 -89.66109) (xy 118.145412 -89.70347) (xy 118.097862 -89.739957)
			(xy 118.045956 -89.769924) (xy 117.990583 -89.79286) (xy 117.93269 -89.808373) (xy 117.873268 -89.816196)
			(xy 117.813332 -89.816196) (xy 117.75391 -89.808373) (xy 117.696017 -89.79286) (xy 117.640644 -89.769924)
			(xy 117.588738 -89.739957) (xy 117.541188 -89.70347) (xy 117.498808 -89.66109) (xy 117.462321 -89.61354)
			(xy 117.432354 -89.561634) (xy 117.409418 -89.506261) (xy 117.393905 -89.448368) (xy 117.386082 -89.388946)
			(xy 117.385592 -89.358978) (xy 4.308094 -89.358978) (xy 4.308094 -90.1446) (xy 346.641928 -90.1446)
			(xy 346.641928 -89.281) (xy 346.642418 -89.251016) (xy 346.650246 -89.19156) (xy 346.665767 -89.133635)
			(xy 346.688716 -89.078231) (xy 346.7187 -89.026297) (xy 346.755206 -88.978721) (xy 346.797611 -88.936316)
			(xy 346.845187 -88.89981) (xy 346.897121 -88.869826) (xy 346.952525 -88.846877) (xy 347.01045 -88.831356)
			(xy 347.069906 -88.823528) (xy 347.129874 -88.823528) (xy 347.18933 -88.831356) (xy 347.247255 -88.846877)
			(xy 347.302659 -88.869826) (xy 347.354593 -88.89981) (xy 347.402169 -88.936316) (xy 347.444574 -88.978721)
			(xy 347.48108 -89.026297) (xy 347.511064 -89.078231) (xy 347.534013 -89.133635) (xy 347.549534 -89.19156)
			(xy 347.557362 -89.251016) (xy 347.557852 -89.281) (xy 347.557852 -90.1446) (xy 347.557362 -90.174584)
			(xy 347.549534 -90.23404) (xy 347.534013 -90.291965) (xy 347.511064 -90.347369) (xy 347.48108 -90.399303)
			(xy 347.444574 -90.446879) (xy 347.402169 -90.489284) (xy 347.354593 -90.52579) (xy 347.302659 -90.555774)
			(xy 347.247255 -90.578723) (xy 347.18933 -90.594244) (xy 347.129874 -90.602072) (xy 347.069906 -90.602072)
			(xy 347.01045 -90.594244) (xy 346.952525 -90.578723) (xy 346.897121 -90.555774) (xy 346.845187 -90.52579)
			(xy 346.797611 -90.489284) (xy 346.755206 -90.446879) (xy 346.7187 -90.399303) (xy 346.688716 -90.347369)
			(xy 346.665767 -90.291965) (xy 346.650246 -90.23404) (xy 346.642418 -90.174584) (xy 346.641928 -90.1446)
			(xy 4.308094 -90.1446) (xy 4.308094 -94.088485) (xy 109.149614 -94.088485) (xy 109.149614 -94.028515)
			(xy 109.157442 -93.969058) (xy 109.172963 -93.911131) (xy 109.195912 -93.855726) (xy 109.225897 -93.80379)
			(xy 109.262405 -93.756213) (xy 109.30481 -93.713807) (xy 109.352387 -93.6773) (xy 109.404322 -93.647314)
			(xy 109.459727 -93.624364) (xy 109.517654 -93.608843) (xy 109.577111 -93.601014) (xy 109.607096 -93.600524)
			(xy 110.470696 -93.600524) (xy 110.500681 -93.601021) (xy 110.560138 -93.608848) (xy 110.618064 -93.624369)
			(xy 110.673469 -93.647318) (xy 110.725405 -93.677303) (xy 110.772982 -93.71381) (xy 110.815388 -93.756215)
			(xy 110.851895 -93.803792) (xy 110.88188 -93.855727) (xy 110.90483 -93.911132) (xy 110.920351 -93.969058)
			(xy 110.928179 -94.028515) (xy 110.928179 -94.088485) (xy 110.920351 -94.147942) (xy 110.90483 -94.205868)
			(xy 110.88188 -94.261273) (xy 110.851895 -94.313208) (xy 110.815388 -94.360785) (xy 110.772982 -94.40319)
			(xy 110.725405 -94.439697) (xy 110.673469 -94.469682) (xy 110.618064 -94.492631) (xy 110.560138 -94.508152)
			(xy 110.500681 -94.515979) (xy 110.470696 -94.516448) (xy 109.607096 -94.516448) (xy 109.577111 -94.515986)
			(xy 109.517654 -94.508157) (xy 109.459727 -94.492636) (xy 109.404322 -94.469686) (xy 109.352387 -94.4397)
			(xy 109.30481 -94.403193) (xy 109.262405 -94.360787) (xy 109.225897 -94.31321) (xy 109.195912 -94.261274)
			(xy 109.172963 -94.205869) (xy 109.157442 -94.147942) (xy 109.149614 -94.088485) (xy 4.308094 -94.088485)
			(xy 4.308094 -95.214948) (xy 47.274239 -95.214948) (xy 47.278194 -95.123111) (xy 47.290029 -95.031954)
			(xy 47.309656 -94.942151) (xy 47.33693 -94.854369) (xy 47.37165 -94.769255) (xy 47.413558 -94.687442)
			(xy 47.462344 -94.609534) (xy 47.517647 -94.536109) (xy 47.579057 -94.467709) (xy 47.646119 -94.404842)
			(xy 47.718338 -94.347972) (xy 47.795178 -94.297521) (xy 47.876071 -94.253862) (xy 47.960417 -94.217319)
			(xy 48.047593 -94.188162) (xy 48.136952 -94.166608) (xy 48.227833 -94.152814) (xy 48.319564 -94.146884)
			(xy 48.411465 -94.148862) (xy 48.502856 -94.158733) (xy 48.59306 -94.176423) (xy 48.681409 -94.201803)
			(xy 48.767249 -94.234683) (xy 48.849945 -94.274821) (xy 48.928885 -94.32192) (xy 49.003483 -94.37563)
			(xy 49.073189 -94.435554) (xy 49.137484 -94.501248) (xy 49.195895 -94.572226) (xy 49.247987 -94.647963)
			(xy 49.293376 -94.727898) (xy 49.331726 -94.811438) (xy 49.362751 -94.897966) (xy 49.386224 -94.986841)
			(xy 49.40197 -95.077405) (xy 49.409872 -95.168987) (xy 49.410366 -95.214948) (xy 71.639189 -95.214948)
			(xy 71.643144 -95.123111) (xy 71.654979 -95.031954) (xy 71.674606 -94.942151) (xy 71.70188 -94.854369)
			(xy 71.7366 -94.769255) (xy 71.778508 -94.687442) (xy 71.827294 -94.609534) (xy 71.882597 -94.536109)
			(xy 71.944007 -94.467709) (xy 72.011069 -94.404842) (xy 72.083288 -94.347972) (xy 72.160128 -94.297521)
			(xy 72.241021 -94.253862) (xy 72.325367 -94.217319) (xy 72.412543 -94.188162) (xy 72.501902 -94.166608)
			(xy 72.592783 -94.152814) (xy 72.684514 -94.146884) (xy 72.776415 -94.148862) (xy 72.867806 -94.158733)
			(xy 72.95801 -94.176423) (xy 73.046359 -94.201803) (xy 73.132199 -94.234683) (xy 73.214895 -94.274821)
			(xy 73.293835 -94.32192) (xy 73.368433 -94.37563) (xy 73.438139 -94.435554) (xy 73.502434 -94.501248)
			(xy 73.560845 -94.572226) (xy 73.612937 -94.647963) (xy 73.658326 -94.727898) (xy 73.696676 -94.811438)
			(xy 73.727701 -94.897966) (xy 73.751174 -94.986841) (xy 73.76692 -95.077405) (xy 73.774822 -95.168987)
			(xy 73.775316 -95.214948) (xy 73.774822 -95.260909) (xy 73.774772 -95.261486) (xy 163.375394 -95.261486)
			(xy 163.375394 -95.168314) (xy 163.383515 -95.075496) (xy 163.399694 -94.983738) (xy 163.423808 -94.893741)
			(xy 163.455675 -94.806187) (xy 163.495052 -94.721744) (xy 163.541638 -94.641054) (xy 163.595079 -94.564731)
			(xy 163.654969 -94.493357) (xy 163.720852 -94.427473) (xy 163.792226 -94.367583) (xy 163.868549 -94.314141)
			(xy 163.949238 -94.267554) (xy 164.033681 -94.228178) (xy 164.121235 -94.19631) (xy 164.211233 -94.172195)
			(xy 164.30299 -94.156015) (xy 164.395808 -94.147894) (xy 164.442394 -94.147386) (xy 164.442648 -94.147386)
			(xy 164.489237 -94.1478) (xy 164.582061 -94.155925) (xy 164.673824 -94.172109) (xy 164.763826 -94.196229)
			(xy 164.851385 -94.228101) (xy 164.935832 -94.267483) (xy 165.016526 -94.314074) (xy 165.092852 -94.367522)
			(xy 165.164229 -94.427418) (xy 165.230115 -94.493306) (xy 165.290008 -94.564687) (xy 165.343451 -94.641015)
			(xy 165.390039 -94.721711) (xy 165.429417 -94.80616) (xy 165.461286 -94.893719) (xy 165.485401 -94.983723)
			(xy 165.501581 -95.075487) (xy 165.509702 -95.168311) (xy 165.509702 -95.214948) (xy 187.739796 -95.214948)
			(xy 187.743748 -95.123155) (xy 187.755578 -95.032041) (xy 187.775195 -94.942281) (xy 187.802457 -94.85454)
			(xy 187.83716 -94.769468) (xy 187.879048 -94.687693) (xy 187.927811 -94.609822) (xy 187.983087 -94.536432)
			(xy 188.044468 -94.468065) (xy 188.111499 -94.405227) (xy 188.183683 -94.348385) (xy 188.260487 -94.297958)
			(xy 188.341341 -94.25432) (xy 188.425647 -94.217794) (xy 188.512781 -94.188651) (xy 188.602098 -94.167106)
			(xy 188.692936 -94.15332) (xy 188.784623 -94.147393) (xy 188.87648 -94.14937) (xy 188.967828 -94.159236)
			(xy 189.057988 -94.176918) (xy 189.146296 -94.202285) (xy 189.232095 -94.23515) (xy 189.314752 -94.275269)
			(xy 189.393654 -94.322345) (xy 189.468217 -94.376029) (xy 189.537889 -94.435925) (xy 189.602154 -94.501588)
			(xy 189.660537 -94.572532) (xy 189.712604 -94.648233) (xy 189.757972 -94.72813) (xy 189.796303 -94.81163)
			(xy 189.827314 -94.898117) (xy 189.850775 -94.98695) (xy 189.866514 -95.07747) (xy 189.874412 -95.169009)
			(xy 189.874906 -95.214948) (xy 279.474181 -95.214948) (xy 279.478136 -95.123111) (xy 279.489971 -95.031954)
			(xy 279.509598 -94.942151) (xy 279.536872 -94.854369) (xy 279.571592 -94.769255) (xy 279.6135 -94.687442)
			(xy 279.662286 -94.609534) (xy 279.717589 -94.536109) (xy 279.778999 -94.467709) (xy 279.846061 -94.404842)
			(xy 279.91828 -94.347972) (xy 279.99512 -94.297521) (xy 280.076013 -94.253862) (xy 280.160359 -94.217319)
			(xy 280.247535 -94.188162) (xy 280.336894 -94.166608) (xy 280.427775 -94.152814) (xy 280.519506 -94.146884)
			(xy 280.611407 -94.148862) (xy 280.702798 -94.158733) (xy 280.793002 -94.176423) (xy 280.881351 -94.201803)
			(xy 280.967191 -94.234683) (xy 281.049887 -94.274821) (xy 281.128827 -94.32192) (xy 281.203425 -94.37563)
			(xy 281.273131 -94.435554) (xy 281.337426 -94.501248) (xy 281.395837 -94.572226) (xy 281.447929 -94.647963)
			(xy 281.493318 -94.727898) (xy 281.531668 -94.811438) (xy 281.562693 -94.897966) (xy 281.586166 -94.986841)
			(xy 281.601912 -95.077405) (xy 281.609814 -95.168987) (xy 281.610308 -95.214948) (xy 303.839131 -95.214948)
			(xy 303.843086 -95.123111) (xy 303.854921 -95.031954) (xy 303.874548 -94.942151) (xy 303.901822 -94.854369)
			(xy 303.936542 -94.769255) (xy 303.97845 -94.687442) (xy 304.027236 -94.609534) (xy 304.082539 -94.536109)
			(xy 304.143949 -94.467709) (xy 304.211011 -94.404842) (xy 304.28323 -94.347972) (xy 304.36007 -94.297521)
			(xy 304.440963 -94.253862) (xy 304.525309 -94.217319) (xy 304.612485 -94.188162) (xy 304.701844 -94.166608)
			(xy 304.792725 -94.152814) (xy 304.884456 -94.146884) (xy 304.976357 -94.148862) (xy 305.067748 -94.158733)
			(xy 305.157952 -94.176423) (xy 305.246301 -94.201803) (xy 305.332141 -94.234683) (xy 305.414837 -94.274821)
			(xy 305.493777 -94.32192) (xy 305.568375 -94.37563) (xy 305.638081 -94.435554) (xy 305.702376 -94.501248)
			(xy 305.760787 -94.572226) (xy 305.812879 -94.647963) (xy 305.858268 -94.727898) (xy 305.896618 -94.811438)
			(xy 305.91901 -94.87389) (xy 338.405861 -94.87389) (xy 338.405861 -94.81391) (xy 338.413691 -94.754443)
			(xy 338.429215 -94.696507) (xy 338.45217 -94.641093) (xy 338.482161 -94.58915) (xy 338.518676 -94.541565)
			(xy 338.561089 -94.499155) (xy 338.608676 -94.462643) (xy 338.660622 -94.432655) (xy 338.716037 -94.409705)
			(xy 338.773975 -94.394184) (xy 338.833442 -94.386359) (xy 338.863432 -94.385892) (xy 339.727032 -94.385892)
			(xy 339.757012 -94.386476) (xy 339.816458 -94.394306) (xy 339.874374 -94.409828) (xy 339.929769 -94.432777)
			(xy 339.981694 -94.462759) (xy 340.029262 -94.499262) (xy 340.071659 -94.541662) (xy 340.108159 -94.589232)
			(xy 340.138137 -94.64116) (xy 340.161082 -94.696556) (xy 340.1766 -94.754473) (xy 340.184426 -94.81392)
			(xy 340.184426 -94.87388) (xy 340.1766 -94.933327) (xy 340.161082 -94.991244) (xy 340.138137 -95.04664)
			(xy 340.108159 -95.098568) (xy 340.071659 -95.146138) (xy 340.029262 -95.188538) (xy 339.994846 -95.214948)
			(xy 395.574279 -95.214948) (xy 395.578234 -95.123111) (xy 395.590069 -95.031954) (xy 395.609696 -94.942151)
			(xy 395.63697 -94.854369) (xy 395.67169 -94.769255) (xy 395.713598 -94.687442) (xy 395.762384 -94.609534)
			(xy 395.817687 -94.536109) (xy 395.879097 -94.467709) (xy 395.946159 -94.404842) (xy 396.018378 -94.347972)
			(xy 396.095218 -94.297521) (xy 396.176111 -94.253862) (xy 396.260457 -94.217319) (xy 396.347633 -94.188162)
			(xy 396.436992 -94.166608) (xy 396.527873 -94.152814) (xy 396.619604 -94.146884) (xy 396.711505 -94.148862)
			(xy 396.802896 -94.158733) (xy 396.8931 -94.176423) (xy 396.981449 -94.201803) (xy 397.067289 -94.234683)
			(xy 397.149985 -94.274821) (xy 397.228925 -94.32192) (xy 397.303523 -94.37563) (xy 397.373229 -94.435554)
			(xy 397.437524 -94.501248) (xy 397.495935 -94.572226) (xy 397.548027 -94.647963) (xy 397.593416 -94.727898)
			(xy 397.631766 -94.811438) (xy 397.662791 -94.897966) (xy 397.686264 -94.986841) (xy 397.70201 -95.077405)
			(xy 397.709912 -95.168987) (xy 397.710406 -95.214948) (xy 419.939229 -95.214948) (xy 419.943184 -95.123111)
			(xy 419.955019 -95.031954) (xy 419.974646 -94.942151) (xy 420.00192 -94.854369) (xy 420.03664 -94.769255)
			(xy 420.078548 -94.687442) (xy 420.127334 -94.609534) (xy 420.182637 -94.536109) (xy 420.244047 -94.467709)
			(xy 420.311109 -94.404842) (xy 420.383328 -94.347972) (xy 420.460168 -94.297521) (xy 420.541061 -94.253862)
			(xy 420.625407 -94.217319) (xy 420.712583 -94.188162) (xy 420.801942 -94.166608) (xy 420.892823 -94.152814)
			(xy 420.984554 -94.146884) (xy 421.076455 -94.148862) (xy 421.167846 -94.158733) (xy 421.25805 -94.176423)
			(xy 421.346399 -94.201803) (xy 421.432239 -94.234683) (xy 421.514935 -94.274821) (xy 421.593875 -94.32192)
			(xy 421.668473 -94.37563) (xy 421.738179 -94.435554) (xy 421.802474 -94.501248) (xy 421.860885 -94.572226)
			(xy 421.912977 -94.647963) (xy 421.958366 -94.727898) (xy 421.996716 -94.811438) (xy 422.027741 -94.897966)
			(xy 422.051214 -94.986841) (xy 422.06696 -95.077405) (xy 422.074862 -95.168987) (xy 422.075356 -95.214948)
			(xy 422.074862 -95.260909) (xy 422.06696 -95.352491) (xy 422.051214 -95.443055) (xy 422.027741 -95.53193)
			(xy 421.996716 -95.618458) (xy 421.958366 -95.701998) (xy 421.912977 -95.781933) (xy 421.860885 -95.85767)
			(xy 421.802474 -95.928648) (xy 421.738179 -95.994342) (xy 421.668473 -96.054266) (xy 421.593875 -96.107976)
			(xy 421.514935 -96.155075) (xy 421.432239 -96.195213) (xy 421.346399 -96.228093) (xy 421.25805 -96.253473)
			(xy 421.167846 -96.271163) (xy 421.076455 -96.281034) (xy 420.984554 -96.283012) (xy 420.892823 -96.277082)
			(xy 420.801942 -96.263288) (xy 420.712583 -96.241734) (xy 420.625407 -96.212577) (xy 420.541061 -96.176034)
			(xy 420.460168 -96.132375) (xy 420.383328 -96.081924) (xy 420.311109 -96.025054) (xy 420.244047 -95.962187)
			(xy 420.182637 -95.893787) (xy 420.127334 -95.820362) (xy 420.078548 -95.742454) (xy 420.03664 -95.660641)
			(xy 420.00192 -95.575527) (xy 419.974646 -95.487745) (xy 419.955019 -95.397942) (xy 419.943184 -95.306785)
			(xy 419.939229 -95.214948) (xy 397.710406 -95.214948) (xy 397.709912 -95.260909) (xy 397.70201 -95.352491)
			(xy 397.686264 -95.443055) (xy 397.662791 -95.53193) (xy 397.631766 -95.618458) (xy 397.593416 -95.701998)
			(xy 397.548027 -95.781933) (xy 397.495935 -95.85767) (xy 397.437524 -95.928648) (xy 397.373229 -95.994342)
			(xy 397.303523 -96.054266) (xy 397.228925 -96.107976) (xy 397.149985 -96.155075) (xy 397.067289 -96.195213)
			(xy 396.981449 -96.228093) (xy 396.8931 -96.253473) (xy 396.802896 -96.271163) (xy 396.711505 -96.281034)
			(xy 396.619604 -96.283012) (xy 396.527873 -96.277082) (xy 396.436992 -96.263288) (xy 396.347633 -96.241734)
			(xy 396.260457 -96.212577) (xy 396.176111 -96.176034) (xy 396.095218 -96.132375) (xy 396.018378 -96.081924)
			(xy 395.946159 -96.025054) (xy 395.879097 -95.962187) (xy 395.817687 -95.893787) (xy 395.762384 -95.820362)
			(xy 395.713598 -95.742454) (xy 395.67169 -95.660641) (xy 395.63697 -95.575527) (xy 395.609696 -95.487745)
			(xy 395.590069 -95.397942) (xy 395.578234 -95.306785) (xy 395.574279 -95.214948) (xy 339.994846 -95.214948)
			(xy 339.981694 -95.225041) (xy 339.929769 -95.255023) (xy 339.874374 -95.277972) (xy 339.816458 -95.293494)
			(xy 339.757012 -95.301324) (xy 339.727032 -95.301816) (xy 338.863432 -95.301816) (xy 338.833442 -95.301441)
			(xy 338.773975 -95.293616) (xy 338.716037 -95.278095) (xy 338.660622 -95.255145) (xy 338.608676 -95.225157)
			(xy 338.561089 -95.188645) (xy 338.518676 -95.146235) (xy 338.482161 -95.09865) (xy 338.45217 -95.046707)
			(xy 338.429215 -94.991293) (xy 338.413691 -94.933357) (xy 338.405861 -94.87389) (xy 305.91901 -94.87389)
			(xy 305.927643 -94.897966) (xy 305.951116 -94.986841) (xy 305.966862 -95.077405) (xy 305.974764 -95.168987)
			(xy 305.975258 -95.214948) (xy 305.974764 -95.260909) (xy 305.966862 -95.352491) (xy 305.951116 -95.443055)
			(xy 305.927643 -95.53193) (xy 305.896618 -95.618458) (xy 305.858268 -95.701998) (xy 305.812879 -95.781933)
			(xy 305.760787 -95.85767) (xy 305.702376 -95.928648) (xy 305.638081 -95.994342) (xy 305.568375 -96.054266)
			(xy 305.493777 -96.107976) (xy 305.414837 -96.155075) (xy 305.332141 -96.195213) (xy 305.246301 -96.228093)
			(xy 305.157952 -96.253473) (xy 305.067748 -96.271163) (xy 304.976357 -96.281034) (xy 304.884456 -96.283012)
			(xy 304.792725 -96.277082) (xy 304.701844 -96.263288) (xy 304.612485 -96.241734) (xy 304.525309 -96.212577)
			(xy 304.440963 -96.176034) (xy 304.36007 -96.132375) (xy 304.28323 -96.081924) (xy 304.211011 -96.025054)
			(xy 304.143949 -95.962187) (xy 304.082539 -95.893787) (xy 304.027236 -95.820362) (xy 303.97845 -95.742454)
			(xy 303.936542 -95.660641) (xy 303.901822 -95.575527) (xy 303.874548 -95.487745) (xy 303.854921 -95.397942)
			(xy 303.843086 -95.306785) (xy 303.839131 -95.214948) (xy 281.610308 -95.214948) (xy 281.609814 -95.260909)
			(xy 281.601912 -95.352491) (xy 281.586166 -95.443055) (xy 281.562693 -95.53193) (xy 281.531668 -95.618458)
			(xy 281.493318 -95.701998) (xy 281.447929 -95.781933) (xy 281.395837 -95.85767) (xy 281.337426 -95.928648)
			(xy 281.273131 -95.994342) (xy 281.203425 -96.054266) (xy 281.128827 -96.107976) (xy 281.049887 -96.155075)
			(xy 280.967191 -96.195213) (xy 280.881351 -96.228093) (xy 280.793002 -96.253473) (xy 280.702798 -96.271163)
			(xy 280.611407 -96.281034) (xy 280.519506 -96.283012) (xy 280.427775 -96.277082) (xy 280.336894 -96.263288)
			(xy 280.247535 -96.241734) (xy 280.160359 -96.212577) (xy 280.076013 -96.176034) (xy 279.99512 -96.132375)
			(xy 279.91828 -96.081924) (xy 279.846061 -96.025054) (xy 279.778999 -95.962187) (xy 279.717589 -95.893787)
			(xy 279.662286 -95.820362) (xy 279.6135 -95.742454) (xy 279.571592 -95.660641) (xy 279.536872 -95.575527)
			(xy 279.509598 -95.487745) (xy 279.489971 -95.397942) (xy 279.478136 -95.306785) (xy 279.474181 -95.214948)
			(xy 189.874906 -95.214948) (xy 189.874412 -95.260887) (xy 189.866514 -95.352426) (xy 189.850775 -95.442946)
			(xy 189.827314 -95.531779) (xy 189.796303 -95.618266) (xy 189.757972 -95.701766) (xy 189.712604 -95.781663)
			(xy 189.660537 -95.857364) (xy 189.602154 -95.928308) (xy 189.537889 -95.993971) (xy 189.468217 -96.053867)
			(xy 189.393654 -96.107551) (xy 189.314752 -96.154627) (xy 189.232095 -96.194746) (xy 189.146296 -96.227611)
			(xy 189.057988 -96.252978) (xy 188.967828 -96.27066) (xy 188.87648 -96.280526) (xy 188.784623 -96.282503)
			(xy 188.692936 -96.276576) (xy 188.602098 -96.26279) (xy 188.512781 -96.241245) (xy 188.425647 -96.212102)
			(xy 188.341341 -96.175576) (xy 188.260487 -96.131938) (xy 188.183683 -96.081511) (xy 188.111499 -96.024669)
			(xy 188.044468 -95.961831) (xy 187.983087 -95.893464) (xy 187.927811 -95.820074) (xy 187.879048 -95.742203)
			(xy 187.83716 -95.660428) (xy 187.802457 -95.575356) (xy 187.775195 -95.487615) (xy 187.755578 -95.397855)
			(xy 187.743748 -95.306741) (xy 187.739796 -95.214948) (xy 165.509702 -95.214948) (xy 165.509702 -95.261489)
			(xy 165.501581 -95.354313) (xy 165.485401 -95.446077) (xy 165.461286 -95.536081) (xy 165.429417 -95.62364)
			(xy 165.390039 -95.708089) (xy 165.343451 -95.788785) (xy 165.290008 -95.865113) (xy 165.230115 -95.936494)
			(xy 165.164229 -96.002382) (xy 165.092852 -96.062278) (xy 165.016526 -96.115726) (xy 164.935832 -96.162317)
			(xy 164.851385 -96.201699) (xy 164.763826 -96.233571) (xy 164.673824 -96.257691) (xy 164.582061 -96.273875)
			(xy 164.489237 -96.282) (xy 164.442648 -96.28251) (xy 164.442394 -96.28251) (xy 164.395808 -96.281906)
			(xy 164.30299 -96.273785) (xy 164.211233 -96.257605) (xy 164.121235 -96.23349) (xy 164.033681 -96.201622)
			(xy 163.949238 -96.162246) (xy 163.868549 -96.115659) (xy 163.792226 -96.062217) (xy 163.720852 -96.002327)
			(xy 163.654969 -95.936443) (xy 163.595079 -95.865069) (xy 163.541638 -95.788746) (xy 163.495052 -95.708056)
			(xy 163.455675 -95.623613) (xy 163.423808 -95.536059) (xy 163.399694 -95.446062) (xy 163.383515 -95.354304)
			(xy 163.375394 -95.261486) (xy 73.774772 -95.261486) (xy 73.76692 -95.352491) (xy 73.751174 -95.443055)
			(xy 73.727701 -95.53193) (xy 73.696676 -95.618458) (xy 73.658326 -95.701998) (xy 73.612937 -95.781933)
			(xy 73.560845 -95.85767) (xy 73.502434 -95.928648) (xy 73.438139 -95.994342) (xy 73.368433 -96.054266)
			(xy 73.293835 -96.107976) (xy 73.214895 -96.155075) (xy 73.132199 -96.195213) (xy 73.046359 -96.228093)
			(xy 72.95801 -96.253473) (xy 72.867806 -96.271163) (xy 72.776415 -96.281034) (xy 72.684514 -96.283012)
			(xy 72.592783 -96.277082) (xy 72.501902 -96.263288) (xy 72.412543 -96.241734) (xy 72.325367 -96.212577)
			(xy 72.241021 -96.176034) (xy 72.160128 -96.132375) (xy 72.083288 -96.081924) (xy 72.011069 -96.025054)
			(xy 71.944007 -95.962187) (xy 71.882597 -95.893787) (xy 71.827294 -95.820362) (xy 71.778508 -95.742454)
			(xy 71.7366 -95.660641) (xy 71.70188 -95.575527) (xy 71.674606 -95.487745) (xy 71.654979 -95.397942)
			(xy 71.643144 -95.306785) (xy 71.639189 -95.214948) (xy 49.410366 -95.214948) (xy 49.409872 -95.260909)
			(xy 49.40197 -95.352491) (xy 49.386224 -95.443055) (xy 49.362751 -95.53193) (xy 49.331726 -95.618458)
			(xy 49.293376 -95.701998) (xy 49.247987 -95.781933) (xy 49.195895 -95.85767) (xy 49.137484 -95.928648)
			(xy 49.073189 -95.994342) (xy 49.003483 -96.054266) (xy 48.928885 -96.107976) (xy 48.849945 -96.155075)
			(xy 48.767249 -96.195213) (xy 48.681409 -96.228093) (xy 48.59306 -96.253473) (xy 48.502856 -96.271163)
			(xy 48.411465 -96.281034) (xy 48.319564 -96.283012) (xy 48.227833 -96.277082) (xy 48.136952 -96.263288)
			(xy 48.047593 -96.241734) (xy 47.960417 -96.212577) (xy 47.876071 -96.176034) (xy 47.795178 -96.132375)
			(xy 47.718338 -96.081924) (xy 47.646119 -96.025054) (xy 47.579057 -95.962187) (xy 47.517647 -95.893787)
			(xy 47.462344 -95.820362) (xy 47.413558 -95.742454) (xy 47.37165 -95.660641) (xy 47.33693 -95.575527)
			(xy 47.309656 -95.487745) (xy 47.290029 -95.397942) (xy 47.278194 -95.306785) (xy 47.274239 -95.214948)
			(xy 4.308094 -95.214948) (xy 4.308094 -98.766863) (xy 206.090008 -98.766863) (xy 206.090008 -98.633301)
			(xy 206.098072 -98.499983) (xy 206.114172 -98.367395) (xy 206.138247 -98.236021) (xy 206.17021 -98.10634)
			(xy 206.209945 -97.978826) (xy 206.257307 -97.853943) (xy 206.312122 -97.732148) (xy 206.374192 -97.613885)
			(xy 206.443288 -97.499586) (xy 206.51916 -97.389666) (xy 206.60153 -97.284529) (xy 206.690098 -97.184556)
			(xy 206.78454 -97.090114) (xy 206.884513 -97.001546) (xy 206.98965 -96.919176) (xy 207.09957 -96.843304)
			(xy 207.213869 -96.774208) (xy 207.332132 -96.712138) (xy 207.453927 -96.657323) (xy 207.57881 -96.609961)
			(xy 207.706324 -96.570226) (xy 207.836005 -96.538263) (xy 207.967379 -96.514188) (xy 208.099967 -96.498088)
			(xy 208.233285 -96.490024) (xy 208.366847 -96.490024) (xy 208.500165 -96.498088) (xy 208.632753 -96.514188)
			(xy 208.764127 -96.538263) (xy 208.893808 -96.570226) (xy 209.021322 -96.609961) (xy 209.146205 -96.657323)
			(xy 209.268 -96.712138) (xy 209.386263 -96.774208) (xy 209.500562 -96.843304) (xy 209.610482 -96.919176)
			(xy 209.715619 -97.001546) (xy 209.815592 -97.090114) (xy 209.910034 -97.184556) (xy 209.998602 -97.284529)
			(xy 210.080972 -97.389666) (xy 210.156844 -97.499586) (xy 210.22594 -97.613885) (xy 210.28801 -97.732148)
			(xy 210.342825 -97.853943) (xy 210.390187 -97.978826) (xy 210.429922 -98.10634) (xy 210.461885 -98.236021)
			(xy 210.48596 -98.367395) (xy 210.50206 -98.499983) (xy 210.510124 -98.633301) (xy 210.510628 -98.700082)
			(xy 210.510124 -98.766863) (xy 257.089906 -98.766863) (xy 257.089906 -98.633301) (xy 257.09797 -98.499983)
			(xy 257.11407 -98.367395) (xy 257.138145 -98.236021) (xy 257.170108 -98.10634) (xy 257.209843 -97.978826)
			(xy 257.257205 -97.853943) (xy 257.31202 -97.732148) (xy 257.37409 -97.613885) (xy 257.443186 -97.499586)
			(xy 257.519058 -97.389666) (xy 257.601428 -97.284529) (xy 257.689996 -97.184556) (xy 257.784438 -97.090114)
			(xy 257.884411 -97.001546) (xy 257.989548 -96.919176) (xy 258.099468 -96.843304) (xy 258.213767 -96.774208)
			(xy 258.33203 -96.712138) (xy 258.453825 -96.657323) (xy 258.578708 -96.609961) (xy 258.706222 -96.570226)
			(xy 258.835903 -96.538263) (xy 258.967277 -96.514188) (xy 259.099865 -96.498088) (xy 259.233183 -96.490024)
			(xy 259.366745 -96.490024) (xy 259.500063 -96.498088) (xy 259.632651 -96.514188) (xy 259.764025 -96.538263)
			(xy 259.893706 -96.570226) (xy 260.02122 -96.609961) (xy 260.146103 -96.657323) (xy 260.267898 -96.712138)
			(xy 260.386161 -96.774208) (xy 260.50046 -96.843304) (xy 260.61038 -96.919176) (xy 260.715517 -97.001546)
			(xy 260.81549 -97.090114) (xy 260.909932 -97.184556) (xy 260.9985 -97.284529) (xy 261.08087 -97.389666)
			(xy 261.156742 -97.499586) (xy 261.225838 -97.613885) (xy 261.287908 -97.732148) (xy 261.342723 -97.853943)
			(xy 261.390085 -97.978826) (xy 261.42982 -98.10634) (xy 261.461783 -98.236021) (xy 261.485858 -98.367395)
			(xy 261.501958 -98.499983) (xy 261.510022 -98.633301) (xy 261.510526 -98.700082) (xy 261.510022 -98.766863)
			(xy 261.501958 -98.900181) (xy 261.485858 -99.032769) (xy 261.461783 -99.164143) (xy 261.42982 -99.293824)
			(xy 261.390085 -99.421338) (xy 261.342723 -99.546221) (xy 261.287908 -99.668016) (xy 261.225838 -99.786279)
			(xy 261.156742 -99.900578) (xy 261.08087 -100.010498) (xy 260.9985 -100.115635) (xy 260.943379 -100.177854)
			(xy 269.509748 -100.177854) (xy 269.509748 -99.314254) (xy 269.510238 -99.28427) (xy 269.518066 -99.224814)
			(xy 269.533587 -99.166889) (xy 269.556536 -99.111485) (xy 269.58652 -99.059551) (xy 269.623026 -99.011975)
			(xy 269.665431 -98.96957) (xy 269.713007 -98.933064) (xy 269.764941 -98.90308) (xy 269.820345 -98.880131)
			(xy 269.87827 -98.86461) (xy 269.937726 -98.856782) (xy 269.997694 -98.856782) (xy 270.05715 -98.86461)
			(xy 270.115075 -98.880131) (xy 270.170479 -98.90308) (xy 270.222413 -98.933064) (xy 270.269989 -98.96957)
			(xy 270.312394 -99.011975) (xy 270.3489 -99.059551) (xy 270.378884 -99.111485) (xy 270.401833 -99.166889)
			(xy 270.417354 -99.224814) (xy 270.425182 -99.28427) (xy 270.425672 -99.314254) (xy 270.425672 -100.17633)
			(xy 285.8389 -100.17633) (xy 285.8389 -99.31273) (xy 285.83939 -99.282746) (xy 285.847218 -99.22329)
			(xy 285.862739 -99.165365) (xy 285.885688 -99.109961) (xy 285.915672 -99.058027) (xy 285.952178 -99.010451)
			(xy 285.994583 -98.968046) (xy 286.042159 -98.93154) (xy 286.094093 -98.901556) (xy 286.149497 -98.878607)
			(xy 286.207422 -98.863086) (xy 286.266878 -98.855258) (xy 286.326846 -98.855258) (xy 286.386302 -98.863086)
			(xy 286.444227 -98.878607) (xy 286.499631 -98.901556) (xy 286.551565 -98.93154) (xy 286.599141 -98.968046)
			(xy 286.641546 -99.010451) (xy 286.678052 -99.058027) (xy 286.708036 -99.109961) (xy 286.730985 -99.165365)
			(xy 286.746506 -99.22329) (xy 286.754334 -99.282746) (xy 286.754824 -99.31273) (xy 286.754824 -100.17633)
			(xy 286.754799 -100.177854) (xy 385.6101 -100.177854) (xy 385.6101 -99.314254) (xy 385.61059 -99.284286)
			(xy 385.618413 -99.224864) (xy 385.633926 -99.166971) (xy 385.656862 -99.111598) (xy 385.686829 -99.059692)
			(xy 385.723316 -99.012142) (xy 385.765696 -98.969762) (xy 385.813246 -98.933275) (xy 385.865152 -98.903308)
			(xy 385.920525 -98.880372) (xy 385.978418 -98.864859) (xy 386.03784 -98.857036) (xy 386.097776 -98.857036)
			(xy 386.157198 -98.864859) (xy 386.215091 -98.880372) (xy 386.270464 -98.903308) (xy 386.32237 -98.933275)
			(xy 386.36992 -98.969762) (xy 386.4123 -99.012142) (xy 386.448787 -99.059692) (xy 386.478754 -99.111598)
			(xy 386.50169 -99.166971) (xy 386.517203 -99.224864) (xy 386.525026 -99.284286) (xy 386.525516 -99.314254)
			(xy 386.525516 -100.17633) (xy 401.939252 -100.17633) (xy 401.939252 -99.31273) (xy 401.939742 -99.282762)
			(xy 401.947565 -99.22334) (xy 401.963078 -99.165447) (xy 401.986014 -99.110074) (xy 402.015981 -99.058168)
			(xy 402.052468 -99.010618) (xy 402.094848 -98.968238) (xy 402.142398 -98.931751) (xy 402.194304 -98.901784)
			(xy 402.249677 -98.878848) (xy 402.30757 -98.863335) (xy 402.366992 -98.855512) (xy 402.426928 -98.855512)
			(xy 402.48635 -98.863335) (xy 402.544243 -98.878848) (xy 402.599616 -98.901784) (xy 402.651522 -98.931751)
			(xy 402.699072 -98.968238) (xy 402.741452 -99.010618) (xy 402.777939 -99.058168) (xy 402.807906 -99.110074)
			(xy 402.830842 -99.165447) (xy 402.846355 -99.22334) (xy 402.854178 -99.282762) (xy 402.854668 -99.31273)
			(xy 402.854668 -100.17633) (xy 402.854178 -100.206298) (xy 402.846355 -100.26572) (xy 402.830842 -100.323613)
			(xy 402.807906 -100.378986) (xy 402.777939 -100.430892) (xy 402.741452 -100.478442) (xy 402.699072 -100.520822)
			(xy 402.651522 -100.557309) (xy 402.599616 -100.587276) (xy 402.544243 -100.610212) (xy 402.48635 -100.625725)
			(xy 402.426928 -100.633548) (xy 402.366992 -100.633548) (xy 402.30757 -100.625725) (xy 402.249677 -100.610212)
			(xy 402.194304 -100.587276) (xy 402.142398 -100.557309) (xy 402.094848 -100.520822) (xy 402.052468 -100.478442)
			(xy 402.015981 -100.430892) (xy 401.986014 -100.378986) (xy 401.963078 -100.323613) (xy 401.947565 -100.26572)
			(xy 401.939742 -100.206298) (xy 401.939252 -100.17633) (xy 386.525516 -100.17633) (xy 386.525516 -100.177854)
			(xy 386.525026 -100.207822) (xy 386.517203 -100.267244) (xy 386.50169 -100.325137) (xy 386.478754 -100.38051)
			(xy 386.448787 -100.432416) (xy 386.4123 -100.479966) (xy 386.36992 -100.522346) (xy 386.32237 -100.558833)
			(xy 386.270464 -100.5888) (xy 386.215091 -100.611736) (xy 386.157198 -100.627249) (xy 386.097776 -100.635072)
			(xy 386.03784 -100.635072) (xy 385.978418 -100.627249) (xy 385.920525 -100.611736) (xy 385.865152 -100.5888)
			(xy 385.813246 -100.558833) (xy 385.765696 -100.522346) (xy 385.723316 -100.479966) (xy 385.686829 -100.432416)
			(xy 385.656862 -100.38051) (xy 385.633926 -100.325137) (xy 385.618413 -100.267244) (xy 385.61059 -100.207822)
			(xy 385.6101 -100.177854) (xy 286.754799 -100.177854) (xy 286.754334 -100.206314) (xy 286.746506 -100.26577)
			(xy 286.730985 -100.323695) (xy 286.708036 -100.379099) (xy 286.678052 -100.431033) (xy 286.641546 -100.478609)
			(xy 286.599141 -100.521014) (xy 286.551565 -100.55752) (xy 286.499631 -100.587504) (xy 286.444227 -100.610453)
			(xy 286.386302 -100.625974) (xy 286.326846 -100.633802) (xy 286.266878 -100.633802) (xy 286.207422 -100.625974)
			(xy 286.149497 -100.610453) (xy 286.094093 -100.587504) (xy 286.042159 -100.55752) (xy 285.994583 -100.521014)
			(xy 285.952178 -100.478609) (xy 285.915672 -100.431033) (xy 285.885688 -100.379099) (xy 285.862739 -100.323695)
			(xy 285.847218 -100.26577) (xy 285.83939 -100.206314) (xy 285.8389 -100.17633) (xy 270.425672 -100.17633)
			(xy 270.425672 -100.177854) (xy 270.425182 -100.207838) (xy 270.417354 -100.267294) (xy 270.401833 -100.325219)
			(xy 270.378884 -100.380623) (xy 270.3489 -100.432557) (xy 270.312394 -100.480133) (xy 270.269989 -100.522538)
			(xy 270.222413 -100.559044) (xy 270.170479 -100.589028) (xy 270.115075 -100.611977) (xy 270.05715 -100.627498)
			(xy 269.997694 -100.635326) (xy 269.937726 -100.635326) (xy 269.87827 -100.627498) (xy 269.820345 -100.611977)
			(xy 269.764941 -100.589028) (xy 269.713007 -100.559044) (xy 269.665431 -100.522538) (xy 269.623026 -100.480133)
			(xy 269.58652 -100.432557) (xy 269.556536 -100.380623) (xy 269.533587 -100.325219) (xy 269.518066 -100.267294)
			(xy 269.510238 -100.207838) (xy 269.509748 -100.177854) (xy 260.943379 -100.177854) (xy 260.909932 -100.215608)
			(xy 260.81549 -100.31005) (xy 260.715517 -100.398618) (xy 260.61038 -100.480988) (xy 260.50046 -100.55686)
			(xy 260.386161 -100.625956) (xy 260.267898 -100.688026) (xy 260.146103 -100.742841) (xy 260.02122 -100.790203)
			(xy 259.893706 -100.829938) (xy 259.764025 -100.861901) (xy 259.632651 -100.885976) (xy 259.500063 -100.902076)
			(xy 259.366745 -100.91014) (xy 259.233183 -100.91014) (xy 259.099865 -100.902076) (xy 258.967277 -100.885976)
			(xy 258.835903 -100.861901) (xy 258.706222 -100.829938) (xy 258.578708 -100.790203) (xy 258.453825 -100.742841)
			(xy 258.33203 -100.688026) (xy 258.213767 -100.625956) (xy 258.099468 -100.55686) (xy 257.989548 -100.480988)
			(xy 257.884411 -100.398618) (xy 257.784438 -100.31005) (xy 257.689996 -100.215608) (xy 257.601428 -100.115635)
			(xy 257.519058 -100.010498) (xy 257.443186 -99.900578) (xy 257.37409 -99.786279) (xy 257.31202 -99.668016)
			(xy 257.257205 -99.546221) (xy 257.209843 -99.421338) (xy 257.170108 -99.293824) (xy 257.138145 -99.164143)
			(xy 257.11407 -99.032769) (xy 257.09797 -98.900181) (xy 257.089906 -98.766863) (xy 210.510124 -98.766863)
			(xy 210.50206 -98.900181) (xy 210.48596 -99.032769) (xy 210.461885 -99.164143) (xy 210.429922 -99.293824)
			(xy 210.390187 -99.421338) (xy 210.342825 -99.546221) (xy 210.28801 -99.668016) (xy 210.22594 -99.786279)
			(xy 210.156844 -99.900578) (xy 210.080972 -100.010498) (xy 209.998602 -100.115635) (xy 209.910034 -100.215608)
			(xy 209.815592 -100.31005) (xy 209.715619 -100.398618) (xy 209.610482 -100.480988) (xy 209.500562 -100.55686)
			(xy 209.386263 -100.625956) (xy 209.268 -100.688026) (xy 209.146205 -100.742841) (xy 209.021322 -100.790203)
			(xy 208.893808 -100.829938) (xy 208.764127 -100.861901) (xy 208.632753 -100.885976) (xy 208.500165 -100.902076)
			(xy 208.366847 -100.91014) (xy 208.233285 -100.91014) (xy 208.099967 -100.902076) (xy 207.967379 -100.885976)
			(xy 207.836005 -100.861901) (xy 207.706324 -100.829938) (xy 207.57881 -100.790203) (xy 207.453927 -100.742841)
			(xy 207.332132 -100.688026) (xy 207.213869 -100.625956) (xy 207.09957 -100.55686) (xy 206.98965 -100.480988)
			(xy 206.884513 -100.398618) (xy 206.78454 -100.31005) (xy 206.690098 -100.215608) (xy 206.60153 -100.115635)
			(xy 206.51916 -100.010498) (xy 206.443288 -99.900578) (xy 206.374192 -99.786279) (xy 206.312122 -99.668016)
			(xy 206.257307 -99.546221) (xy 206.209945 -99.421338) (xy 206.17021 -99.293824) (xy 206.138247 -99.164143)
			(xy 206.114172 -99.032769) (xy 206.098072 -98.900181) (xy 206.090008 -98.766863) (xy 4.308094 -98.766863)
			(xy 4.308094 -100.177854) (xy 37.31006 -100.177854) (xy 37.31006 -99.314254) (xy 37.31055 -99.284286)
			(xy 37.318373 -99.224864) (xy 37.333886 -99.166971) (xy 37.356822 -99.111598) (xy 37.386789 -99.059692)
			(xy 37.423276 -99.012142) (xy 37.465656 -98.969762) (xy 37.513206 -98.933275) (xy 37.565112 -98.903308)
			(xy 37.620485 -98.880372) (xy 37.678378 -98.864859) (xy 37.7378 -98.857036) (xy 37.797736 -98.857036)
			(xy 37.857158 -98.864859) (xy 37.915051 -98.880372) (xy 37.970424 -98.903308) (xy 38.02233 -98.933275)
			(xy 38.06988 -98.969762) (xy 38.11226 -99.012142) (xy 38.148747 -99.059692) (xy 38.178714 -99.111598)
			(xy 38.20165 -99.166971) (xy 38.217163 -99.224864) (xy 38.224986 -99.284286) (xy 38.225476 -99.314254)
			(xy 38.225476 -100.17633) (xy 53.639212 -100.17633) (xy 53.639212 -99.31273) (xy 53.639702 -99.282762)
			(xy 53.647525 -99.22334) (xy 53.663038 -99.165447) (xy 53.685974 -99.110074) (xy 53.715941 -99.058168)
			(xy 53.752428 -99.010618) (xy 53.794808 -98.968238) (xy 53.842358 -98.931751) (xy 53.894264 -98.901784)
			(xy 53.949637 -98.878848) (xy 54.00753 -98.863335) (xy 54.066952 -98.855512) (xy 54.126888 -98.855512)
			(xy 54.18631 -98.863335) (xy 54.244203 -98.878848) (xy 54.299576 -98.901784) (xy 54.351482 -98.931751)
			(xy 54.399032 -98.968238) (xy 54.441412 -99.010618) (xy 54.477899 -99.058168) (xy 54.507866 -99.110074)
			(xy 54.530802 -99.165447) (xy 54.546315 -99.22334) (xy 54.554138 -99.282762) (xy 54.554628 -99.31273)
			(xy 54.554628 -100.17633) (xy 54.554603 -100.177854) (xy 153.409904 -100.177854) (xy 153.409904 -99.314254)
			(xy 153.410394 -99.28427) (xy 153.418222 -99.224814) (xy 153.433743 -99.166889) (xy 153.456692 -99.111485)
			(xy 153.486676 -99.059551) (xy 153.523182 -99.011975) (xy 153.565587 -98.96957) (xy 153.613163 -98.933064)
			(xy 153.665097 -98.90308) (xy 153.720501 -98.880131) (xy 153.778426 -98.86461) (xy 153.837882 -98.856782)
			(xy 153.89785 -98.856782) (xy 153.957306 -98.86461) (xy 154.015231 -98.880131) (xy 154.070635 -98.90308)
			(xy 154.122569 -98.933064) (xy 154.170145 -98.96957) (xy 154.21255 -99.011975) (xy 154.249056 -99.059551)
			(xy 154.27904 -99.111485) (xy 154.301989 -99.166889) (xy 154.31751 -99.224814) (xy 154.325338 -99.28427)
			(xy 154.325828 -99.314254) (xy 154.325828 -100.17633) (xy 169.739056 -100.17633) (xy 169.739056 -99.31273)
			(xy 169.739546 -99.282746) (xy 169.747374 -99.22329) (xy 169.762895 -99.165365) (xy 169.785844 -99.109961)
			(xy 169.815828 -99.058027) (xy 169.852334 -99.010451) (xy 169.894739 -98.968046) (xy 169.942315 -98.93154)
			(xy 169.994249 -98.901556) (xy 170.049653 -98.878607) (xy 170.107578 -98.863086) (xy 170.167034 -98.855258)
			(xy 170.227002 -98.855258) (xy 170.286458 -98.863086) (xy 170.344383 -98.878607) (xy 170.399787 -98.901556)
			(xy 170.451721 -98.93154) (xy 170.499297 -98.968046) (xy 170.541702 -99.010451) (xy 170.578208 -99.058027)
			(xy 170.608192 -99.109961) (xy 170.631141 -99.165365) (xy 170.646662 -99.22329) (xy 170.65449 -99.282746)
			(xy 170.65498 -99.31273) (xy 170.65498 -100.17633) (xy 170.65449 -100.206314) (xy 170.646662 -100.26577)
			(xy 170.631141 -100.323695) (xy 170.608192 -100.379099) (xy 170.578208 -100.431033) (xy 170.541702 -100.478609)
			(xy 170.499297 -100.521014) (xy 170.451721 -100.55752) (xy 170.399787 -100.587504) (xy 170.344383 -100.610453)
			(xy 170.286458 -100.625974) (xy 170.227002 -100.633802) (xy 170.167034 -100.633802) (xy 170.107578 -100.625974)
			(xy 170.049653 -100.610453) (xy 169.994249 -100.587504) (xy 169.942315 -100.55752) (xy 169.894739 -100.521014)
			(xy 169.852334 -100.478609) (xy 169.815828 -100.431033) (xy 169.785844 -100.379099) (xy 169.762895 -100.323695)
			(xy 169.747374 -100.26577) (xy 169.739546 -100.206314) (xy 169.739056 -100.17633) (xy 154.325828 -100.17633)
			(xy 154.325828 -100.177854) (xy 154.325338 -100.207838) (xy 154.31751 -100.267294) (xy 154.301989 -100.325219)
			(xy 154.27904 -100.380623) (xy 154.249056 -100.432557) (xy 154.21255 -100.480133) (xy 154.170145 -100.522538)
			(xy 154.122569 -100.559044) (xy 154.070635 -100.589028) (xy 154.015231 -100.611977) (xy 153.957306 -100.627498)
			(xy 153.89785 -100.635326) (xy 153.837882 -100.635326) (xy 153.778426 -100.627498) (xy 153.720501 -100.611977)
			(xy 153.665097 -100.589028) (xy 153.613163 -100.559044) (xy 153.565587 -100.522538) (xy 153.523182 -100.480133)
			(xy 153.486676 -100.432557) (xy 153.456692 -100.380623) (xy 153.433743 -100.325219) (xy 153.418222 -100.267294)
			(xy 153.410394 -100.207838) (xy 153.409904 -100.177854) (xy 54.554603 -100.177854) (xy 54.554138 -100.206298)
			(xy 54.546315 -100.26572) (xy 54.530802 -100.323613) (xy 54.507866 -100.378986) (xy 54.477899 -100.430892)
			(xy 54.441412 -100.478442) (xy 54.399032 -100.520822) (xy 54.351482 -100.557309) (xy 54.299576 -100.587276)
			(xy 54.244203 -100.610212) (xy 54.18631 -100.625725) (xy 54.126888 -100.633548) (xy 54.066952 -100.633548)
			(xy 54.00753 -100.625725) (xy 53.949637 -100.610212) (xy 53.894264 -100.587276) (xy 53.842358 -100.557309)
			(xy 53.794808 -100.520822) (xy 53.752428 -100.478442) (xy 53.715941 -100.430892) (xy 53.685974 -100.378986)
			(xy 53.663038 -100.323613) (xy 53.647525 -100.26572) (xy 53.639702 -100.206298) (xy 53.639212 -100.17633)
			(xy 38.225476 -100.17633) (xy 38.225476 -100.177854) (xy 38.224986 -100.207822) (xy 38.217163 -100.267244)
			(xy 38.20165 -100.325137) (xy 38.178714 -100.38051) (xy 38.148747 -100.432416) (xy 38.11226 -100.479966)
			(xy 38.06988 -100.522346) (xy 38.02233 -100.558833) (xy 37.970424 -100.5888) (xy 37.915051 -100.611736)
			(xy 37.857158 -100.627249) (xy 37.797736 -100.635072) (xy 37.7378 -100.635072) (xy 37.678378 -100.627249)
			(xy 37.620485 -100.611736) (xy 37.565112 -100.5888) (xy 37.513206 -100.558833) (xy 37.465656 -100.522346)
			(xy 37.423276 -100.479966) (xy 37.386789 -100.432416) (xy 37.356822 -100.38051) (xy 37.333886 -100.325137)
			(xy 37.318373 -100.267244) (xy 37.31055 -100.207822) (xy 37.31006 -100.177854) (xy 4.308094 -100.177854)
			(xy 4.308094 -101.984302) (xy 35.277552 -101.984302) (xy 35.277552 -101.120702) (xy 35.278042 -101.090734)
			(xy 35.285865 -101.031312) (xy 35.301378 -100.973419) (xy 35.324314 -100.918046) (xy 35.354281 -100.86614)
			(xy 35.390768 -100.81859) (xy 35.433148 -100.77621) (xy 35.480698 -100.739723) (xy 35.532604 -100.709756)
			(xy 35.587977 -100.68682) (xy 35.64587 -100.671307) (xy 35.705292 -100.663484) (xy 35.765228 -100.663484)
			(xy 35.82465 -100.671307) (xy 35.882543 -100.68682) (xy 35.937916 -100.709756) (xy 35.989822 -100.739723)
			(xy 36.037372 -100.77621) (xy 36.079752 -100.81859) (xy 36.116239 -100.86614) (xy 36.146206 -100.918046)
			(xy 36.169142 -100.973419) (xy 36.184655 -101.031312) (xy 36.192478 -101.090734) (xy 36.192968 -101.120702)
			(xy 36.192968 -101.976428) (xy 51.785012 -101.976428) (xy 51.785012 -101.112828) (xy 51.785502 -101.08286)
			(xy 51.793325 -101.023438) (xy 51.808838 -100.965545) (xy 51.831774 -100.910172) (xy 51.861741 -100.858266)
			(xy 51.898228 -100.810716) (xy 51.940608 -100.768336) (xy 51.988158 -100.731849) (xy 52.040064 -100.701882)
			(xy 52.095437 -100.678946) (xy 52.15333 -100.663433) (xy 52.212752 -100.65561) (xy 52.272688 -100.65561)
			(xy 52.33211 -100.663433) (xy 52.390003 -100.678946) (xy 52.445376 -100.701882) (xy 52.497282 -100.731849)
			(xy 52.544832 -100.768336) (xy 52.587212 -100.810716) (xy 52.623699 -100.858266) (xy 52.653666 -100.910172)
			(xy 52.676602 -100.965545) (xy 52.692115 -101.023438) (xy 52.699938 -101.08286) (xy 52.700428 -101.112828)
			(xy 52.700428 -101.976428) (xy 52.700299 -101.984302) (xy 151.377396 -101.984302) (xy 151.377396 -101.120702)
			(xy 151.377886 -101.090718) (xy 151.385714 -101.031262) (xy 151.401235 -100.973337) (xy 151.424184 -100.917933)
			(xy 151.454168 -100.865999) (xy 151.490674 -100.818423) (xy 151.533079 -100.776018) (xy 151.580655 -100.739512)
			(xy 151.632589 -100.709528) (xy 151.687993 -100.686579) (xy 151.745918 -100.671058) (xy 151.805374 -100.66323)
			(xy 151.865342 -100.66323) (xy 151.924798 -100.671058) (xy 151.982723 -100.686579) (xy 152.038127 -100.709528)
			(xy 152.090061 -100.739512) (xy 152.137637 -100.776018) (xy 152.180042 -100.818423) (xy 152.216548 -100.865999)
			(xy 152.246532 -100.917933) (xy 152.269481 -100.973337) (xy 152.285002 -101.031262) (xy 152.29283 -101.090718)
			(xy 152.29332 -101.120702) (xy 152.29332 -101.976428) (xy 167.884856 -101.976428) (xy 167.884856 -101.112828)
			(xy 167.885346 -101.082844) (xy 167.893174 -101.023388) (xy 167.908695 -100.965463) (xy 167.931644 -100.910059)
			(xy 167.961628 -100.858125) (xy 167.998134 -100.810549) (xy 168.040539 -100.768144) (xy 168.088115 -100.731638)
			(xy 168.140049 -100.701654) (xy 168.195453 -100.678705) (xy 168.253378 -100.663184) (xy 168.312834 -100.655356)
			(xy 168.372802 -100.655356) (xy 168.432258 -100.663184) (xy 168.490183 -100.678705) (xy 168.545587 -100.701654)
			(xy 168.597521 -100.731638) (xy 168.645097 -100.768144) (xy 168.687502 -100.810549) (xy 168.724008 -100.858125)
			(xy 168.753992 -100.910059) (xy 168.776941 -100.965463) (xy 168.792462 -101.023388) (xy 168.80029 -101.082844)
			(xy 168.80078 -101.112828) (xy 168.80078 -101.976428) (xy 168.800651 -101.984302) (xy 267.47724 -101.984302)
			(xy 267.47724 -101.120702) (xy 267.47773 -101.090718) (xy 267.485558 -101.031262) (xy 267.501079 -100.973337)
			(xy 267.524028 -100.917933) (xy 267.554012 -100.865999) (xy 267.590518 -100.818423) (xy 267.632923 -100.776018)
			(xy 267.680499 -100.739512) (xy 267.732433 -100.709528) (xy 267.787837 -100.686579) (xy 267.845762 -100.671058)
			(xy 267.905218 -100.66323) (xy 267.965186 -100.66323) (xy 268.024642 -100.671058) (xy 268.082567 -100.686579)
			(xy 268.137971 -100.709528) (xy 268.189905 -100.739512) (xy 268.237481 -100.776018) (xy 268.279886 -100.818423)
			(xy 268.316392 -100.865999) (xy 268.346376 -100.917933) (xy 268.369325 -100.973337) (xy 268.384846 -101.031262)
			(xy 268.392674 -101.090718) (xy 268.393164 -101.120702) (xy 268.393164 -101.976428) (xy 283.9847 -101.976428)
			(xy 283.9847 -101.112828) (xy 283.98519 -101.082844) (xy 283.993018 -101.023388) (xy 284.008539 -100.965463)
			(xy 284.031488 -100.910059) (xy 284.061472 -100.858125) (xy 284.097978 -100.810549) (xy 284.140383 -100.768144)
			(xy 284.187959 -100.731638) (xy 284.239893 -100.701654) (xy 284.295297 -100.678705) (xy 284.353222 -100.663184)
			(xy 284.412678 -100.655356) (xy 284.472646 -100.655356) (xy 284.532102 -100.663184) (xy 284.590027 -100.678705)
			(xy 284.645431 -100.701654) (xy 284.697365 -100.731638) (xy 284.744941 -100.768144) (xy 284.787346 -100.810549)
			(xy 284.823852 -100.858125) (xy 284.853836 -100.910059) (xy 284.876785 -100.965463) (xy 284.892306 -101.023388)
			(xy 284.900134 -101.082844) (xy 284.900624 -101.112828) (xy 284.900624 -101.976428) (xy 284.900495 -101.984302)
			(xy 383.577592 -101.984302) (xy 383.577592 -101.120702) (xy 383.578082 -101.090734) (xy 383.585905 -101.031312)
			(xy 383.601418 -100.973419) (xy 383.624354 -100.918046) (xy 383.654321 -100.86614) (xy 383.690808 -100.81859)
			(xy 383.733188 -100.77621) (xy 383.780738 -100.739723) (xy 383.832644 -100.709756) (xy 383.888017 -100.68682)
			(xy 383.94591 -100.671307) (xy 384.005332 -100.663484) (xy 384.065268 -100.663484) (xy 384.12469 -100.671307)
			(xy 384.182583 -100.68682) (xy 384.237956 -100.709756) (xy 384.289862 -100.739723) (xy 384.337412 -100.77621)
			(xy 384.379792 -100.81859) (xy 384.416279 -100.86614) (xy 384.446246 -100.918046) (xy 384.469182 -100.973419)
			(xy 384.484695 -101.031312) (xy 384.492518 -101.090734) (xy 384.493008 -101.120702) (xy 384.493008 -101.976428)
			(xy 400.085052 -101.976428) (xy 400.085052 -101.112828) (xy 400.085542 -101.08286) (xy 400.093365 -101.023438)
			(xy 400.108878 -100.965545) (xy 400.131814 -100.910172) (xy 400.161781 -100.858266) (xy 400.198268 -100.810716)
			(xy 400.240648 -100.768336) (xy 400.288198 -100.731849) (xy 400.340104 -100.701882) (xy 400.395477 -100.678946)
			(xy 400.45337 -100.663433) (xy 400.512792 -100.65561) (xy 400.572728 -100.65561) (xy 400.63215 -100.663433)
			(xy 400.690043 -100.678946) (xy 400.745416 -100.701882) (xy 400.797322 -100.731849) (xy 400.844872 -100.768336)
			(xy 400.887252 -100.810716) (xy 400.923739 -100.858266) (xy 400.953706 -100.910172) (xy 400.976642 -100.965545)
			(xy 400.992155 -101.023438) (xy 400.999978 -101.08286) (xy 401.000468 -101.112828) (xy 401.000468 -101.976428)
			(xy 400.999978 -102.006396) (xy 400.992155 -102.065818) (xy 400.976642 -102.123711) (xy 400.953706 -102.179084)
			(xy 400.923739 -102.23099) (xy 400.887252 -102.27854) (xy 400.844872 -102.32092) (xy 400.797322 -102.357407)
			(xy 400.745416 -102.387374) (xy 400.690043 -102.41031) (xy 400.63215 -102.425823) (xy 400.572728 -102.433646)
			(xy 400.512792 -102.433646) (xy 400.45337 -102.425823) (xy 400.395477 -102.41031) (xy 400.340104 -102.387374)
			(xy 400.288198 -102.357407) (xy 400.240648 -102.32092) (xy 400.198268 -102.27854) (xy 400.161781 -102.23099)
			(xy 400.131814 -102.179084) (xy 400.108878 -102.123711) (xy 400.093365 -102.065818) (xy 400.085542 -102.006396)
			(xy 400.085052 -101.976428) (xy 384.493008 -101.976428) (xy 384.493008 -101.984302) (xy 384.492518 -102.01427)
			(xy 384.484695 -102.073692) (xy 384.469182 -102.131585) (xy 384.446246 -102.186958) (xy 384.416279 -102.238864)
			(xy 384.379792 -102.286414) (xy 384.337412 -102.328794) (xy 384.289862 -102.365281) (xy 384.237956 -102.395248)
			(xy 384.182583 -102.418184) (xy 384.12469 -102.433697) (xy 384.065268 -102.44152) (xy 384.005332 -102.44152)
			(xy 383.94591 -102.433697) (xy 383.888017 -102.418184) (xy 383.832644 -102.395248) (xy 383.780738 -102.365281)
			(xy 383.733188 -102.328794) (xy 383.690808 -102.286414) (xy 383.654321 -102.238864) (xy 383.624354 -102.186958)
			(xy 383.601418 -102.131585) (xy 383.585905 -102.073692) (xy 383.578082 -102.01427) (xy 383.577592 -101.984302)
			(xy 284.900495 -101.984302) (xy 284.900134 -102.006412) (xy 284.892306 -102.065868) (xy 284.876785 -102.123793)
			(xy 284.853836 -102.179197) (xy 284.823852 -102.231131) (xy 284.787346 -102.278707) (xy 284.744941 -102.321112)
			(xy 284.697365 -102.357618) (xy 284.645431 -102.387602) (xy 284.590027 -102.410551) (xy 284.532102 -102.426072)
			(xy 284.472646 -102.4339) (xy 284.412678 -102.4339) (xy 284.353222 -102.426072) (xy 284.295297 -102.410551)
			(xy 284.239893 -102.387602) (xy 284.187959 -102.357618) (xy 284.140383 -102.321112) (xy 284.097978 -102.278707)
			(xy 284.061472 -102.231131) (xy 284.031488 -102.179197) (xy 284.008539 -102.123793) (xy 283.993018 -102.065868)
			(xy 283.98519 -102.006412) (xy 283.9847 -101.976428) (xy 268.393164 -101.976428) (xy 268.393164 -101.984302)
			(xy 268.392674 -102.014286) (xy 268.384846 -102.073742) (xy 268.369325 -102.131667) (xy 268.346376 -102.187071)
			(xy 268.316392 -102.239005) (xy 268.279886 -102.286581) (xy 268.237481 -102.328986) (xy 268.189905 -102.365492)
			(xy 268.137971 -102.395476) (xy 268.082567 -102.418425) (xy 268.024642 -102.433946) (xy 267.965186 -102.441774)
			(xy 267.905218 -102.441774) (xy 267.845762 -102.433946) (xy 267.787837 -102.418425) (xy 267.732433 -102.395476)
			(xy 267.680499 -102.365492) (xy 267.632923 -102.328986) (xy 267.590518 -102.286581) (xy 267.554012 -102.239005)
			(xy 267.524028 -102.187071) (xy 267.501079 -102.131667) (xy 267.485558 -102.073742) (xy 267.47773 -102.014286)
			(xy 267.47724 -101.984302) (xy 168.800651 -101.984302) (xy 168.80029 -102.006412) (xy 168.792462 -102.065868)
			(xy 168.776941 -102.123793) (xy 168.753992 -102.179197) (xy 168.724008 -102.231131) (xy 168.687502 -102.278707)
			(xy 168.645097 -102.321112) (xy 168.597521 -102.357618) (xy 168.545587 -102.387602) (xy 168.490183 -102.410551)
			(xy 168.432258 -102.426072) (xy 168.372802 -102.4339) (xy 168.312834 -102.4339) (xy 168.253378 -102.426072)
			(xy 168.195453 -102.410551) (xy 168.140049 -102.387602) (xy 168.088115 -102.357618) (xy 168.040539 -102.321112)
			(xy 167.998134 -102.278707) (xy 167.961628 -102.231131) (xy 167.931644 -102.179197) (xy 167.908695 -102.123793)
			(xy 167.893174 -102.065868) (xy 167.885346 -102.006412) (xy 167.884856 -101.976428) (xy 152.29332 -101.976428)
			(xy 152.29332 -101.984302) (xy 152.29283 -102.014286) (xy 152.285002 -102.073742) (xy 152.269481 -102.131667)
			(xy 152.246532 -102.187071) (xy 152.216548 -102.239005) (xy 152.180042 -102.286581) (xy 152.137637 -102.328986)
			(xy 152.090061 -102.365492) (xy 152.038127 -102.395476) (xy 151.982723 -102.418425) (xy 151.924798 -102.433946)
			(xy 151.865342 -102.441774) (xy 151.805374 -102.441774) (xy 151.745918 -102.433946) (xy 151.687993 -102.418425)
			(xy 151.632589 -102.395476) (xy 151.580655 -102.365492) (xy 151.533079 -102.328986) (xy 151.490674 -102.286581)
			(xy 151.454168 -102.239005) (xy 151.424184 -102.187071) (xy 151.401235 -102.131667) (xy 151.385714 -102.073742)
			(xy 151.377886 -102.014286) (xy 151.377396 -101.984302) (xy 52.700299 -101.984302) (xy 52.699938 -102.006396)
			(xy 52.692115 -102.065818) (xy 52.676602 -102.123711) (xy 52.653666 -102.179084) (xy 52.623699 -102.23099)
			(xy 52.587212 -102.27854) (xy 52.544832 -102.32092) (xy 52.497282 -102.357407) (xy 52.445376 -102.387374)
			(xy 52.390003 -102.41031) (xy 52.33211 -102.425823) (xy 52.272688 -102.433646) (xy 52.212752 -102.433646)
			(xy 52.15333 -102.425823) (xy 52.095437 -102.41031) (xy 52.040064 -102.387374) (xy 51.988158 -102.357407)
			(xy 51.940608 -102.32092) (xy 51.898228 -102.27854) (xy 51.861741 -102.23099) (xy 51.831774 -102.179084)
			(xy 51.808838 -102.123711) (xy 51.793325 -102.065818) (xy 51.785502 -102.006396) (xy 51.785012 -101.976428)
			(xy 36.192968 -101.976428) (xy 36.192968 -101.984302) (xy 36.192478 -102.01427) (xy 36.184655 -102.073692)
			(xy 36.169142 -102.131585) (xy 36.146206 -102.186958) (xy 36.116239 -102.238864) (xy 36.079752 -102.286414)
			(xy 36.037372 -102.328794) (xy 35.989822 -102.365281) (xy 35.937916 -102.395248) (xy 35.882543 -102.418184)
			(xy 35.82465 -102.433697) (xy 35.765228 -102.44152) (xy 35.705292 -102.44152) (xy 35.64587 -102.433697)
			(xy 35.587977 -102.418184) (xy 35.532604 -102.395248) (xy 35.480698 -102.365281) (xy 35.433148 -102.328794)
			(xy 35.390768 -102.286414) (xy 35.354281 -102.238864) (xy 35.324314 -102.186958) (xy 35.301378 -102.131585)
			(xy 35.285865 -102.073692) (xy 35.278042 -102.01427) (xy 35.277552 -101.984302) (xy 4.308094 -101.984302)
			(xy 4.308094 -103.777796) (xy 37.31006 -103.777796) (xy 37.31006 -102.914196) (xy 37.31055 -102.884228)
			(xy 37.318373 -102.824806) (xy 37.333886 -102.766913) (xy 37.356822 -102.71154) (xy 37.386789 -102.659634)
			(xy 37.423276 -102.612084) (xy 37.465656 -102.569704) (xy 37.513206 -102.533217) (xy 37.565112 -102.50325)
			(xy 37.620485 -102.480314) (xy 37.678378 -102.464801) (xy 37.7378 -102.456978) (xy 37.797736 -102.456978)
			(xy 37.857158 -102.464801) (xy 37.915051 -102.480314) (xy 37.970424 -102.50325) (xy 38.02233 -102.533217)
			(xy 38.06988 -102.569704) (xy 38.11226 -102.612084) (xy 38.148747 -102.659634) (xy 38.178714 -102.71154)
			(xy 38.20165 -102.766913) (xy 38.217163 -102.824806) (xy 38.224986 -102.884228) (xy 38.225476 -102.914196)
			(xy 38.225476 -103.776272) (xy 53.639212 -103.776272) (xy 53.639212 -102.912672) (xy 53.639702 -102.882704)
			(xy 53.647525 -102.823282) (xy 53.663038 -102.765389) (xy 53.685974 -102.710016) (xy 53.715941 -102.65811)
			(xy 53.752428 -102.61056) (xy 53.794808 -102.56818) (xy 53.842358 -102.531693) (xy 53.894264 -102.501726)
			(xy 53.949637 -102.47879) (xy 54.00753 -102.463277) (xy 54.066952 -102.455454) (xy 54.126888 -102.455454)
			(xy 54.18631 -102.463277) (xy 54.244203 -102.47879) (xy 54.299576 -102.501726) (xy 54.351482 -102.531693)
			(xy 54.399032 -102.56818) (xy 54.441412 -102.61056) (xy 54.477899 -102.65811) (xy 54.507866 -102.710016)
			(xy 54.530802 -102.765389) (xy 54.546315 -102.823282) (xy 54.554138 -102.882704) (xy 54.554628 -102.912672)
			(xy 54.554628 -103.776272) (xy 54.554603 -103.777796) (xy 153.409904 -103.777796) (xy 153.409904 -102.914196)
			(xy 153.410394 -102.884212) (xy 153.418222 -102.824756) (xy 153.433743 -102.766831) (xy 153.456692 -102.711427)
			(xy 153.486676 -102.659493) (xy 153.523182 -102.611917) (xy 153.565587 -102.569512) (xy 153.613163 -102.533006)
			(xy 153.665097 -102.503022) (xy 153.720501 -102.480073) (xy 153.778426 -102.464552) (xy 153.837882 -102.456724)
			(xy 153.89785 -102.456724) (xy 153.957306 -102.464552) (xy 154.015231 -102.480073) (xy 154.070635 -102.503022)
			(xy 154.122569 -102.533006) (xy 154.170145 -102.569512) (xy 154.21255 -102.611917) (xy 154.249056 -102.659493)
			(xy 154.27904 -102.711427) (xy 154.301989 -102.766831) (xy 154.31751 -102.824756) (xy 154.325338 -102.884212)
			(xy 154.325828 -102.914196) (xy 154.325828 -103.776272) (xy 169.739056 -103.776272) (xy 169.739056 -102.912672)
			(xy 169.739546 -102.882688) (xy 169.747374 -102.823232) (xy 169.762895 -102.765307) (xy 169.785844 -102.709903)
			(xy 169.815828 -102.657969) (xy 169.852334 -102.610393) (xy 169.894739 -102.567988) (xy 169.942315 -102.531482)
			(xy 169.994249 -102.501498) (xy 170.049653 -102.478549) (xy 170.107578 -102.463028) (xy 170.167034 -102.4552)
			(xy 170.227002 -102.4552) (xy 170.286458 -102.463028) (xy 170.344383 -102.478549) (xy 170.399787 -102.501498)
			(xy 170.451721 -102.531482) (xy 170.499297 -102.567988) (xy 170.541702 -102.610393) (xy 170.578208 -102.657969)
			(xy 170.608192 -102.709903) (xy 170.631141 -102.765307) (xy 170.646662 -102.823232) (xy 170.65449 -102.882688)
			(xy 170.65498 -102.912672) (xy 170.65498 -103.776272) (xy 170.654955 -103.777796) (xy 269.509748 -103.777796)
			(xy 269.509748 -102.914196) (xy 269.510238 -102.884212) (xy 269.518066 -102.824756) (xy 269.533587 -102.766831)
			(xy 269.556536 -102.711427) (xy 269.58652 -102.659493) (xy 269.623026 -102.611917) (xy 269.665431 -102.569512)
			(xy 269.713007 -102.533006) (xy 269.764941 -102.503022) (xy 269.820345 -102.480073) (xy 269.87827 -102.464552)
			(xy 269.937726 -102.456724) (xy 269.997694 -102.456724) (xy 270.05715 -102.464552) (xy 270.115075 -102.480073)
			(xy 270.170479 -102.503022) (xy 270.222413 -102.533006) (xy 270.269989 -102.569512) (xy 270.312394 -102.611917)
			(xy 270.3489 -102.659493) (xy 270.378884 -102.711427) (xy 270.401833 -102.766831) (xy 270.417354 -102.824756)
			(xy 270.425182 -102.884212) (xy 270.425672 -102.914196) (xy 270.425672 -103.776272) (xy 285.8389 -103.776272)
			(xy 285.8389 -102.912672) (xy 285.83939 -102.882688) (xy 285.847218 -102.823232) (xy 285.862739 -102.765307)
			(xy 285.885688 -102.709903) (xy 285.915672 -102.657969) (xy 285.952178 -102.610393) (xy 285.994583 -102.567988)
			(xy 286.042159 -102.531482) (xy 286.094093 -102.501498) (xy 286.149497 -102.478549) (xy 286.207422 -102.463028)
			(xy 286.266878 -102.4552) (xy 286.326846 -102.4552) (xy 286.386302 -102.463028) (xy 286.444227 -102.478549)
			(xy 286.499631 -102.501498) (xy 286.551565 -102.531482) (xy 286.599141 -102.567988) (xy 286.641546 -102.610393)
			(xy 286.678052 -102.657969) (xy 286.708036 -102.709903) (xy 286.730985 -102.765307) (xy 286.746506 -102.823232)
			(xy 286.754334 -102.882688) (xy 286.754824 -102.912672) (xy 286.754824 -103.776272) (xy 286.754799 -103.777796)
			(xy 385.6101 -103.777796) (xy 385.6101 -102.914196) (xy 385.61059 -102.884228) (xy 385.618413 -102.824806)
			(xy 385.633926 -102.766913) (xy 385.656862 -102.71154) (xy 385.686829 -102.659634) (xy 385.723316 -102.612084)
			(xy 385.765696 -102.569704) (xy 385.813246 -102.533217) (xy 385.865152 -102.50325) (xy 385.920525 -102.480314)
			(xy 385.978418 -102.464801) (xy 386.03784 -102.456978) (xy 386.097776 -102.456978) (xy 386.157198 -102.464801)
			(xy 386.215091 -102.480314) (xy 386.270464 -102.50325) (xy 386.32237 -102.533217) (xy 386.36992 -102.569704)
			(xy 386.4123 -102.612084) (xy 386.448787 -102.659634) (xy 386.478754 -102.71154) (xy 386.50169 -102.766913)
			(xy 386.517203 -102.824806) (xy 386.525026 -102.884228) (xy 386.525516 -102.914196) (xy 386.525516 -103.776272)
			(xy 401.939252 -103.776272) (xy 401.939252 -102.912672) (xy 401.939742 -102.882704) (xy 401.947565 -102.823282)
			(xy 401.963078 -102.765389) (xy 401.986014 -102.710016) (xy 402.015981 -102.65811) (xy 402.052468 -102.61056)
			(xy 402.094848 -102.56818) (xy 402.142398 -102.531693) (xy 402.194304 -102.501726) (xy 402.249677 -102.47879)
			(xy 402.30757 -102.463277) (xy 402.366992 -102.455454) (xy 402.426928 -102.455454) (xy 402.48635 -102.463277)
			(xy 402.544243 -102.47879) (xy 402.599616 -102.501726) (xy 402.651522 -102.531693) (xy 402.699072 -102.56818)
			(xy 402.741452 -102.61056) (xy 402.777939 -102.65811) (xy 402.807906 -102.710016) (xy 402.830842 -102.765389)
			(xy 402.846355 -102.823282) (xy 402.854178 -102.882704) (xy 402.854668 -102.912672) (xy 402.854668 -103.776272)
			(xy 402.854178 -103.80624) (xy 402.846355 -103.865662) (xy 402.830842 -103.923555) (xy 402.807906 -103.978928)
			(xy 402.777939 -104.030834) (xy 402.741452 -104.078384) (xy 402.699072 -104.120764) (xy 402.651522 -104.157251)
			(xy 402.599616 -104.187218) (xy 402.544243 -104.210154) (xy 402.48635 -104.225667) (xy 402.426928 -104.23349)
			(xy 402.366992 -104.23349) (xy 402.30757 -104.225667) (xy 402.249677 -104.210154) (xy 402.194304 -104.187218)
			(xy 402.142398 -104.157251) (xy 402.094848 -104.120764) (xy 402.052468 -104.078384) (xy 402.015981 -104.030834)
			(xy 401.986014 -103.978928) (xy 401.963078 -103.923555) (xy 401.947565 -103.865662) (xy 401.939742 -103.80624)
			(xy 401.939252 -103.776272) (xy 386.525516 -103.776272) (xy 386.525516 -103.777796) (xy 386.525026 -103.807764)
			(xy 386.517203 -103.867186) (xy 386.50169 -103.925079) (xy 386.478754 -103.980452) (xy 386.448787 -104.032358)
			(xy 386.4123 -104.079908) (xy 386.36992 -104.122288) (xy 386.32237 -104.158775) (xy 386.270464 -104.188742)
			(xy 386.215091 -104.211678) (xy 386.157198 -104.227191) (xy 386.097776 -104.235014) (xy 386.03784 -104.235014)
			(xy 385.978418 -104.227191) (xy 385.920525 -104.211678) (xy 385.865152 -104.188742) (xy 385.813246 -104.158775)
			(xy 385.765696 -104.122288) (xy 385.723316 -104.079908) (xy 385.686829 -104.032358) (xy 385.656862 -103.980452)
			(xy 385.633926 -103.925079) (xy 385.618413 -103.867186) (xy 385.61059 -103.807764) (xy 385.6101 -103.777796)
			(xy 286.754799 -103.777796) (xy 286.754334 -103.806256) (xy 286.746506 -103.865712) (xy 286.730985 -103.923637)
			(xy 286.708036 -103.979041) (xy 286.678052 -104.030975) (xy 286.641546 -104.078551) (xy 286.599141 -104.120956)
			(xy 286.551565 -104.157462) (xy 286.499631 -104.187446) (xy 286.444227 -104.210395) (xy 286.386302 -104.225916)
			(xy 286.326846 -104.233744) (xy 286.266878 -104.233744) (xy 286.207422 -104.225916) (xy 286.149497 -104.210395)
			(xy 286.094093 -104.187446) (xy 286.042159 -104.157462) (xy 285.994583 -104.120956) (xy 285.952178 -104.078551)
			(xy 285.915672 -104.030975) (xy 285.885688 -103.979041) (xy 285.862739 -103.923637) (xy 285.847218 -103.865712)
			(xy 285.83939 -103.806256) (xy 285.8389 -103.776272) (xy 270.425672 -103.776272) (xy 270.425672 -103.777796)
			(xy 270.425182 -103.80778) (xy 270.417354 -103.867236) (xy 270.401833 -103.925161) (xy 270.378884 -103.980565)
			(xy 270.3489 -104.032499) (xy 270.312394 -104.080075) (xy 270.269989 -104.12248) (xy 270.222413 -104.158986)
			(xy 270.170479 -104.18897) (xy 270.115075 -104.211919) (xy 270.05715 -104.22744) (xy 269.997694 -104.235268)
			(xy 269.937726 -104.235268) (xy 269.87827 -104.22744) (xy 269.820345 -104.211919) (xy 269.764941 -104.18897)
			(xy 269.713007 -104.158986) (xy 269.665431 -104.12248) (xy 269.623026 -104.080075) (xy 269.58652 -104.032499)
			(xy 269.556536 -103.980565) (xy 269.533587 -103.925161) (xy 269.518066 -103.867236) (xy 269.510238 -103.80778)
			(xy 269.509748 -103.777796) (xy 170.654955 -103.777796) (xy 170.65449 -103.806256) (xy 170.646662 -103.865712)
			(xy 170.631141 -103.923637) (xy 170.608192 -103.979041) (xy 170.578208 -104.030975) (xy 170.541702 -104.078551)
			(xy 170.499297 -104.120956) (xy 170.451721 -104.157462) (xy 170.399787 -104.187446) (xy 170.344383 -104.210395)
			(xy 170.286458 -104.225916) (xy 170.227002 -104.233744) (xy 170.167034 -104.233744) (xy 170.107578 -104.225916)
			(xy 170.049653 -104.210395) (xy 169.994249 -104.187446) (xy 169.942315 -104.157462) (xy 169.894739 -104.120956)
			(xy 169.852334 -104.078551) (xy 169.815828 -104.030975) (xy 169.785844 -103.979041) (xy 169.762895 -103.923637)
			(xy 169.747374 -103.865712) (xy 169.739546 -103.806256) (xy 169.739056 -103.776272) (xy 154.325828 -103.776272)
			(xy 154.325828 -103.777796) (xy 154.325338 -103.80778) (xy 154.31751 -103.867236) (xy 154.301989 -103.925161)
			(xy 154.27904 -103.980565) (xy 154.249056 -104.032499) (xy 154.21255 -104.080075) (xy 154.170145 -104.12248)
			(xy 154.122569 -104.158986) (xy 154.070635 -104.18897) (xy 154.015231 -104.211919) (xy 153.957306 -104.22744)
			(xy 153.89785 -104.235268) (xy 153.837882 -104.235268) (xy 153.778426 -104.22744) (xy 153.720501 -104.211919)
			(xy 153.665097 -104.18897) (xy 153.613163 -104.158986) (xy 153.565587 -104.12248) (xy 153.523182 -104.080075)
			(xy 153.486676 -104.032499) (xy 153.456692 -103.980565) (xy 153.433743 -103.925161) (xy 153.418222 -103.867236)
			(xy 153.410394 -103.80778) (xy 153.409904 -103.777796) (xy 54.554603 -103.777796) (xy 54.554138 -103.80624)
			(xy 54.546315 -103.865662) (xy 54.530802 -103.923555) (xy 54.507866 -103.978928) (xy 54.477899 -104.030834)
			(xy 54.441412 -104.078384) (xy 54.399032 -104.120764) (xy 54.351482 -104.157251) (xy 54.299576 -104.187218)
			(xy 54.244203 -104.210154) (xy 54.18631 -104.225667) (xy 54.126888 -104.23349) (xy 54.066952 -104.23349)
			(xy 54.00753 -104.225667) (xy 53.949637 -104.210154) (xy 53.894264 -104.187218) (xy 53.842358 -104.157251)
			(xy 53.794808 -104.120764) (xy 53.752428 -104.078384) (xy 53.715941 -104.030834) (xy 53.685974 -103.978928)
			(xy 53.663038 -103.923555) (xy 53.647525 -103.865662) (xy 53.639702 -103.80624) (xy 53.639212 -103.776272)
			(xy 38.225476 -103.776272) (xy 38.225476 -103.777796) (xy 38.224986 -103.807764) (xy 38.217163 -103.867186)
			(xy 38.20165 -103.925079) (xy 38.178714 -103.980452) (xy 38.148747 -104.032358) (xy 38.11226 -104.079908)
			(xy 38.06988 -104.122288) (xy 38.02233 -104.158775) (xy 37.970424 -104.188742) (xy 37.915051 -104.211678)
			(xy 37.857158 -104.227191) (xy 37.797736 -104.235014) (xy 37.7378 -104.235014) (xy 37.678378 -104.227191)
			(xy 37.620485 -104.211678) (xy 37.565112 -104.188742) (xy 37.513206 -104.158775) (xy 37.465656 -104.122288)
			(xy 37.423276 -104.079908) (xy 37.386789 -104.032358) (xy 37.356822 -103.980452) (xy 37.333886 -103.925079)
			(xy 37.318373 -103.867186) (xy 37.31055 -103.807764) (xy 37.31006 -103.777796) (xy 4.308094 -103.777796)
			(xy 4.308094 -105.584498) (xy 34.667952 -105.584498) (xy 34.667952 -104.720898) (xy 34.668442 -104.69093)
			(xy 34.676265 -104.631508) (xy 34.691778 -104.573615) (xy 34.714714 -104.518242) (xy 34.744681 -104.466336)
			(xy 34.781168 -104.418786) (xy 34.823548 -104.376406) (xy 34.871098 -104.339919) (xy 34.923004 -104.309952)
			(xy 34.978377 -104.287016) (xy 35.03627 -104.271503) (xy 35.095692 -104.26368) (xy 35.155628 -104.26368)
			(xy 35.21505 -104.271503) (xy 35.272943 -104.287016) (xy 35.328316 -104.309952) (xy 35.380222 -104.339919)
			(xy 35.427772 -104.376406) (xy 35.470152 -104.418786) (xy 35.506639 -104.466336) (xy 35.536606 -104.518242)
			(xy 35.559542 -104.573615) (xy 35.575055 -104.631508) (xy 35.582878 -104.69093) (xy 35.583368 -104.720898)
			(xy 35.583368 -105.57637) (xy 51.785012 -105.57637) (xy 51.785012 -104.71277) (xy 51.785502 -104.682802)
			(xy 51.793325 -104.62338) (xy 51.808838 -104.565487) (xy 51.831774 -104.510114) (xy 51.861741 -104.458208)
			(xy 51.898228 -104.410658) (xy 51.940608 -104.368278) (xy 51.988158 -104.331791) (xy 52.040064 -104.301824)
			(xy 52.095437 -104.278888) (xy 52.15333 -104.263375) (xy 52.212752 -104.255552) (xy 52.272688 -104.255552)
			(xy 52.33211 -104.263375) (xy 52.390003 -104.278888) (xy 52.445376 -104.301824) (xy 52.497282 -104.331791)
			(xy 52.544832 -104.368278) (xy 52.587212 -104.410658) (xy 52.623699 -104.458208) (xy 52.653666 -104.510114)
			(xy 52.676602 -104.565487) (xy 52.692115 -104.62338) (xy 52.699938 -104.682802) (xy 52.700428 -104.71277)
			(xy 52.700428 -105.57637) (xy 52.700295 -105.584498) (xy 150.767796 -105.584498) (xy 150.767796 -104.720898)
			(xy 150.768286 -104.690914) (xy 150.776114 -104.631458) (xy 150.791635 -104.573533) (xy 150.814584 -104.518129)
			(xy 150.844568 -104.466195) (xy 150.881074 -104.418619) (xy 150.923479 -104.376214) (xy 150.971055 -104.339708)
			(xy 151.022989 -104.309724) (xy 151.078393 -104.286775) (xy 151.136318 -104.271254) (xy 151.195774 -104.263426)
			(xy 151.255742 -104.263426) (xy 151.315198 -104.271254) (xy 151.373123 -104.286775) (xy 151.428527 -104.309724)
			(xy 151.480461 -104.339708) (xy 151.528037 -104.376214) (xy 151.570442 -104.418619) (xy 151.606948 -104.466195)
			(xy 151.636932 -104.518129) (xy 151.659881 -104.573533) (xy 151.675402 -104.631458) (xy 151.68323 -104.690914)
			(xy 151.68372 -104.720898) (xy 151.68372 -105.57637) (xy 167.884856 -105.57637) (xy 167.884856 -104.71277)
			(xy 167.885346 -104.682786) (xy 167.893174 -104.62333) (xy 167.908695 -104.565405) (xy 167.931644 -104.510001)
			(xy 167.961628 -104.458067) (xy 167.998134 -104.410491) (xy 168.040539 -104.368086) (xy 168.088115 -104.33158)
			(xy 168.140049 -104.301596) (xy 168.195453 -104.278647) (xy 168.253378 -104.263126) (xy 168.312834 -104.255298)
			(xy 168.372802 -104.255298) (xy 168.432258 -104.263126) (xy 168.490183 -104.278647) (xy 168.545587 -104.301596)
			(xy 168.597521 -104.33158) (xy 168.645097 -104.368086) (xy 168.687502 -104.410491) (xy 168.724008 -104.458067)
			(xy 168.753992 -104.510001) (xy 168.776941 -104.565405) (xy 168.792462 -104.62333) (xy 168.80029 -104.682786)
			(xy 168.80078 -104.71277) (xy 168.80078 -105.57637) (xy 168.800647 -105.584498) (xy 266.86764 -105.584498)
			(xy 266.86764 -104.720898) (xy 266.86813 -104.690914) (xy 266.875958 -104.631458) (xy 266.891479 -104.573533)
			(xy 266.914428 -104.518129) (xy 266.944412 -104.466195) (xy 266.980918 -104.418619) (xy 267.023323 -104.376214)
			(xy 267.070899 -104.339708) (xy 267.122833 -104.309724) (xy 267.178237 -104.286775) (xy 267.236162 -104.271254)
			(xy 267.295618 -104.263426) (xy 267.355586 -104.263426) (xy 267.415042 -104.271254) (xy 267.472967 -104.286775)
			(xy 267.528371 -104.309724) (xy 267.580305 -104.339708) (xy 267.627881 -104.376214) (xy 267.670286 -104.418619)
			(xy 267.706792 -104.466195) (xy 267.736776 -104.518129) (xy 267.759725 -104.573533) (xy 267.775246 -104.631458)
			(xy 267.783074 -104.690914) (xy 267.783564 -104.720898) (xy 267.783564 -105.57637) (xy 283.9847 -105.57637)
			(xy 283.9847 -104.71277) (xy 283.98519 -104.682786) (xy 283.993018 -104.62333) (xy 284.008539 -104.565405)
			(xy 284.031488 -104.510001) (xy 284.061472 -104.458067) (xy 284.097978 -104.410491) (xy 284.140383 -104.368086)
			(xy 284.187959 -104.33158) (xy 284.239893 -104.301596) (xy 284.295297 -104.278647) (xy 284.353222 -104.263126)
			(xy 284.412678 -104.255298) (xy 284.472646 -104.255298) (xy 284.532102 -104.263126) (xy 284.590027 -104.278647)
			(xy 284.645431 -104.301596) (xy 284.697365 -104.33158) (xy 284.744941 -104.368086) (xy 284.787346 -104.410491)
			(xy 284.823852 -104.458067) (xy 284.853836 -104.510001) (xy 284.876785 -104.565405) (xy 284.892306 -104.62333)
			(xy 284.900134 -104.682786) (xy 284.900624 -104.71277) (xy 284.900624 -105.57637) (xy 284.900491 -105.584498)
			(xy 382.967992 -105.584498) (xy 382.967992 -104.720898) (xy 382.968482 -104.69093) (xy 382.976305 -104.631508)
			(xy 382.991818 -104.573615) (xy 383.014754 -104.518242) (xy 383.044721 -104.466336) (xy 383.081208 -104.418786)
			(xy 383.123588 -104.376406) (xy 383.171138 -104.339919) (xy 383.223044 -104.309952) (xy 383.278417 -104.287016)
			(xy 383.33631 -104.271503) (xy 383.395732 -104.26368) (xy 383.455668 -104.26368) (xy 383.51509 -104.271503)
			(xy 383.572983 -104.287016) (xy 383.628356 -104.309952) (xy 383.680262 -104.339919) (xy 383.727812 -104.376406)
			(xy 383.770192 -104.418786) (xy 383.806679 -104.466336) (xy 383.836646 -104.518242) (xy 383.859582 -104.573615)
			(xy 383.875095 -104.631508) (xy 383.882918 -104.69093) (xy 383.883408 -104.720898) (xy 383.883408 -105.57637)
			(xy 400.085052 -105.57637) (xy 400.085052 -104.71277) (xy 400.085542 -104.682802) (xy 400.093365 -104.62338)
			(xy 400.108878 -104.565487) (xy 400.131814 -104.510114) (xy 400.161781 -104.458208) (xy 400.198268 -104.410658)
			(xy 400.240648 -104.368278) (xy 400.288198 -104.331791) (xy 400.340104 -104.301824) (xy 400.395477 -104.278888)
			(xy 400.45337 -104.263375) (xy 400.512792 -104.255552) (xy 400.572728 -104.255552) (xy 400.63215 -104.263375)
			(xy 400.690043 -104.278888) (xy 400.745416 -104.301824) (xy 400.797322 -104.331791) (xy 400.844872 -104.368278)
			(xy 400.887252 -104.410658) (xy 400.923739 -104.458208) (xy 400.953706 -104.510114) (xy 400.976642 -104.565487)
			(xy 400.992155 -104.62338) (xy 400.999978 -104.682802) (xy 401.000468 -104.71277) (xy 401.000468 -105.57637)
			(xy 400.999978 -105.606338) (xy 400.992155 -105.66576) (xy 400.976642 -105.723653) (xy 400.953706 -105.779026)
			(xy 400.923739 -105.830932) (xy 400.887252 -105.878482) (xy 400.844872 -105.920862) (xy 400.797322 -105.957349)
			(xy 400.745416 -105.987316) (xy 400.690043 -106.010252) (xy 400.63215 -106.025765) (xy 400.572728 -106.033588)
			(xy 400.512792 -106.033588) (xy 400.45337 -106.025765) (xy 400.395477 -106.010252) (xy 400.340104 -105.987316)
			(xy 400.288198 -105.957349) (xy 400.240648 -105.920862) (xy 400.198268 -105.878482) (xy 400.161781 -105.830932)
			(xy 400.131814 -105.779026) (xy 400.108878 -105.723653) (xy 400.093365 -105.66576) (xy 400.085542 -105.606338)
			(xy 400.085052 -105.57637) (xy 383.883408 -105.57637) (xy 383.883408 -105.584498) (xy 383.882918 -105.614466)
			(xy 383.875095 -105.673888) (xy 383.859582 -105.731781) (xy 383.836646 -105.787154) (xy 383.806679 -105.83906)
			(xy 383.770192 -105.88661) (xy 383.727812 -105.92899) (xy 383.680262 -105.965477) (xy 383.628356 -105.995444)
			(xy 383.572983 -106.01838) (xy 383.51509 -106.033893) (xy 383.455668 -106.041716) (xy 383.395732 -106.041716)
			(xy 383.33631 -106.033893) (xy 383.278417 -106.01838) (xy 383.223044 -105.995444) (xy 383.171138 -105.965477)
			(xy 383.123588 -105.92899) (xy 383.081208 -105.88661) (xy 383.044721 -105.83906) (xy 383.014754 -105.787154)
			(xy 382.991818 -105.731781) (xy 382.976305 -105.673888) (xy 382.968482 -105.614466) (xy 382.967992 -105.584498)
			(xy 284.900491 -105.584498) (xy 284.900134 -105.606354) (xy 284.892306 -105.66581) (xy 284.876785 -105.723735)
			(xy 284.853836 -105.779139) (xy 284.823852 -105.831073) (xy 284.787346 -105.878649) (xy 284.744941 -105.921054)
			(xy 284.697365 -105.95756) (xy 284.645431 -105.987544) (xy 284.590027 -106.010493) (xy 284.532102 -106.026014)
			(xy 284.472646 -106.033842) (xy 284.412678 -106.033842) (xy 284.353222 -106.026014) (xy 284.295297 -106.010493)
			(xy 284.239893 -105.987544) (xy 284.187959 -105.95756) (xy 284.140383 -105.921054) (xy 284.097978 -105.878649)
			(xy 284.061472 -105.831073) (xy 284.031488 -105.779139) (xy 284.008539 -105.723735) (xy 283.993018 -105.66581)
			(xy 283.98519 -105.606354) (xy 283.9847 -105.57637) (xy 267.783564 -105.57637) (xy 267.783564 -105.584498)
			(xy 267.783074 -105.614482) (xy 267.775246 -105.673938) (xy 267.759725 -105.731863) (xy 267.736776 -105.787267)
			(xy 267.706792 -105.839201) (xy 267.670286 -105.886777) (xy 267.627881 -105.929182) (xy 267.580305 -105.965688)
			(xy 267.528371 -105.995672) (xy 267.472967 -106.018621) (xy 267.415042 -106.034142) (xy 267.355586 -106.04197)
			(xy 267.295618 -106.04197) (xy 267.236162 -106.034142) (xy 267.178237 -106.018621) (xy 267.122833 -105.995672)
			(xy 267.070899 -105.965688) (xy 267.023323 -105.929182) (xy 266.980918 -105.886777) (xy 266.944412 -105.839201)
			(xy 266.914428 -105.787267) (xy 266.891479 -105.731863) (xy 266.875958 -105.673938) (xy 266.86813 -105.614482)
			(xy 266.86764 -105.584498) (xy 168.800647 -105.584498) (xy 168.80029 -105.606354) (xy 168.792462 -105.66581)
			(xy 168.776941 -105.723735) (xy 168.753992 -105.779139) (xy 168.724008 -105.831073) (xy 168.687502 -105.878649)
			(xy 168.645097 -105.921054) (xy 168.597521 -105.95756) (xy 168.545587 -105.987544) (xy 168.490183 -106.010493)
			(xy 168.432258 -106.026014) (xy 168.372802 -106.033842) (xy 168.312834 -106.033842) (xy 168.253378 -106.026014)
			(xy 168.195453 -106.010493) (xy 168.140049 -105.987544) (xy 168.088115 -105.95756) (xy 168.040539 -105.921054)
			(xy 167.998134 -105.878649) (xy 167.961628 -105.831073) (xy 167.931644 -105.779139) (xy 167.908695 -105.723735)
			(xy 167.893174 -105.66581) (xy 167.885346 -105.606354) (xy 167.884856 -105.57637) (xy 151.68372 -105.57637)
			(xy 151.68372 -105.584498) (xy 151.68323 -105.614482) (xy 151.675402 -105.673938) (xy 151.659881 -105.731863)
			(xy 151.636932 -105.787267) (xy 151.606948 -105.839201) (xy 151.570442 -105.886777) (xy 151.528037 -105.929182)
			(xy 151.480461 -105.965688) (xy 151.428527 -105.995672) (xy 151.373123 -106.018621) (xy 151.315198 -106.034142)
			(xy 151.255742 -106.04197) (xy 151.195774 -106.04197) (xy 151.136318 -106.034142) (xy 151.078393 -106.018621)
			(xy 151.022989 -105.995672) (xy 150.971055 -105.965688) (xy 150.923479 -105.929182) (xy 150.881074 -105.886777)
			(xy 150.844568 -105.839201) (xy 150.814584 -105.787267) (xy 150.791635 -105.731863) (xy 150.776114 -105.673938)
			(xy 150.768286 -105.614482) (xy 150.767796 -105.584498) (xy 52.700295 -105.584498) (xy 52.699938 -105.606338)
			(xy 52.692115 -105.66576) (xy 52.676602 -105.723653) (xy 52.653666 -105.779026) (xy 52.623699 -105.830932)
			(xy 52.587212 -105.878482) (xy 52.544832 -105.920862) (xy 52.497282 -105.957349) (xy 52.445376 -105.987316)
			(xy 52.390003 -106.010252) (xy 52.33211 -106.025765) (xy 52.272688 -106.033588) (xy 52.212752 -106.033588)
			(xy 52.15333 -106.025765) (xy 52.095437 -106.010252) (xy 52.040064 -105.987316) (xy 51.988158 -105.957349)
			(xy 51.940608 -105.920862) (xy 51.898228 -105.878482) (xy 51.861741 -105.830932) (xy 51.831774 -105.779026)
			(xy 51.808838 -105.723653) (xy 51.793325 -105.66576) (xy 51.785502 -105.606338) (xy 51.785012 -105.57637)
			(xy 35.583368 -105.57637) (xy 35.583368 -105.584498) (xy 35.582878 -105.614466) (xy 35.575055 -105.673888)
			(xy 35.559542 -105.731781) (xy 35.536606 -105.787154) (xy 35.506639 -105.83906) (xy 35.470152 -105.88661)
			(xy 35.427772 -105.92899) (xy 35.380222 -105.965477) (xy 35.328316 -105.995444) (xy 35.272943 -106.01838)
			(xy 35.21505 -106.033893) (xy 35.155628 -106.041716) (xy 35.095692 -106.041716) (xy 35.03627 -106.033893)
			(xy 34.978377 -106.01838) (xy 34.923004 -105.995444) (xy 34.871098 -105.965477) (xy 34.823548 -105.92899)
			(xy 34.781168 -105.88661) (xy 34.744681 -105.83906) (xy 34.714714 -105.787154) (xy 34.691778 -105.731781)
			(xy 34.676265 -105.673888) (xy 34.668442 -105.614466) (xy 34.667952 -105.584498) (xy 4.308094 -105.584498)
			(xy 4.308094 -107.377738) (xy 37.31006 -107.377738) (xy 37.31006 -106.514138) (xy 37.31055 -106.48417)
			(xy 37.318373 -106.424748) (xy 37.333886 -106.366855) (xy 37.356822 -106.311482) (xy 37.386789 -106.259576)
			(xy 37.423276 -106.212026) (xy 37.465656 -106.169646) (xy 37.513206 -106.133159) (xy 37.565112 -106.103192)
			(xy 37.620485 -106.080256) (xy 37.678378 -106.064743) (xy 37.7378 -106.05692) (xy 37.797736 -106.05692)
			(xy 37.857158 -106.064743) (xy 37.915051 -106.080256) (xy 37.970424 -106.103192) (xy 38.02233 -106.133159)
			(xy 38.06988 -106.169646) (xy 38.11226 -106.212026) (xy 38.148747 -106.259576) (xy 38.178714 -106.311482)
			(xy 38.20165 -106.366855) (xy 38.217163 -106.424748) (xy 38.224986 -106.48417) (xy 38.225476 -106.514138)
			(xy 38.225476 -107.376214) (xy 53.639212 -107.376214) (xy 53.639212 -106.512614) (xy 53.639702 -106.482646)
			(xy 53.647525 -106.423224) (xy 53.663038 -106.365331) (xy 53.685974 -106.309958) (xy 53.715941 -106.258052)
			(xy 53.752428 -106.210502) (xy 53.794808 -106.168122) (xy 53.842358 -106.131635) (xy 53.894264 -106.101668)
			(xy 53.949637 -106.078732) (xy 54.00753 -106.063219) (xy 54.066952 -106.055396) (xy 54.126888 -106.055396)
			(xy 54.18631 -106.063219) (xy 54.244203 -106.078732) (xy 54.299576 -106.101668) (xy 54.351482 -106.131635)
			(xy 54.399032 -106.168122) (xy 54.441412 -106.210502) (xy 54.477899 -106.258052) (xy 54.507866 -106.309958)
			(xy 54.530802 -106.365331) (xy 54.546315 -106.423224) (xy 54.554138 -106.482646) (xy 54.554628 -106.512614)
			(xy 54.554628 -107.376214) (xy 54.554603 -107.377738) (xy 153.409904 -107.377738) (xy 153.409904 -106.514138)
			(xy 153.410394 -106.484154) (xy 153.418222 -106.424698) (xy 153.433743 -106.366773) (xy 153.456692 -106.311369)
			(xy 153.486676 -106.259435) (xy 153.523182 -106.211859) (xy 153.565587 -106.169454) (xy 153.613163 -106.132948)
			(xy 153.665097 -106.102964) (xy 153.720501 -106.080015) (xy 153.778426 -106.064494) (xy 153.837882 -106.056666)
			(xy 153.89785 -106.056666) (xy 153.957306 -106.064494) (xy 154.015231 -106.080015) (xy 154.070635 -106.102964)
			(xy 154.122569 -106.132948) (xy 154.170145 -106.169454) (xy 154.21255 -106.211859) (xy 154.249056 -106.259435)
			(xy 154.27904 -106.311369) (xy 154.301989 -106.366773) (xy 154.31751 -106.424698) (xy 154.325338 -106.484154)
			(xy 154.325828 -106.514138) (xy 154.325828 -107.376214) (xy 169.739056 -107.376214) (xy 169.739056 -106.512614)
			(xy 169.739546 -106.48263) (xy 169.747374 -106.423174) (xy 169.762895 -106.365249) (xy 169.785844 -106.309845)
			(xy 169.815828 -106.257911) (xy 169.852334 -106.210335) (xy 169.894739 -106.16793) (xy 169.942315 -106.131424)
			(xy 169.994249 -106.10144) (xy 170.049653 -106.078491) (xy 170.107578 -106.06297) (xy 170.167034 -106.055142)
			(xy 170.227002 -106.055142) (xy 170.286458 -106.06297) (xy 170.344383 -106.078491) (xy 170.399787 -106.10144)
			(xy 170.451721 -106.131424) (xy 170.499297 -106.16793) (xy 170.541702 -106.210335) (xy 170.578208 -106.257911)
			(xy 170.608192 -106.309845) (xy 170.631141 -106.365249) (xy 170.646662 -106.423174) (xy 170.65449 -106.48263)
			(xy 170.65498 -106.512614) (xy 170.65498 -107.376214) (xy 170.654955 -107.377738) (xy 269.509748 -107.377738)
			(xy 269.509748 -106.514138) (xy 269.510238 -106.484154) (xy 269.518066 -106.424698) (xy 269.533587 -106.366773)
			(xy 269.556536 -106.311369) (xy 269.58652 -106.259435) (xy 269.623026 -106.211859) (xy 269.665431 -106.169454)
			(xy 269.713007 -106.132948) (xy 269.764941 -106.102964) (xy 269.820345 -106.080015) (xy 269.87827 -106.064494)
			(xy 269.937726 -106.056666) (xy 269.997694 -106.056666) (xy 270.05715 -106.064494) (xy 270.115075 -106.080015)
			(xy 270.170479 -106.102964) (xy 270.222413 -106.132948) (xy 270.269989 -106.169454) (xy 270.312394 -106.211859)
			(xy 270.3489 -106.259435) (xy 270.378884 -106.311369) (xy 270.401833 -106.366773) (xy 270.417354 -106.424698)
			(xy 270.425182 -106.484154) (xy 270.425672 -106.514138) (xy 270.425672 -107.376214) (xy 285.8389 -107.376214)
			(xy 285.8389 -106.512614) (xy 285.83939 -106.48263) (xy 285.847218 -106.423174) (xy 285.862739 -106.365249)
			(xy 285.885688 -106.309845) (xy 285.915672 -106.257911) (xy 285.952178 -106.210335) (xy 285.994583 -106.16793)
			(xy 286.042159 -106.131424) (xy 286.094093 -106.10144) (xy 286.149497 -106.078491) (xy 286.207422 -106.06297)
			(xy 286.266878 -106.055142) (xy 286.326846 -106.055142) (xy 286.386302 -106.06297) (xy 286.444227 -106.078491)
			(xy 286.499631 -106.10144) (xy 286.551565 -106.131424) (xy 286.599141 -106.16793) (xy 286.641546 -106.210335)
			(xy 286.678052 -106.257911) (xy 286.708036 -106.309845) (xy 286.730985 -106.365249) (xy 286.746506 -106.423174)
			(xy 286.754334 -106.48263) (xy 286.754824 -106.512614) (xy 286.754824 -107.376214) (xy 286.754799 -107.377738)
			(xy 385.6101 -107.377738) (xy 385.6101 -106.514138) (xy 385.61059 -106.48417) (xy 385.618413 -106.424748)
			(xy 385.633926 -106.366855) (xy 385.656862 -106.311482) (xy 385.686829 -106.259576) (xy 385.723316 -106.212026)
			(xy 385.765696 -106.169646) (xy 385.813246 -106.133159) (xy 385.865152 -106.103192) (xy 385.920525 -106.080256)
			(xy 385.978418 -106.064743) (xy 386.03784 -106.05692) (xy 386.097776 -106.05692) (xy 386.157198 -106.064743)
			(xy 386.215091 -106.080256) (xy 386.270464 -106.103192) (xy 386.32237 -106.133159) (xy 386.36992 -106.169646)
			(xy 386.4123 -106.212026) (xy 386.448787 -106.259576) (xy 386.478754 -106.311482) (xy 386.50169 -106.366855)
			(xy 386.517203 -106.424748) (xy 386.525026 -106.48417) (xy 386.525516 -106.514138) (xy 386.525516 -107.376214)
			(xy 401.939252 -107.376214) (xy 401.939252 -106.512614) (xy 401.939742 -106.482646) (xy 401.947565 -106.423224)
			(xy 401.963078 -106.365331) (xy 401.986014 -106.309958) (xy 402.015981 -106.258052) (xy 402.052468 -106.210502)
			(xy 402.094848 -106.168122) (xy 402.142398 -106.131635) (xy 402.194304 -106.101668) (xy 402.249677 -106.078732)
			(xy 402.30757 -106.063219) (xy 402.366992 -106.055396) (xy 402.426928 -106.055396) (xy 402.48635 -106.063219)
			(xy 402.544243 -106.078732) (xy 402.599616 -106.101668) (xy 402.651522 -106.131635) (xy 402.699072 -106.168122)
			(xy 402.741452 -106.210502) (xy 402.777939 -106.258052) (xy 402.807906 -106.309958) (xy 402.830842 -106.365331)
			(xy 402.846355 -106.423224) (xy 402.854178 -106.482646) (xy 402.854668 -106.512614) (xy 402.854668 -107.376214)
			(xy 402.854178 -107.406182) (xy 402.846355 -107.465604) (xy 402.830842 -107.523497) (xy 402.807906 -107.57887)
			(xy 402.777939 -107.630776) (xy 402.741452 -107.678326) (xy 402.699072 -107.720706) (xy 402.651522 -107.757193)
			(xy 402.599616 -107.78716) (xy 402.544243 -107.810096) (xy 402.48635 -107.825609) (xy 402.426928 -107.833432)
			(xy 402.366992 -107.833432) (xy 402.30757 -107.825609) (xy 402.249677 -107.810096) (xy 402.194304 -107.78716)
			(xy 402.142398 -107.757193) (xy 402.094848 -107.720706) (xy 402.052468 -107.678326) (xy 402.015981 -107.630776)
			(xy 401.986014 -107.57887) (xy 401.963078 -107.523497) (xy 401.947565 -107.465604) (xy 401.939742 -107.406182)
			(xy 401.939252 -107.376214) (xy 386.525516 -107.376214) (xy 386.525516 -107.377738) (xy 386.525026 -107.407706)
			(xy 386.517203 -107.467128) (xy 386.50169 -107.525021) (xy 386.478754 -107.580394) (xy 386.448787 -107.6323)
			(xy 386.4123 -107.67985) (xy 386.36992 -107.72223) (xy 386.32237 -107.758717) (xy 386.270464 -107.788684)
			(xy 386.215091 -107.81162) (xy 386.157198 -107.827133) (xy 386.097776 -107.834956) (xy 386.03784 -107.834956)
			(xy 385.978418 -107.827133) (xy 385.920525 -107.81162) (xy 385.865152 -107.788684) (xy 385.813246 -107.758717)
			(xy 385.765696 -107.72223) (xy 385.723316 -107.67985) (xy 385.686829 -107.6323) (xy 385.656862 -107.580394)
			(xy 385.633926 -107.525021) (xy 385.618413 -107.467128) (xy 385.61059 -107.407706) (xy 385.6101 -107.377738)
			(xy 286.754799 -107.377738) (xy 286.754334 -107.406198) (xy 286.746506 -107.465654) (xy 286.730985 -107.523579)
			(xy 286.708036 -107.578983) (xy 286.678052 -107.630917) (xy 286.641546 -107.678493) (xy 286.599141 -107.720898)
			(xy 286.551565 -107.757404) (xy 286.499631 -107.787388) (xy 286.444227 -107.810337) (xy 286.386302 -107.825858)
			(xy 286.326846 -107.833686) (xy 286.266878 -107.833686) (xy 286.207422 -107.825858) (xy 286.149497 -107.810337)
			(xy 286.094093 -107.787388) (xy 286.042159 -107.757404) (xy 285.994583 -107.720898) (xy 285.952178 -107.678493)
			(xy 285.915672 -107.630917) (xy 285.885688 -107.578983) (xy 285.862739 -107.523579) (xy 285.847218 -107.465654)
			(xy 285.83939 -107.406198) (xy 285.8389 -107.376214) (xy 270.425672 -107.376214) (xy 270.425672 -107.377738)
			(xy 270.425182 -107.407722) (xy 270.417354 -107.467178) (xy 270.401833 -107.525103) (xy 270.378884 -107.580507)
			(xy 270.3489 -107.632441) (xy 270.312394 -107.680017) (xy 270.269989 -107.722422) (xy 270.222413 -107.758928)
			(xy 270.170479 -107.788912) (xy 270.115075 -107.811861) (xy 270.05715 -107.827382) (xy 269.997694 -107.83521)
			(xy 269.937726 -107.83521) (xy 269.87827 -107.827382) (xy 269.820345 -107.811861) (xy 269.764941 -107.788912)
			(xy 269.713007 -107.758928) (xy 269.665431 -107.722422) (xy 269.623026 -107.680017) (xy 269.58652 -107.632441)
			(xy 269.556536 -107.580507) (xy 269.533587 -107.525103) (xy 269.518066 -107.467178) (xy 269.510238 -107.407722)
			(xy 269.509748 -107.377738) (xy 170.654955 -107.377738) (xy 170.65449 -107.406198) (xy 170.646662 -107.465654)
			(xy 170.631141 -107.523579) (xy 170.608192 -107.578983) (xy 170.578208 -107.630917) (xy 170.541702 -107.678493)
			(xy 170.499297 -107.720898) (xy 170.451721 -107.757404) (xy 170.399787 -107.787388) (xy 170.344383 -107.810337)
			(xy 170.286458 -107.825858) (xy 170.227002 -107.833686) (xy 170.167034 -107.833686) (xy 170.107578 -107.825858)
			(xy 170.049653 -107.810337) (xy 169.994249 -107.787388) (xy 169.942315 -107.757404) (xy 169.894739 -107.720898)
			(xy 169.852334 -107.678493) (xy 169.815828 -107.630917) (xy 169.785844 -107.578983) (xy 169.762895 -107.523579)
			(xy 169.747374 -107.465654) (xy 169.739546 -107.406198) (xy 169.739056 -107.376214) (xy 154.325828 -107.376214)
			(xy 154.325828 -107.377738) (xy 154.325338 -107.407722) (xy 154.31751 -107.467178) (xy 154.301989 -107.525103)
			(xy 154.27904 -107.580507) (xy 154.249056 -107.632441) (xy 154.21255 -107.680017) (xy 154.170145 -107.722422)
			(xy 154.122569 -107.758928) (xy 154.070635 -107.788912) (xy 154.015231 -107.811861) (xy 153.957306 -107.827382)
			(xy 153.89785 -107.83521) (xy 153.837882 -107.83521) (xy 153.778426 -107.827382) (xy 153.720501 -107.811861)
			(xy 153.665097 -107.788912) (xy 153.613163 -107.758928) (xy 153.565587 -107.722422) (xy 153.523182 -107.680017)
			(xy 153.486676 -107.632441) (xy 153.456692 -107.580507) (xy 153.433743 -107.525103) (xy 153.418222 -107.467178)
			(xy 153.410394 -107.407722) (xy 153.409904 -107.377738) (xy 54.554603 -107.377738) (xy 54.554138 -107.406182)
			(xy 54.546315 -107.465604) (xy 54.530802 -107.523497) (xy 54.507866 -107.57887) (xy 54.477899 -107.630776)
			(xy 54.441412 -107.678326) (xy 54.399032 -107.720706) (xy 54.351482 -107.757193) (xy 54.299576 -107.78716)
			(xy 54.244203 -107.810096) (xy 54.18631 -107.825609) (xy 54.126888 -107.833432) (xy 54.066952 -107.833432)
			(xy 54.00753 -107.825609) (xy 53.949637 -107.810096) (xy 53.894264 -107.78716) (xy 53.842358 -107.757193)
			(xy 53.794808 -107.720706) (xy 53.752428 -107.678326) (xy 53.715941 -107.630776) (xy 53.685974 -107.57887)
			(xy 53.663038 -107.523497) (xy 53.647525 -107.465604) (xy 53.639702 -107.406182) (xy 53.639212 -107.376214)
			(xy 38.225476 -107.376214) (xy 38.225476 -107.377738) (xy 38.224986 -107.407706) (xy 38.217163 -107.467128)
			(xy 38.20165 -107.525021) (xy 38.178714 -107.580394) (xy 38.148747 -107.6323) (xy 38.11226 -107.67985)
			(xy 38.06988 -107.72223) (xy 38.02233 -107.758717) (xy 37.970424 -107.788684) (xy 37.915051 -107.81162)
			(xy 37.857158 -107.827133) (xy 37.797736 -107.834956) (xy 37.7378 -107.834956) (xy 37.678378 -107.827133)
			(xy 37.620485 -107.81162) (xy 37.565112 -107.788684) (xy 37.513206 -107.758717) (xy 37.465656 -107.72223)
			(xy 37.423276 -107.67985) (xy 37.386789 -107.6323) (xy 37.356822 -107.580394) (xy 37.333886 -107.525021)
			(xy 37.318373 -107.467128) (xy 37.31055 -107.407706) (xy 37.31006 -107.377738) (xy 4.308094 -107.377738)
			(xy 4.308094 -109.18444) (xy 34.667952 -109.18444) (xy 34.667952 -108.32084) (xy 34.668442 -108.290872)
			(xy 34.676265 -108.23145) (xy 34.691778 -108.173557) (xy 34.714714 -108.118184) (xy 34.744681 -108.066278)
			(xy 34.781168 -108.018728) (xy 34.823548 -107.976348) (xy 34.871098 -107.939861) (xy 34.923004 -107.909894)
			(xy 34.978377 -107.886958) (xy 35.03627 -107.871445) (xy 35.095692 -107.863622) (xy 35.155628 -107.863622)
			(xy 35.21505 -107.871445) (xy 35.272943 -107.886958) (xy 35.328316 -107.909894) (xy 35.380222 -107.939861)
			(xy 35.427772 -107.976348) (xy 35.470152 -108.018728) (xy 35.506639 -108.066278) (xy 35.536606 -108.118184)
			(xy 35.559542 -108.173557) (xy 35.575055 -108.23145) (xy 35.582878 -108.290872) (xy 35.583368 -108.32084)
			(xy 35.583368 -109.176312) (xy 51.785012 -109.176312) (xy 51.785012 -108.312712) (xy 51.785502 -108.282744)
			(xy 51.793325 -108.223322) (xy 51.808838 -108.165429) (xy 51.831774 -108.110056) (xy 51.861741 -108.05815)
			(xy 51.898228 -108.0106) (xy 51.940608 -107.96822) (xy 51.988158 -107.931733) (xy 52.040064 -107.901766)
			(xy 52.095437 -107.87883) (xy 52.15333 -107.863317) (xy 52.212752 -107.855494) (xy 52.272688 -107.855494)
			(xy 52.33211 -107.863317) (xy 52.390003 -107.87883) (xy 52.445376 -107.901766) (xy 52.497282 -107.931733)
			(xy 52.544832 -107.96822) (xy 52.587212 -108.0106) (xy 52.623699 -108.05815) (xy 52.653666 -108.110056)
			(xy 52.676602 -108.165429) (xy 52.692115 -108.223322) (xy 52.699938 -108.282744) (xy 52.700428 -108.312712)
			(xy 52.700428 -109.176312) (xy 52.700295 -109.18444) (xy 150.767796 -109.18444) (xy 150.767796 -108.32084)
			(xy 150.768286 -108.290856) (xy 150.776114 -108.2314) (xy 150.791635 -108.173475) (xy 150.814584 -108.118071)
			(xy 150.844568 -108.066137) (xy 150.881074 -108.018561) (xy 150.923479 -107.976156) (xy 150.971055 -107.93965)
			(xy 151.022989 -107.909666) (xy 151.078393 -107.886717) (xy 151.136318 -107.871196) (xy 151.195774 -107.863368)
			(xy 151.255742 -107.863368) (xy 151.315198 -107.871196) (xy 151.373123 -107.886717) (xy 151.428527 -107.909666)
			(xy 151.480461 -107.93965) (xy 151.528037 -107.976156) (xy 151.570442 -108.018561) (xy 151.606948 -108.066137)
			(xy 151.636932 -108.118071) (xy 151.659881 -108.173475) (xy 151.675402 -108.2314) (xy 151.68323 -108.290856)
			(xy 151.68372 -108.32084) (xy 151.68372 -109.176312) (xy 167.884856 -109.176312) (xy 167.884856 -108.312712)
			(xy 167.885346 -108.282728) (xy 167.893174 -108.223272) (xy 167.908695 -108.165347) (xy 167.931644 -108.109943)
			(xy 167.961628 -108.058009) (xy 167.998134 -108.010433) (xy 168.040539 -107.968028) (xy 168.088115 -107.931522)
			(xy 168.140049 -107.901538) (xy 168.195453 -107.878589) (xy 168.253378 -107.863068) (xy 168.312834 -107.85524)
			(xy 168.372802 -107.85524) (xy 168.432258 -107.863068) (xy 168.490183 -107.878589) (xy 168.545587 -107.901538)
			(xy 168.597521 -107.931522) (xy 168.645097 -107.968028) (xy 168.687502 -108.010433) (xy 168.724008 -108.058009)
			(xy 168.753992 -108.109943) (xy 168.776941 -108.165347) (xy 168.792462 -108.223272) (xy 168.80029 -108.282728)
			(xy 168.80078 -108.312712) (xy 168.80078 -109.176312) (xy 168.800647 -109.18444) (xy 266.86764 -109.18444)
			(xy 266.86764 -108.32084) (xy 266.86813 -108.290856) (xy 266.875958 -108.2314) (xy 266.891479 -108.173475)
			(xy 266.914428 -108.118071) (xy 266.944412 -108.066137) (xy 266.980918 -108.018561) (xy 267.023323 -107.976156)
			(xy 267.070899 -107.93965) (xy 267.122833 -107.909666) (xy 267.178237 -107.886717) (xy 267.236162 -107.871196)
			(xy 267.295618 -107.863368) (xy 267.355586 -107.863368) (xy 267.415042 -107.871196) (xy 267.472967 -107.886717)
			(xy 267.528371 -107.909666) (xy 267.580305 -107.93965) (xy 267.627881 -107.976156) (xy 267.670286 -108.018561)
			(xy 267.706792 -108.066137) (xy 267.736776 -108.118071) (xy 267.759725 -108.173475) (xy 267.775246 -108.2314)
			(xy 267.783074 -108.290856) (xy 267.783564 -108.32084) (xy 267.783564 -109.176312) (xy 283.9847 -109.176312)
			(xy 283.9847 -108.312712) (xy 283.98519 -108.282728) (xy 283.993018 -108.223272) (xy 284.008539 -108.165347)
			(xy 284.031488 -108.109943) (xy 284.061472 -108.058009) (xy 284.097978 -108.010433) (xy 284.140383 -107.968028)
			(xy 284.187959 -107.931522) (xy 284.239893 -107.901538) (xy 284.295297 -107.878589) (xy 284.353222 -107.863068)
			(xy 284.412678 -107.85524) (xy 284.472646 -107.85524) (xy 284.532102 -107.863068) (xy 284.590027 -107.878589)
			(xy 284.645431 -107.901538) (xy 284.697365 -107.931522) (xy 284.744941 -107.968028) (xy 284.787346 -108.010433)
			(xy 284.823852 -108.058009) (xy 284.853836 -108.109943) (xy 284.876785 -108.165347) (xy 284.892306 -108.223272)
			(xy 284.900134 -108.282728) (xy 284.900624 -108.312712) (xy 284.900624 -109.176312) (xy 284.900491 -109.18444)
			(xy 382.967992 -109.18444) (xy 382.967992 -108.32084) (xy 382.968482 -108.290872) (xy 382.976305 -108.23145)
			(xy 382.991818 -108.173557) (xy 383.014754 -108.118184) (xy 383.044721 -108.066278) (xy 383.081208 -108.018728)
			(xy 383.123588 -107.976348) (xy 383.171138 -107.939861) (xy 383.223044 -107.909894) (xy 383.278417 -107.886958)
			(xy 383.33631 -107.871445) (xy 383.395732 -107.863622) (xy 383.455668 -107.863622) (xy 383.51509 -107.871445)
			(xy 383.572983 -107.886958) (xy 383.628356 -107.909894) (xy 383.680262 -107.939861) (xy 383.727812 -107.976348)
			(xy 383.770192 -108.018728) (xy 383.806679 -108.066278) (xy 383.836646 -108.118184) (xy 383.859582 -108.173557)
			(xy 383.875095 -108.23145) (xy 383.882918 -108.290872) (xy 383.883408 -108.32084) (xy 383.883408 -109.176312)
			(xy 400.085052 -109.176312) (xy 400.085052 -108.312712) (xy 400.085542 -108.282744) (xy 400.093365 -108.223322)
			(xy 400.108878 -108.165429) (xy 400.131814 -108.110056) (xy 400.161781 -108.05815) (xy 400.198268 -108.0106)
			(xy 400.240648 -107.96822) (xy 400.288198 -107.931733) (xy 400.340104 -107.901766) (xy 400.395477 -107.87883)
			(xy 400.45337 -107.863317) (xy 400.512792 -107.855494) (xy 400.572728 -107.855494) (xy 400.63215 -107.863317)
			(xy 400.690043 -107.87883) (xy 400.745416 -107.901766) (xy 400.797322 -107.931733) (xy 400.844872 -107.96822)
			(xy 400.887252 -108.0106) (xy 400.923739 -108.05815) (xy 400.953706 -108.110056) (xy 400.976642 -108.165429)
			(xy 400.992155 -108.223322) (xy 400.999978 -108.282744) (xy 401.000468 -108.312712) (xy 401.000468 -109.176312)
			(xy 400.999978 -109.20628) (xy 400.992155 -109.265702) (xy 400.976642 -109.323595) (xy 400.953706 -109.378968)
			(xy 400.923739 -109.430874) (xy 400.887252 -109.478424) (xy 400.844872 -109.520804) (xy 400.797322 -109.557291)
			(xy 400.745416 -109.587258) (xy 400.690043 -109.610194) (xy 400.63215 -109.625707) (xy 400.572728 -109.63353)
			(xy 400.512792 -109.63353) (xy 400.45337 -109.625707) (xy 400.395477 -109.610194) (xy 400.340104 -109.587258)
			(xy 400.288198 -109.557291) (xy 400.240648 -109.520804) (xy 400.198268 -109.478424) (xy 400.161781 -109.430874)
			(xy 400.131814 -109.378968) (xy 400.108878 -109.323595) (xy 400.093365 -109.265702) (xy 400.085542 -109.20628)
			(xy 400.085052 -109.176312) (xy 383.883408 -109.176312) (xy 383.883408 -109.18444) (xy 383.882918 -109.214408)
			(xy 383.875095 -109.27383) (xy 383.859582 -109.331723) (xy 383.836646 -109.387096) (xy 383.806679 -109.439002)
			(xy 383.770192 -109.486552) (xy 383.727812 -109.528932) (xy 383.680262 -109.565419) (xy 383.628356 -109.595386)
			(xy 383.572983 -109.618322) (xy 383.51509 -109.633835) (xy 383.455668 -109.641658) (xy 383.395732 -109.641658)
			(xy 383.33631 -109.633835) (xy 383.278417 -109.618322) (xy 383.223044 -109.595386) (xy 383.171138 -109.565419)
			(xy 383.123588 -109.528932) (xy 383.081208 -109.486552) (xy 383.044721 -109.439002) (xy 383.014754 -109.387096)
			(xy 382.991818 -109.331723) (xy 382.976305 -109.27383) (xy 382.968482 -109.214408) (xy 382.967992 -109.18444)
			(xy 284.900491 -109.18444) (xy 284.900134 -109.206296) (xy 284.892306 -109.265752) (xy 284.876785 -109.323677)
			(xy 284.853836 -109.379081) (xy 284.823852 -109.431015) (xy 284.787346 -109.478591) (xy 284.744941 -109.520996)
			(xy 284.697365 -109.557502) (xy 284.645431 -109.587486) (xy 284.590027 -109.610435) (xy 284.532102 -109.625956)
			(xy 284.472646 -109.633784) (xy 284.412678 -109.633784) (xy 284.353222 -109.625956) (xy 284.295297 -109.610435)
			(xy 284.239893 -109.587486) (xy 284.187959 -109.557502) (xy 284.140383 -109.520996) (xy 284.097978 -109.478591)
			(xy 284.061472 -109.431015) (xy 284.031488 -109.379081) (xy 284.008539 -109.323677) (xy 283.993018 -109.265752)
			(xy 283.98519 -109.206296) (xy 283.9847 -109.176312) (xy 267.783564 -109.176312) (xy 267.783564 -109.18444)
			(xy 267.783074 -109.214424) (xy 267.775246 -109.27388) (xy 267.759725 -109.331805) (xy 267.736776 -109.387209)
			(xy 267.706792 -109.439143) (xy 267.670286 -109.486719) (xy 267.627881 -109.529124) (xy 267.580305 -109.56563)
			(xy 267.528371 -109.595614) (xy 267.472967 -109.618563) (xy 267.415042 -109.634084) (xy 267.355586 -109.641912)
			(xy 267.295618 -109.641912) (xy 267.236162 -109.634084) (xy 267.178237 -109.618563) (xy 267.122833 -109.595614)
			(xy 267.070899 -109.56563) (xy 267.023323 -109.529124) (xy 266.980918 -109.486719) (xy 266.944412 -109.439143)
			(xy 266.914428 -109.387209) (xy 266.891479 -109.331805) (xy 266.875958 -109.27388) (xy 266.86813 -109.214424)
			(xy 266.86764 -109.18444) (xy 168.800647 -109.18444) (xy 168.80029 -109.206296) (xy 168.792462 -109.265752)
			(xy 168.776941 -109.323677) (xy 168.753992 -109.379081) (xy 168.724008 -109.431015) (xy 168.687502 -109.478591)
			(xy 168.645097 -109.520996) (xy 168.597521 -109.557502) (xy 168.545587 -109.587486) (xy 168.490183 -109.610435)
			(xy 168.432258 -109.625956) (xy 168.372802 -109.633784) (xy 168.312834 -109.633784) (xy 168.253378 -109.625956)
			(xy 168.195453 -109.610435) (xy 168.140049 -109.587486) (xy 168.088115 -109.557502) (xy 168.040539 -109.520996)
			(xy 167.998134 -109.478591) (xy 167.961628 -109.431015) (xy 167.931644 -109.379081) (xy 167.908695 -109.323677)
			(xy 167.893174 -109.265752) (xy 167.885346 -109.206296) (xy 167.884856 -109.176312) (xy 151.68372 -109.176312)
			(xy 151.68372 -109.18444) (xy 151.68323 -109.214424) (xy 151.675402 -109.27388) (xy 151.659881 -109.331805)
			(xy 151.636932 -109.387209) (xy 151.606948 -109.439143) (xy 151.570442 -109.486719) (xy 151.528037 -109.529124)
			(xy 151.480461 -109.56563) (xy 151.428527 -109.595614) (xy 151.373123 -109.618563) (xy 151.315198 -109.634084)
			(xy 151.255742 -109.641912) (xy 151.195774 -109.641912) (xy 151.136318 -109.634084) (xy 151.078393 -109.618563)
			(xy 151.022989 -109.595614) (xy 150.971055 -109.56563) (xy 150.923479 -109.529124) (xy 150.881074 -109.486719)
			(xy 150.844568 -109.439143) (xy 150.814584 -109.387209) (xy 150.791635 -109.331805) (xy 150.776114 -109.27388)
			(xy 150.768286 -109.214424) (xy 150.767796 -109.18444) (xy 52.700295 -109.18444) (xy 52.699938 -109.20628)
			(xy 52.692115 -109.265702) (xy 52.676602 -109.323595) (xy 52.653666 -109.378968) (xy 52.623699 -109.430874)
			(xy 52.587212 -109.478424) (xy 52.544832 -109.520804) (xy 52.497282 -109.557291) (xy 52.445376 -109.587258)
			(xy 52.390003 -109.610194) (xy 52.33211 -109.625707) (xy 52.272688 -109.63353) (xy 52.212752 -109.63353)
			(xy 52.15333 -109.625707) (xy 52.095437 -109.610194) (xy 52.040064 -109.587258) (xy 51.988158 -109.557291)
			(xy 51.940608 -109.520804) (xy 51.898228 -109.478424) (xy 51.861741 -109.430874) (xy 51.831774 -109.378968)
			(xy 51.808838 -109.323595) (xy 51.793325 -109.265702) (xy 51.785502 -109.20628) (xy 51.785012 -109.176312)
			(xy 35.583368 -109.176312) (xy 35.583368 -109.18444) (xy 35.582878 -109.214408) (xy 35.575055 -109.27383)
			(xy 35.559542 -109.331723) (xy 35.536606 -109.387096) (xy 35.506639 -109.439002) (xy 35.470152 -109.486552)
			(xy 35.427772 -109.528932) (xy 35.380222 -109.565419) (xy 35.328316 -109.595386) (xy 35.272943 -109.618322)
			(xy 35.21505 -109.633835) (xy 35.155628 -109.641658) (xy 35.095692 -109.641658) (xy 35.03627 -109.633835)
			(xy 34.978377 -109.618322) (xy 34.923004 -109.595386) (xy 34.871098 -109.565419) (xy 34.823548 -109.528932)
			(xy 34.781168 -109.486552) (xy 34.744681 -109.439002) (xy 34.714714 -109.387096) (xy 34.691778 -109.331723)
			(xy 34.676265 -109.27383) (xy 34.668442 -109.214408) (xy 34.667952 -109.18444) (xy 4.308094 -109.18444)
			(xy 4.308094 -110.977934) (xy 37.31006 -110.977934) (xy 37.31006 -110.114334) (xy 37.31055 -110.084366)
			(xy 37.318373 -110.024944) (xy 37.333886 -109.967051) (xy 37.356822 -109.911678) (xy 37.386789 -109.859772)
			(xy 37.423276 -109.812222) (xy 37.465656 -109.769842) (xy 37.513206 -109.733355) (xy 37.565112 -109.703388)
			(xy 37.620485 -109.680452) (xy 37.678378 -109.664939) (xy 37.7378 -109.657116) (xy 37.797736 -109.657116)
			(xy 37.857158 -109.664939) (xy 37.915051 -109.680452) (xy 37.970424 -109.703388) (xy 38.02233 -109.733355)
			(xy 38.06988 -109.769842) (xy 38.11226 -109.812222) (xy 38.148747 -109.859772) (xy 38.178714 -109.911678)
			(xy 38.20165 -109.967051) (xy 38.217163 -110.024944) (xy 38.224986 -110.084366) (xy 38.225476 -110.114334)
			(xy 38.225476 -110.97641) (xy 53.639212 -110.97641) (xy 53.639212 -110.11281) (xy 53.639702 -110.082842)
			(xy 53.647525 -110.02342) (xy 53.663038 -109.965527) (xy 53.685974 -109.910154) (xy 53.715941 -109.858248)
			(xy 53.752428 -109.810698) (xy 53.794808 -109.768318) (xy 53.842358 -109.731831) (xy 53.894264 -109.701864)
			(xy 53.949637 -109.678928) (xy 54.00753 -109.663415) (xy 54.066952 -109.655592) (xy 54.126888 -109.655592)
			(xy 54.18631 -109.663415) (xy 54.244203 -109.678928) (xy 54.299576 -109.701864) (xy 54.351482 -109.731831)
			(xy 54.399032 -109.768318) (xy 54.441412 -109.810698) (xy 54.477899 -109.858248) (xy 54.507866 -109.910154)
			(xy 54.530802 -109.965527) (xy 54.546315 -110.02342) (xy 54.554138 -110.082842) (xy 54.554628 -110.11281)
			(xy 54.554628 -110.97641) (xy 54.554603 -110.977934) (xy 153.409904 -110.977934) (xy 153.409904 -110.114334)
			(xy 153.410394 -110.08435) (xy 153.418222 -110.024894) (xy 153.433743 -109.966969) (xy 153.456692 -109.911565)
			(xy 153.486676 -109.859631) (xy 153.523182 -109.812055) (xy 153.565587 -109.76965) (xy 153.613163 -109.733144)
			(xy 153.665097 -109.70316) (xy 153.720501 -109.680211) (xy 153.778426 -109.66469) (xy 153.837882 -109.656862)
			(xy 153.89785 -109.656862) (xy 153.957306 -109.66469) (xy 154.015231 -109.680211) (xy 154.070635 -109.70316)
			(xy 154.122569 -109.733144) (xy 154.170145 -109.76965) (xy 154.21255 -109.812055) (xy 154.249056 -109.859631)
			(xy 154.27904 -109.911565) (xy 154.301989 -109.966969) (xy 154.31751 -110.024894) (xy 154.325338 -110.08435)
			(xy 154.325828 -110.114334) (xy 154.325828 -110.97641) (xy 169.739056 -110.97641) (xy 169.739056 -110.11281)
			(xy 169.739546 -110.082826) (xy 169.747374 -110.02337) (xy 169.762895 -109.965445) (xy 169.785844 -109.910041)
			(xy 169.815828 -109.858107) (xy 169.852334 -109.810531) (xy 169.894739 -109.768126) (xy 169.942315 -109.73162)
			(xy 169.994249 -109.701636) (xy 170.049653 -109.678687) (xy 170.107578 -109.663166) (xy 170.167034 -109.655338)
			(xy 170.227002 -109.655338) (xy 170.286458 -109.663166) (xy 170.344383 -109.678687) (xy 170.399787 -109.701636)
			(xy 170.451721 -109.73162) (xy 170.499297 -109.768126) (xy 170.541702 -109.810531) (xy 170.578208 -109.858107)
			(xy 170.608192 -109.910041) (xy 170.631141 -109.965445) (xy 170.646662 -110.02337) (xy 170.65449 -110.082826)
			(xy 170.65498 -110.11281) (xy 170.65498 -110.97641) (xy 170.654955 -110.977934) (xy 269.509748 -110.977934)
			(xy 269.509748 -110.114334) (xy 269.510238 -110.08435) (xy 269.518066 -110.024894) (xy 269.533587 -109.966969)
			(xy 269.556536 -109.911565) (xy 269.58652 -109.859631) (xy 269.623026 -109.812055) (xy 269.665431 -109.76965)
			(xy 269.713007 -109.733144) (xy 269.764941 -109.70316) (xy 269.820345 -109.680211) (xy 269.87827 -109.66469)
			(xy 269.937726 -109.656862) (xy 269.997694 -109.656862) (xy 270.05715 -109.66469) (xy 270.115075 -109.680211)
			(xy 270.170479 -109.70316) (xy 270.222413 -109.733144) (xy 270.269989 -109.76965) (xy 270.312394 -109.812055)
			(xy 270.3489 -109.859631) (xy 270.378884 -109.911565) (xy 270.401833 -109.966969) (xy 270.417354 -110.024894)
			(xy 270.425182 -110.08435) (xy 270.425672 -110.114334) (xy 270.425672 -110.97641) (xy 285.8389 -110.97641)
			(xy 285.8389 -110.11281) (xy 285.83939 -110.082826) (xy 285.847218 -110.02337) (xy 285.862739 -109.965445)
			(xy 285.885688 -109.910041) (xy 285.915672 -109.858107) (xy 285.952178 -109.810531) (xy 285.994583 -109.768126)
			(xy 286.042159 -109.73162) (xy 286.094093 -109.701636) (xy 286.149497 -109.678687) (xy 286.207422 -109.663166)
			(xy 286.266878 -109.655338) (xy 286.326846 -109.655338) (xy 286.386302 -109.663166) (xy 286.444227 -109.678687)
			(xy 286.499631 -109.701636) (xy 286.551565 -109.73162) (xy 286.599141 -109.768126) (xy 286.641546 -109.810531)
			(xy 286.678052 -109.858107) (xy 286.708036 -109.910041) (xy 286.730985 -109.965445) (xy 286.746506 -110.02337)
			(xy 286.754334 -110.082826) (xy 286.754824 -110.11281) (xy 286.754824 -110.97641) (xy 286.754799 -110.977934)
			(xy 385.6101 -110.977934) (xy 385.6101 -110.114334) (xy 385.61059 -110.084366) (xy 385.618413 -110.024944)
			(xy 385.633926 -109.967051) (xy 385.656862 -109.911678) (xy 385.686829 -109.859772) (xy 385.723316 -109.812222)
			(xy 385.765696 -109.769842) (xy 385.813246 -109.733355) (xy 385.865152 -109.703388) (xy 385.920525 -109.680452)
			(xy 385.978418 -109.664939) (xy 386.03784 -109.657116) (xy 386.097776 -109.657116) (xy 386.157198 -109.664939)
			(xy 386.215091 -109.680452) (xy 386.270464 -109.703388) (xy 386.32237 -109.733355) (xy 386.36992 -109.769842)
			(xy 386.4123 -109.812222) (xy 386.448787 -109.859772) (xy 386.478754 -109.911678) (xy 386.50169 -109.967051)
			(xy 386.517203 -110.024944) (xy 386.525026 -110.084366) (xy 386.525516 -110.114334) (xy 386.525516 -110.97641)
			(xy 401.939252 -110.97641) (xy 401.939252 -110.11281) (xy 401.939742 -110.082842) (xy 401.947565 -110.02342)
			(xy 401.963078 -109.965527) (xy 401.986014 -109.910154) (xy 402.015981 -109.858248) (xy 402.052468 -109.810698)
			(xy 402.094848 -109.768318) (xy 402.142398 -109.731831) (xy 402.194304 -109.701864) (xy 402.249677 -109.678928)
			(xy 402.30757 -109.663415) (xy 402.366992 -109.655592) (xy 402.426928 -109.655592) (xy 402.48635 -109.663415)
			(xy 402.544243 -109.678928) (xy 402.599616 -109.701864) (xy 402.651522 -109.731831) (xy 402.699072 -109.768318)
			(xy 402.741452 -109.810698) (xy 402.777939 -109.858248) (xy 402.807906 -109.910154) (xy 402.830842 -109.965527)
			(xy 402.846355 -110.02342) (xy 402.854178 -110.082842) (xy 402.854668 -110.11281) (xy 402.854668 -110.97641)
			(xy 402.854178 -111.006378) (xy 402.846355 -111.0658) (xy 402.830842 -111.123693) (xy 402.807906 -111.179066)
			(xy 402.777939 -111.230972) (xy 402.741452 -111.278522) (xy 402.699072 -111.320902) (xy 402.651522 -111.357389)
			(xy 402.599616 -111.387356) (xy 402.544243 -111.410292) (xy 402.48635 -111.425805) (xy 402.426928 -111.433628)
			(xy 402.366992 -111.433628) (xy 402.30757 -111.425805) (xy 402.249677 -111.410292) (xy 402.194304 -111.387356)
			(xy 402.142398 -111.357389) (xy 402.094848 -111.320902) (xy 402.052468 -111.278522) (xy 402.015981 -111.230972)
			(xy 401.986014 -111.179066) (xy 401.963078 -111.123693) (xy 401.947565 -111.0658) (xy 401.939742 -111.006378)
			(xy 401.939252 -110.97641) (xy 386.525516 -110.97641) (xy 386.525516 -110.977934) (xy 386.525026 -111.007902)
			(xy 386.517203 -111.067324) (xy 386.50169 -111.125217) (xy 386.478754 -111.18059) (xy 386.448787 -111.232496)
			(xy 386.4123 -111.280046) (xy 386.36992 -111.322426) (xy 386.32237 -111.358913) (xy 386.270464 -111.38888)
			(xy 386.215091 -111.411816) (xy 386.157198 -111.427329) (xy 386.097776 -111.435152) (xy 386.03784 -111.435152)
			(xy 385.978418 -111.427329) (xy 385.920525 -111.411816) (xy 385.865152 -111.38888) (xy 385.813246 -111.358913)
			(xy 385.765696 -111.322426) (xy 385.723316 -111.280046) (xy 385.686829 -111.232496) (xy 385.656862 -111.18059)
			(xy 385.633926 -111.125217) (xy 385.618413 -111.067324) (xy 385.61059 -111.007902) (xy 385.6101 -110.977934)
			(xy 286.754799 -110.977934) (xy 286.754334 -111.006394) (xy 286.746506 -111.06585) (xy 286.730985 -111.123775)
			(xy 286.708036 -111.179179) (xy 286.678052 -111.231113) (xy 286.641546 -111.278689) (xy 286.599141 -111.321094)
			(xy 286.551565 -111.3576) (xy 286.499631 -111.387584) (xy 286.444227 -111.410533) (xy 286.386302 -111.426054)
			(xy 286.326846 -111.433882) (xy 286.266878 -111.433882) (xy 286.207422 -111.426054) (xy 286.149497 -111.410533)
			(xy 286.094093 -111.387584) (xy 286.042159 -111.3576) (xy 285.994583 -111.321094) (xy 285.952178 -111.278689)
			(xy 285.915672 -111.231113) (xy 285.885688 -111.179179) (xy 285.862739 -111.123775) (xy 285.847218 -111.06585)
			(xy 285.83939 -111.006394) (xy 285.8389 -110.97641) (xy 270.425672 -110.97641) (xy 270.425672 -110.977934)
			(xy 270.425182 -111.007918) (xy 270.417354 -111.067374) (xy 270.401833 -111.125299) (xy 270.378884 -111.180703)
			(xy 270.3489 -111.232637) (xy 270.312394 -111.280213) (xy 270.269989 -111.322618) (xy 270.222413 -111.359124)
			(xy 270.170479 -111.389108) (xy 270.115075 -111.412057) (xy 270.05715 -111.427578) (xy 269.997694 -111.435406)
			(xy 269.937726 -111.435406) (xy 269.87827 -111.427578) (xy 269.820345 -111.412057) (xy 269.764941 -111.389108)
			(xy 269.713007 -111.359124) (xy 269.665431 -111.322618) (xy 269.623026 -111.280213) (xy 269.58652 -111.232637)
			(xy 269.556536 -111.180703) (xy 269.533587 -111.125299) (xy 269.518066 -111.067374) (xy 269.510238 -111.007918)
			(xy 269.509748 -110.977934) (xy 170.654955 -110.977934) (xy 170.65449 -111.006394) (xy 170.646662 -111.06585)
			(xy 170.631141 -111.123775) (xy 170.608192 -111.179179) (xy 170.578208 -111.231113) (xy 170.541702 -111.278689)
			(xy 170.499297 -111.321094) (xy 170.451721 -111.3576) (xy 170.399787 -111.387584) (xy 170.344383 -111.410533)
			(xy 170.286458 -111.426054) (xy 170.227002 -111.433882) (xy 170.167034 -111.433882) (xy 170.107578 -111.426054)
			(xy 170.049653 -111.410533) (xy 169.994249 -111.387584) (xy 169.942315 -111.3576) (xy 169.894739 -111.321094)
			(xy 169.852334 -111.278689) (xy 169.815828 -111.231113) (xy 169.785844 -111.179179) (xy 169.762895 -111.123775)
			(xy 169.747374 -111.06585) (xy 169.739546 -111.006394) (xy 169.739056 -110.97641) (xy 154.325828 -110.97641)
			(xy 154.325828 -110.977934) (xy 154.325338 -111.007918) (xy 154.31751 -111.067374) (xy 154.301989 -111.125299)
			(xy 154.27904 -111.180703) (xy 154.249056 -111.232637) (xy 154.21255 -111.280213) (xy 154.170145 -111.322618)
			(xy 154.122569 -111.359124) (xy 154.070635 -111.389108) (xy 154.015231 -111.412057) (xy 153.957306 -111.427578)
			(xy 153.89785 -111.435406) (xy 153.837882 -111.435406) (xy 153.778426 -111.427578) (xy 153.720501 -111.412057)
			(xy 153.665097 -111.389108) (xy 153.613163 -111.359124) (xy 153.565587 -111.322618) (xy 153.523182 -111.280213)
			(xy 153.486676 -111.232637) (xy 153.456692 -111.180703) (xy 153.433743 -111.125299) (xy 153.418222 -111.067374)
			(xy 153.410394 -111.007918) (xy 153.409904 -110.977934) (xy 54.554603 -110.977934) (xy 54.554138 -111.006378)
			(xy 54.546315 -111.0658) (xy 54.530802 -111.123693) (xy 54.507866 -111.179066) (xy 54.477899 -111.230972)
			(xy 54.441412 -111.278522) (xy 54.399032 -111.320902) (xy 54.351482 -111.357389) (xy 54.299576 -111.387356)
			(xy 54.244203 -111.410292) (xy 54.18631 -111.425805) (xy 54.126888 -111.433628) (xy 54.066952 -111.433628)
			(xy 54.00753 -111.425805) (xy 53.949637 -111.410292) (xy 53.894264 -111.387356) (xy 53.842358 -111.357389)
			(xy 53.794808 -111.320902) (xy 53.752428 -111.278522) (xy 53.715941 -111.230972) (xy 53.685974 -111.179066)
			(xy 53.663038 -111.123693) (xy 53.647525 -111.0658) (xy 53.639702 -111.006378) (xy 53.639212 -110.97641)
			(xy 38.225476 -110.97641) (xy 38.225476 -110.977934) (xy 38.224986 -111.007902) (xy 38.217163 -111.067324)
			(xy 38.20165 -111.125217) (xy 38.178714 -111.18059) (xy 38.148747 -111.232496) (xy 38.11226 -111.280046)
			(xy 38.06988 -111.322426) (xy 38.02233 -111.358913) (xy 37.970424 -111.38888) (xy 37.915051 -111.411816)
			(xy 37.857158 -111.427329) (xy 37.797736 -111.435152) (xy 37.7378 -111.435152) (xy 37.678378 -111.427329)
			(xy 37.620485 -111.411816) (xy 37.565112 -111.38888) (xy 37.513206 -111.358913) (xy 37.465656 -111.322426)
			(xy 37.423276 -111.280046) (xy 37.386789 -111.232496) (xy 37.356822 -111.18059) (xy 37.333886 -111.125217)
			(xy 37.318373 -111.067324) (xy 37.31055 -111.007902) (xy 37.31006 -110.977934) (xy 4.308094 -110.977934)
			(xy 4.308094 -112.784382) (xy 34.667952 -112.784382) (xy 34.667952 -111.920782) (xy 34.668442 -111.890814)
			(xy 34.676265 -111.831392) (xy 34.691778 -111.773499) (xy 34.714714 -111.718126) (xy 34.744681 -111.66622)
			(xy 34.781168 -111.61867) (xy 34.823548 -111.57629) (xy 34.871098 -111.539803) (xy 34.923004 -111.509836)
			(xy 34.978377 -111.4869) (xy 35.03627 -111.471387) (xy 35.095692 -111.463564) (xy 35.155628 -111.463564)
			(xy 35.21505 -111.471387) (xy 35.272943 -111.4869) (xy 35.328316 -111.509836) (xy 35.380222 -111.539803)
			(xy 35.427772 -111.57629) (xy 35.470152 -111.61867) (xy 35.506639 -111.66622) (xy 35.536606 -111.718126)
			(xy 35.559542 -111.773499) (xy 35.575055 -111.831392) (xy 35.582878 -111.890814) (xy 35.583368 -111.920782)
			(xy 35.583368 -112.776508) (xy 51.785012 -112.776508) (xy 51.785012 -111.912908) (xy 51.785502 -111.88294)
			(xy 51.793325 -111.823518) (xy 51.808838 -111.765625) (xy 51.831774 -111.710252) (xy 51.861741 -111.658346)
			(xy 51.898228 -111.610796) (xy 51.940608 -111.568416) (xy 51.988158 -111.531929) (xy 52.040064 -111.501962)
			(xy 52.095437 -111.479026) (xy 52.15333 -111.463513) (xy 52.212752 -111.45569) (xy 52.272688 -111.45569)
			(xy 52.33211 -111.463513) (xy 52.390003 -111.479026) (xy 52.445376 -111.501962) (xy 52.497282 -111.531929)
			(xy 52.544832 -111.568416) (xy 52.587212 -111.610796) (xy 52.623699 -111.658346) (xy 52.653666 -111.710252)
			(xy 52.676602 -111.765625) (xy 52.692115 -111.823518) (xy 52.699938 -111.88294) (xy 52.700428 -111.912908)
			(xy 52.700428 -112.776508) (xy 52.700299 -112.784382) (xy 150.767796 -112.784382) (xy 150.767796 -111.920782)
			(xy 150.768286 -111.890798) (xy 150.776114 -111.831342) (xy 150.791635 -111.773417) (xy 150.814584 -111.718013)
			(xy 150.844568 -111.666079) (xy 150.881074 -111.618503) (xy 150.923479 -111.576098) (xy 150.971055 -111.539592)
			(xy 151.022989 -111.509608) (xy 151.078393 -111.486659) (xy 151.136318 -111.471138) (xy 151.195774 -111.46331)
			(xy 151.255742 -111.46331) (xy 151.315198 -111.471138) (xy 151.373123 -111.486659) (xy 151.428527 -111.509608)
			(xy 151.480461 -111.539592) (xy 151.528037 -111.576098) (xy 151.570442 -111.618503) (xy 151.606948 -111.666079)
			(xy 151.636932 -111.718013) (xy 151.659881 -111.773417) (xy 151.675402 -111.831342) (xy 151.68323 -111.890798)
			(xy 151.68372 -111.920782) (xy 151.68372 -112.776508) (xy 167.884856 -112.776508) (xy 167.884856 -111.912908)
			(xy 167.885346 -111.882924) (xy 167.893174 -111.823468) (xy 167.908695 -111.765543) (xy 167.931644 -111.710139)
			(xy 167.961628 -111.658205) (xy 167.998134 -111.610629) (xy 168.040539 -111.568224) (xy 168.088115 -111.531718)
			(xy 168.140049 -111.501734) (xy 168.195453 -111.478785) (xy 168.253378 -111.463264) (xy 168.312834 -111.455436)
			(xy 168.372802 -111.455436) (xy 168.432258 -111.463264) (xy 168.490183 -111.478785) (xy 168.545587 -111.501734)
			(xy 168.597521 -111.531718) (xy 168.645097 -111.568224) (xy 168.687502 -111.610629) (xy 168.724008 -111.658205)
			(xy 168.753992 -111.710139) (xy 168.776941 -111.765543) (xy 168.792462 -111.823468) (xy 168.80029 -111.882924)
			(xy 168.80078 -111.912908) (xy 168.80078 -112.776508) (xy 168.800651 -112.784382) (xy 266.86764 -112.784382)
			(xy 266.86764 -111.920782) (xy 266.86813 -111.890798) (xy 266.875958 -111.831342) (xy 266.891479 -111.773417)
			(xy 266.914428 -111.718013) (xy 266.944412 -111.666079) (xy 266.980918 -111.618503) (xy 267.023323 -111.576098)
			(xy 267.070899 -111.539592) (xy 267.122833 -111.509608) (xy 267.178237 -111.486659) (xy 267.236162 -111.471138)
			(xy 267.295618 -111.46331) (xy 267.355586 -111.46331) (xy 267.415042 -111.471138) (xy 267.472967 -111.486659)
			(xy 267.528371 -111.509608) (xy 267.580305 -111.539592) (xy 267.627881 -111.576098) (xy 267.670286 -111.618503)
			(xy 267.706792 -111.666079) (xy 267.736776 -111.718013) (xy 267.759725 -111.773417) (xy 267.775246 -111.831342)
			(xy 267.783074 -111.890798) (xy 267.783564 -111.920782) (xy 267.783564 -112.776508) (xy 283.9847 -112.776508)
			(xy 283.9847 -111.912908) (xy 283.98519 -111.882924) (xy 283.993018 -111.823468) (xy 284.008539 -111.765543)
			(xy 284.031488 -111.710139) (xy 284.061472 -111.658205) (xy 284.097978 -111.610629) (xy 284.140383 -111.568224)
			(xy 284.187959 -111.531718) (xy 284.239893 -111.501734) (xy 284.295297 -111.478785) (xy 284.353222 -111.463264)
			(xy 284.412678 -111.455436) (xy 284.472646 -111.455436) (xy 284.532102 -111.463264) (xy 284.590027 -111.478785)
			(xy 284.645431 -111.501734) (xy 284.697365 -111.531718) (xy 284.744941 -111.568224) (xy 284.787346 -111.610629)
			(xy 284.823852 -111.658205) (xy 284.853836 -111.710139) (xy 284.876785 -111.765543) (xy 284.892306 -111.823468)
			(xy 284.900134 -111.882924) (xy 284.900624 -111.912908) (xy 284.900624 -112.776508) (xy 284.900495 -112.784382)
			(xy 382.967992 -112.784382) (xy 382.967992 -111.920782) (xy 382.968482 -111.890814) (xy 382.976305 -111.831392)
			(xy 382.991818 -111.773499) (xy 383.014754 -111.718126) (xy 383.044721 -111.66622) (xy 383.081208 -111.61867)
			(xy 383.123588 -111.57629) (xy 383.171138 -111.539803) (xy 383.223044 -111.509836) (xy 383.278417 -111.4869)
			(xy 383.33631 -111.471387) (xy 383.395732 -111.463564) (xy 383.455668 -111.463564) (xy 383.51509 -111.471387)
			(xy 383.572983 -111.4869) (xy 383.628356 -111.509836) (xy 383.680262 -111.539803) (xy 383.727812 -111.57629)
			(xy 383.770192 -111.61867) (xy 383.806679 -111.66622) (xy 383.836646 -111.718126) (xy 383.859582 -111.773499)
			(xy 383.875095 -111.831392) (xy 383.882918 -111.890814) (xy 383.883408 -111.920782) (xy 383.883408 -112.776508)
			(xy 400.085052 -112.776508) (xy 400.085052 -111.912908) (xy 400.085542 -111.88294) (xy 400.093365 -111.823518)
			(xy 400.108878 -111.765625) (xy 400.131814 -111.710252) (xy 400.161781 -111.658346) (xy 400.198268 -111.610796)
			(xy 400.240648 -111.568416) (xy 400.288198 -111.531929) (xy 400.340104 -111.501962) (xy 400.395477 -111.479026)
			(xy 400.45337 -111.463513) (xy 400.512792 -111.45569) (xy 400.572728 -111.45569) (xy 400.63215 -111.463513)
			(xy 400.690043 -111.479026) (xy 400.745416 -111.501962) (xy 400.797322 -111.531929) (xy 400.844872 -111.568416)
			(xy 400.887252 -111.610796) (xy 400.923739 -111.658346) (xy 400.953706 -111.710252) (xy 400.976642 -111.765625)
			(xy 400.992155 -111.823518) (xy 400.999978 -111.88294) (xy 401.000468 -111.912908) (xy 401.000468 -112.776508)
			(xy 400.999978 -112.806476) (xy 400.992155 -112.865898) (xy 400.976642 -112.923791) (xy 400.953706 -112.979164)
			(xy 400.923739 -113.03107) (xy 400.887252 -113.07862) (xy 400.844872 -113.121) (xy 400.797322 -113.157487)
			(xy 400.745416 -113.187454) (xy 400.690043 -113.21039) (xy 400.63215 -113.225903) (xy 400.572728 -113.233726)
			(xy 400.512792 -113.233726) (xy 400.45337 -113.225903) (xy 400.395477 -113.21039) (xy 400.340104 -113.187454)
			(xy 400.288198 -113.157487) (xy 400.240648 -113.121) (xy 400.198268 -113.07862) (xy 400.161781 -113.03107)
			(xy 400.131814 -112.979164) (xy 400.108878 -112.923791) (xy 400.093365 -112.865898) (xy 400.085542 -112.806476)
			(xy 400.085052 -112.776508) (xy 383.883408 -112.776508) (xy 383.883408 -112.784382) (xy 383.882918 -112.81435)
			(xy 383.875095 -112.873772) (xy 383.859582 -112.931665) (xy 383.836646 -112.987038) (xy 383.806679 -113.038944)
			(xy 383.770192 -113.086494) (xy 383.727812 -113.128874) (xy 383.680262 -113.165361) (xy 383.628356 -113.195328)
			(xy 383.572983 -113.218264) (xy 383.51509 -113.233777) (xy 383.455668 -113.2416) (xy 383.395732 -113.2416)
			(xy 383.33631 -113.233777) (xy 383.278417 -113.218264) (xy 383.223044 -113.195328) (xy 383.171138 -113.165361)
			(xy 383.123588 -113.128874) (xy 383.081208 -113.086494) (xy 383.044721 -113.038944) (xy 383.014754 -112.987038)
			(xy 382.991818 -112.931665) (xy 382.976305 -112.873772) (xy 382.968482 -112.81435) (xy 382.967992 -112.784382)
			(xy 284.900495 -112.784382) (xy 284.900134 -112.806492) (xy 284.892306 -112.865948) (xy 284.876785 -112.923873)
			(xy 284.853836 -112.979277) (xy 284.823852 -113.031211) (xy 284.787346 -113.078787) (xy 284.744941 -113.121192)
			(xy 284.697365 -113.157698) (xy 284.645431 -113.187682) (xy 284.590027 -113.210631) (xy 284.532102 -113.226152)
			(xy 284.472646 -113.23398) (xy 284.412678 -113.23398) (xy 284.353222 -113.226152) (xy 284.295297 -113.210631)
			(xy 284.239893 -113.187682) (xy 284.187959 -113.157698) (xy 284.140383 -113.121192) (xy 284.097978 -113.078787)
			(xy 284.061472 -113.031211) (xy 284.031488 -112.979277) (xy 284.008539 -112.923873) (xy 283.993018 -112.865948)
			(xy 283.98519 -112.806492) (xy 283.9847 -112.776508) (xy 267.783564 -112.776508) (xy 267.783564 -112.784382)
			(xy 267.783074 -112.814366) (xy 267.775246 -112.873822) (xy 267.759725 -112.931747) (xy 267.736776 -112.987151)
			(xy 267.706792 -113.039085) (xy 267.670286 -113.086661) (xy 267.627881 -113.129066) (xy 267.580305 -113.165572)
			(xy 267.528371 -113.195556) (xy 267.472967 -113.218505) (xy 267.415042 -113.234026) (xy 267.355586 -113.241854)
			(xy 267.295618 -113.241854) (xy 267.236162 -113.234026) (xy 267.178237 -113.218505) (xy 267.122833 -113.195556)
			(xy 267.070899 -113.165572) (xy 267.023323 -113.129066) (xy 266.980918 -113.086661) (xy 266.944412 -113.039085)
			(xy 266.914428 -112.987151) (xy 266.891479 -112.931747) (xy 266.875958 -112.873822) (xy 266.86813 -112.814366)
			(xy 266.86764 -112.784382) (xy 168.800651 -112.784382) (xy 168.80029 -112.806492) (xy 168.792462 -112.865948)
			(xy 168.776941 -112.923873) (xy 168.753992 -112.979277) (xy 168.724008 -113.031211) (xy 168.687502 -113.078787)
			(xy 168.645097 -113.121192) (xy 168.597521 -113.157698) (xy 168.545587 -113.187682) (xy 168.490183 -113.210631)
			(xy 168.432258 -113.226152) (xy 168.372802 -113.23398) (xy 168.312834 -113.23398) (xy 168.253378 -113.226152)
			(xy 168.195453 -113.210631) (xy 168.140049 -113.187682) (xy 168.088115 -113.157698) (xy 168.040539 -113.121192)
			(xy 167.998134 -113.078787) (xy 167.961628 -113.031211) (xy 167.931644 -112.979277) (xy 167.908695 -112.923873)
			(xy 167.893174 -112.865948) (xy 167.885346 -112.806492) (xy 167.884856 -112.776508) (xy 151.68372 -112.776508)
			(xy 151.68372 -112.784382) (xy 151.68323 -112.814366) (xy 151.675402 -112.873822) (xy 151.659881 -112.931747)
			(xy 151.636932 -112.987151) (xy 151.606948 -113.039085) (xy 151.570442 -113.086661) (xy 151.528037 -113.129066)
			(xy 151.480461 -113.165572) (xy 151.428527 -113.195556) (xy 151.373123 -113.218505) (xy 151.315198 -113.234026)
			(xy 151.255742 -113.241854) (xy 151.195774 -113.241854) (xy 151.136318 -113.234026) (xy 151.078393 -113.218505)
			(xy 151.022989 -113.195556) (xy 150.971055 -113.165572) (xy 150.923479 -113.129066) (xy 150.881074 -113.086661)
			(xy 150.844568 -113.039085) (xy 150.814584 -112.987151) (xy 150.791635 -112.931747) (xy 150.776114 -112.873822)
			(xy 150.768286 -112.814366) (xy 150.767796 -112.784382) (xy 52.700299 -112.784382) (xy 52.699938 -112.806476)
			(xy 52.692115 -112.865898) (xy 52.676602 -112.923791) (xy 52.653666 -112.979164) (xy 52.623699 -113.03107)
			(xy 52.587212 -113.07862) (xy 52.544832 -113.121) (xy 52.497282 -113.157487) (xy 52.445376 -113.187454)
			(xy 52.390003 -113.21039) (xy 52.33211 -113.225903) (xy 52.272688 -113.233726) (xy 52.212752 -113.233726)
			(xy 52.15333 -113.225903) (xy 52.095437 -113.21039) (xy 52.040064 -113.187454) (xy 51.988158 -113.157487)
			(xy 51.940608 -113.121) (xy 51.898228 -113.07862) (xy 51.861741 -113.03107) (xy 51.831774 -112.979164)
			(xy 51.808838 -112.923791) (xy 51.793325 -112.865898) (xy 51.785502 -112.806476) (xy 51.785012 -112.776508)
			(xy 35.583368 -112.776508) (xy 35.583368 -112.784382) (xy 35.582878 -112.81435) (xy 35.575055 -112.873772)
			(xy 35.559542 -112.931665) (xy 35.536606 -112.987038) (xy 35.506639 -113.038944) (xy 35.470152 -113.086494)
			(xy 35.427772 -113.128874) (xy 35.380222 -113.165361) (xy 35.328316 -113.195328) (xy 35.272943 -113.218264)
			(xy 35.21505 -113.233777) (xy 35.155628 -113.2416) (xy 35.095692 -113.2416) (xy 35.03627 -113.233777)
			(xy 34.978377 -113.218264) (xy 34.923004 -113.195328) (xy 34.871098 -113.165361) (xy 34.823548 -113.128874)
			(xy 34.781168 -113.086494) (xy 34.744681 -113.038944) (xy 34.714714 -112.987038) (xy 34.691778 -112.931665)
			(xy 34.676265 -112.873772) (xy 34.668442 -112.81435) (xy 34.667952 -112.784382) (xy 4.308094 -112.784382)
			(xy 4.308094 -117.758718) (xy 74.474832 -117.758718) (xy 74.474832 -116.895118) (xy 74.475322 -116.865134)
			(xy 74.48315 -116.805678) (xy 74.498671 -116.747753) (xy 74.52162 -116.692349) (xy 74.551604 -116.640415)
			(xy 74.58811 -116.592839) (xy 74.630515 -116.550434) (xy 74.678091 -116.513928) (xy 74.730025 -116.483944)
			(xy 74.785429 -116.460995) (xy 74.843354 -116.445474) (xy 74.90281 -116.437646) (xy 74.962778 -116.437646)
			(xy 75.022234 -116.445474) (xy 75.080159 -116.460995) (xy 75.135563 -116.483944) (xy 75.187497 -116.513928)
			(xy 75.235073 -116.550434) (xy 75.277478 -116.592839) (xy 75.313984 -116.640415) (xy 75.343968 -116.692349)
			(xy 75.366917 -116.747753) (xy 75.382438 -116.805678) (xy 75.390266 -116.865134) (xy 75.390756 -116.895118)
			(xy 75.390756 -117.758718) (xy 190.574676 -117.758718) (xy 190.574676 -116.895118) (xy 190.575166 -116.865134)
			(xy 190.582994 -116.805678) (xy 190.598515 -116.747753) (xy 190.621464 -116.692349) (xy 190.651448 -116.640415)
			(xy 190.687954 -116.592839) (xy 190.730359 -116.550434) (xy 190.777935 -116.513928) (xy 190.829869 -116.483944)
			(xy 190.885273 -116.460995) (xy 190.943198 -116.445474) (xy 191.002654 -116.437646) (xy 191.062622 -116.437646)
			(xy 191.122078 -116.445474) (xy 191.180003 -116.460995) (xy 191.235407 -116.483944) (xy 191.287341 -116.513928)
			(xy 191.334917 -116.550434) (xy 191.377322 -116.592839) (xy 191.413828 -116.640415) (xy 191.443812 -116.692349)
			(xy 191.466761 -116.747753) (xy 191.482282 -116.805678) (xy 191.49011 -116.865134) (xy 191.4906 -116.895118)
			(xy 191.4906 -117.758718) (xy 306.675028 -117.758718) (xy 306.675028 -116.895118) (xy 306.675518 -116.86515)
			(xy 306.683341 -116.805728) (xy 306.698854 -116.747835) (xy 306.72179 -116.692462) (xy 306.751757 -116.640556)
			(xy 306.788244 -116.593006) (xy 306.830624 -116.550626) (xy 306.878174 -116.514139) (xy 306.93008 -116.484172)
			(xy 306.985453 -116.461236) (xy 307.043346 -116.445723) (xy 307.102768 -116.4379) (xy 307.162704 -116.4379)
			(xy 307.222126 -116.445723) (xy 307.280019 -116.461236) (xy 307.335392 -116.484172) (xy 307.387298 -116.514139)
			(xy 307.434848 -116.550626) (xy 307.477228 -116.593006) (xy 307.513715 -116.640556) (xy 307.543682 -116.692462)
			(xy 307.566618 -116.747835) (xy 307.582131 -116.805728) (xy 307.589954 -116.86515) (xy 307.590444 -116.895118)
			(xy 307.590444 -117.758718) (xy 307.590436 -117.759226) (xy 422.774872 -117.759226) (xy 422.774872 -116.895626)
			(xy 422.775362 -116.865642) (xy 422.78319 -116.806186) (xy 422.798711 -116.748261) (xy 422.82166 -116.692857)
			(xy 422.851644 -116.640923) (xy 422.88815 -116.593347) (xy 422.930555 -116.550942) (xy 422.978131 -116.514436)
			(xy 423.030065 -116.484452) (xy 423.085469 -116.461503) (xy 423.143394 -116.445982) (xy 423.20285 -116.438154)
			(xy 423.262818 -116.438154) (xy 423.322274 -116.445982) (xy 423.380199 -116.461503) (xy 423.435603 -116.484452)
			(xy 423.487537 -116.514436) (xy 423.535113 -116.550942) (xy 423.577518 -116.593347) (xy 423.614024 -116.640923)
			(xy 423.644008 -116.692857) (xy 423.666957 -116.748261) (xy 423.682478 -116.806186) (xy 423.690306 -116.865642)
			(xy 423.690796 -116.895626) (xy 423.690796 -117.759226) (xy 423.690306 -117.78921) (xy 423.682478 -117.848666)
			(xy 423.666957 -117.906591) (xy 423.644008 -117.961995) (xy 423.614024 -118.013929) (xy 423.577518 -118.061505)
			(xy 423.535113 -118.10391) (xy 423.487537 -118.140416) (xy 423.435603 -118.1704) (xy 423.380199 -118.193349)
			(xy 423.322274 -118.20887) (xy 423.262818 -118.216698) (xy 423.20285 -118.216698) (xy 423.143394 -118.20887)
			(xy 423.085469 -118.193349) (xy 423.030065 -118.1704) (xy 422.978131 -118.140416) (xy 422.930555 -118.10391)
			(xy 422.88815 -118.061505) (xy 422.851644 -118.013929) (xy 422.82166 -117.961995) (xy 422.798711 -117.906591)
			(xy 422.78319 -117.848666) (xy 422.775362 -117.78921) (xy 422.774872 -117.759226) (xy 307.590436 -117.759226)
			(xy 307.589954 -117.788686) (xy 307.582131 -117.848108) (xy 307.566618 -117.906001) (xy 307.543682 -117.961374)
			(xy 307.513715 -118.01328) (xy 307.477228 -118.06083) (xy 307.434848 -118.10321) (xy 307.387298 -118.139697)
			(xy 307.335392 -118.169664) (xy 307.280019 -118.1926) (xy 307.222126 -118.208113) (xy 307.162704 -118.215936)
			(xy 307.102768 -118.215936) (xy 307.043346 -118.208113) (xy 306.985453 -118.1926) (xy 306.93008 -118.169664)
			(xy 306.878174 -118.139697) (xy 306.830624 -118.10321) (xy 306.788244 -118.06083) (xy 306.751757 -118.01328)
			(xy 306.72179 -117.961374) (xy 306.698854 -117.906001) (xy 306.683341 -117.848108) (xy 306.675518 -117.788686)
			(xy 306.675028 -117.758718) (xy 191.4906 -117.758718) (xy 191.49011 -117.788702) (xy 191.482282 -117.848158)
			(xy 191.466761 -117.906083) (xy 191.443812 -117.961487) (xy 191.413828 -118.013421) (xy 191.377322 -118.060997)
			(xy 191.334917 -118.103402) (xy 191.287341 -118.139908) (xy 191.235407 -118.169892) (xy 191.180003 -118.192841)
			(xy 191.122078 -118.208362) (xy 191.062622 -118.21619) (xy 191.002654 -118.21619) (xy 190.943198 -118.208362)
			(xy 190.885273 -118.192841) (xy 190.829869 -118.169892) (xy 190.777935 -118.139908) (xy 190.730359 -118.103402)
			(xy 190.687954 -118.060997) (xy 190.651448 -118.013421) (xy 190.621464 -117.961487) (xy 190.598515 -117.906083)
			(xy 190.582994 -117.848158) (xy 190.575166 -117.788702) (xy 190.574676 -117.758718) (xy 75.390756 -117.758718)
			(xy 75.390266 -117.788702) (xy 75.382438 -117.848158) (xy 75.366917 -117.906083) (xy 75.343968 -117.961487)
			(xy 75.313984 -118.013421) (xy 75.277478 -118.060997) (xy 75.235073 -118.103402) (xy 75.187497 -118.139908)
			(xy 75.135563 -118.169892) (xy 75.080159 -118.192841) (xy 75.022234 -118.208362) (xy 74.962778 -118.21619)
			(xy 74.90281 -118.21619) (xy 74.843354 -118.208362) (xy 74.785429 -118.192841) (xy 74.730025 -118.169892)
			(xy 74.678091 -118.139908) (xy 74.630515 -118.103402) (xy 74.58811 -118.060997) (xy 74.551604 -118.013421)
			(xy 74.52162 -117.961487) (xy 74.498671 -117.906083) (xy 74.48315 -117.848158) (xy 74.475322 -117.788702)
			(xy 74.474832 -117.758718) (xy 4.308094 -117.758718) (xy 4.308094 -120.087898) (xy 34.667952 -120.087898)
			(xy 34.667952 -119.224298) (xy 34.668442 -119.19433) (xy 34.676265 -119.134908) (xy 34.691778 -119.077015)
			(xy 34.714714 -119.021642) (xy 34.744681 -118.969736) (xy 34.781168 -118.922186) (xy 34.823548 -118.879806)
			(xy 34.871098 -118.843319) (xy 34.923004 -118.813352) (xy 34.978377 -118.790416) (xy 35.03627 -118.774903)
			(xy 35.095692 -118.76708) (xy 35.155628 -118.76708) (xy 35.21505 -118.774903) (xy 35.272943 -118.790416)
			(xy 35.328316 -118.813352) (xy 35.380222 -118.843319) (xy 35.427772 -118.879806) (xy 35.470152 -118.922186)
			(xy 35.506639 -118.969736) (xy 35.536606 -119.021642) (xy 35.559542 -119.077015) (xy 35.575055 -119.134908)
			(xy 35.582878 -119.19433) (xy 35.583368 -119.224298) (xy 35.583368 -120.086374) (xy 53.639212 -120.086374)
			(xy 53.639212 -119.222774) (xy 53.639702 -119.192806) (xy 53.647525 -119.133384) (xy 53.663038 -119.075491)
			(xy 53.685974 -119.020118) (xy 53.715941 -118.968212) (xy 53.752428 -118.920662) (xy 53.794808 -118.878282)
			(xy 53.842358 -118.841795) (xy 53.894264 -118.811828) (xy 53.949637 -118.788892) (xy 54.00753 -118.773379)
			(xy 54.066952 -118.765556) (xy 54.126888 -118.765556) (xy 54.18631 -118.773379) (xy 54.244203 -118.788892)
			(xy 54.299576 -118.811828) (xy 54.351482 -118.841795) (xy 54.399032 -118.878282) (xy 54.441412 -118.920662)
			(xy 54.477899 -118.968212) (xy 54.507866 -119.020118) (xy 54.530802 -119.075491) (xy 54.546315 -119.133384)
			(xy 54.554138 -119.192806) (xy 54.554628 -119.222774) (xy 54.554628 -119.567198) (xy 66.599308 -119.567198)
			(xy 66.599308 -118.703598) (xy 66.599798 -118.673614) (xy 66.607626 -118.614158) (xy 66.623147 -118.556233)
			(xy 66.646096 -118.500829) (xy 66.67608 -118.448895) (xy 66.712586 -118.401319) (xy 66.754991 -118.358914)
			(xy 66.802567 -118.322408) (xy 66.854501 -118.292424) (xy 66.909905 -118.269475) (xy 66.96783 -118.253954)
			(xy 67.027286 -118.246126) (xy 67.087254 -118.246126) (xy 67.14671 -118.253954) (xy 67.204635 -118.269475)
			(xy 67.260039 -118.292424) (xy 67.311973 -118.322408) (xy 67.359549 -118.358914) (xy 67.401954 -118.401319)
			(xy 67.43846 -118.448895) (xy 67.468444 -118.500829) (xy 67.491393 -118.556233) (xy 67.506914 -118.614158)
			(xy 67.514742 -118.673614) (xy 67.515232 -118.703598) (xy 67.515232 -119.55907) (xy 81.07426 -119.55907)
			(xy 81.07426 -118.69547) (xy 81.07475 -118.665486) (xy 81.082578 -118.60603) (xy 81.098099 -118.548105)
			(xy 81.121048 -118.492701) (xy 81.151032 -118.440767) (xy 81.187538 -118.393191) (xy 81.229943 -118.350786)
			(xy 81.277519 -118.31428) (xy 81.329453 -118.284296) (xy 81.384857 -118.261347) (xy 81.442782 -118.245826)
			(xy 81.502238 -118.237998) (xy 81.562206 -118.237998) (xy 81.621662 -118.245826) (xy 81.679587 -118.261347)
			(xy 81.734991 -118.284296) (xy 81.786925 -118.31428) (xy 81.834501 -118.350786) (xy 81.876906 -118.393191)
			(xy 81.913412 -118.440767) (xy 81.943396 -118.492701) (xy 81.966345 -118.548105) (xy 81.981866 -118.60603)
			(xy 81.989694 -118.665486) (xy 81.990184 -118.69547) (xy 81.990184 -119.55907) (xy 81.989694 -119.589054)
			(xy 81.981866 -119.64851) (xy 81.966345 -119.706435) (xy 81.943396 -119.761839) (xy 81.913412 -119.813773)
			(xy 81.876906 -119.861349) (xy 81.834501 -119.903754) (xy 81.786925 -119.94026) (xy 81.734991 -119.970244)
			(xy 81.679587 -119.993193) (xy 81.621662 -120.008714) (xy 81.562206 -120.016542) (xy 81.502238 -120.016542)
			(xy 81.442782 -120.008714) (xy 81.384857 -119.993193) (xy 81.329453 -119.970244) (xy 81.277519 -119.94026)
			(xy 81.229943 -119.903754) (xy 81.187538 -119.861349) (xy 81.151032 -119.813773) (xy 81.121048 -119.761839)
			(xy 81.098099 -119.706435) (xy 81.082578 -119.64851) (xy 81.07475 -119.589054) (xy 81.07426 -119.55907)
			(xy 67.515232 -119.55907) (xy 67.515232 -119.567198) (xy 67.514742 -119.597182) (xy 67.506914 -119.656638)
			(xy 67.491393 -119.714563) (xy 67.468444 -119.769967) (xy 67.43846 -119.821901) (xy 67.401954 -119.869477)
			(xy 67.359549 -119.911882) (xy 67.311973 -119.948388) (xy 67.260039 -119.978372) (xy 67.204635 -120.001321)
			(xy 67.14671 -120.016842) (xy 67.087254 -120.02467) (xy 67.027286 -120.02467) (xy 66.96783 -120.016842)
			(xy 66.909905 -120.001321) (xy 66.854501 -119.978372) (xy 66.802567 -119.948388) (xy 66.754991 -119.911882)
			(xy 66.712586 -119.869477) (xy 66.67608 -119.821901) (xy 66.646096 -119.769967) (xy 66.623147 -119.714563)
			(xy 66.607626 -119.656638) (xy 66.599798 -119.597182) (xy 66.599308 -119.567198) (xy 54.554628 -119.567198)
			(xy 54.554628 -120.086374) (xy 54.554138 -120.116342) (xy 54.546315 -120.175764) (xy 54.530802 -120.233657)
			(xy 54.507866 -120.28903) (xy 54.477899 -120.340936) (xy 54.441412 -120.388486) (xy 54.399032 -120.430866)
			(xy 54.351482 -120.467353) (xy 54.299576 -120.49732) (xy 54.244203 -120.520256) (xy 54.18631 -120.535769)
			(xy 54.126888 -120.543592) (xy 54.066952 -120.543592) (xy 54.00753 -120.535769) (xy 53.949637 -120.520256)
			(xy 53.894264 -120.49732) (xy 53.842358 -120.467353) (xy 53.794808 -120.430866) (xy 53.752428 -120.388486)
			(xy 53.715941 -120.340936) (xy 53.685974 -120.28903) (xy 53.663038 -120.233657) (xy 53.647525 -120.175764)
			(xy 53.639702 -120.116342) (xy 53.639212 -120.086374) (xy 35.583368 -120.086374) (xy 35.583368 -120.087898)
			(xy 35.582878 -120.117866) (xy 35.575055 -120.177288) (xy 35.559542 -120.235181) (xy 35.536606 -120.290554)
			(xy 35.506639 -120.34246) (xy 35.470152 -120.39001) (xy 35.427772 -120.43239) (xy 35.380222 -120.468877)
			(xy 35.328316 -120.498844) (xy 35.272943 -120.52178) (xy 35.21505 -120.537293) (xy 35.155628 -120.545116)
			(xy 35.095692 -120.545116) (xy 35.03627 -120.537293) (xy 34.978377 -120.52178) (xy 34.923004 -120.498844)
			(xy 34.871098 -120.468877) (xy 34.823548 -120.43239) (xy 34.781168 -120.39001) (xy 34.744681 -120.34246)
			(xy 34.714714 -120.290554) (xy 34.691778 -120.235181) (xy 34.676265 -120.177288) (xy 34.668442 -120.117866)
			(xy 34.667952 -120.087898) (xy 4.308094 -120.087898) (xy 4.308094 -121.894346) (xy 37.31006 -121.894346)
			(xy 37.31006 -121.030746) (xy 37.31055 -121.000778) (xy 37.318373 -120.941356) (xy 37.333886 -120.883463)
			(xy 37.356822 -120.82809) (xy 37.386789 -120.776184) (xy 37.423276 -120.728634) (xy 37.465656 -120.686254)
			(xy 37.513206 -120.649767) (xy 37.565112 -120.6198) (xy 37.620485 -120.596864) (xy 37.678378 -120.581351)
			(xy 37.7378 -120.573528) (xy 37.797736 -120.573528) (xy 37.857158 -120.581351) (xy 37.915051 -120.596864)
			(xy 37.970424 -120.6198) (xy 38.02233 -120.649767) (xy 38.06988 -120.686254) (xy 38.11226 -120.728634)
			(xy 38.148747 -120.776184) (xy 38.178714 -120.82809) (xy 38.20165 -120.883463) (xy 38.217163 -120.941356)
			(xy 38.224986 -121.000778) (xy 38.225476 -121.030746) (xy 38.225476 -121.886472) (xy 51.785012 -121.886472)
			(xy 51.785012 -121.022872) (xy 51.785502 -120.992904) (xy 51.793325 -120.933482) (xy 51.808838 -120.875589)
			(xy 51.831774 -120.820216) (xy 51.861741 -120.76831) (xy 51.898228 -120.72076) (xy 51.940608 -120.67838)
			(xy 51.988158 -120.641893) (xy 52.040064 -120.611926) (xy 52.095437 -120.58899) (xy 52.15333 -120.573477)
			(xy 52.212752 -120.565654) (xy 52.272688 -120.565654) (xy 52.33211 -120.573477) (xy 52.390003 -120.58899)
			(xy 52.445376 -120.611926) (xy 52.497282 -120.641893) (xy 52.544832 -120.67838) (xy 52.587212 -120.72076)
			(xy 52.623699 -120.76831) (xy 52.653666 -120.820216) (xy 52.676602 -120.875589) (xy 52.692115 -120.933482)
			(xy 52.699938 -120.992904) (xy 52.700428 -121.022872) (xy 52.700428 -121.367296) (xy 64.745108 -121.367296)
			(xy 64.745108 -120.503696) (xy 64.745598 -120.473712) (xy 64.753426 -120.414256) (xy 64.768947 -120.356331)
			(xy 64.791896 -120.300927) (xy 64.82188 -120.248993) (xy 64.858386 -120.201417) (xy 64.900791 -120.159012)
			(xy 64.948367 -120.122506) (xy 65.000301 -120.092522) (xy 65.055705 -120.069573) (xy 65.11363 -120.054052)
			(xy 65.173086 -120.046224) (xy 65.233054 -120.046224) (xy 65.29251 -120.054052) (xy 65.350435 -120.069573)
			(xy 65.405839 -120.092522) (xy 65.457773 -120.122506) (xy 65.505349 -120.159012) (xy 65.547754 -120.201417)
			(xy 65.58426 -120.248993) (xy 65.614244 -120.300927) (xy 65.637193 -120.356331) (xy 65.652714 -120.414256)
			(xy 65.660542 -120.473712) (xy 65.661032 -120.503696) (xy 65.661032 -121.365772) (xy 83.716368 -121.365772)
			(xy 83.716368 -120.502172) (xy 83.716858 -120.472188) (xy 83.724686 -120.412732) (xy 83.740207 -120.354807)
			(xy 83.763156 -120.299403) (xy 83.79314 -120.247469) (xy 83.829646 -120.199893) (xy 83.872051 -120.157488)
			(xy 83.919627 -120.120982) (xy 83.971561 -120.090998) (xy 84.026965 -120.068049) (xy 84.08489 -120.052528)
			(xy 84.144346 -120.0447) (xy 84.204314 -120.0447) (xy 84.26377 -120.052528) (xy 84.321695 -120.068049)
			(xy 84.369615 -120.087898) (xy 150.767796 -120.087898) (xy 150.767796 -119.224298) (xy 150.768286 -119.194314)
			(xy 150.776114 -119.134858) (xy 150.791635 -119.076933) (xy 150.814584 -119.021529) (xy 150.844568 -118.969595)
			(xy 150.881074 -118.922019) (xy 150.923479 -118.879614) (xy 150.971055 -118.843108) (xy 151.022989 -118.813124)
			(xy 151.078393 -118.790175) (xy 151.136318 -118.774654) (xy 151.195774 -118.766826) (xy 151.255742 -118.766826)
			(xy 151.315198 -118.774654) (xy 151.373123 -118.790175) (xy 151.428527 -118.813124) (xy 151.480461 -118.843108)
			(xy 151.528037 -118.879614) (xy 151.570442 -118.922019) (xy 151.606948 -118.969595) (xy 151.636932 -119.021529)
			(xy 151.659881 -119.076933) (xy 151.675402 -119.134858) (xy 151.68323 -119.194314) (xy 151.68372 -119.224298)
			(xy 151.68372 -120.086374) (xy 169.739056 -120.086374) (xy 169.739056 -119.222774) (xy 169.739546 -119.19279)
			(xy 169.747374 -119.133334) (xy 169.762895 -119.075409) (xy 169.785844 -119.020005) (xy 169.815828 -118.968071)
			(xy 169.852334 -118.920495) (xy 169.894739 -118.87809) (xy 169.942315 -118.841584) (xy 169.994249 -118.8116)
			(xy 170.049653 -118.788651) (xy 170.107578 -118.77313) (xy 170.167034 -118.765302) (xy 170.227002 -118.765302)
			(xy 170.286458 -118.77313) (xy 170.344383 -118.788651) (xy 170.399787 -118.8116) (xy 170.451721 -118.841584)
			(xy 170.499297 -118.87809) (xy 170.541702 -118.920495) (xy 170.578208 -118.968071) (xy 170.608192 -119.020005)
			(xy 170.631141 -119.075409) (xy 170.646662 -119.133334) (xy 170.65449 -119.19279) (xy 170.65498 -119.222774)
			(xy 170.65498 -119.567198) (xy 182.69966 -119.567198) (xy 182.69966 -118.703598) (xy 182.70015 -118.67363)
			(xy 182.707973 -118.614208) (xy 182.723486 -118.556315) (xy 182.746422 -118.500942) (xy 182.776389 -118.449036)
			(xy 182.812876 -118.401486) (xy 182.855256 -118.359106) (xy 182.902806 -118.322619) (xy 182.954712 -118.292652)
			(xy 183.010085 -118.269716) (xy 183.067978 -118.254203) (xy 183.1274 -118.24638) (xy 183.187336 -118.24638)
			(xy 183.246758 -118.254203) (xy 183.304651 -118.269716) (xy 183.360024 -118.292652) (xy 183.41193 -118.322619)
			(xy 183.45948 -118.359106) (xy 183.50186 -118.401486) (xy 183.538347 -118.449036) (xy 183.568314 -118.500942)
			(xy 183.59125 -118.556315) (xy 183.606763 -118.614208) (xy 183.614586 -118.67363) (xy 183.615076 -118.703598)
			(xy 183.615076 -119.559324) (xy 197.174612 -119.559324) (xy 197.174612 -118.695724) (xy 197.175102 -118.665756)
			(xy 197.182925 -118.606334) (xy 197.198438 -118.548441) (xy 197.221374 -118.493068) (xy 197.251341 -118.441162)
			(xy 197.287828 -118.393612) (xy 197.330208 -118.351232) (xy 197.377758 -118.314745) (xy 197.429664 -118.284778)
			(xy 197.485037 -118.261842) (xy 197.54293 -118.246329) (xy 197.602352 -118.238506) (xy 197.662288 -118.238506)
			(xy 197.72171 -118.246329) (xy 197.779603 -118.261842) (xy 197.834976 -118.284778) (xy 197.886882 -118.314745)
			(xy 197.934432 -118.351232) (xy 197.976812 -118.393612) (xy 198.013299 -118.441162) (xy 198.043266 -118.493068)
			(xy 198.066202 -118.548441) (xy 198.081715 -118.606334) (xy 198.089538 -118.665756) (xy 198.090028 -118.695724)
			(xy 198.090028 -119.559324) (xy 198.089538 -119.589292) (xy 198.081715 -119.648714) (xy 198.066202 -119.706607)
			(xy 198.043266 -119.76198) (xy 198.013299 -119.813886) (xy 197.976812 -119.861436) (xy 197.934432 -119.903816)
			(xy 197.886882 -119.940303) (xy 197.834976 -119.97027) (xy 197.779603 -119.993206) (xy 197.72171 -120.008719)
			(xy 197.662288 -120.016542) (xy 197.602352 -120.016542) (xy 197.54293 -120.008719) (xy 197.485037 -119.993206)
			(xy 197.429664 -119.97027) (xy 197.377758 -119.940303) (xy 197.330208 -119.903816) (xy 197.287828 -119.861436)
			(xy 197.251341 -119.813886) (xy 197.221374 -119.76198) (xy 197.198438 -119.706607) (xy 197.182925 -119.648714)
			(xy 197.175102 -119.589292) (xy 197.174612 -119.559324) (xy 183.615076 -119.559324) (xy 183.615076 -119.567198)
			(xy 183.614586 -119.597166) (xy 183.606763 -119.656588) (xy 183.59125 -119.714481) (xy 183.568314 -119.769854)
			(xy 183.538347 -119.82176) (xy 183.50186 -119.86931) (xy 183.45948 -119.91169) (xy 183.41193 -119.948177)
			(xy 183.360024 -119.978144) (xy 183.304651 -120.00108) (xy 183.246758 -120.016593) (xy 183.187336 -120.024416)
			(xy 183.1274 -120.024416) (xy 183.067978 -120.016593) (xy 183.010085 -120.00108) (xy 182.954712 -119.978144)
			(xy 182.902806 -119.948177) (xy 182.855256 -119.91169) (xy 182.812876 -119.86931) (xy 182.776389 -119.82176)
			(xy 182.746422 -119.769854) (xy 182.723486 -119.714481) (xy 182.707973 -119.656588) (xy 182.70015 -119.597166)
			(xy 182.69966 -119.567198) (xy 170.65498 -119.567198) (xy 170.65498 -120.086374) (xy 170.65449 -120.116358)
			(xy 170.646662 -120.175814) (xy 170.631141 -120.233739) (xy 170.608192 -120.289143) (xy 170.578208 -120.341077)
			(xy 170.541702 -120.388653) (xy 170.499297 -120.431058) (xy 170.451721 -120.467564) (xy 170.399787 -120.497548)
			(xy 170.344383 -120.520497) (xy 170.286458 -120.536018) (xy 170.227002 -120.543846) (xy 170.167034 -120.543846)
			(xy 170.107578 -120.536018) (xy 170.049653 -120.520497) (xy 169.994249 -120.497548) (xy 169.942315 -120.467564)
			(xy 169.894739 -120.431058) (xy 169.852334 -120.388653) (xy 169.815828 -120.341077) (xy 169.785844 -120.289143)
			(xy 169.762895 -120.233739) (xy 169.747374 -120.175814) (xy 169.739546 -120.116358) (xy 169.739056 -120.086374)
			(xy 151.68372 -120.086374) (xy 151.68372 -120.087898) (xy 151.68323 -120.117882) (xy 151.675402 -120.177338)
			(xy 151.659881 -120.235263) (xy 151.636932 -120.290667) (xy 151.606948 -120.342601) (xy 151.570442 -120.390177)
			(xy 151.528037 -120.432582) (xy 151.480461 -120.469088) (xy 151.428527 -120.499072) (xy 151.373123 -120.522021)
			(xy 151.315198 -120.537542) (xy 151.255742 -120.54537) (xy 151.195774 -120.54537) (xy 151.136318 -120.537542)
			(xy 151.078393 -120.522021) (xy 151.022989 -120.499072) (xy 150.971055 -120.469088) (xy 150.923479 -120.432582)
			(xy 150.881074 -120.390177) (xy 150.844568 -120.342601) (xy 150.814584 -120.290667) (xy 150.791635 -120.235263)
			(xy 150.776114 -120.177338) (xy 150.768286 -120.117882) (xy 150.767796 -120.087898) (xy 84.369615 -120.087898)
			(xy 84.377099 -120.090998) (xy 84.429033 -120.120982) (xy 84.476609 -120.157488) (xy 84.519014 -120.199893)
			(xy 84.55552 -120.247469) (xy 84.585504 -120.299403) (xy 84.608453 -120.354807) (xy 84.623974 -120.412732)
			(xy 84.631802 -120.472188) (xy 84.632292 -120.502172) (xy 84.632292 -121.365772) (xy 84.631802 -121.395756)
			(xy 84.623974 -121.455212) (xy 84.608453 -121.513137) (xy 84.585504 -121.568541) (xy 84.55552 -121.620475)
			(xy 84.519014 -121.668051) (xy 84.476609 -121.710456) (xy 84.429033 -121.746962) (xy 84.377099 -121.776946)
			(xy 84.321695 -121.799895) (xy 84.26377 -121.815416) (xy 84.204314 -121.823244) (xy 84.144346 -121.823244)
			(xy 84.08489 -121.815416) (xy 84.026965 -121.799895) (xy 83.971561 -121.776946) (xy 83.919627 -121.746962)
			(xy 83.872051 -121.710456) (xy 83.829646 -121.668051) (xy 83.79314 -121.620475) (xy 83.763156 -121.568541)
			(xy 83.740207 -121.513137) (xy 83.724686 -121.455212) (xy 83.716858 -121.395756) (xy 83.716368 -121.365772)
			(xy 65.661032 -121.365772) (xy 65.661032 -121.367296) (xy 65.660542 -121.39728) (xy 65.652714 -121.456736)
			(xy 65.637193 -121.514661) (xy 65.614244 -121.570065) (xy 65.58426 -121.621999) (xy 65.547754 -121.669575)
			(xy 65.505349 -121.71198) (xy 65.457773 -121.748486) (xy 65.405839 -121.77847) (xy 65.350435 -121.801419)
			(xy 65.29251 -121.81694) (xy 65.233054 -121.824768) (xy 65.173086 -121.824768) (xy 65.11363 -121.81694)
			(xy 65.055705 -121.801419) (xy 65.000301 -121.77847) (xy 64.948367 -121.748486) (xy 64.900791 -121.71198)
			(xy 64.858386 -121.669575) (xy 64.82188 -121.621999) (xy 64.791896 -121.570065) (xy 64.768947 -121.514661)
			(xy 64.753426 -121.456736) (xy 64.745598 -121.39728) (xy 64.745108 -121.367296) (xy 52.700428 -121.367296)
			(xy 52.700428 -121.886472) (xy 52.699938 -121.91644) (xy 52.692115 -121.975862) (xy 52.676602 -122.033755)
			(xy 52.653666 -122.089128) (xy 52.623699 -122.141034) (xy 52.587212 -122.188584) (xy 52.544832 -122.230964)
			(xy 52.497282 -122.267451) (xy 52.445376 -122.297418) (xy 52.390003 -122.320354) (xy 52.33211 -122.335867)
			(xy 52.272688 -122.34369) (xy 52.212752 -122.34369) (xy 52.15333 -122.335867) (xy 52.095437 -122.320354)
			(xy 52.040064 -122.297418) (xy 51.988158 -122.267451) (xy 51.940608 -122.230964) (xy 51.898228 -122.188584)
			(xy 51.861741 -122.141034) (xy 51.831774 -122.089128) (xy 51.808838 -122.033755) (xy 51.793325 -121.975862)
			(xy 51.785502 -121.91644) (xy 51.785012 -121.886472) (xy 38.225476 -121.886472) (xy 38.225476 -121.894346)
			(xy 38.224986 -121.924314) (xy 38.217163 -121.983736) (xy 38.20165 -122.041629) (xy 38.178714 -122.097002)
			(xy 38.148747 -122.148908) (xy 38.11226 -122.196458) (xy 38.06988 -122.238838) (xy 38.02233 -122.275325)
			(xy 37.970424 -122.305292) (xy 37.915051 -122.328228) (xy 37.857158 -122.343741) (xy 37.797736 -122.351564)
			(xy 37.7378 -122.351564) (xy 37.678378 -122.343741) (xy 37.620485 -122.328228) (xy 37.565112 -122.305292)
			(xy 37.513206 -122.275325) (xy 37.465656 -122.238838) (xy 37.423276 -122.196458) (xy 37.386789 -122.148908)
			(xy 37.356822 -122.097002) (xy 37.333886 -122.041629) (xy 37.318373 -121.983736) (xy 37.31055 -121.924314)
			(xy 37.31006 -121.894346) (xy 4.308094 -121.894346) (xy 4.308094 -123.68784) (xy 34.667952 -123.68784)
			(xy 34.667952 -122.82424) (xy 34.668442 -122.794272) (xy 34.676265 -122.73485) (xy 34.691778 -122.676957)
			(xy 34.714714 -122.621584) (xy 34.744681 -122.569678) (xy 34.781168 -122.522128) (xy 34.823548 -122.479748)
			(xy 34.871098 -122.443261) (xy 34.923004 -122.413294) (xy 34.978377 -122.390358) (xy 35.03627 -122.374845)
			(xy 35.095692 -122.367022) (xy 35.155628 -122.367022) (xy 35.21505 -122.374845) (xy 35.272943 -122.390358)
			(xy 35.328316 -122.413294) (xy 35.380222 -122.443261) (xy 35.427772 -122.479748) (xy 35.470152 -122.522128)
			(xy 35.506639 -122.569678) (xy 35.536606 -122.621584) (xy 35.559542 -122.676957) (xy 35.575055 -122.73485)
			(xy 35.582878 -122.794272) (xy 35.583368 -122.82424) (xy 35.583368 -123.686316) (xy 53.639212 -123.686316)
			(xy 53.639212 -122.822716) (xy 53.639702 -122.792748) (xy 53.647525 -122.733326) (xy 53.663038 -122.675433)
			(xy 53.685974 -122.62006) (xy 53.715941 -122.568154) (xy 53.752428 -122.520604) (xy 53.794808 -122.478224)
			(xy 53.842358 -122.441737) (xy 53.894264 -122.41177) (xy 53.949637 -122.388834) (xy 54.00753 -122.373321)
			(xy 54.066952 -122.365498) (xy 54.126888 -122.365498) (xy 54.18631 -122.373321) (xy 54.244203 -122.388834)
			(xy 54.299576 -122.41177) (xy 54.351482 -122.441737) (xy 54.399032 -122.478224) (xy 54.441412 -122.520604)
			(xy 54.477899 -122.568154) (xy 54.507866 -122.62006) (xy 54.530802 -122.675433) (xy 54.546315 -122.733326)
			(xy 54.554138 -122.792748) (xy 54.554628 -122.822716) (xy 54.554628 -123.16714) (xy 66.599308 -123.16714)
			(xy 66.599308 -122.30354) (xy 66.599798 -122.273556) (xy 66.607626 -122.2141) (xy 66.623147 -122.156175)
			(xy 66.646096 -122.100771) (xy 66.67608 -122.048837) (xy 66.712586 -122.001261) (xy 66.754991 -121.958856)
			(xy 66.802567 -121.92235) (xy 66.854501 -121.892366) (xy 66.909905 -121.869417) (xy 66.96783 -121.853896)
			(xy 67.027286 -121.846068) (xy 67.087254 -121.846068) (xy 67.14671 -121.853896) (xy 67.204635 -121.869417)
			(xy 67.260039 -121.892366) (xy 67.311973 -121.92235) (xy 67.359549 -121.958856) (xy 67.401954 -122.001261)
			(xy 67.43846 -122.048837) (xy 67.468444 -122.100771) (xy 67.491393 -122.156175) (xy 67.506914 -122.2141)
			(xy 67.514742 -122.273556) (xy 67.515232 -122.30354) (xy 67.515232 -123.159266) (xy 81.07426 -123.159266)
			(xy 81.07426 -122.295666) (xy 81.07475 -122.265682) (xy 81.082578 -122.206226) (xy 81.098099 -122.148301)
			(xy 81.121048 -122.092897) (xy 81.151032 -122.040963) (xy 81.187538 -121.993387) (xy 81.229943 -121.950982)
			(xy 81.277519 -121.914476) (xy 81.329453 -121.884492) (xy 81.384857 -121.861543) (xy 81.442782 -121.846022)
			(xy 81.502238 -121.838194) (xy 81.562206 -121.838194) (xy 81.621662 -121.846022) (xy 81.679587 -121.861543)
			(xy 81.734991 -121.884492) (xy 81.752059 -121.894346) (xy 153.409904 -121.894346) (xy 153.409904 -121.030746)
			(xy 153.410394 -121.000762) (xy 153.418222 -120.941306) (xy 153.433743 -120.883381) (xy 153.456692 -120.827977)
			(xy 153.486676 -120.776043) (xy 153.523182 -120.728467) (xy 153.565587 -120.686062) (xy 153.613163 -120.649556)
			(xy 153.665097 -120.619572) (xy 153.720501 -120.596623) (xy 153.778426 -120.581102) (xy 153.837882 -120.573274)
			(xy 153.89785 -120.573274) (xy 153.957306 -120.581102) (xy 154.015231 -120.596623) (xy 154.070635 -120.619572)
			(xy 154.122569 -120.649556) (xy 154.170145 -120.686062) (xy 154.21255 -120.728467) (xy 154.249056 -120.776043)
			(xy 154.27904 -120.827977) (xy 154.301989 -120.883381) (xy 154.31751 -120.941306) (xy 154.325338 -121.000762)
			(xy 154.325828 -121.030746) (xy 154.325828 -121.886472) (xy 167.884856 -121.886472) (xy 167.884856 -121.022872)
			(xy 167.885346 -120.992888) (xy 167.893174 -120.933432) (xy 167.908695 -120.875507) (xy 167.931644 -120.820103)
			(xy 167.961628 -120.768169) (xy 167.998134 -120.720593) (xy 168.040539 -120.678188) (xy 168.088115 -120.641682)
			(xy 168.140049 -120.611698) (xy 168.195453 -120.588749) (xy 168.253378 -120.573228) (xy 168.312834 -120.5654)
			(xy 168.372802 -120.5654) (xy 168.432258 -120.573228) (xy 168.490183 -120.588749) (xy 168.545587 -120.611698)
			(xy 168.597521 -120.641682) (xy 168.645097 -120.678188) (xy 168.687502 -120.720593) (xy 168.724008 -120.768169)
			(xy 168.753992 -120.820103) (xy 168.776941 -120.875507) (xy 168.792462 -120.933432) (xy 168.80029 -120.992888)
			(xy 168.80078 -121.022872) (xy 168.80078 -121.367296) (xy 180.84546 -121.367296) (xy 180.84546 -120.503696)
			(xy 180.84595 -120.473728) (xy 180.853773 -120.414306) (xy 180.869286 -120.356413) (xy 180.892222 -120.30104)
			(xy 180.922189 -120.249134) (xy 180.958676 -120.201584) (xy 181.001056 -120.159204) (xy 181.048606 -120.122717)
			(xy 181.100512 -120.09275) (xy 181.155885 -120.069814) (xy 181.213778 -120.054301) (xy 181.2732 -120.046478)
			(xy 181.333136 -120.046478) (xy 181.392558 -120.054301) (xy 181.450451 -120.069814) (xy 181.505824 -120.09275)
			(xy 181.55773 -120.122717) (xy 181.60528 -120.159204) (xy 181.64766 -120.201584) (xy 181.684147 -120.249134)
			(xy 181.714114 -120.30104) (xy 181.73705 -120.356413) (xy 181.752563 -120.414306) (xy 181.760386 -120.473728)
			(xy 181.760876 -120.503696) (xy 181.760876 -121.365772) (xy 199.81672 -121.365772) (xy 199.81672 -120.502172)
			(xy 199.81721 -120.472204) (xy 199.825033 -120.412782) (xy 199.840546 -120.354889) (xy 199.863482 -120.299516)
			(xy 199.893449 -120.24761) (xy 199.929936 -120.20006) (xy 199.972316 -120.15768) (xy 200.019866 -120.121193)
			(xy 200.071772 -120.091226) (xy 200.127145 -120.06829) (xy 200.185038 -120.052777) (xy 200.24446 -120.044954)
			(xy 200.304396 -120.044954) (xy 200.363818 -120.052777) (xy 200.421711 -120.06829) (xy 200.469049 -120.087898)
			(xy 266.86764 -120.087898) (xy 266.86764 -119.224298) (xy 266.86813 -119.194314) (xy 266.875958 -119.134858)
			(xy 266.891479 -119.076933) (xy 266.914428 -119.021529) (xy 266.944412 -118.969595) (xy 266.980918 -118.922019)
			(xy 267.023323 -118.879614) (xy 267.070899 -118.843108) (xy 267.122833 -118.813124) (xy 267.178237 -118.790175)
			(xy 267.236162 -118.774654) (xy 267.295618 -118.766826) (xy 267.355586 -118.766826) (xy 267.415042 -118.774654)
			(xy 267.472967 -118.790175) (xy 267.528371 -118.813124) (xy 267.580305 -118.843108) (xy 267.627881 -118.879614)
			(xy 267.670286 -118.922019) (xy 267.706792 -118.969595) (xy 267.736776 -119.021529) (xy 267.759725 -119.076933)
			(xy 267.775246 -119.134858) (xy 267.783074 -119.194314) (xy 267.783564 -119.224298) (xy 267.783564 -120.086374)
			(xy 285.8389 -120.086374) (xy 285.8389 -119.222774) (xy 285.83939 -119.19279) (xy 285.847218 -119.133334)
			(xy 285.862739 -119.075409) (xy 285.885688 -119.020005) (xy 285.915672 -118.968071) (xy 285.952178 -118.920495)
			(xy 285.994583 -118.87809) (xy 286.042159 -118.841584) (xy 286.094093 -118.8116) (xy 286.149497 -118.788651)
			(xy 286.207422 -118.77313) (xy 286.266878 -118.765302) (xy 286.326846 -118.765302) (xy 286.386302 -118.77313)
			(xy 286.444227 -118.788651) (xy 286.499631 -118.8116) (xy 286.551565 -118.841584) (xy 286.599141 -118.87809)
			(xy 286.641546 -118.920495) (xy 286.678052 -118.968071) (xy 286.708036 -119.020005) (xy 286.730985 -119.075409)
			(xy 286.746506 -119.133334) (xy 286.754334 -119.19279) (xy 286.754824 -119.222774) (xy 286.754824 -119.567198)
			(xy 298.799504 -119.567198) (xy 298.799504 -118.703598) (xy 298.799994 -118.67363) (xy 298.807817 -118.614208)
			(xy 298.82333 -118.556315) (xy 298.846266 -118.500942) (xy 298.876233 -118.449036) (xy 298.91272 -118.401486)
			(xy 298.9551 -118.359106) (xy 299.00265 -118.322619) (xy 299.054556 -118.292652) (xy 299.109929 -118.269716)
			(xy 299.167822 -118.254203) (xy 299.227244 -118.24638) (xy 299.28718 -118.24638) (xy 299.346602 -118.254203)
			(xy 299.404495 -118.269716) (xy 299.459868 -118.292652) (xy 299.511774 -118.322619) (xy 299.559324 -118.359106)
			(xy 299.601704 -118.401486) (xy 299.638191 -118.449036) (xy 299.668158 -118.500942) (xy 299.691094 -118.556315)
			(xy 299.706607 -118.614208) (xy 299.71443 -118.67363) (xy 299.71492 -118.703598) (xy 299.71492 -119.559324)
			(xy 313.274456 -119.559324) (xy 313.274456 -118.695724) (xy 313.274946 -118.665756) (xy 313.282769 -118.606334)
			(xy 313.298282 -118.548441) (xy 313.321218 -118.493068) (xy 313.351185 -118.441162) (xy 313.387672 -118.393612)
			(xy 313.430052 -118.351232) (xy 313.477602 -118.314745) (xy 313.529508 -118.284778) (xy 313.584881 -118.261842)
			(xy 313.642774 -118.246329) (xy 313.702196 -118.238506) (xy 313.762132 -118.238506) (xy 313.821554 -118.246329)
			(xy 313.879447 -118.261842) (xy 313.93482 -118.284778) (xy 313.986726 -118.314745) (xy 314.034276 -118.351232)
			(xy 314.076656 -118.393612) (xy 314.113143 -118.441162) (xy 314.14311 -118.493068) (xy 314.166046 -118.548441)
			(xy 314.181559 -118.606334) (xy 314.189382 -118.665756) (xy 314.189872 -118.695724) (xy 314.189872 -119.559324)
			(xy 314.189382 -119.589292) (xy 314.181559 -119.648714) (xy 314.166046 -119.706607) (xy 314.14311 -119.76198)
			(xy 314.113143 -119.813886) (xy 314.076656 -119.861436) (xy 314.034276 -119.903816) (xy 313.986726 -119.940303)
			(xy 313.93482 -119.97027) (xy 313.879447 -119.993206) (xy 313.821554 -120.008719) (xy 313.762132 -120.016542)
			(xy 313.702196 -120.016542) (xy 313.642774 -120.008719) (xy 313.584881 -119.993206) (xy 313.529508 -119.97027)
			(xy 313.477602 -119.940303) (xy 313.430052 -119.903816) (xy 313.387672 -119.861436) (xy 313.351185 -119.813886)
			(xy 313.321218 -119.76198) (xy 313.298282 -119.706607) (xy 313.282769 -119.648714) (xy 313.274946 -119.589292)
			(xy 313.274456 -119.559324) (xy 299.71492 -119.559324) (xy 299.71492 -119.567198) (xy 299.71443 -119.597166)
			(xy 299.706607 -119.656588) (xy 299.691094 -119.714481) (xy 299.668158 -119.769854) (xy 299.638191 -119.82176)
			(xy 299.601704 -119.86931) (xy 299.559324 -119.91169) (xy 299.511774 -119.948177) (xy 299.459868 -119.978144)
			(xy 299.404495 -120.00108) (xy 299.346602 -120.016593) (xy 299.28718 -120.024416) (xy 299.227244 -120.024416)
			(xy 299.167822 -120.016593) (xy 299.109929 -120.00108) (xy 299.054556 -119.978144) (xy 299.00265 -119.948177)
			(xy 298.9551 -119.91169) (xy 298.91272 -119.86931) (xy 298.876233 -119.82176) (xy 298.846266 -119.769854)
			(xy 298.82333 -119.714481) (xy 298.807817 -119.656588) (xy 298.799994 -119.597166) (xy 298.799504 -119.567198)
			(xy 286.754824 -119.567198) (xy 286.754824 -120.086374) (xy 286.754334 -120.116358) (xy 286.746506 -120.175814)
			(xy 286.730985 -120.233739) (xy 286.708036 -120.289143) (xy 286.678052 -120.341077) (xy 286.641546 -120.388653)
			(xy 286.599141 -120.431058) (xy 286.551565 -120.467564) (xy 286.499631 -120.497548) (xy 286.444227 -120.520497)
			(xy 286.386302 -120.536018) (xy 286.326846 -120.543846) (xy 286.266878 -120.543846) (xy 286.207422 -120.536018)
			(xy 286.149497 -120.520497) (xy 286.094093 -120.497548) (xy 286.042159 -120.467564) (xy 285.994583 -120.431058)
			(xy 285.952178 -120.388653) (xy 285.915672 -120.341077) (xy 285.885688 -120.289143) (xy 285.862739 -120.233739)
			(xy 285.847218 -120.175814) (xy 285.83939 -120.116358) (xy 285.8389 -120.086374) (xy 267.783564 -120.086374)
			(xy 267.783564 -120.087898) (xy 267.783074 -120.117882) (xy 267.775246 -120.177338) (xy 267.759725 -120.235263)
			(xy 267.736776 -120.290667) (xy 267.706792 -120.342601) (xy 267.670286 -120.390177) (xy 267.627881 -120.432582)
			(xy 267.580305 -120.469088) (xy 267.528371 -120.499072) (xy 267.472967 -120.522021) (xy 267.415042 -120.537542)
			(xy 267.355586 -120.54537) (xy 267.295618 -120.54537) (xy 267.236162 -120.537542) (xy 267.178237 -120.522021)
			(xy 267.122833 -120.499072) (xy 267.070899 -120.469088) (xy 267.023323 -120.432582) (xy 266.980918 -120.390177)
			(xy 266.944412 -120.342601) (xy 266.914428 -120.290667) (xy 266.891479 -120.235263) (xy 266.875958 -120.177338)
			(xy 266.86813 -120.117882) (xy 266.86764 -120.087898) (xy 200.469049 -120.087898) (xy 200.477084 -120.091226)
			(xy 200.52899 -120.121193) (xy 200.57654 -120.15768) (xy 200.61892 -120.20006) (xy 200.655407 -120.24761)
			(xy 200.685374 -120.299516) (xy 200.70831 -120.354889) (xy 200.723823 -120.412782) (xy 200.731646 -120.472204)
			(xy 200.732136 -120.502172) (xy 200.732136 -121.365772) (xy 200.731646 -121.39574) (xy 200.723823 -121.455162)
			(xy 200.70831 -121.513055) (xy 200.685374 -121.568428) (xy 200.655407 -121.620334) (xy 200.61892 -121.667884)
			(xy 200.57654 -121.710264) (xy 200.52899 -121.746751) (xy 200.477084 -121.776718) (xy 200.421711 -121.799654)
			(xy 200.363818 -121.815167) (xy 200.304396 -121.82299) (xy 200.24446 -121.82299) (xy 200.185038 -121.815167)
			(xy 200.127145 -121.799654) (xy 200.071772 -121.776718) (xy 200.019866 -121.746751) (xy 199.972316 -121.710264)
			(xy 199.929936 -121.667884) (xy 199.893449 -121.620334) (xy 199.863482 -121.568428) (xy 199.840546 -121.513055)
			(xy 199.825033 -121.455162) (xy 199.81721 -121.39574) (xy 199.81672 -121.365772) (xy 181.760876 -121.365772)
			(xy 181.760876 -121.367296) (xy 181.760386 -121.397264) (xy 181.752563 -121.456686) (xy 181.73705 -121.514579)
			(xy 181.714114 -121.569952) (xy 181.684147 -121.621858) (xy 181.64766 -121.669408) (xy 181.60528 -121.711788)
			(xy 181.55773 -121.748275) (xy 181.505824 -121.778242) (xy 181.450451 -121.801178) (xy 181.392558 -121.816691)
			(xy 181.333136 -121.824514) (xy 181.2732 -121.824514) (xy 181.213778 -121.816691) (xy 181.155885 -121.801178)
			(xy 181.100512 -121.778242) (xy 181.048606 -121.748275) (xy 181.001056 -121.711788) (xy 180.958676 -121.669408)
			(xy 180.922189 -121.621858) (xy 180.892222 -121.569952) (xy 180.869286 -121.514579) (xy 180.853773 -121.456686)
			(xy 180.84595 -121.397264) (xy 180.84546 -121.367296) (xy 168.80078 -121.367296) (xy 168.80078 -121.886472)
			(xy 168.80029 -121.916456) (xy 168.792462 -121.975912) (xy 168.776941 -122.033837) (xy 168.753992 -122.089241)
			(xy 168.724008 -122.141175) (xy 168.687502 -122.188751) (xy 168.645097 -122.231156) (xy 168.597521 -122.267662)
			(xy 168.545587 -122.297646) (xy 168.490183 -122.320595) (xy 168.432258 -122.336116) (xy 168.372802 -122.343944)
			(xy 168.312834 -122.343944) (xy 168.253378 -122.336116) (xy 168.195453 -122.320595) (xy 168.140049 -122.297646)
			(xy 168.088115 -122.267662) (xy 168.040539 -122.231156) (xy 167.998134 -122.188751) (xy 167.961628 -122.141175)
			(xy 167.931644 -122.089241) (xy 167.908695 -122.033837) (xy 167.893174 -121.975912) (xy 167.885346 -121.916456)
			(xy 167.884856 -121.886472) (xy 154.325828 -121.886472) (xy 154.325828 -121.894346) (xy 154.325338 -121.92433)
			(xy 154.31751 -121.983786) (xy 154.301989 -122.041711) (xy 154.27904 -122.097115) (xy 154.249056 -122.149049)
			(xy 154.21255 -122.196625) (xy 154.170145 -122.23903) (xy 154.122569 -122.275536) (xy 154.070635 -122.30552)
			(xy 154.015231 -122.328469) (xy 153.957306 -122.34399) (xy 153.89785 -122.351818) (xy 153.837882 -122.351818)
			(xy 153.778426 -122.34399) (xy 153.720501 -122.328469) (xy 153.665097 -122.30552) (xy 153.613163 -122.275536)
			(xy 153.565587 -122.23903) (xy 153.523182 -122.196625) (xy 153.486676 -122.149049) (xy 153.456692 -122.097115)
			(xy 153.433743 -122.041711) (xy 153.418222 -121.983786) (xy 153.410394 -121.92433) (xy 153.409904 -121.894346)
			(xy 81.752059 -121.894346) (xy 81.786925 -121.914476) (xy 81.834501 -121.950982) (xy 81.876906 -121.993387)
			(xy 81.913412 -122.040963) (xy 81.943396 -122.092897) (xy 81.966345 -122.148301) (xy 81.981866 -122.206226)
			(xy 81.989694 -122.265682) (xy 81.990184 -122.295666) (xy 81.990184 -123.159266) (xy 81.989694 -123.18925)
			(xy 81.981866 -123.248706) (xy 81.966345 -123.306631) (xy 81.943396 -123.362035) (xy 81.913412 -123.413969)
			(xy 81.876906 -123.461545) (xy 81.834501 -123.50395) (xy 81.786925 -123.540456) (xy 81.734991 -123.57044)
			(xy 81.679587 -123.593389) (xy 81.621662 -123.60891) (xy 81.562206 -123.616738) (xy 81.502238 -123.616738)
			(xy 81.442782 -123.60891) (xy 81.384857 -123.593389) (xy 81.329453 -123.57044) (xy 81.277519 -123.540456)
			(xy 81.229943 -123.50395) (xy 81.187538 -123.461545) (xy 81.151032 -123.413969) (xy 81.121048 -123.362035)
			(xy 81.098099 -123.306631) (xy 81.082578 -123.248706) (xy 81.07475 -123.18925) (xy 81.07426 -123.159266)
			(xy 67.515232 -123.159266) (xy 67.515232 -123.16714) (xy 67.514742 -123.197124) (xy 67.506914 -123.25658)
			(xy 67.491393 -123.314505) (xy 67.468444 -123.369909) (xy 67.43846 -123.421843) (xy 67.401954 -123.469419)
			(xy 67.359549 -123.511824) (xy 67.311973 -123.54833) (xy 67.260039 -123.578314) (xy 67.204635 -123.601263)
			(xy 67.14671 -123.616784) (xy 67.087254 -123.624612) (xy 67.027286 -123.624612) (xy 66.96783 -123.616784)
			(xy 66.909905 -123.601263) (xy 66.854501 -123.578314) (xy 66.802567 -123.54833) (xy 66.754991 -123.511824)
			(xy 66.712586 -123.469419) (xy 66.67608 -123.421843) (xy 66.646096 -123.369909) (xy 66.623147 -123.314505)
			(xy 66.607626 -123.25658) (xy 66.599798 -123.197124) (xy 66.599308 -123.16714) (xy 54.554628 -123.16714)
			(xy 54.554628 -123.686316) (xy 54.554138 -123.716284) (xy 54.546315 -123.775706) (xy 54.530802 -123.833599)
			(xy 54.507866 -123.888972) (xy 54.477899 -123.940878) (xy 54.441412 -123.988428) (xy 54.399032 -124.030808)
			(xy 54.351482 -124.067295) (xy 54.299576 -124.097262) (xy 54.244203 -124.120198) (xy 54.18631 -124.135711)
			(xy 54.126888 -124.143534) (xy 54.066952 -124.143534) (xy 54.00753 -124.135711) (xy 53.949637 -124.120198)
			(xy 53.894264 -124.097262) (xy 53.842358 -124.067295) (xy 53.794808 -124.030808) (xy 53.752428 -123.988428)
			(xy 53.715941 -123.940878) (xy 53.685974 -123.888972) (xy 53.663038 -123.833599) (xy 53.647525 -123.775706)
			(xy 53.639702 -123.716284) (xy 53.639212 -123.686316) (xy 35.583368 -123.686316) (xy 35.583368 -123.68784)
			(xy 35.582878 -123.717808) (xy 35.575055 -123.77723) (xy 35.559542 -123.835123) (xy 35.536606 -123.890496)
			(xy 35.506639 -123.942402) (xy 35.470152 -123.989952) (xy 35.427772 -124.032332) (xy 35.380222 -124.068819)
			(xy 35.328316 -124.098786) (xy 35.272943 -124.121722) (xy 35.21505 -124.137235) (xy 35.155628 -124.145058)
			(xy 35.095692 -124.145058) (xy 35.03627 -124.137235) (xy 34.978377 -124.121722) (xy 34.923004 -124.098786)
			(xy 34.871098 -124.068819) (xy 34.823548 -124.032332) (xy 34.781168 -123.989952) (xy 34.744681 -123.942402)
			(xy 34.714714 -123.890496) (xy 34.691778 -123.835123) (xy 34.676265 -123.77723) (xy 34.668442 -123.717808)
			(xy 34.667952 -123.68784) (xy 4.308094 -123.68784) (xy 4.308094 -125.494542) (xy 37.31006 -125.494542)
			(xy 37.31006 -124.630942) (xy 37.31055 -124.600974) (xy 37.318373 -124.541552) (xy 37.333886 -124.483659)
			(xy 37.356822 -124.428286) (xy 37.386789 -124.37638) (xy 37.423276 -124.32883) (xy 37.465656 -124.28645)
			(xy 37.513206 -124.249963) (xy 37.565112 -124.219996) (xy 37.620485 -124.19706) (xy 37.678378 -124.181547)
			(xy 37.7378 -124.173724) (xy 37.797736 -124.173724) (xy 37.857158 -124.181547) (xy 37.915051 -124.19706)
			(xy 37.970424 -124.219996) (xy 38.02233 -124.249963) (xy 38.06988 -124.28645) (xy 38.11226 -124.32883)
			(xy 38.148747 -124.37638) (xy 38.178714 -124.428286) (xy 38.20165 -124.483659) (xy 38.217163 -124.541552)
			(xy 38.224986 -124.600974) (xy 38.225476 -124.630942) (xy 38.225476 -125.486414) (xy 51.785012 -125.486414)
			(xy 51.785012 -124.622814) (xy 51.785502 -124.592846) (xy 51.793325 -124.533424) (xy 51.808838 -124.475531)
			(xy 51.831774 -124.420158) (xy 51.861741 -124.368252) (xy 51.898228 -124.320702) (xy 51.940608 -124.278322)
			(xy 51.988158 -124.241835) (xy 52.040064 -124.211868) (xy 52.095437 -124.188932) (xy 52.15333 -124.173419)
			(xy 52.212752 -124.165596) (xy 52.272688 -124.165596) (xy 52.33211 -124.173419) (xy 52.390003 -124.188932)
			(xy 52.445376 -124.211868) (xy 52.497282 -124.241835) (xy 52.544832 -124.278322) (xy 52.587212 -124.320702)
			(xy 52.623699 -124.368252) (xy 52.653666 -124.420158) (xy 52.676602 -124.475531) (xy 52.692115 -124.533424)
			(xy 52.699938 -124.592846) (xy 52.700428 -124.622814) (xy 52.700428 -124.967238) (xy 64.745108 -124.967238)
			(xy 64.745108 -124.103638) (xy 64.745598 -124.073654) (xy 64.753426 -124.014198) (xy 64.768947 -123.956273)
			(xy 64.791896 -123.900869) (xy 64.82188 -123.848935) (xy 64.858386 -123.801359) (xy 64.900791 -123.758954)
			(xy 64.948367 -123.722448) (xy 65.000301 -123.692464) (xy 65.055705 -123.669515) (xy 65.11363 -123.653994)
			(xy 65.173086 -123.646166) (xy 65.233054 -123.646166) (xy 65.29251 -123.653994) (xy 65.350435 -123.669515)
			(xy 65.405839 -123.692464) (xy 65.457773 -123.722448) (xy 65.505349 -123.758954) (xy 65.547754 -123.801359)
			(xy 65.58426 -123.848935) (xy 65.614244 -123.900869) (xy 65.637193 -123.956273) (xy 65.652714 -124.014198)
			(xy 65.660542 -124.073654) (xy 65.661032 -124.103638) (xy 65.661032 -124.965714) (xy 83.716368 -124.965714)
			(xy 83.716368 -124.102114) (xy 83.716858 -124.07213) (xy 83.724686 -124.012674) (xy 83.740207 -123.954749)
			(xy 83.763156 -123.899345) (xy 83.79314 -123.847411) (xy 83.829646 -123.799835) (xy 83.872051 -123.75743)
			(xy 83.919627 -123.720924) (xy 83.971561 -123.69094) (xy 84.026965 -123.667991) (xy 84.08489 -123.65247)
			(xy 84.144346 -123.644642) (xy 84.204314 -123.644642) (xy 84.26377 -123.65247) (xy 84.321695 -123.667991)
			(xy 84.369615 -123.68784) (xy 150.767796 -123.68784) (xy 150.767796 -122.82424) (xy 150.768286 -122.794256)
			(xy 150.776114 -122.7348) (xy 150.791635 -122.676875) (xy 150.814584 -122.621471) (xy 150.844568 -122.569537)
			(xy 150.881074 -122.521961) (xy 150.923479 -122.479556) (xy 150.971055 -122.44305) (xy 151.022989 -122.413066)
			(xy 151.078393 -122.390117) (xy 151.136318 -122.374596) (xy 151.195774 -122.366768) (xy 151.255742 -122.366768)
			(xy 151.315198 -122.374596) (xy 151.373123 -122.390117) (xy 151.428527 -122.413066) (xy 151.480461 -122.44305)
			(xy 151.528037 -122.479556) (xy 151.570442 -122.521961) (xy 151.606948 -122.569537) (xy 151.636932 -122.621471)
			(xy 151.659881 -122.676875) (xy 151.675402 -122.7348) (xy 151.68323 -122.794256) (xy 151.68372 -122.82424)
			(xy 151.68372 -123.686316) (xy 169.739056 -123.686316) (xy 169.739056 -122.822716) (xy 169.739546 -122.792732)
			(xy 169.747374 -122.733276) (xy 169.762895 -122.675351) (xy 169.785844 -122.619947) (xy 169.815828 -122.568013)
			(xy 169.852334 -122.520437) (xy 169.894739 -122.478032) (xy 169.942315 -122.441526) (xy 169.994249 -122.411542)
			(xy 170.049653 -122.388593) (xy 170.107578 -122.373072) (xy 170.167034 -122.365244) (xy 170.227002 -122.365244)
			(xy 170.286458 -122.373072) (xy 170.344383 -122.388593) (xy 170.399787 -122.411542) (xy 170.451721 -122.441526)
			(xy 170.499297 -122.478032) (xy 170.541702 -122.520437) (xy 170.578208 -122.568013) (xy 170.608192 -122.619947)
			(xy 170.631141 -122.675351) (xy 170.646662 -122.733276) (xy 170.65449 -122.792732) (xy 170.65498 -122.822716)
			(xy 170.65498 -123.16714) (xy 182.69966 -123.16714) (xy 182.69966 -122.30354) (xy 182.70015 -122.273572)
			(xy 182.707973 -122.21415) (xy 182.723486 -122.156257) (xy 182.746422 -122.100884) (xy 182.776389 -122.048978)
			(xy 182.812876 -122.001428) (xy 182.855256 -121.959048) (xy 182.902806 -121.922561) (xy 182.954712 -121.892594)
			(xy 183.010085 -121.869658) (xy 183.067978 -121.854145) (xy 183.1274 -121.846322) (xy 183.187336 -121.846322)
			(xy 183.246758 -121.854145) (xy 183.304651 -121.869658) (xy 183.360024 -121.892594) (xy 183.41193 -121.922561)
			(xy 183.45948 -121.959048) (xy 183.50186 -122.001428) (xy 183.538347 -122.048978) (xy 183.568314 -122.100884)
			(xy 183.59125 -122.156257) (xy 183.606763 -122.21415) (xy 183.614586 -122.273572) (xy 183.615076 -122.30354)
			(xy 183.615076 -123.159266) (xy 197.174612 -123.159266) (xy 197.174612 -122.295666) (xy 197.175102 -122.265698)
			(xy 197.182925 -122.206276) (xy 197.198438 -122.148383) (xy 197.221374 -122.09301) (xy 197.251341 -122.041104)
			(xy 197.287828 -121.993554) (xy 197.330208 -121.951174) (xy 197.377758 -121.914687) (xy 197.429664 -121.88472)
			(xy 197.485037 -121.861784) (xy 197.54293 -121.846271) (xy 197.602352 -121.838448) (xy 197.662288 -121.838448)
			(xy 197.72171 -121.846271) (xy 197.779603 -121.861784) (xy 197.834976 -121.88472) (xy 197.851649 -121.894346)
			(xy 269.509748 -121.894346) (xy 269.509748 -121.030746) (xy 269.510238 -121.000762) (xy 269.518066 -120.941306)
			(xy 269.533587 -120.883381) (xy 269.556536 -120.827977) (xy 269.58652 -120.776043) (xy 269.623026 -120.728467)
			(xy 269.665431 -120.686062) (xy 269.713007 -120.649556) (xy 269.764941 -120.619572) (xy 269.820345 -120.596623)
			(xy 269.87827 -120.581102) (xy 269.937726 -120.573274) (xy 269.997694 -120.573274) (xy 270.05715 -120.581102)
			(xy 270.115075 -120.596623) (xy 270.170479 -120.619572) (xy 270.222413 -120.649556) (xy 270.269989 -120.686062)
			(xy 270.312394 -120.728467) (xy 270.3489 -120.776043) (xy 270.378884 -120.827977) (xy 270.401833 -120.883381)
			(xy 270.417354 -120.941306) (xy 270.425182 -121.000762) (xy 270.425672 -121.030746) (xy 270.425672 -121.886472)
			(xy 283.9847 -121.886472) (xy 283.9847 -121.022872) (xy 283.98519 -120.992888) (xy 283.993018 -120.933432)
			(xy 284.008539 -120.875507) (xy 284.031488 -120.820103) (xy 284.061472 -120.768169) (xy 284.097978 -120.720593)
			(xy 284.140383 -120.678188) (xy 284.187959 -120.641682) (xy 284.239893 -120.611698) (xy 284.295297 -120.588749)
			(xy 284.353222 -120.573228) (xy 284.412678 -120.5654) (xy 284.472646 -120.5654) (xy 284.532102 -120.573228)
			(xy 284.590027 -120.588749) (xy 284.645431 -120.611698) (xy 284.697365 -120.641682) (xy 284.744941 -120.678188)
			(xy 284.787346 -120.720593) (xy 284.823852 -120.768169) (xy 284.853836 -120.820103) (xy 284.876785 -120.875507)
			(xy 284.892306 -120.933432) (xy 284.900134 -120.992888) (xy 284.900624 -121.022872) (xy 284.900624 -121.367296)
			(xy 296.945304 -121.367296) (xy 296.945304 -120.503696) (xy 296.945794 -120.473728) (xy 296.953617 -120.414306)
			(xy 296.96913 -120.356413) (xy 296.992066 -120.30104) (xy 297.022033 -120.249134) (xy 297.05852 -120.201584)
			(xy 297.1009 -120.159204) (xy 297.14845 -120.122717) (xy 297.200356 -120.09275) (xy 297.255729 -120.069814)
			(xy 297.313622 -120.054301) (xy 297.373044 -120.046478) (xy 297.43298 -120.046478) (xy 297.492402 -120.054301)
			(xy 297.550295 -120.069814) (xy 297.605668 -120.09275) (xy 297.657574 -120.122717) (xy 297.705124 -120.159204)
			(xy 297.747504 -120.201584) (xy 297.783991 -120.249134) (xy 297.813958 -120.30104) (xy 297.836894 -120.356413)
			(xy 297.852407 -120.414306) (xy 297.86023 -120.473728) (xy 297.86072 -120.503696) (xy 297.86072 -121.365772)
			(xy 315.916564 -121.365772) (xy 315.916564 -120.502172) (xy 315.917054 -120.472204) (xy 315.924877 -120.412782)
			(xy 315.94039 -120.354889) (xy 315.963326 -120.299516) (xy 315.993293 -120.24761) (xy 316.02978 -120.20006)
			(xy 316.07216 -120.15768) (xy 316.11971 -120.121193) (xy 316.171616 -120.091226) (xy 316.226989 -120.06829)
			(xy 316.284882 -120.052777) (xy 316.344304 -120.044954) (xy 316.40424 -120.044954) (xy 316.463662 -120.052777)
			(xy 316.521555 -120.06829) (xy 316.568893 -120.087898) (xy 382.967992 -120.087898) (xy 382.967992 -119.224298)
			(xy 382.968482 -119.19433) (xy 382.976305 -119.134908) (xy 382.991818 -119.077015) (xy 383.014754 -119.021642)
			(xy 383.044721 -118.969736) (xy 383.081208 -118.922186) (xy 383.123588 -118.879806) (xy 383.171138 -118.843319)
			(xy 383.223044 -118.813352) (xy 383.278417 -118.790416) (xy 383.33631 -118.774903) (xy 383.395732 -118.76708)
			(xy 383.455668 -118.76708) (xy 383.51509 -118.774903) (xy 383.572983 -118.790416) (xy 383.628356 -118.813352)
			(xy 383.680262 -118.843319) (xy 383.727812 -118.879806) (xy 383.770192 -118.922186) (xy 383.806679 -118.969736)
			(xy 383.836646 -119.021642) (xy 383.859582 -119.077015) (xy 383.875095 -119.134908) (xy 383.882918 -119.19433)
			(xy 383.883408 -119.224298) (xy 383.883408 -120.086374) (xy 401.939252 -120.086374) (xy 401.939252 -119.222774)
			(xy 401.939742 -119.192806) (xy 401.947565 -119.133384) (xy 401.963078 -119.075491) (xy 401.986014 -119.020118)
			(xy 402.015981 -118.968212) (xy 402.052468 -118.920662) (xy 402.094848 -118.878282) (xy 402.142398 -118.841795)
			(xy 402.194304 -118.811828) (xy 402.249677 -118.788892) (xy 402.30757 -118.773379) (xy 402.366992 -118.765556)
			(xy 402.426928 -118.765556) (xy 402.48635 -118.773379) (xy 402.544243 -118.788892) (xy 402.599616 -118.811828)
			(xy 402.651522 -118.841795) (xy 402.699072 -118.878282) (xy 402.741452 -118.920662) (xy 402.777939 -118.968212)
			(xy 402.807906 -119.020118) (xy 402.830842 -119.075491) (xy 402.846355 -119.133384) (xy 402.854178 -119.192806)
			(xy 402.854668 -119.222774) (xy 402.854668 -119.567198) (xy 414.899348 -119.567198) (xy 414.899348 -118.703598)
			(xy 414.899838 -118.673614) (xy 414.907666 -118.614158) (xy 414.923187 -118.556233) (xy 414.946136 -118.500829)
			(xy 414.97612 -118.448895) (xy 415.012626 -118.401319) (xy 415.055031 -118.358914) (xy 415.102607 -118.322408)
			(xy 415.154541 -118.292424) (xy 415.209945 -118.269475) (xy 415.26787 -118.253954) (xy 415.327326 -118.246126)
			(xy 415.387294 -118.246126) (xy 415.44675 -118.253954) (xy 415.504675 -118.269475) (xy 415.560079 -118.292424)
			(xy 415.612013 -118.322408) (xy 415.659589 -118.358914) (xy 415.701994 -118.401319) (xy 415.7385 -118.448895)
			(xy 415.768484 -118.500829) (xy 415.791433 -118.556233) (xy 415.806954 -118.614158) (xy 415.814782 -118.673614)
			(xy 415.815272 -118.703598) (xy 415.815272 -119.559324) (xy 429.3743 -119.559324) (xy 429.3743 -118.695724)
			(xy 429.37479 -118.66574) (xy 429.382618 -118.606284) (xy 429.398139 -118.548359) (xy 429.421088 -118.492955)
			(xy 429.451072 -118.441021) (xy 429.487578 -118.393445) (xy 429.529983 -118.35104) (xy 429.577559 -118.314534)
			(xy 429.629493 -118.28455) (xy 429.684897 -118.261601) (xy 429.742822 -118.24608) (xy 429.802278 -118.238252)
			(xy 429.862246 -118.238252) (xy 429.921702 -118.24608) (xy 429.979627 -118.261601) (xy 430.035031 -118.28455)
			(xy 430.086965 -118.314534) (xy 430.134541 -118.35104) (xy 430.176946 -118.393445) (xy 430.213452 -118.441021)
			(xy 430.243436 -118.492955) (xy 430.266385 -118.548359) (xy 430.281906 -118.606284) (xy 430.289734 -118.66574)
			(xy 430.290224 -118.695724) (xy 430.290224 -119.559324) (xy 430.289734 -119.589308) (xy 430.281906 -119.648764)
			(xy 430.266385 -119.706689) (xy 430.243436 -119.762093) (xy 430.213452 -119.814027) (xy 430.176946 -119.861603)
			(xy 430.134541 -119.904008) (xy 430.086965 -119.940514) (xy 430.035031 -119.970498) (xy 429.979627 -119.993447)
			(xy 429.921702 -120.008968) (xy 429.862246 -120.016796) (xy 429.802278 -120.016796) (xy 429.742822 -120.008968)
			(xy 429.684897 -119.993447) (xy 429.629493 -119.970498) (xy 429.577559 -119.940514) (xy 429.529983 -119.904008)
			(xy 429.487578 -119.861603) (xy 429.451072 -119.814027) (xy 429.421088 -119.762093) (xy 429.398139 -119.706689)
			(xy 429.382618 -119.648764) (xy 429.37479 -119.589308) (xy 429.3743 -119.559324) (xy 415.815272 -119.559324)
			(xy 415.815272 -119.567198) (xy 415.814782 -119.597182) (xy 415.806954 -119.656638) (xy 415.791433 -119.714563)
			(xy 415.768484 -119.769967) (xy 415.7385 -119.821901) (xy 415.701994 -119.869477) (xy 415.659589 -119.911882)
			(xy 415.612013 -119.948388) (xy 415.560079 -119.978372) (xy 415.504675 -120.001321) (xy 415.44675 -120.016842)
			(xy 415.387294 -120.02467) (xy 415.327326 -120.02467) (xy 415.26787 -120.016842) (xy 415.209945 -120.001321)
			(xy 415.154541 -119.978372) (xy 415.102607 -119.948388) (xy 415.055031 -119.911882) (xy 415.012626 -119.869477)
			(xy 414.97612 -119.821901) (xy 414.946136 -119.769967) (xy 414.923187 -119.714563) (xy 414.907666 -119.656638)
			(xy 414.899838 -119.597182) (xy 414.899348 -119.567198) (xy 402.854668 -119.567198) (xy 402.854668 -120.086374)
			(xy 402.854178 -120.116342) (xy 402.846355 -120.175764) (xy 402.830842 -120.233657) (xy 402.807906 -120.28903)
			(xy 402.777939 -120.340936) (xy 402.741452 -120.388486) (xy 402.699072 -120.430866) (xy 402.651522 -120.467353)
			(xy 402.599616 -120.49732) (xy 402.544243 -120.520256) (xy 402.48635 -120.535769) (xy 402.426928 -120.543592)
			(xy 402.366992 -120.543592) (xy 402.30757 -120.535769) (xy 402.249677 -120.520256) (xy 402.194304 -120.49732)
			(xy 402.142398 -120.467353) (xy 402.094848 -120.430866) (xy 402.052468 -120.388486) (xy 402.015981 -120.340936)
			(xy 401.986014 -120.28903) (xy 401.963078 -120.233657) (xy 401.947565 -120.175764) (xy 401.939742 -120.116342)
			(xy 401.939252 -120.086374) (xy 383.883408 -120.086374) (xy 383.883408 -120.087898) (xy 383.882918 -120.117866)
			(xy 383.875095 -120.177288) (xy 383.859582 -120.235181) (xy 383.836646 -120.290554) (xy 383.806679 -120.34246)
			(xy 383.770192 -120.39001) (xy 383.727812 -120.43239) (xy 383.680262 -120.468877) (xy 383.628356 -120.498844)
			(xy 383.572983 -120.52178) (xy 383.51509 -120.537293) (xy 383.455668 -120.545116) (xy 383.395732 -120.545116)
			(xy 383.33631 -120.537293) (xy 383.278417 -120.52178) (xy 383.223044 -120.498844) (xy 383.171138 -120.468877)
			(xy 383.123588 -120.43239) (xy 383.081208 -120.39001) (xy 383.044721 -120.34246) (xy 383.014754 -120.290554)
			(xy 382.991818 -120.235181) (xy 382.976305 -120.177288) (xy 382.968482 -120.117866) (xy 382.967992 -120.087898)
			(xy 316.568893 -120.087898) (xy 316.576928 -120.091226) (xy 316.628834 -120.121193) (xy 316.676384 -120.15768)
			(xy 316.718764 -120.20006) (xy 316.755251 -120.24761) (xy 316.785218 -120.299516) (xy 316.808154 -120.354889)
			(xy 316.823667 -120.412782) (xy 316.83149 -120.472204) (xy 316.83198 -120.502172) (xy 316.83198 -121.365772)
			(xy 316.83149 -121.39574) (xy 316.823667 -121.455162) (xy 316.808154 -121.513055) (xy 316.785218 -121.568428)
			(xy 316.755251 -121.620334) (xy 316.718764 -121.667884) (xy 316.676384 -121.710264) (xy 316.628834 -121.746751)
			(xy 316.576928 -121.776718) (xy 316.521555 -121.799654) (xy 316.463662 -121.815167) (xy 316.40424 -121.82299)
			(xy 316.344304 -121.82299) (xy 316.284882 -121.815167) (xy 316.226989 -121.799654) (xy 316.171616 -121.776718)
			(xy 316.11971 -121.746751) (xy 316.07216 -121.710264) (xy 316.02978 -121.667884) (xy 315.993293 -121.620334)
			(xy 315.963326 -121.568428) (xy 315.94039 -121.513055) (xy 315.924877 -121.455162) (xy 315.917054 -121.39574)
			(xy 315.916564 -121.365772) (xy 297.86072 -121.365772) (xy 297.86072 -121.367296) (xy 297.86023 -121.397264)
			(xy 297.852407 -121.456686) (xy 297.836894 -121.514579) (xy 297.813958 -121.569952) (xy 297.783991 -121.621858)
			(xy 297.747504 -121.669408) (xy 297.705124 -121.711788) (xy 297.657574 -121.748275) (xy 297.605668 -121.778242)
			(xy 297.550295 -121.801178) (xy 297.492402 -121.816691) (xy 297.43298 -121.824514) (xy 297.373044 -121.824514)
			(xy 297.313622 -121.816691) (xy 297.255729 -121.801178) (xy 297.200356 -121.778242) (xy 297.14845 -121.748275)
			(xy 297.1009 -121.711788) (xy 297.05852 -121.669408) (xy 297.022033 -121.621858) (xy 296.992066 -121.569952)
			(xy 296.96913 -121.514579) (xy 296.953617 -121.456686) (xy 296.945794 -121.397264) (xy 296.945304 -121.367296)
			(xy 284.900624 -121.367296) (xy 284.900624 -121.886472) (xy 284.900134 -121.916456) (xy 284.892306 -121.975912)
			(xy 284.876785 -122.033837) (xy 284.853836 -122.089241) (xy 284.823852 -122.141175) (xy 284.787346 -122.188751)
			(xy 284.744941 -122.231156) (xy 284.697365 -122.267662) (xy 284.645431 -122.297646) (xy 284.590027 -122.320595)
			(xy 284.532102 -122.336116) (xy 284.472646 -122.343944) (xy 284.412678 -122.343944) (xy 284.353222 -122.336116)
			(xy 284.295297 -122.320595) (xy 284.239893 -122.297646) (xy 284.187959 -122.267662) (xy 284.140383 -122.231156)
			(xy 284.097978 -122.188751) (xy 284.061472 -122.141175) (xy 284.031488 -122.089241) (xy 284.008539 -122.033837)
			(xy 283.993018 -121.975912) (xy 283.98519 -121.916456) (xy 283.9847 -121.886472) (xy 270.425672 -121.886472)
			(xy 270.425672 -121.894346) (xy 270.425182 -121.92433) (xy 270.417354 -121.983786) (xy 270.401833 -122.041711)
			(xy 270.378884 -122.097115) (xy 270.3489 -122.149049) (xy 270.312394 -122.196625) (xy 270.269989 -122.23903)
			(xy 270.222413 -122.275536) (xy 270.170479 -122.30552) (xy 270.115075 -122.328469) (xy 270.05715 -122.34399)
			(xy 269.997694 -122.351818) (xy 269.937726 -122.351818) (xy 269.87827 -122.34399) (xy 269.820345 -122.328469)
			(xy 269.764941 -122.30552) (xy 269.713007 -122.275536) (xy 269.665431 -122.23903) (xy 269.623026 -122.196625)
			(xy 269.58652 -122.149049) (xy 269.556536 -122.097115) (xy 269.533587 -122.041711) (xy 269.518066 -121.983786)
			(xy 269.510238 -121.92433) (xy 269.509748 -121.894346) (xy 197.851649 -121.894346) (xy 197.886882 -121.914687)
			(xy 197.934432 -121.951174) (xy 197.976812 -121.993554) (xy 198.013299 -122.041104) (xy 198.043266 -122.09301)
			(xy 198.066202 -122.148383) (xy 198.081715 -122.206276) (xy 198.089538 -122.265698) (xy 198.090028 -122.295666)
			(xy 198.090028 -123.159266) (xy 198.089538 -123.189234) (xy 198.081715 -123.248656) (xy 198.066202 -123.306549)
			(xy 198.043266 -123.361922) (xy 198.013299 -123.413828) (xy 197.976812 -123.461378) (xy 197.934432 -123.503758)
			(xy 197.886882 -123.540245) (xy 197.834976 -123.570212) (xy 197.779603 -123.593148) (xy 197.72171 -123.608661)
			(xy 197.662288 -123.616484) (xy 197.602352 -123.616484) (xy 197.54293 -123.608661) (xy 197.485037 -123.593148)
			(xy 197.429664 -123.570212) (xy 197.377758 -123.540245) (xy 197.330208 -123.503758) (xy 197.287828 -123.461378)
			(xy 197.251341 -123.413828) (xy 197.221374 -123.361922) (xy 197.198438 -123.306549) (xy 197.182925 -123.248656)
			(xy 197.175102 -123.189234) (xy 197.174612 -123.159266) (xy 183.615076 -123.159266) (xy 183.615076 -123.16714)
			(xy 183.614586 -123.197108) (xy 183.606763 -123.25653) (xy 183.59125 -123.314423) (xy 183.568314 -123.369796)
			(xy 183.538347 -123.421702) (xy 183.50186 -123.469252) (xy 183.45948 -123.511632) (xy 183.41193 -123.548119)
			(xy 183.360024 -123.578086) (xy 183.304651 -123.601022) (xy 183.246758 -123.616535) (xy 183.187336 -123.624358)
			(xy 183.1274 -123.624358) (xy 183.067978 -123.616535) (xy 183.010085 -123.601022) (xy 182.954712 -123.578086)
			(xy 182.902806 -123.548119) (xy 182.855256 -123.511632) (xy 182.812876 -123.469252) (xy 182.776389 -123.421702)
			(xy 182.746422 -123.369796) (xy 182.723486 -123.314423) (xy 182.707973 -123.25653) (xy 182.70015 -123.197108)
			(xy 182.69966 -123.16714) (xy 170.65498 -123.16714) (xy 170.65498 -123.686316) (xy 170.65449 -123.7163)
			(xy 170.646662 -123.775756) (xy 170.631141 -123.833681) (xy 170.608192 -123.889085) (xy 170.578208 -123.941019)
			(xy 170.541702 -123.988595) (xy 170.499297 -124.031) (xy 170.451721 -124.067506) (xy 170.399787 -124.09749)
			(xy 170.344383 -124.120439) (xy 170.286458 -124.13596) (xy 170.227002 -124.143788) (xy 170.167034 -124.143788)
			(xy 170.107578 -124.13596) (xy 170.049653 -124.120439) (xy 169.994249 -124.09749) (xy 169.942315 -124.067506)
			(xy 169.894739 -124.031) (xy 169.852334 -123.988595) (xy 169.815828 -123.941019) (xy 169.785844 -123.889085)
			(xy 169.762895 -123.833681) (xy 169.747374 -123.775756) (xy 169.739546 -123.7163) (xy 169.739056 -123.686316)
			(xy 151.68372 -123.686316) (xy 151.68372 -123.68784) (xy 151.68323 -123.717824) (xy 151.675402 -123.77728)
			(xy 151.659881 -123.835205) (xy 151.636932 -123.890609) (xy 151.606948 -123.942543) (xy 151.570442 -123.990119)
			(xy 151.528037 -124.032524) (xy 151.480461 -124.06903) (xy 151.428527 -124.099014) (xy 151.373123 -124.121963)
			(xy 151.315198 -124.137484) (xy 151.255742 -124.145312) (xy 151.195774 -124.145312) (xy 151.136318 -124.137484)
			(xy 151.078393 -124.121963) (xy 151.022989 -124.099014) (xy 150.971055 -124.06903) (xy 150.923479 -124.032524)
			(xy 150.881074 -123.990119) (xy 150.844568 -123.942543) (xy 150.814584 -123.890609) (xy 150.791635 -123.835205)
			(xy 150.776114 -123.77728) (xy 150.768286 -123.717824) (xy 150.767796 -123.68784) (xy 84.369615 -123.68784)
			(xy 84.377099 -123.69094) (xy 84.429033 -123.720924) (xy 84.476609 -123.75743) (xy 84.519014 -123.799835)
			(xy 84.55552 -123.847411) (xy 84.585504 -123.899345) (xy 84.608453 -123.954749) (xy 84.623974 -124.012674)
			(xy 84.631802 -124.07213) (xy 84.632292 -124.102114) (xy 84.632292 -124.965714) (xy 84.631802 -124.995698)
			(xy 84.623974 -125.055154) (xy 84.608453 -125.113079) (xy 84.585504 -125.168483) (xy 84.55552 -125.220417)
			(xy 84.519014 -125.267993) (xy 84.476609 -125.310398) (xy 84.429033 -125.346904) (xy 84.377099 -125.376888)
			(xy 84.321695 -125.399837) (xy 84.26377 -125.415358) (xy 84.204314 -125.423186) (xy 84.144346 -125.423186)
			(xy 84.08489 -125.415358) (xy 84.026965 -125.399837) (xy 83.971561 -125.376888) (xy 83.919627 -125.346904)
			(xy 83.872051 -125.310398) (xy 83.829646 -125.267993) (xy 83.79314 -125.220417) (xy 83.763156 -125.168483)
			(xy 83.740207 -125.113079) (xy 83.724686 -125.055154) (xy 83.716858 -124.995698) (xy 83.716368 -124.965714)
			(xy 65.661032 -124.965714) (xy 65.661032 -124.967238) (xy 65.660542 -124.997222) (xy 65.652714 -125.056678)
			(xy 65.637193 -125.114603) (xy 65.614244 -125.170007) (xy 65.58426 -125.221941) (xy 65.547754 -125.269517)
			(xy 65.505349 -125.311922) (xy 65.457773 -125.348428) (xy 65.405839 -125.378412) (xy 65.350435 -125.401361)
			(xy 65.29251 -125.416882) (xy 65.233054 -125.42471) (xy 65.173086 -125.42471) (xy 65.11363 -125.416882)
			(xy 65.055705 -125.401361) (xy 65.000301 -125.378412) (xy 64.948367 -125.348428) (xy 64.900791 -125.311922)
			(xy 64.858386 -125.269517) (xy 64.82188 -125.221941) (xy 64.791896 -125.170007) (xy 64.768947 -125.114603)
			(xy 64.753426 -125.056678) (xy 64.745598 -124.997222) (xy 64.745108 -124.967238) (xy 52.700428 -124.967238)
			(xy 52.700428 -125.486414) (xy 52.700295 -125.494542) (xy 153.409904 -125.494542) (xy 153.409904 -124.630942)
			(xy 153.410394 -124.600958) (xy 153.418222 -124.541502) (xy 153.433743 -124.483577) (xy 153.456692 -124.428173)
			(xy 153.486676 -124.376239) (xy 153.523182 -124.328663) (xy 153.565587 -124.286258) (xy 153.613163 -124.249752)
			(xy 153.665097 -124.219768) (xy 153.720501 -124.196819) (xy 153.778426 -124.181298) (xy 153.837882 -124.17347)
			(xy 153.89785 -124.17347) (xy 153.957306 -124.181298) (xy 154.015231 -124.196819) (xy 154.070635 -124.219768)
			(xy 154.122569 -124.249752) (xy 154.170145 -124.286258) (xy 154.21255 -124.328663) (xy 154.249056 -124.376239)
			(xy 154.27904 -124.428173) (xy 154.301989 -124.483577) (xy 154.31751 -124.541502) (xy 154.325338 -124.600958)
			(xy 154.325828 -124.630942) (xy 154.325828 -125.486414) (xy 167.884856 -125.486414) (xy 167.884856 -124.622814)
			(xy 167.885346 -124.59283) (xy 167.893174 -124.533374) (xy 167.908695 -124.475449) (xy 167.931644 -124.420045)
			(xy 167.961628 -124.368111) (xy 167.998134 -124.320535) (xy 168.040539 -124.27813) (xy 168.088115 -124.241624)
			(xy 168.140049 -124.21164) (xy 168.195453 -124.188691) (xy 168.253378 -124.17317) (xy 168.312834 -124.165342)
			(xy 168.372802 -124.165342) (xy 168.432258 -124.17317) (xy 168.490183 -124.188691) (xy 168.545587 -124.21164)
			(xy 168.597521 -124.241624) (xy 168.645097 -124.27813) (xy 168.687502 -124.320535) (xy 168.724008 -124.368111)
			(xy 168.753992 -124.420045) (xy 168.776941 -124.475449) (xy 168.792462 -124.533374) (xy 168.80029 -124.59283)
			(xy 168.80078 -124.622814) (xy 168.80078 -124.967238) (xy 180.84546 -124.967238) (xy 180.84546 -124.103638)
			(xy 180.84595 -124.07367) (xy 180.853773 -124.014248) (xy 180.869286 -123.956355) (xy 180.892222 -123.900982)
			(xy 180.922189 -123.849076) (xy 180.958676 -123.801526) (xy 181.001056 -123.759146) (xy 181.048606 -123.722659)
			(xy 181.100512 -123.692692) (xy 181.155885 -123.669756) (xy 181.213778 -123.654243) (xy 181.2732 -123.64642)
			(xy 181.333136 -123.64642) (xy 181.392558 -123.654243) (xy 181.450451 -123.669756) (xy 181.505824 -123.692692)
			(xy 181.55773 -123.722659) (xy 181.60528 -123.759146) (xy 181.64766 -123.801526) (xy 181.684147 -123.849076)
			(xy 181.714114 -123.900982) (xy 181.73705 -123.956355) (xy 181.752563 -124.014248) (xy 181.760386 -124.07367)
			(xy 181.760876 -124.103638) (xy 181.760876 -124.965714) (xy 199.81672 -124.965714) (xy 199.81672 -124.102114)
			(xy 199.81721 -124.072146) (xy 199.825033 -124.012724) (xy 199.840546 -123.954831) (xy 199.863482 -123.899458)
			(xy 199.893449 -123.847552) (xy 199.929936 -123.800002) (xy 199.972316 -123.757622) (xy 200.019866 -123.721135)
			(xy 200.071772 -123.691168) (xy 200.127145 -123.668232) (xy 200.185038 -123.652719) (xy 200.24446 -123.644896)
			(xy 200.304396 -123.644896) (xy 200.363818 -123.652719) (xy 200.421711 -123.668232) (xy 200.469049 -123.68784)
			(xy 266.86764 -123.68784) (xy 266.86764 -122.82424) (xy 266.86813 -122.794256) (xy 266.875958 -122.7348)
			(xy 266.891479 -122.676875) (xy 266.914428 -122.621471) (xy 266.944412 -122.569537) (xy 266.980918 -122.521961)
			(xy 267.023323 -122.479556) (xy 267.070899 -122.44305) (xy 267.122833 -122.413066) (xy 267.178237 -122.390117)
			(xy 267.236162 -122.374596) (xy 267.295618 -122.366768) (xy 267.355586 -122.366768) (xy 267.415042 -122.374596)
			(xy 267.472967 -122.390117) (xy 267.528371 -122.413066) (xy 267.580305 -122.44305) (xy 267.627881 -122.479556)
			(xy 267.670286 -122.521961) (xy 267.706792 -122.569537) (xy 267.736776 -122.621471) (xy 267.759725 -122.676875)
			(xy 267.775246 -122.7348) (xy 267.783074 -122.794256) (xy 267.783564 -122.82424) (xy 267.783564 -123.686316)
			(xy 285.8389 -123.686316) (xy 285.8389 -122.822716) (xy 285.83939 -122.792732) (xy 285.847218 -122.733276)
			(xy 285.862739 -122.675351) (xy 285.885688 -122.619947) (xy 285.915672 -122.568013) (xy 285.952178 -122.520437)
			(xy 285.994583 -122.478032) (xy 286.042159 -122.441526) (xy 286.094093 -122.411542) (xy 286.149497 -122.388593)
			(xy 286.207422 -122.373072) (xy 286.266878 -122.365244) (xy 286.326846 -122.365244) (xy 286.386302 -122.373072)
			(xy 286.444227 -122.388593) (xy 286.499631 -122.411542) (xy 286.551565 -122.441526) (xy 286.599141 -122.478032)
			(xy 286.641546 -122.520437) (xy 286.678052 -122.568013) (xy 286.708036 -122.619947) (xy 286.730985 -122.675351)
			(xy 286.746506 -122.733276) (xy 286.754334 -122.792732) (xy 286.754824 -122.822716) (xy 286.754824 -123.16714)
			(xy 298.799504 -123.16714) (xy 298.799504 -122.30354) (xy 298.799994 -122.273572) (xy 298.807817 -122.21415)
			(xy 298.82333 -122.156257) (xy 298.846266 -122.100884) (xy 298.876233 -122.048978) (xy 298.91272 -122.001428)
			(xy 298.9551 -121.959048) (xy 299.00265 -121.922561) (xy 299.054556 -121.892594) (xy 299.109929 -121.869658)
			(xy 299.167822 -121.854145) (xy 299.227244 -121.846322) (xy 299.28718 -121.846322) (xy 299.346602 -121.854145)
			(xy 299.404495 -121.869658) (xy 299.459868 -121.892594) (xy 299.511774 -121.922561) (xy 299.559324 -121.959048)
			(xy 299.601704 -122.001428) (xy 299.638191 -122.048978) (xy 299.668158 -122.100884) (xy 299.691094 -122.156257)
			(xy 299.706607 -122.21415) (xy 299.71443 -122.273572) (xy 299.71492 -122.30354) (xy 299.71492 -123.159266)
			(xy 313.274456 -123.159266) (xy 313.274456 -122.295666) (xy 313.274946 -122.265698) (xy 313.282769 -122.206276)
			(xy 313.298282 -122.148383) (xy 313.321218 -122.09301) (xy 313.351185 -122.041104) (xy 313.387672 -121.993554)
			(xy 313.430052 -121.951174) (xy 313.477602 -121.914687) (xy 313.529508 -121.88472) (xy 313.584881 -121.861784)
			(xy 313.642774 -121.846271) (xy 313.702196 -121.838448) (xy 313.762132 -121.838448) (xy 313.821554 -121.846271)
			(xy 313.879447 -121.861784) (xy 313.93482 -121.88472) (xy 313.951493 -121.894346) (xy 385.6101 -121.894346)
			(xy 385.6101 -121.030746) (xy 385.61059 -121.000778) (xy 385.618413 -120.941356) (xy 385.633926 -120.883463)
			(xy 385.656862 -120.82809) (xy 385.686829 -120.776184) (xy 385.723316 -120.728634) (xy 385.765696 -120.686254)
			(xy 385.813246 -120.649767) (xy 385.865152 -120.6198) (xy 385.920525 -120.596864) (xy 385.978418 -120.581351)
			(xy 386.03784 -120.573528) (xy 386.097776 -120.573528) (xy 386.157198 -120.581351) (xy 386.215091 -120.596864)
			(xy 386.270464 -120.6198) (xy 386.32237 -120.649767) (xy 386.36992 -120.686254) (xy 386.4123 -120.728634)
			(xy 386.448787 -120.776184) (xy 386.478754 -120.82809) (xy 386.50169 -120.883463) (xy 386.517203 -120.941356)
			(xy 386.525026 -121.000778) (xy 386.525516 -121.030746) (xy 386.525516 -121.886472) (xy 400.085052 -121.886472)
			(xy 400.085052 -121.022872) (xy 400.085542 -120.992904) (xy 400.093365 -120.933482) (xy 400.108878 -120.875589)
			(xy 400.131814 -120.820216) (xy 400.161781 -120.76831) (xy 400.198268 -120.72076) (xy 400.240648 -120.67838)
			(xy 400.288198 -120.641893) (xy 400.340104 -120.611926) (xy 400.395477 -120.58899) (xy 400.45337 -120.573477)
			(xy 400.512792 -120.565654) (xy 400.572728 -120.565654) (xy 400.63215 -120.573477) (xy 400.690043 -120.58899)
			(xy 400.745416 -120.611926) (xy 400.797322 -120.641893) (xy 400.844872 -120.67838) (xy 400.887252 -120.72076)
			(xy 400.923739 -120.76831) (xy 400.953706 -120.820216) (xy 400.976642 -120.875589) (xy 400.992155 -120.933482)
			(xy 400.999978 -120.992904) (xy 401.000468 -121.022872) (xy 401.000468 -121.367296) (xy 413.045148 -121.367296)
			(xy 413.045148 -120.503696) (xy 413.045638 -120.473712) (xy 413.053466 -120.414256) (xy 413.068987 -120.356331)
			(xy 413.091936 -120.300927) (xy 413.12192 -120.248993) (xy 413.158426 -120.201417) (xy 413.200831 -120.159012)
			(xy 413.248407 -120.122506) (xy 413.300341 -120.092522) (xy 413.355745 -120.069573) (xy 413.41367 -120.054052)
			(xy 413.473126 -120.046224) (xy 413.533094 -120.046224) (xy 413.59255 -120.054052) (xy 413.650475 -120.069573)
			(xy 413.705879 -120.092522) (xy 413.757813 -120.122506) (xy 413.805389 -120.159012) (xy 413.847794 -120.201417)
			(xy 413.8843 -120.248993) (xy 413.914284 -120.300927) (xy 413.937233 -120.356331) (xy 413.952754 -120.414256)
			(xy 413.960582 -120.473712) (xy 413.961072 -120.503696) (xy 413.961072 -121.365772) (xy 432.016408 -121.365772)
			(xy 432.016408 -120.502172) (xy 432.016898 -120.472188) (xy 432.024726 -120.412732) (xy 432.040247 -120.354807)
			(xy 432.063196 -120.299403) (xy 432.09318 -120.247469) (xy 432.129686 -120.199893) (xy 432.172091 -120.157488)
			(xy 432.219667 -120.120982) (xy 432.271601 -120.090998) (xy 432.327005 -120.068049) (xy 432.38493 -120.052528)
			(xy 432.444386 -120.0447) (xy 432.504354 -120.0447) (xy 432.56381 -120.052528) (xy 432.621735 -120.068049)
			(xy 432.677139 -120.090998) (xy 432.729073 -120.120982) (xy 432.776649 -120.157488) (xy 432.819054 -120.199893)
			(xy 432.85556 -120.247469) (xy 432.885544 -120.299403) (xy 432.908493 -120.354807) (xy 432.924014 -120.412732)
			(xy 432.931842 -120.472188) (xy 432.932332 -120.502172) (xy 432.932332 -121.365772) (xy 432.931842 -121.395756)
			(xy 432.924014 -121.455212) (xy 432.908493 -121.513137) (xy 432.885544 -121.568541) (xy 432.85556 -121.620475)
			(xy 432.819054 -121.668051) (xy 432.776649 -121.710456) (xy 432.729073 -121.746962) (xy 432.677139 -121.776946)
			(xy 432.621735 -121.799895) (xy 432.56381 -121.815416) (xy 432.504354 -121.823244) (xy 432.444386 -121.823244)
			(xy 432.38493 -121.815416) (xy 432.327005 -121.799895) (xy 432.271601 -121.776946) (xy 432.219667 -121.746962)
			(xy 432.172091 -121.710456) (xy 432.129686 -121.668051) (xy 432.09318 -121.620475) (xy 432.063196 -121.568541)
			(xy 432.040247 -121.513137) (xy 432.024726 -121.455212) (xy 432.016898 -121.395756) (xy 432.016408 -121.365772)
			(xy 413.961072 -121.365772) (xy 413.961072 -121.367296) (xy 413.960582 -121.39728) (xy 413.952754 -121.456736)
			(xy 413.937233 -121.514661) (xy 413.914284 -121.570065) (xy 413.8843 -121.621999) (xy 413.847794 -121.669575)
			(xy 413.805389 -121.71198) (xy 413.757813 -121.748486) (xy 413.705879 -121.77847) (xy 413.650475 -121.801419)
			(xy 413.59255 -121.81694) (xy 413.533094 -121.824768) (xy 413.473126 -121.824768) (xy 413.41367 -121.81694)
			(xy 413.355745 -121.801419) (xy 413.300341 -121.77847) (xy 413.248407 -121.748486) (xy 413.200831 -121.71198)
			(xy 413.158426 -121.669575) (xy 413.12192 -121.621999) (xy 413.091936 -121.570065) (xy 413.068987 -121.514661)
			(xy 413.053466 -121.456736) (xy 413.045638 -121.39728) (xy 413.045148 -121.367296) (xy 401.000468 -121.367296)
			(xy 401.000468 -121.886472) (xy 400.999978 -121.91644) (xy 400.992155 -121.975862) (xy 400.976642 -122.033755)
			(xy 400.953706 -122.089128) (xy 400.923739 -122.141034) (xy 400.887252 -122.188584) (xy 400.844872 -122.230964)
			(xy 400.797322 -122.267451) (xy 400.745416 -122.297418) (xy 400.690043 -122.320354) (xy 400.63215 -122.335867)
			(xy 400.572728 -122.34369) (xy 400.512792 -122.34369) (xy 400.45337 -122.335867) (xy 400.395477 -122.320354)
			(xy 400.340104 -122.297418) (xy 400.288198 -122.267451) (xy 400.240648 -122.230964) (xy 400.198268 -122.188584)
			(xy 400.161781 -122.141034) (xy 400.131814 -122.089128) (xy 400.108878 -122.033755) (xy 400.093365 -121.975862)
			(xy 400.085542 -121.91644) (xy 400.085052 -121.886472) (xy 386.525516 -121.886472) (xy 386.525516 -121.894346)
			(xy 386.525026 -121.924314) (xy 386.517203 -121.983736) (xy 386.50169 -122.041629) (xy 386.478754 -122.097002)
			(xy 386.448787 -122.148908) (xy 386.4123 -122.196458) (xy 386.36992 -122.238838) (xy 386.32237 -122.275325)
			(xy 386.270464 -122.305292) (xy 386.215091 -122.328228) (xy 386.157198 -122.343741) (xy 386.097776 -122.351564)
			(xy 386.03784 -122.351564) (xy 385.978418 -122.343741) (xy 385.920525 -122.328228) (xy 385.865152 -122.305292)
			(xy 385.813246 -122.275325) (xy 385.765696 -122.238838) (xy 385.723316 -122.196458) (xy 385.686829 -122.148908)
			(xy 385.656862 -122.097002) (xy 385.633926 -122.041629) (xy 385.618413 -121.983736) (xy 385.61059 -121.924314)
			(xy 385.6101 -121.894346) (xy 313.951493 -121.894346) (xy 313.986726 -121.914687) (xy 314.034276 -121.951174)
			(xy 314.076656 -121.993554) (xy 314.113143 -122.041104) (xy 314.14311 -122.09301) (xy 314.166046 -122.148383)
			(xy 314.181559 -122.206276) (xy 314.189382 -122.265698) (xy 314.189872 -122.295666) (xy 314.189872 -123.159266)
			(xy 314.189382 -123.189234) (xy 314.181559 -123.248656) (xy 314.166046 -123.306549) (xy 314.14311 -123.361922)
			(xy 314.113143 -123.413828) (xy 314.076656 -123.461378) (xy 314.034276 -123.503758) (xy 313.986726 -123.540245)
			(xy 313.93482 -123.570212) (xy 313.879447 -123.593148) (xy 313.821554 -123.608661) (xy 313.762132 -123.616484)
			(xy 313.702196 -123.616484) (xy 313.642774 -123.608661) (xy 313.584881 -123.593148) (xy 313.529508 -123.570212)
			(xy 313.477602 -123.540245) (xy 313.430052 -123.503758) (xy 313.387672 -123.461378) (xy 313.351185 -123.413828)
			(xy 313.321218 -123.361922) (xy 313.298282 -123.306549) (xy 313.282769 -123.248656) (xy 313.274946 -123.189234)
			(xy 313.274456 -123.159266) (xy 299.71492 -123.159266) (xy 299.71492 -123.16714) (xy 299.71443 -123.197108)
			(xy 299.706607 -123.25653) (xy 299.691094 -123.314423) (xy 299.668158 -123.369796) (xy 299.638191 -123.421702)
			(xy 299.601704 -123.469252) (xy 299.559324 -123.511632) (xy 299.511774 -123.548119) (xy 299.459868 -123.578086)
			(xy 299.404495 -123.601022) (xy 299.346602 -123.616535) (xy 299.28718 -123.624358) (xy 299.227244 -123.624358)
			(xy 299.167822 -123.616535) (xy 299.109929 -123.601022) (xy 299.054556 -123.578086) (xy 299.00265 -123.548119)
			(xy 298.9551 -123.511632) (xy 298.91272 -123.469252) (xy 298.876233 -123.421702) (xy 298.846266 -123.369796)
			(xy 298.82333 -123.314423) (xy 298.807817 -123.25653) (xy 298.799994 -123.197108) (xy 298.799504 -123.16714)
			(xy 286.754824 -123.16714) (xy 286.754824 -123.686316) (xy 286.754334 -123.7163) (xy 286.746506 -123.775756)
			(xy 286.730985 -123.833681) (xy 286.708036 -123.889085) (xy 286.678052 -123.941019) (xy 286.641546 -123.988595)
			(xy 286.599141 -124.031) (xy 286.551565 -124.067506) (xy 286.499631 -124.09749) (xy 286.444227 -124.120439)
			(xy 286.386302 -124.13596) (xy 286.326846 -124.143788) (xy 286.266878 -124.143788) (xy 286.207422 -124.13596)
			(xy 286.149497 -124.120439) (xy 286.094093 -124.09749) (xy 286.042159 -124.067506) (xy 285.994583 -124.031)
			(xy 285.952178 -123.988595) (xy 285.915672 -123.941019) (xy 285.885688 -123.889085) (xy 285.862739 -123.833681)
			(xy 285.847218 -123.775756) (xy 285.83939 -123.7163) (xy 285.8389 -123.686316) (xy 267.783564 -123.686316)
			(xy 267.783564 -123.68784) (xy 267.783074 -123.717824) (xy 267.775246 -123.77728) (xy 267.759725 -123.835205)
			(xy 267.736776 -123.890609) (xy 267.706792 -123.942543) (xy 267.670286 -123.990119) (xy 267.627881 -124.032524)
			(xy 267.580305 -124.06903) (xy 267.528371 -124.099014) (xy 267.472967 -124.121963) (xy 267.415042 -124.137484)
			(xy 267.355586 -124.145312) (xy 267.295618 -124.145312) (xy 267.236162 -124.137484) (xy 267.178237 -124.121963)
			(xy 267.122833 -124.099014) (xy 267.070899 -124.06903) (xy 267.023323 -124.032524) (xy 266.980918 -123.990119)
			(xy 266.944412 -123.942543) (xy 266.914428 -123.890609) (xy 266.891479 -123.835205) (xy 266.875958 -123.77728)
			(xy 266.86813 -123.717824) (xy 266.86764 -123.68784) (xy 200.469049 -123.68784) (xy 200.477084 -123.691168)
			(xy 200.52899 -123.721135) (xy 200.57654 -123.757622) (xy 200.61892 -123.800002) (xy 200.655407 -123.847552)
			(xy 200.685374 -123.899458) (xy 200.70831 -123.954831) (xy 200.723823 -124.012724) (xy 200.731646 -124.072146)
			(xy 200.732136 -124.102114) (xy 200.732136 -124.965714) (xy 200.731646 -124.995682) (xy 200.723823 -125.055104)
			(xy 200.70831 -125.112997) (xy 200.685374 -125.16837) (xy 200.655407 -125.220276) (xy 200.61892 -125.267826)
			(xy 200.57654 -125.310206) (xy 200.52899 -125.346693) (xy 200.477084 -125.37666) (xy 200.421711 -125.399596)
			(xy 200.363818 -125.415109) (xy 200.304396 -125.422932) (xy 200.24446 -125.422932) (xy 200.185038 -125.415109)
			(xy 200.127145 -125.399596) (xy 200.071772 -125.37666) (xy 200.019866 -125.346693) (xy 199.972316 -125.310206)
			(xy 199.929936 -125.267826) (xy 199.893449 -125.220276) (xy 199.863482 -125.16837) (xy 199.840546 -125.112997)
			(xy 199.825033 -125.055104) (xy 199.81721 -124.995682) (xy 199.81672 -124.965714) (xy 181.760876 -124.965714)
			(xy 181.760876 -124.967238) (xy 181.760386 -124.997206) (xy 181.752563 -125.056628) (xy 181.73705 -125.114521)
			(xy 181.714114 -125.169894) (xy 181.684147 -125.2218) (xy 181.64766 -125.26935) (xy 181.60528 -125.31173)
			(xy 181.55773 -125.348217) (xy 181.505824 -125.378184) (xy 181.450451 -125.40112) (xy 181.392558 -125.416633)
			(xy 181.333136 -125.424456) (xy 181.2732 -125.424456) (xy 181.213778 -125.416633) (xy 181.155885 -125.40112)
			(xy 181.100512 -125.378184) (xy 181.048606 -125.348217) (xy 181.001056 -125.31173) (xy 180.958676 -125.26935)
			(xy 180.922189 -125.2218) (xy 180.892222 -125.169894) (xy 180.869286 -125.114521) (xy 180.853773 -125.056628)
			(xy 180.84595 -124.997206) (xy 180.84546 -124.967238) (xy 168.80078 -124.967238) (xy 168.80078 -125.486414)
			(xy 168.800647 -125.494542) (xy 269.509748 -125.494542) (xy 269.509748 -124.630942) (xy 269.510238 -124.600958)
			(xy 269.518066 -124.541502) (xy 269.533587 -124.483577) (xy 269.556536 -124.428173) (xy 269.58652 -124.376239)
			(xy 269.623026 -124.328663) (xy 269.665431 -124.286258) (xy 269.713007 -124.249752) (xy 269.764941 -124.219768)
			(xy 269.820345 -124.196819) (xy 269.87827 -124.181298) (xy 269.937726 -124.17347) (xy 269.997694 -124.17347)
			(xy 270.05715 -124.181298) (xy 270.115075 -124.196819) (xy 270.170479 -124.219768) (xy 270.222413 -124.249752)
			(xy 270.269989 -124.286258) (xy 270.312394 -124.328663) (xy 270.3489 -124.376239) (xy 270.378884 -124.428173)
			(xy 270.401833 -124.483577) (xy 270.417354 -124.541502) (xy 270.425182 -124.600958) (xy 270.425672 -124.630942)
			(xy 270.425672 -125.486414) (xy 283.9847 -125.486414) (xy 283.9847 -124.622814) (xy 283.98519 -124.59283)
			(xy 283.993018 -124.533374) (xy 284.008539 -124.475449) (xy 284.031488 -124.420045) (xy 284.061472 -124.368111)
			(xy 284.097978 -124.320535) (xy 284.140383 -124.27813) (xy 284.187959 -124.241624) (xy 284.239893 -124.21164)
			(xy 284.295297 -124.188691) (xy 284.353222 -124.17317) (xy 284.412678 -124.165342) (xy 284.472646 -124.165342)
			(xy 284.532102 -124.17317) (xy 284.590027 -124.188691) (xy 284.645431 -124.21164) (xy 284.697365 -124.241624)
			(xy 284.744941 -124.27813) (xy 284.787346 -124.320535) (xy 284.823852 -124.368111) (xy 284.853836 -124.420045)
			(xy 284.876785 -124.475449) (xy 284.892306 -124.533374) (xy 284.900134 -124.59283) (xy 284.900624 -124.622814)
			(xy 284.900624 -124.967238) (xy 296.945304 -124.967238) (xy 296.945304 -124.103638) (xy 296.945794 -124.07367)
			(xy 296.953617 -124.014248) (xy 296.96913 -123.956355) (xy 296.992066 -123.900982) (xy 297.022033 -123.849076)
			(xy 297.05852 -123.801526) (xy 297.1009 -123.759146) (xy 297.14845 -123.722659) (xy 297.200356 -123.692692)
			(xy 297.255729 -123.669756) (xy 297.313622 -123.654243) (xy 297.373044 -123.64642) (xy 297.43298 -123.64642)
			(xy 297.492402 -123.654243) (xy 297.550295 -123.669756) (xy 297.605668 -123.692692) (xy 297.657574 -123.722659)
			(xy 297.705124 -123.759146) (xy 297.747504 -123.801526) (xy 297.783991 -123.849076) (xy 297.813958 -123.900982)
			(xy 297.836894 -123.956355) (xy 297.852407 -124.014248) (xy 297.86023 -124.07367) (xy 297.86072 -124.103638)
			(xy 297.86072 -124.965714) (xy 315.916564 -124.965714) (xy 315.916564 -124.102114) (xy 315.917054 -124.072146)
			(xy 315.924877 -124.012724) (xy 315.94039 -123.954831) (xy 315.963326 -123.899458) (xy 315.993293 -123.847552)
			(xy 316.02978 -123.800002) (xy 316.07216 -123.757622) (xy 316.11971 -123.721135) (xy 316.171616 -123.691168)
			(xy 316.226989 -123.668232) (xy 316.284882 -123.652719) (xy 316.344304 -123.644896) (xy 316.40424 -123.644896)
			(xy 316.463662 -123.652719) (xy 316.521555 -123.668232) (xy 316.568893 -123.68784) (xy 382.967992 -123.68784)
			(xy 382.967992 -122.82424) (xy 382.968482 -122.794272) (xy 382.976305 -122.73485) (xy 382.991818 -122.676957)
			(xy 383.014754 -122.621584) (xy 383.044721 -122.569678) (xy 383.081208 -122.522128) (xy 383.123588 -122.479748)
			(xy 383.171138 -122.443261) (xy 383.223044 -122.413294) (xy 383.278417 -122.390358) (xy 383.33631 -122.374845)
			(xy 383.395732 -122.367022) (xy 383.455668 -122.367022) (xy 383.51509 -122.374845) (xy 383.572983 -122.390358)
			(xy 383.628356 -122.413294) (xy 383.680262 -122.443261) (xy 383.727812 -122.479748) (xy 383.770192 -122.522128)
			(xy 383.806679 -122.569678) (xy 383.836646 -122.621584) (xy 383.859582 -122.676957) (xy 383.875095 -122.73485)
			(xy 383.882918 -122.794272) (xy 383.883408 -122.82424) (xy 383.883408 -123.686316) (xy 401.939252 -123.686316)
			(xy 401.939252 -122.822716) (xy 401.939742 -122.792748) (xy 401.947565 -122.733326) (xy 401.963078 -122.675433)
			(xy 401.986014 -122.62006) (xy 402.015981 -122.568154) (xy 402.052468 -122.520604) (xy 402.094848 -122.478224)
			(xy 402.142398 -122.441737) (xy 402.194304 -122.41177) (xy 402.249677 -122.388834) (xy 402.30757 -122.373321)
			(xy 402.366992 -122.365498) (xy 402.426928 -122.365498) (xy 402.48635 -122.373321) (xy 402.544243 -122.388834)
			(xy 402.599616 -122.41177) (xy 402.651522 -122.441737) (xy 402.699072 -122.478224) (xy 402.741452 -122.520604)
			(xy 402.777939 -122.568154) (xy 402.807906 -122.62006) (xy 402.830842 -122.675433) (xy 402.846355 -122.733326)
			(xy 402.854178 -122.792748) (xy 402.854668 -122.822716) (xy 402.854668 -123.16714) (xy 414.899348 -123.16714)
			(xy 414.899348 -122.30354) (xy 414.899838 -122.273556) (xy 414.907666 -122.2141) (xy 414.923187 -122.156175)
			(xy 414.946136 -122.100771) (xy 414.97612 -122.048837) (xy 415.012626 -122.001261) (xy 415.055031 -121.958856)
			(xy 415.102607 -121.92235) (xy 415.154541 -121.892366) (xy 415.209945 -121.869417) (xy 415.26787 -121.853896)
			(xy 415.327326 -121.846068) (xy 415.387294 -121.846068) (xy 415.44675 -121.853896) (xy 415.504675 -121.869417)
			(xy 415.560079 -121.892366) (xy 415.612013 -121.92235) (xy 415.659589 -121.958856) (xy 415.701994 -122.001261)
			(xy 415.7385 -122.048837) (xy 415.768484 -122.100771) (xy 415.791433 -122.156175) (xy 415.806954 -122.2141)
			(xy 415.814782 -122.273556) (xy 415.815272 -122.30354) (xy 415.815272 -123.159266) (xy 429.3743 -123.159266)
			(xy 429.3743 -122.295666) (xy 429.37479 -122.265682) (xy 429.382618 -122.206226) (xy 429.398139 -122.148301)
			(xy 429.421088 -122.092897) (xy 429.451072 -122.040963) (xy 429.487578 -121.993387) (xy 429.529983 -121.950982)
			(xy 429.577559 -121.914476) (xy 429.629493 -121.884492) (xy 429.684897 -121.861543) (xy 429.742822 -121.846022)
			(xy 429.802278 -121.838194) (xy 429.862246 -121.838194) (xy 429.921702 -121.846022) (xy 429.979627 -121.861543)
			(xy 430.035031 -121.884492) (xy 430.086965 -121.914476) (xy 430.134541 -121.950982) (xy 430.176946 -121.993387)
			(xy 430.213452 -122.040963) (xy 430.243436 -122.092897) (xy 430.266385 -122.148301) (xy 430.281906 -122.206226)
			(xy 430.289734 -122.265682) (xy 430.290224 -122.295666) (xy 430.290224 -123.159266) (xy 430.289734 -123.18925)
			(xy 430.281906 -123.248706) (xy 430.266385 -123.306631) (xy 430.243436 -123.362035) (xy 430.213452 -123.413969)
			(xy 430.176946 -123.461545) (xy 430.134541 -123.50395) (xy 430.086965 -123.540456) (xy 430.035031 -123.57044)
			(xy 429.979627 -123.593389) (xy 429.921702 -123.60891) (xy 429.862246 -123.616738) (xy 429.802278 -123.616738)
			(xy 429.742822 -123.60891) (xy 429.684897 -123.593389) (xy 429.629493 -123.57044) (xy 429.577559 -123.540456)
			(xy 429.529983 -123.50395) (xy 429.487578 -123.461545) (xy 429.451072 -123.413969) (xy 429.421088 -123.362035)
			(xy 429.398139 -123.306631) (xy 429.382618 -123.248706) (xy 429.37479 -123.18925) (xy 429.3743 -123.159266)
			(xy 415.815272 -123.159266) (xy 415.815272 -123.16714) (xy 415.814782 -123.197124) (xy 415.806954 -123.25658)
			(xy 415.791433 -123.314505) (xy 415.768484 -123.369909) (xy 415.7385 -123.421843) (xy 415.701994 -123.469419)
			(xy 415.659589 -123.511824) (xy 415.612013 -123.54833) (xy 415.560079 -123.578314) (xy 415.504675 -123.601263)
			(xy 415.44675 -123.616784) (xy 415.387294 -123.624612) (xy 415.327326 -123.624612) (xy 415.26787 -123.616784)
			(xy 415.209945 -123.601263) (xy 415.154541 -123.578314) (xy 415.102607 -123.54833) (xy 415.055031 -123.511824)
			(xy 415.012626 -123.469419) (xy 414.97612 -123.421843) (xy 414.946136 -123.369909) (xy 414.923187 -123.314505)
			(xy 414.907666 -123.25658) (xy 414.899838 -123.197124) (xy 414.899348 -123.16714) (xy 402.854668 -123.16714)
			(xy 402.854668 -123.686316) (xy 402.854178 -123.716284) (xy 402.846355 -123.775706) (xy 402.830842 -123.833599)
			(xy 402.807906 -123.888972) (xy 402.777939 -123.940878) (xy 402.741452 -123.988428) (xy 402.699072 -124.030808)
			(xy 402.651522 -124.067295) (xy 402.599616 -124.097262) (xy 402.544243 -124.120198) (xy 402.48635 -124.135711)
			(xy 402.426928 -124.143534) (xy 402.366992 -124.143534) (xy 402.30757 -124.135711) (xy 402.249677 -124.120198)
			(xy 402.194304 -124.097262) (xy 402.142398 -124.067295) (xy 402.094848 -124.030808) (xy 402.052468 -123.988428)
			(xy 402.015981 -123.940878) (xy 401.986014 -123.888972) (xy 401.963078 -123.833599) (xy 401.947565 -123.775706)
			(xy 401.939742 -123.716284) (xy 401.939252 -123.686316) (xy 383.883408 -123.686316) (xy 383.883408 -123.68784)
			(xy 383.882918 -123.717808) (xy 383.875095 -123.77723) (xy 383.859582 -123.835123) (xy 383.836646 -123.890496)
			(xy 383.806679 -123.942402) (xy 383.770192 -123.989952) (xy 383.727812 -124.032332) (xy 383.680262 -124.068819)
			(xy 383.628356 -124.098786) (xy 383.572983 -124.121722) (xy 383.51509 -124.137235) (xy 383.455668 -124.145058)
			(xy 383.395732 -124.145058) (xy 383.33631 -124.137235) (xy 383.278417 -124.121722) (xy 383.223044 -124.098786)
			(xy 383.171138 -124.068819) (xy 383.123588 -124.032332) (xy 383.081208 -123.989952) (xy 383.044721 -123.942402)
			(xy 383.014754 -123.890496) (xy 382.991818 -123.835123) (xy 382.976305 -123.77723) (xy 382.968482 -123.717808)
			(xy 382.967992 -123.68784) (xy 316.568893 -123.68784) (xy 316.576928 -123.691168) (xy 316.628834 -123.721135)
			(xy 316.676384 -123.757622) (xy 316.718764 -123.800002) (xy 316.755251 -123.847552) (xy 316.785218 -123.899458)
			(xy 316.808154 -123.954831) (xy 316.823667 -124.012724) (xy 316.83149 -124.072146) (xy 316.83198 -124.102114)
			(xy 316.83198 -124.965714) (xy 316.83149 -124.995682) (xy 316.823667 -125.055104) (xy 316.808154 -125.112997)
			(xy 316.785218 -125.16837) (xy 316.755251 -125.220276) (xy 316.718764 -125.267826) (xy 316.676384 -125.310206)
			(xy 316.628834 -125.346693) (xy 316.576928 -125.37666) (xy 316.521555 -125.399596) (xy 316.463662 -125.415109)
			(xy 316.40424 -125.422932) (xy 316.344304 -125.422932) (xy 316.284882 -125.415109) (xy 316.226989 -125.399596)
			(xy 316.171616 -125.37666) (xy 316.11971 -125.346693) (xy 316.07216 -125.310206) (xy 316.02978 -125.267826)
			(xy 315.993293 -125.220276) (xy 315.963326 -125.16837) (xy 315.94039 -125.112997) (xy 315.924877 -125.055104)
			(xy 315.917054 -124.995682) (xy 315.916564 -124.965714) (xy 297.86072 -124.965714) (xy 297.86072 -124.967238)
			(xy 297.86023 -124.997206) (xy 297.852407 -125.056628) (xy 297.836894 -125.114521) (xy 297.813958 -125.169894)
			(xy 297.783991 -125.2218) (xy 297.747504 -125.26935) (xy 297.705124 -125.31173) (xy 297.657574 -125.348217)
			(xy 297.605668 -125.378184) (xy 297.550295 -125.40112) (xy 297.492402 -125.416633) (xy 297.43298 -125.424456)
			(xy 297.373044 -125.424456) (xy 297.313622 -125.416633) (xy 297.255729 -125.40112) (xy 297.200356 -125.378184)
			(xy 297.14845 -125.348217) (xy 297.1009 -125.31173) (xy 297.05852 -125.26935) (xy 297.022033 -125.2218)
			(xy 296.992066 -125.169894) (xy 296.96913 -125.114521) (xy 296.953617 -125.056628) (xy 296.945794 -124.997206)
			(xy 296.945304 -124.967238) (xy 284.900624 -124.967238) (xy 284.900624 -125.486414) (xy 284.900491 -125.494542)
			(xy 385.6101 -125.494542) (xy 385.6101 -124.630942) (xy 385.61059 -124.600974) (xy 385.618413 -124.541552)
			(xy 385.633926 -124.483659) (xy 385.656862 -124.428286) (xy 385.686829 -124.37638) (xy 385.723316 -124.32883)
			(xy 385.765696 -124.28645) (xy 385.813246 -124.249963) (xy 385.865152 -124.219996) (xy 385.920525 -124.19706)
			(xy 385.978418 -124.181547) (xy 386.03784 -124.173724) (xy 386.097776 -124.173724) (xy 386.157198 -124.181547)
			(xy 386.215091 -124.19706) (xy 386.270464 -124.219996) (xy 386.32237 -124.249963) (xy 386.36992 -124.28645)
			(xy 386.4123 -124.32883) (xy 386.448787 -124.37638) (xy 386.478754 -124.428286) (xy 386.50169 -124.483659)
			(xy 386.517203 -124.541552) (xy 386.525026 -124.600974) (xy 386.525516 -124.630942) (xy 386.525516 -125.486414)
			(xy 400.085052 -125.486414) (xy 400.085052 -124.622814) (xy 400.085542 -124.592846) (xy 400.093365 -124.533424)
			(xy 400.108878 -124.475531) (xy 400.131814 -124.420158) (xy 400.161781 -124.368252) (xy 400.198268 -124.320702)
			(xy 400.240648 -124.278322) (xy 400.288198 -124.241835) (xy 400.340104 -124.211868) (xy 400.395477 -124.188932)
			(xy 400.45337 -124.173419) (xy 400.512792 -124.165596) (xy 400.572728 -124.165596) (xy 400.63215 -124.173419)
			(xy 400.690043 -124.188932) (xy 400.745416 -124.211868) (xy 400.797322 -124.241835) (xy 400.844872 -124.278322)
			(xy 400.887252 -124.320702) (xy 400.923739 -124.368252) (xy 400.953706 -124.420158) (xy 400.976642 -124.475531)
			(xy 400.992155 -124.533424) (xy 400.999978 -124.592846) (xy 401.000468 -124.622814) (xy 401.000468 -124.967238)
			(xy 413.045148 -124.967238) (xy 413.045148 -124.103638) (xy 413.045638 -124.073654) (xy 413.053466 -124.014198)
			(xy 413.068987 -123.956273) (xy 413.091936 -123.900869) (xy 413.12192 -123.848935) (xy 413.158426 -123.801359)
			(xy 413.200831 -123.758954) (xy 413.248407 -123.722448) (xy 413.300341 -123.692464) (xy 413.355745 -123.669515)
			(xy 413.41367 -123.653994) (xy 413.473126 -123.646166) (xy 413.533094 -123.646166) (xy 413.59255 -123.653994)
			(xy 413.650475 -123.669515) (xy 413.705879 -123.692464) (xy 413.757813 -123.722448) (xy 413.805389 -123.758954)
			(xy 413.847794 -123.801359) (xy 413.8843 -123.848935) (xy 413.914284 -123.900869) (xy 413.937233 -123.956273)
			(xy 413.952754 -124.014198) (xy 413.960582 -124.073654) (xy 413.961072 -124.103638) (xy 413.961072 -124.965714)
			(xy 432.016408 -124.965714) (xy 432.016408 -124.102114) (xy 432.016898 -124.07213) (xy 432.024726 -124.012674)
			(xy 432.040247 -123.954749) (xy 432.063196 -123.899345) (xy 432.09318 -123.847411) (xy 432.129686 -123.799835)
			(xy 432.172091 -123.75743) (xy 432.219667 -123.720924) (xy 432.271601 -123.69094) (xy 432.327005 -123.667991)
			(xy 432.38493 -123.65247) (xy 432.444386 -123.644642) (xy 432.504354 -123.644642) (xy 432.56381 -123.65247)
			(xy 432.621735 -123.667991) (xy 432.677139 -123.69094) (xy 432.729073 -123.720924) (xy 432.776649 -123.75743)
			(xy 432.819054 -123.799835) (xy 432.85556 -123.847411) (xy 432.885544 -123.899345) (xy 432.908493 -123.954749)
			(xy 432.924014 -124.012674) (xy 432.931842 -124.07213) (xy 432.932332 -124.102114) (xy 432.932332 -124.965714)
			(xy 432.931842 -124.995698) (xy 432.924014 -125.055154) (xy 432.908493 -125.113079) (xy 432.885544 -125.168483)
			(xy 432.85556 -125.220417) (xy 432.819054 -125.267993) (xy 432.776649 -125.310398) (xy 432.729073 -125.346904)
			(xy 432.677139 -125.376888) (xy 432.621735 -125.399837) (xy 432.56381 -125.415358) (xy 432.504354 -125.423186)
			(xy 432.444386 -125.423186) (xy 432.38493 -125.415358) (xy 432.327005 -125.399837) (xy 432.271601 -125.376888)
			(xy 432.219667 -125.346904) (xy 432.172091 -125.310398) (xy 432.129686 -125.267993) (xy 432.09318 -125.220417)
			(xy 432.063196 -125.168483) (xy 432.040247 -125.113079) (xy 432.024726 -125.055154) (xy 432.016898 -124.995698)
			(xy 432.016408 -124.965714) (xy 413.961072 -124.965714) (xy 413.961072 -124.967238) (xy 413.960582 -124.997222)
			(xy 413.952754 -125.056678) (xy 413.937233 -125.114603) (xy 413.914284 -125.170007) (xy 413.8843 -125.221941)
			(xy 413.847794 -125.269517) (xy 413.805389 -125.311922) (xy 413.757813 -125.348428) (xy 413.705879 -125.378412)
			(xy 413.650475 -125.401361) (xy 413.59255 -125.416882) (xy 413.533094 -125.42471) (xy 413.473126 -125.42471)
			(xy 413.41367 -125.416882) (xy 413.355745 -125.401361) (xy 413.300341 -125.378412) (xy 413.248407 -125.348428)
			(xy 413.200831 -125.311922) (xy 413.158426 -125.269517) (xy 413.12192 -125.221941) (xy 413.091936 -125.170007)
			(xy 413.068987 -125.114603) (xy 413.053466 -125.056678) (xy 413.045638 -124.997222) (xy 413.045148 -124.967238)
			(xy 401.000468 -124.967238) (xy 401.000468 -125.486414) (xy 400.999978 -125.516382) (xy 400.992155 -125.575804)
			(xy 400.976642 -125.633697) (xy 400.953706 -125.68907) (xy 400.923739 -125.740976) (xy 400.887252 -125.788526)
			(xy 400.844872 -125.830906) (xy 400.797322 -125.867393) (xy 400.745416 -125.89736) (xy 400.690043 -125.920296)
			(xy 400.63215 -125.935809) (xy 400.572728 -125.943632) (xy 400.512792 -125.943632) (xy 400.45337 -125.935809)
			(xy 400.395477 -125.920296) (xy 400.340104 -125.89736) (xy 400.288198 -125.867393) (xy 400.240648 -125.830906)
			(xy 400.198268 -125.788526) (xy 400.161781 -125.740976) (xy 400.131814 -125.68907) (xy 400.108878 -125.633697)
			(xy 400.093365 -125.575804) (xy 400.085542 -125.516382) (xy 400.085052 -125.486414) (xy 386.525516 -125.486414)
			(xy 386.525516 -125.494542) (xy 386.525026 -125.52451) (xy 386.517203 -125.583932) (xy 386.50169 -125.641825)
			(xy 386.478754 -125.697198) (xy 386.448787 -125.749104) (xy 386.4123 -125.796654) (xy 386.36992 -125.839034)
			(xy 386.32237 -125.875521) (xy 386.270464 -125.905488) (xy 386.215091 -125.928424) (xy 386.157198 -125.943937)
			(xy 386.097776 -125.95176) (xy 386.03784 -125.95176) (xy 385.978418 -125.943937) (xy 385.920525 -125.928424)
			(xy 385.865152 -125.905488) (xy 385.813246 -125.875521) (xy 385.765696 -125.839034) (xy 385.723316 -125.796654)
			(xy 385.686829 -125.749104) (xy 385.656862 -125.697198) (xy 385.633926 -125.641825) (xy 385.618413 -125.583932)
			(xy 385.61059 -125.52451) (xy 385.6101 -125.494542) (xy 284.900491 -125.494542) (xy 284.900134 -125.516398)
			(xy 284.892306 -125.575854) (xy 284.876785 -125.633779) (xy 284.853836 -125.689183) (xy 284.823852 -125.741117)
			(xy 284.787346 -125.788693) (xy 284.744941 -125.831098) (xy 284.697365 -125.867604) (xy 284.645431 -125.897588)
			(xy 284.590027 -125.920537) (xy 284.532102 -125.936058) (xy 284.472646 -125.943886) (xy 284.412678 -125.943886)
			(xy 284.353222 -125.936058) (xy 284.295297 -125.920537) (xy 284.239893 -125.897588) (xy 284.187959 -125.867604)
			(xy 284.140383 -125.831098) (xy 284.097978 -125.788693) (xy 284.061472 -125.741117) (xy 284.031488 -125.689183)
			(xy 284.008539 -125.633779) (xy 283.993018 -125.575854) (xy 283.98519 -125.516398) (xy 283.9847 -125.486414)
			(xy 270.425672 -125.486414) (xy 270.425672 -125.494542) (xy 270.425182 -125.524526) (xy 270.417354 -125.583982)
			(xy 270.401833 -125.641907) (xy 270.378884 -125.697311) (xy 270.3489 -125.749245) (xy 270.312394 -125.796821)
			(xy 270.269989 -125.839226) (xy 270.222413 -125.875732) (xy 270.170479 -125.905716) (xy 270.115075 -125.928665)
			(xy 270.05715 -125.944186) (xy 269.997694 -125.952014) (xy 269.937726 -125.952014) (xy 269.87827 -125.944186)
			(xy 269.820345 -125.928665) (xy 269.764941 -125.905716) (xy 269.713007 -125.875732) (xy 269.665431 -125.839226)
			(xy 269.623026 -125.796821) (xy 269.58652 -125.749245) (xy 269.556536 -125.697311) (xy 269.533587 -125.641907)
			(xy 269.518066 -125.583982) (xy 269.510238 -125.524526) (xy 269.509748 -125.494542) (xy 168.800647 -125.494542)
			(xy 168.80029 -125.516398) (xy 168.792462 -125.575854) (xy 168.776941 -125.633779) (xy 168.753992 -125.689183)
			(xy 168.724008 -125.741117) (xy 168.687502 -125.788693) (xy 168.645097 -125.831098) (xy 168.597521 -125.867604)
			(xy 168.545587 -125.897588) (xy 168.490183 -125.920537) (xy 168.432258 -125.936058) (xy 168.372802 -125.943886)
			(xy 168.312834 -125.943886) (xy 168.253378 -125.936058) (xy 168.195453 -125.920537) (xy 168.140049 -125.897588)
			(xy 168.088115 -125.867604) (xy 168.040539 -125.831098) (xy 167.998134 -125.788693) (xy 167.961628 -125.741117)
			(xy 167.931644 -125.689183) (xy 167.908695 -125.633779) (xy 167.893174 -125.575854) (xy 167.885346 -125.516398)
			(xy 167.884856 -125.486414) (xy 154.325828 -125.486414) (xy 154.325828 -125.494542) (xy 154.325338 -125.524526)
			(xy 154.31751 -125.583982) (xy 154.301989 -125.641907) (xy 154.27904 -125.697311) (xy 154.249056 -125.749245)
			(xy 154.21255 -125.796821) (xy 154.170145 -125.839226) (xy 154.122569 -125.875732) (xy 154.070635 -125.905716)
			(xy 154.015231 -125.928665) (xy 153.957306 -125.944186) (xy 153.89785 -125.952014) (xy 153.837882 -125.952014)
			(xy 153.778426 -125.944186) (xy 153.720501 -125.928665) (xy 153.665097 -125.905716) (xy 153.613163 -125.875732)
			(xy 153.565587 -125.839226) (xy 153.523182 -125.796821) (xy 153.486676 -125.749245) (xy 153.456692 -125.697311)
			(xy 153.433743 -125.641907) (xy 153.418222 -125.583982) (xy 153.410394 -125.524526) (xy 153.409904 -125.494542)
			(xy 52.700295 -125.494542) (xy 52.699938 -125.516382) (xy 52.692115 -125.575804) (xy 52.676602 -125.633697)
			(xy 52.653666 -125.68907) (xy 52.623699 -125.740976) (xy 52.587212 -125.788526) (xy 52.544832 -125.830906)
			(xy 52.497282 -125.867393) (xy 52.445376 -125.89736) (xy 52.390003 -125.920296) (xy 52.33211 -125.935809)
			(xy 52.272688 -125.943632) (xy 52.212752 -125.943632) (xy 52.15333 -125.935809) (xy 52.095437 -125.920296)
			(xy 52.040064 -125.89736) (xy 51.988158 -125.867393) (xy 51.940608 -125.830906) (xy 51.898228 -125.788526)
			(xy 51.861741 -125.740976) (xy 51.831774 -125.68907) (xy 51.808838 -125.633697) (xy 51.793325 -125.575804)
			(xy 51.785502 -125.516382) (xy 51.785012 -125.486414) (xy 38.225476 -125.486414) (xy 38.225476 -125.494542)
			(xy 38.224986 -125.52451) (xy 38.217163 -125.583932) (xy 38.20165 -125.641825) (xy 38.178714 -125.697198)
			(xy 38.148747 -125.749104) (xy 38.11226 -125.796654) (xy 38.06988 -125.839034) (xy 38.02233 -125.875521)
			(xy 37.970424 -125.905488) (xy 37.915051 -125.928424) (xy 37.857158 -125.943937) (xy 37.797736 -125.95176)
			(xy 37.7378 -125.95176) (xy 37.678378 -125.943937) (xy 37.620485 -125.928424) (xy 37.565112 -125.905488)
			(xy 37.513206 -125.875521) (xy 37.465656 -125.839034) (xy 37.423276 -125.796654) (xy 37.386789 -125.749104)
			(xy 37.356822 -125.697198) (xy 37.333886 -125.641825) (xy 37.318373 -125.583932) (xy 37.31055 -125.52451)
			(xy 37.31006 -125.494542) (xy 4.308094 -125.494542) (xy 4.308094 -131.297934) (xy 34.667952 -131.297934)
			(xy 34.667952 -130.434334) (xy 34.668442 -130.404366) (xy 34.676265 -130.344944) (xy 34.691778 -130.287051)
			(xy 34.714714 -130.231678) (xy 34.744681 -130.179772) (xy 34.781168 -130.132222) (xy 34.823548 -130.089842)
			(xy 34.871098 -130.053355) (xy 34.923004 -130.023388) (xy 34.978377 -130.000452) (xy 35.03627 -129.984939)
			(xy 35.095692 -129.977116) (xy 35.155628 -129.977116) (xy 35.21505 -129.984939) (xy 35.272943 -130.000452)
			(xy 35.328316 -130.023388) (xy 35.380222 -130.053355) (xy 35.427772 -130.089842) (xy 35.470152 -130.132222)
			(xy 35.506639 -130.179772) (xy 35.536606 -130.231678) (xy 35.559542 -130.287051) (xy 35.575055 -130.344944)
			(xy 35.582878 -130.404366) (xy 35.583368 -130.434334) (xy 35.583368 -131.29641) (xy 53.639212 -131.29641)
			(xy 53.639212 -130.43281) (xy 53.639702 -130.402842) (xy 53.647525 -130.34342) (xy 53.663038 -130.285527)
			(xy 53.685974 -130.230154) (xy 53.715941 -130.178248) (xy 53.752428 -130.130698) (xy 53.794808 -130.088318)
			(xy 53.842358 -130.051831) (xy 53.894264 -130.021864) (xy 53.949637 -129.998928) (xy 54.00753 -129.983415)
			(xy 54.066952 -129.975592) (xy 54.126888 -129.975592) (xy 54.18631 -129.983415) (xy 54.244203 -129.998928)
			(xy 54.299576 -130.021864) (xy 54.351482 -130.051831) (xy 54.399032 -130.088318) (xy 54.441412 -130.130698)
			(xy 54.477899 -130.178248) (xy 54.507866 -130.230154) (xy 54.530802 -130.285527) (xy 54.546315 -130.34342)
			(xy 54.554138 -130.402842) (xy 54.554628 -130.43281) (xy 54.554628 -130.777234) (xy 66.599308 -130.777234)
			(xy 66.599308 -129.913634) (xy 66.599798 -129.88365) (xy 66.607626 -129.824194) (xy 66.623147 -129.766269)
			(xy 66.646096 -129.710865) (xy 66.67608 -129.658931) (xy 66.712586 -129.611355) (xy 66.754991 -129.56895)
			(xy 66.802567 -129.532444) (xy 66.854501 -129.50246) (xy 66.909905 -129.479511) (xy 66.96783 -129.46399)
			(xy 67.027286 -129.456162) (xy 67.087254 -129.456162) (xy 67.14671 -129.46399) (xy 67.204635 -129.479511)
			(xy 67.260039 -129.50246) (xy 67.311973 -129.532444) (xy 67.359549 -129.56895) (xy 67.401954 -129.611355)
			(xy 67.43846 -129.658931) (xy 67.468444 -129.710865) (xy 67.491393 -129.766269) (xy 67.506914 -129.824194)
			(xy 67.514742 -129.88365) (xy 67.515232 -129.913634) (xy 67.515232 -130.769106) (xy 81.07426 -130.769106)
			(xy 81.07426 -129.905506) (xy 81.07475 -129.875522) (xy 81.082578 -129.816066) (xy 81.098099 -129.758141)
			(xy 81.121048 -129.702737) (xy 81.151032 -129.650803) (xy 81.187538 -129.603227) (xy 81.229943 -129.560822)
			(xy 81.277519 -129.524316) (xy 81.329453 -129.494332) (xy 81.384857 -129.471383) (xy 81.442782 -129.455862)
			(xy 81.502238 -129.448034) (xy 81.562206 -129.448034) (xy 81.621662 -129.455862) (xy 81.679587 -129.471383)
			(xy 81.734991 -129.494332) (xy 81.786925 -129.524316) (xy 81.834501 -129.560822) (xy 81.876906 -129.603227)
			(xy 81.913412 -129.650803) (xy 81.943396 -129.702737) (xy 81.966345 -129.758141) (xy 81.981866 -129.816066)
			(xy 81.989694 -129.875522) (xy 81.990184 -129.905506) (xy 81.990184 -130.769106) (xy 81.989694 -130.79909)
			(xy 81.981866 -130.858546) (xy 81.966345 -130.916471) (xy 81.943396 -130.971875) (xy 81.913412 -131.023809)
			(xy 81.876906 -131.071385) (xy 81.834501 -131.11379) (xy 81.786925 -131.150296) (xy 81.734991 -131.18028)
			(xy 81.679587 -131.203229) (xy 81.621662 -131.21875) (xy 81.562206 -131.226578) (xy 81.502238 -131.226578)
			(xy 81.442782 -131.21875) (xy 81.384857 -131.203229) (xy 81.329453 -131.18028) (xy 81.277519 -131.150296)
			(xy 81.229943 -131.11379) (xy 81.187538 -131.071385) (xy 81.151032 -131.023809) (xy 81.121048 -130.971875)
			(xy 81.098099 -130.916471) (xy 81.082578 -130.858546) (xy 81.07475 -130.79909) (xy 81.07426 -130.769106)
			(xy 67.515232 -130.769106) (xy 67.515232 -130.777234) (xy 67.514742 -130.807218) (xy 67.506914 -130.866674)
			(xy 67.491393 -130.924599) (xy 67.468444 -130.980003) (xy 67.43846 -131.031937) (xy 67.401954 -131.079513)
			(xy 67.359549 -131.121918) (xy 67.311973 -131.158424) (xy 67.260039 -131.188408) (xy 67.204635 -131.211357)
			(xy 67.14671 -131.226878) (xy 67.087254 -131.234706) (xy 67.027286 -131.234706) (xy 66.96783 -131.226878)
			(xy 66.909905 -131.211357) (xy 66.854501 -131.188408) (xy 66.802567 -131.158424) (xy 66.754991 -131.121918)
			(xy 66.712586 -131.079513) (xy 66.67608 -131.031937) (xy 66.646096 -130.980003) (xy 66.623147 -130.924599)
			(xy 66.607626 -130.866674) (xy 66.599798 -130.807218) (xy 66.599308 -130.777234) (xy 54.554628 -130.777234)
			(xy 54.554628 -131.29641) (xy 54.554138 -131.326378) (xy 54.546315 -131.3858) (xy 54.530802 -131.443693)
			(xy 54.507866 -131.499066) (xy 54.477899 -131.550972) (xy 54.441412 -131.598522) (xy 54.399032 -131.640902)
			(xy 54.351482 -131.677389) (xy 54.299576 -131.707356) (xy 54.244203 -131.730292) (xy 54.18631 -131.745805)
			(xy 54.126888 -131.753628) (xy 54.066952 -131.753628) (xy 54.00753 -131.745805) (xy 53.949637 -131.730292)
			(xy 53.894264 -131.707356) (xy 53.842358 -131.677389) (xy 53.794808 -131.640902) (xy 53.752428 -131.598522)
			(xy 53.715941 -131.550972) (xy 53.685974 -131.499066) (xy 53.663038 -131.443693) (xy 53.647525 -131.3858)
			(xy 53.639702 -131.326378) (xy 53.639212 -131.29641) (xy 35.583368 -131.29641) (xy 35.583368 -131.297934)
			(xy 35.582878 -131.327902) (xy 35.575055 -131.387324) (xy 35.559542 -131.445217) (xy 35.536606 -131.50059)
			(xy 35.506639 -131.552496) (xy 35.470152 -131.600046) (xy 35.427772 -131.642426) (xy 35.380222 -131.678913)
			(xy 35.328316 -131.70888) (xy 35.272943 -131.731816) (xy 35.21505 -131.747329) (xy 35.155628 -131.755152)
			(xy 35.095692 -131.755152) (xy 35.03627 -131.747329) (xy 34.978377 -131.731816) (xy 34.923004 -131.70888)
			(xy 34.871098 -131.678913) (xy 34.823548 -131.642426) (xy 34.781168 -131.600046) (xy 34.744681 -131.552496)
			(xy 34.714714 -131.50059) (xy 34.691778 -131.445217) (xy 34.676265 -131.387324) (xy 34.668442 -131.327902)
			(xy 34.667952 -131.297934) (xy 4.308094 -131.297934) (xy 4.308094 -133.104382) (xy 37.31006 -133.104382)
			(xy 37.31006 -132.240782) (xy 37.31055 -132.210814) (xy 37.318373 -132.151392) (xy 37.333886 -132.093499)
			(xy 37.356822 -132.038126) (xy 37.386789 -131.98622) (xy 37.423276 -131.93867) (xy 37.465656 -131.89629)
			(xy 37.513206 -131.859803) (xy 37.565112 -131.829836) (xy 37.620485 -131.8069) (xy 37.678378 -131.791387)
			(xy 37.7378 -131.783564) (xy 37.797736 -131.783564) (xy 37.857158 -131.791387) (xy 37.915051 -131.8069)
			(xy 37.970424 -131.829836) (xy 38.02233 -131.859803) (xy 38.06988 -131.89629) (xy 38.11226 -131.93867)
			(xy 38.148747 -131.98622) (xy 38.178714 -132.038126) (xy 38.20165 -132.093499) (xy 38.217163 -132.151392)
			(xy 38.224986 -132.210814) (xy 38.225476 -132.240782) (xy 38.225476 -133.096508) (xy 51.785012 -133.096508)
			(xy 51.785012 -132.232908) (xy 51.785502 -132.20294) (xy 51.793325 -132.143518) (xy 51.808838 -132.085625)
			(xy 51.831774 -132.030252) (xy 51.861741 -131.978346) (xy 51.898228 -131.930796) (xy 51.940608 -131.888416)
			(xy 51.988158 -131.851929) (xy 52.040064 -131.821962) (xy 52.095437 -131.799026) (xy 52.15333 -131.783513)
			(xy 52.212752 -131.77569) (xy 52.272688 -131.77569) (xy 52.33211 -131.783513) (xy 52.390003 -131.799026)
			(xy 52.445376 -131.821962) (xy 52.497282 -131.851929) (xy 52.544832 -131.888416) (xy 52.587212 -131.930796)
			(xy 52.623699 -131.978346) (xy 52.653666 -132.030252) (xy 52.676602 -132.085625) (xy 52.692115 -132.143518)
			(xy 52.699938 -132.20294) (xy 52.700428 -132.232908) (xy 52.700428 -132.577332) (xy 64.745108 -132.577332)
			(xy 64.745108 -131.713732) (xy 64.745598 -131.683748) (xy 64.753426 -131.624292) (xy 64.768947 -131.566367)
			(xy 64.791896 -131.510963) (xy 64.82188 -131.459029) (xy 64.858386 -131.411453) (xy 64.900791 -131.369048)
			(xy 64.948367 -131.332542) (xy 65.000301 -131.302558) (xy 65.055705 -131.279609) (xy 65.11363 -131.264088)
			(xy 65.173086 -131.25626) (xy 65.233054 -131.25626) (xy 65.29251 -131.264088) (xy 65.350435 -131.279609)
			(xy 65.405839 -131.302558) (xy 65.457773 -131.332542) (xy 65.505349 -131.369048) (xy 65.547754 -131.411453)
			(xy 65.58426 -131.459029) (xy 65.614244 -131.510963) (xy 65.637193 -131.566367) (xy 65.652714 -131.624292)
			(xy 65.660542 -131.683748) (xy 65.661032 -131.713732) (xy 65.661032 -132.575808) (xy 83.716368 -132.575808)
			(xy 83.716368 -131.712208) (xy 83.716858 -131.682224) (xy 83.724686 -131.622768) (xy 83.740207 -131.564843)
			(xy 83.763156 -131.509439) (xy 83.79314 -131.457505) (xy 83.829646 -131.409929) (xy 83.872051 -131.367524)
			(xy 83.919627 -131.331018) (xy 83.971561 -131.301034) (xy 84.026965 -131.278085) (xy 84.08489 -131.262564)
			(xy 84.144346 -131.254736) (xy 84.204314 -131.254736) (xy 84.26377 -131.262564) (xy 84.321695 -131.278085)
			(xy 84.369615 -131.297934) (xy 150.767796 -131.297934) (xy 150.767796 -130.434334) (xy 150.768286 -130.40435)
			(xy 150.776114 -130.344894) (xy 150.791635 -130.286969) (xy 150.814584 -130.231565) (xy 150.844568 -130.179631)
			(xy 150.881074 -130.132055) (xy 150.923479 -130.08965) (xy 150.971055 -130.053144) (xy 151.022989 -130.02316)
			(xy 151.078393 -130.000211) (xy 151.136318 -129.98469) (xy 151.195774 -129.976862) (xy 151.255742 -129.976862)
			(xy 151.315198 -129.98469) (xy 151.373123 -130.000211) (xy 151.428527 -130.02316) (xy 151.480461 -130.053144)
			(xy 151.528037 -130.08965) (xy 151.570442 -130.132055) (xy 151.606948 -130.179631) (xy 151.636932 -130.231565)
			(xy 151.659881 -130.286969) (xy 151.675402 -130.344894) (xy 151.68323 -130.40435) (xy 151.68372 -130.434334)
			(xy 151.68372 -131.29641) (xy 169.739056 -131.29641) (xy 169.739056 -130.43281) (xy 169.739546 -130.402826)
			(xy 169.747374 -130.34337) (xy 169.762895 -130.285445) (xy 169.785844 -130.230041) (xy 169.815828 -130.178107)
			(xy 169.852334 -130.130531) (xy 169.894739 -130.088126) (xy 169.942315 -130.05162) (xy 169.994249 -130.021636)
			(xy 170.049653 -129.998687) (xy 170.107578 -129.983166) (xy 170.167034 -129.975338) (xy 170.227002 -129.975338)
			(xy 170.286458 -129.983166) (xy 170.344383 -129.998687) (xy 170.399787 -130.021636) (xy 170.451721 -130.05162)
			(xy 170.499297 -130.088126) (xy 170.541702 -130.130531) (xy 170.578208 -130.178107) (xy 170.608192 -130.230041)
			(xy 170.631141 -130.285445) (xy 170.646662 -130.34337) (xy 170.65449 -130.402826) (xy 170.65498 -130.43281)
			(xy 170.65498 -130.777234) (xy 182.69966 -130.777234) (xy 182.69966 -129.913634) (xy 182.70015 -129.883666)
			(xy 182.707973 -129.824244) (xy 182.723486 -129.766351) (xy 182.746422 -129.710978) (xy 182.776389 -129.659072)
			(xy 182.812876 -129.611522) (xy 182.855256 -129.569142) (xy 182.902806 -129.532655) (xy 182.954712 -129.502688)
			(xy 183.010085 -129.479752) (xy 183.067978 -129.464239) (xy 183.1274 -129.456416) (xy 183.187336 -129.456416)
			(xy 183.246758 -129.464239) (xy 183.304651 -129.479752) (xy 183.360024 -129.502688) (xy 183.41193 -129.532655)
			(xy 183.45948 -129.569142) (xy 183.50186 -129.611522) (xy 183.538347 -129.659072) (xy 183.568314 -129.710978)
			(xy 183.59125 -129.766351) (xy 183.606763 -129.824244) (xy 183.614586 -129.883666) (xy 183.615076 -129.913634)
			(xy 183.615076 -130.769106) (xy 197.174612 -130.769106) (xy 197.174612 -129.905506) (xy 197.175102 -129.875538)
			(xy 197.182925 -129.816116) (xy 197.198438 -129.758223) (xy 197.221374 -129.70285) (xy 197.251341 -129.650944)
			(xy 197.287828 -129.603394) (xy 197.330208 -129.561014) (xy 197.377758 -129.524527) (xy 197.429664 -129.49456)
			(xy 197.485037 -129.471624) (xy 197.54293 -129.456111) (xy 197.602352 -129.448288) (xy 197.662288 -129.448288)
			(xy 197.72171 -129.456111) (xy 197.779603 -129.471624) (xy 197.834976 -129.49456) (xy 197.886882 -129.524527)
			(xy 197.934432 -129.561014) (xy 197.976812 -129.603394) (xy 198.013299 -129.650944) (xy 198.043266 -129.70285)
			(xy 198.066202 -129.758223) (xy 198.081715 -129.816116) (xy 198.089538 -129.875538) (xy 198.090028 -129.905506)
			(xy 198.090028 -130.769106) (xy 198.089538 -130.799074) (xy 198.081715 -130.858496) (xy 198.066202 -130.916389)
			(xy 198.043266 -130.971762) (xy 198.013299 -131.023668) (xy 197.976812 -131.071218) (xy 197.934432 -131.113598)
			(xy 197.886882 -131.150085) (xy 197.834976 -131.180052) (xy 197.779603 -131.202988) (xy 197.72171 -131.218501)
			(xy 197.662288 -131.226324) (xy 197.602352 -131.226324) (xy 197.54293 -131.218501) (xy 197.485037 -131.202988)
			(xy 197.429664 -131.180052) (xy 197.377758 -131.150085) (xy 197.330208 -131.113598) (xy 197.287828 -131.071218)
			(xy 197.251341 -131.023668) (xy 197.221374 -130.971762) (xy 197.198438 -130.916389) (xy 197.182925 -130.858496)
			(xy 197.175102 -130.799074) (xy 197.174612 -130.769106) (xy 183.615076 -130.769106) (xy 183.615076 -130.777234)
			(xy 183.614586 -130.807202) (xy 183.606763 -130.866624) (xy 183.59125 -130.924517) (xy 183.568314 -130.97989)
			(xy 183.538347 -131.031796) (xy 183.50186 -131.079346) (xy 183.45948 -131.121726) (xy 183.41193 -131.158213)
			(xy 183.360024 -131.18818) (xy 183.304651 -131.211116) (xy 183.246758 -131.226629) (xy 183.187336 -131.234452)
			(xy 183.1274 -131.234452) (xy 183.067978 -131.226629) (xy 183.010085 -131.211116) (xy 182.954712 -131.18818)
			(xy 182.902806 -131.158213) (xy 182.855256 -131.121726) (xy 182.812876 -131.079346) (xy 182.776389 -131.031796)
			(xy 182.746422 -130.97989) (xy 182.723486 -130.924517) (xy 182.707973 -130.866624) (xy 182.70015 -130.807202)
			(xy 182.69966 -130.777234) (xy 170.65498 -130.777234) (xy 170.65498 -131.29641) (xy 170.65449 -131.326394)
			(xy 170.646662 -131.38585) (xy 170.631141 -131.443775) (xy 170.608192 -131.499179) (xy 170.578208 -131.551113)
			(xy 170.541702 -131.598689) (xy 170.499297 -131.641094) (xy 170.451721 -131.6776) (xy 170.399787 -131.707584)
			(xy 170.344383 -131.730533) (xy 170.286458 -131.746054) (xy 170.227002 -131.753882) (xy 170.167034 -131.753882)
			(xy 170.107578 -131.746054) (xy 170.049653 -131.730533) (xy 169.994249 -131.707584) (xy 169.942315 -131.6776)
			(xy 169.894739 -131.641094) (xy 169.852334 -131.598689) (xy 169.815828 -131.551113) (xy 169.785844 -131.499179)
			(xy 169.762895 -131.443775) (xy 169.747374 -131.38585) (xy 169.739546 -131.326394) (xy 169.739056 -131.29641)
			(xy 151.68372 -131.29641) (xy 151.68372 -131.297934) (xy 151.68323 -131.327918) (xy 151.675402 -131.387374)
			(xy 151.659881 -131.445299) (xy 151.636932 -131.500703) (xy 151.606948 -131.552637) (xy 151.570442 -131.600213)
			(xy 151.528037 -131.642618) (xy 151.480461 -131.679124) (xy 151.428527 -131.709108) (xy 151.373123 -131.732057)
			(xy 151.315198 -131.747578) (xy 151.255742 -131.755406) (xy 151.195774 -131.755406) (xy 151.136318 -131.747578)
			(xy 151.078393 -131.732057) (xy 151.022989 -131.709108) (xy 150.971055 -131.679124) (xy 150.923479 -131.642618)
			(xy 150.881074 -131.600213) (xy 150.844568 -131.552637) (xy 150.814584 -131.500703) (xy 150.791635 -131.445299)
			(xy 150.776114 -131.387374) (xy 150.768286 -131.327918) (xy 150.767796 -131.297934) (xy 84.369615 -131.297934)
			(xy 84.377099 -131.301034) (xy 84.429033 -131.331018) (xy 84.476609 -131.367524) (xy 84.519014 -131.409929)
			(xy 84.55552 -131.457505) (xy 84.585504 -131.509439) (xy 84.608453 -131.564843) (xy 84.623974 -131.622768)
			(xy 84.631802 -131.682224) (xy 84.632292 -131.712208) (xy 84.632292 -132.575808) (xy 84.631802 -132.605792)
			(xy 84.623974 -132.665248) (xy 84.608453 -132.723173) (xy 84.585504 -132.778577) (xy 84.55552 -132.830511)
			(xy 84.519014 -132.878087) (xy 84.476609 -132.920492) (xy 84.429033 -132.956998) (xy 84.377099 -132.986982)
			(xy 84.321695 -133.009931) (xy 84.26377 -133.025452) (xy 84.204314 -133.03328) (xy 84.144346 -133.03328)
			(xy 84.08489 -133.025452) (xy 84.026965 -133.009931) (xy 83.971561 -132.986982) (xy 83.919627 -132.956998)
			(xy 83.872051 -132.920492) (xy 83.829646 -132.878087) (xy 83.79314 -132.830511) (xy 83.763156 -132.778577)
			(xy 83.740207 -132.723173) (xy 83.724686 -132.665248) (xy 83.716858 -132.605792) (xy 83.716368 -132.575808)
			(xy 65.661032 -132.575808) (xy 65.661032 -132.577332) (xy 65.660542 -132.607316) (xy 65.652714 -132.666772)
			(xy 65.637193 -132.724697) (xy 65.614244 -132.780101) (xy 65.58426 -132.832035) (xy 65.547754 -132.879611)
			(xy 65.505349 -132.922016) (xy 65.457773 -132.958522) (xy 65.405839 -132.988506) (xy 65.350435 -133.011455)
			(xy 65.29251 -133.026976) (xy 65.233054 -133.034804) (xy 65.173086 -133.034804) (xy 65.11363 -133.026976)
			(xy 65.055705 -133.011455) (xy 65.000301 -132.988506) (xy 64.948367 -132.958522) (xy 64.900791 -132.922016)
			(xy 64.858386 -132.879611) (xy 64.82188 -132.832035) (xy 64.791896 -132.780101) (xy 64.768947 -132.724697)
			(xy 64.753426 -132.666772) (xy 64.745598 -132.607316) (xy 64.745108 -132.577332) (xy 52.700428 -132.577332)
			(xy 52.700428 -133.096508) (xy 52.699938 -133.126476) (xy 52.692115 -133.185898) (xy 52.676602 -133.243791)
			(xy 52.653666 -133.299164) (xy 52.623699 -133.35107) (xy 52.587212 -133.39862) (xy 52.544832 -133.441)
			(xy 52.497282 -133.477487) (xy 52.445376 -133.507454) (xy 52.390003 -133.53039) (xy 52.33211 -133.545903)
			(xy 52.272688 -133.553726) (xy 52.212752 -133.553726) (xy 52.15333 -133.545903) (xy 52.095437 -133.53039)
			(xy 52.040064 -133.507454) (xy 51.988158 -133.477487) (xy 51.940608 -133.441) (xy 51.898228 -133.39862)
			(xy 51.861741 -133.35107) (xy 51.831774 -133.299164) (xy 51.808838 -133.243791) (xy 51.793325 -133.185898)
			(xy 51.785502 -133.126476) (xy 51.785012 -133.096508) (xy 38.225476 -133.096508) (xy 38.225476 -133.104382)
			(xy 38.224986 -133.13435) (xy 38.217163 -133.193772) (xy 38.20165 -133.251665) (xy 38.178714 -133.307038)
			(xy 38.148747 -133.358944) (xy 38.11226 -133.406494) (xy 38.06988 -133.448874) (xy 38.02233 -133.485361)
			(xy 37.970424 -133.515328) (xy 37.915051 -133.538264) (xy 37.857158 -133.553777) (xy 37.797736 -133.5616)
			(xy 37.7378 -133.5616) (xy 37.678378 -133.553777) (xy 37.620485 -133.538264) (xy 37.565112 -133.515328)
			(xy 37.513206 -133.485361) (xy 37.465656 -133.448874) (xy 37.423276 -133.406494) (xy 37.386789 -133.358944)
			(xy 37.356822 -133.307038) (xy 37.333886 -133.251665) (xy 37.318373 -133.193772) (xy 37.31055 -133.13435)
			(xy 37.31006 -133.104382) (xy 4.308094 -133.104382) (xy 4.308094 -134.897876) (xy 34.667952 -134.897876)
			(xy 34.667952 -134.034276) (xy 34.668442 -134.004308) (xy 34.676265 -133.944886) (xy 34.691778 -133.886993)
			(xy 34.714714 -133.83162) (xy 34.744681 -133.779714) (xy 34.781168 -133.732164) (xy 34.823548 -133.689784)
			(xy 34.871098 -133.653297) (xy 34.923004 -133.62333) (xy 34.978377 -133.600394) (xy 35.03627 -133.584881)
			(xy 35.095692 -133.577058) (xy 35.155628 -133.577058) (xy 35.21505 -133.584881) (xy 35.272943 -133.600394)
			(xy 35.328316 -133.62333) (xy 35.380222 -133.653297) (xy 35.427772 -133.689784) (xy 35.470152 -133.732164)
			(xy 35.506639 -133.779714) (xy 35.536606 -133.83162) (xy 35.559542 -133.886993) (xy 35.575055 -133.944886)
			(xy 35.582878 -134.004308) (xy 35.583368 -134.034276) (xy 35.583368 -134.896352) (xy 53.639212 -134.896352)
			(xy 53.639212 -134.032752) (xy 53.639702 -134.002784) (xy 53.647525 -133.943362) (xy 53.663038 -133.885469)
			(xy 53.685974 -133.830096) (xy 53.715941 -133.77819) (xy 53.752428 -133.73064) (xy 53.794808 -133.68826)
			(xy 53.842358 -133.651773) (xy 53.894264 -133.621806) (xy 53.949637 -133.59887) (xy 54.00753 -133.583357)
			(xy 54.066952 -133.575534) (xy 54.126888 -133.575534) (xy 54.18631 -133.583357) (xy 54.244203 -133.59887)
			(xy 54.299576 -133.621806) (xy 54.351482 -133.651773) (xy 54.399032 -133.68826) (xy 54.441412 -133.73064)
			(xy 54.477899 -133.77819) (xy 54.507866 -133.830096) (xy 54.530802 -133.885469) (xy 54.546315 -133.943362)
			(xy 54.554138 -134.002784) (xy 54.554628 -134.032752) (xy 54.554628 -134.377176) (xy 66.599308 -134.377176)
			(xy 66.599308 -133.513576) (xy 66.599798 -133.483592) (xy 66.607626 -133.424136) (xy 66.623147 -133.366211)
			(xy 66.646096 -133.310807) (xy 66.67608 -133.258873) (xy 66.712586 -133.211297) (xy 66.754991 -133.168892)
			(xy 66.802567 -133.132386) (xy 66.854501 -133.102402) (xy 66.909905 -133.079453) (xy 66.96783 -133.063932)
			(xy 67.027286 -133.056104) (xy 67.087254 -133.056104) (xy 67.14671 -133.063932) (xy 67.204635 -133.079453)
			(xy 67.260039 -133.102402) (xy 67.311973 -133.132386) (xy 67.359549 -133.168892) (xy 67.401954 -133.211297)
			(xy 67.43846 -133.258873) (xy 67.468444 -133.310807) (xy 67.491393 -133.366211) (xy 67.506914 -133.424136)
			(xy 67.514742 -133.483592) (xy 67.515232 -133.513576) (xy 67.515232 -134.369302) (xy 81.07426 -134.369302)
			(xy 81.07426 -133.505702) (xy 81.07475 -133.475718) (xy 81.082578 -133.416262) (xy 81.098099 -133.358337)
			(xy 81.121048 -133.302933) (xy 81.151032 -133.250999) (xy 81.187538 -133.203423) (xy 81.229943 -133.161018)
			(xy 81.277519 -133.124512) (xy 81.329453 -133.094528) (xy 81.384857 -133.071579) (xy 81.442782 -133.056058)
			(xy 81.502238 -133.04823) (xy 81.562206 -133.04823) (xy 81.621662 -133.056058) (xy 81.679587 -133.071579)
			(xy 81.734991 -133.094528) (xy 81.752059 -133.104382) (xy 153.409904 -133.104382) (xy 153.409904 -132.240782)
			(xy 153.410394 -132.210798) (xy 153.418222 -132.151342) (xy 153.433743 -132.093417) (xy 153.456692 -132.038013)
			(xy 153.486676 -131.986079) (xy 153.523182 -131.938503) (xy 153.565587 -131.896098) (xy 153.613163 -131.859592)
			(xy 153.665097 -131.829608) (xy 153.720501 -131.806659) (xy 153.778426 -131.791138) (xy 153.837882 -131.78331)
			(xy 153.89785 -131.78331) (xy 153.957306 -131.791138) (xy 154.015231 -131.806659) (xy 154.070635 -131.829608)
			(xy 154.122569 -131.859592) (xy 154.170145 -131.896098) (xy 154.21255 -131.938503) (xy 154.249056 -131.986079)
			(xy 154.27904 -132.038013) (xy 154.301989 -132.093417) (xy 154.31751 -132.151342) (xy 154.325338 -132.210798)
			(xy 154.325828 -132.240782) (xy 154.325828 -133.096508) (xy 167.884856 -133.096508) (xy 167.884856 -132.232908)
			(xy 167.885346 -132.202924) (xy 167.893174 -132.143468) (xy 167.908695 -132.085543) (xy 167.931644 -132.030139)
			(xy 167.961628 -131.978205) (xy 167.998134 -131.930629) (xy 168.040539 -131.888224) (xy 168.088115 -131.851718)
			(xy 168.140049 -131.821734) (xy 168.195453 -131.798785) (xy 168.253378 -131.783264) (xy 168.312834 -131.775436)
			(xy 168.372802 -131.775436) (xy 168.432258 -131.783264) (xy 168.490183 -131.798785) (xy 168.545587 -131.821734)
			(xy 168.597521 -131.851718) (xy 168.645097 -131.888224) (xy 168.687502 -131.930629) (xy 168.724008 -131.978205)
			(xy 168.753992 -132.030139) (xy 168.776941 -132.085543) (xy 168.792462 -132.143468) (xy 168.80029 -132.202924)
			(xy 168.80078 -132.232908) (xy 168.80078 -132.577332) (xy 180.84546 -132.577332) (xy 180.84546 -131.713732)
			(xy 180.84595 -131.683764) (xy 180.853773 -131.624342) (xy 180.869286 -131.566449) (xy 180.892222 -131.511076)
			(xy 180.922189 -131.45917) (xy 180.958676 -131.41162) (xy 181.001056 -131.36924) (xy 181.048606 -131.332753)
			(xy 181.100512 -131.302786) (xy 181.155885 -131.27985) (xy 181.213778 -131.264337) (xy 181.2732 -131.256514)
			(xy 181.333136 -131.256514) (xy 181.392558 -131.264337) (xy 181.450451 -131.27985) (xy 181.505824 -131.302786)
			(xy 181.55773 -131.332753) (xy 181.60528 -131.36924) (xy 181.64766 -131.41162) (xy 181.684147 -131.45917)
			(xy 181.714114 -131.511076) (xy 181.73705 -131.566449) (xy 181.752563 -131.624342) (xy 181.760386 -131.683764)
			(xy 181.760876 -131.713732) (xy 181.760876 -132.575808) (xy 199.81672 -132.575808) (xy 199.81672 -131.712208)
			(xy 199.81721 -131.68224) (xy 199.825033 -131.622818) (xy 199.840546 -131.564925) (xy 199.863482 -131.509552)
			(xy 199.893449 -131.457646) (xy 199.929936 -131.410096) (xy 199.972316 -131.367716) (xy 200.019866 -131.331229)
			(xy 200.071772 -131.301262) (xy 200.127145 -131.278326) (xy 200.185038 -131.262813) (xy 200.24446 -131.25499)
			(xy 200.304396 -131.25499) (xy 200.363818 -131.262813) (xy 200.421711 -131.278326) (xy 200.469049 -131.297934)
			(xy 266.86764 -131.297934) (xy 266.86764 -130.434334) (xy 266.86813 -130.40435) (xy 266.875958 -130.344894)
			(xy 266.891479 -130.286969) (xy 266.914428 -130.231565) (xy 266.944412 -130.179631) (xy 266.980918 -130.132055)
			(xy 267.023323 -130.08965) (xy 267.070899 -130.053144) (xy 267.122833 -130.02316) (xy 267.178237 -130.000211)
			(xy 267.236162 -129.98469) (xy 267.295618 -129.976862) (xy 267.355586 -129.976862) (xy 267.415042 -129.98469)
			(xy 267.472967 -130.000211) (xy 267.528371 -130.02316) (xy 267.580305 -130.053144) (xy 267.627881 -130.08965)
			(xy 267.670286 -130.132055) (xy 267.706792 -130.179631) (xy 267.736776 -130.231565) (xy 267.759725 -130.286969)
			(xy 267.775246 -130.344894) (xy 267.783074 -130.40435) (xy 267.783564 -130.434334) (xy 267.783564 -131.29641)
			(xy 285.8389 -131.29641) (xy 285.8389 -130.43281) (xy 285.83939 -130.402826) (xy 285.847218 -130.34337)
			(xy 285.862739 -130.285445) (xy 285.885688 -130.230041) (xy 285.915672 -130.178107) (xy 285.952178 -130.130531)
			(xy 285.994583 -130.088126) (xy 286.042159 -130.05162) (xy 286.094093 -130.021636) (xy 286.149497 -129.998687)
			(xy 286.207422 -129.983166) (xy 286.266878 -129.975338) (xy 286.326846 -129.975338) (xy 286.386302 -129.983166)
			(xy 286.444227 -129.998687) (xy 286.499631 -130.021636) (xy 286.551565 -130.05162) (xy 286.599141 -130.088126)
			(xy 286.641546 -130.130531) (xy 286.678052 -130.178107) (xy 286.708036 -130.230041) (xy 286.730985 -130.285445)
			(xy 286.746506 -130.34337) (xy 286.754334 -130.402826) (xy 286.754824 -130.43281) (xy 286.754824 -130.777234)
			(xy 298.799504 -130.777234) (xy 298.799504 -129.913634) (xy 298.799994 -129.883666) (xy 298.807817 -129.824244)
			(xy 298.82333 -129.766351) (xy 298.846266 -129.710978) (xy 298.876233 -129.659072) (xy 298.91272 -129.611522)
			(xy 298.9551 -129.569142) (xy 299.00265 -129.532655) (xy 299.054556 -129.502688) (xy 299.109929 -129.479752)
			(xy 299.167822 -129.464239) (xy 299.227244 -129.456416) (xy 299.28718 -129.456416) (xy 299.346602 -129.464239)
			(xy 299.404495 -129.479752) (xy 299.459868 -129.502688) (xy 299.511774 -129.532655) (xy 299.559324 -129.569142)
			(xy 299.601704 -129.611522) (xy 299.638191 -129.659072) (xy 299.668158 -129.710978) (xy 299.691094 -129.766351)
			(xy 299.706607 -129.824244) (xy 299.71443 -129.883666) (xy 299.71492 -129.913634) (xy 299.71492 -130.769106)
			(xy 313.274456 -130.769106) (xy 313.274456 -129.905506) (xy 313.274946 -129.875538) (xy 313.282769 -129.816116)
			(xy 313.298282 -129.758223) (xy 313.321218 -129.70285) (xy 313.351185 -129.650944) (xy 313.387672 -129.603394)
			(xy 313.430052 -129.561014) (xy 313.477602 -129.524527) (xy 313.529508 -129.49456) (xy 313.584881 -129.471624)
			(xy 313.642774 -129.456111) (xy 313.702196 -129.448288) (xy 313.762132 -129.448288) (xy 313.821554 -129.456111)
			(xy 313.879447 -129.471624) (xy 313.93482 -129.49456) (xy 313.986726 -129.524527) (xy 314.034276 -129.561014)
			(xy 314.076656 -129.603394) (xy 314.113143 -129.650944) (xy 314.14311 -129.70285) (xy 314.166046 -129.758223)
			(xy 314.181559 -129.816116) (xy 314.189382 -129.875538) (xy 314.189872 -129.905506) (xy 314.189872 -130.769106)
			(xy 314.189382 -130.799074) (xy 314.181559 -130.858496) (xy 314.166046 -130.916389) (xy 314.14311 -130.971762)
			(xy 314.113143 -131.023668) (xy 314.076656 -131.071218) (xy 314.034276 -131.113598) (xy 313.986726 -131.150085)
			(xy 313.93482 -131.180052) (xy 313.879447 -131.202988) (xy 313.821554 -131.218501) (xy 313.762132 -131.226324)
			(xy 313.702196 -131.226324) (xy 313.642774 -131.218501) (xy 313.584881 -131.202988) (xy 313.529508 -131.180052)
			(xy 313.477602 -131.150085) (xy 313.430052 -131.113598) (xy 313.387672 -131.071218) (xy 313.351185 -131.023668)
			(xy 313.321218 -130.971762) (xy 313.298282 -130.916389) (xy 313.282769 -130.858496) (xy 313.274946 -130.799074)
			(xy 313.274456 -130.769106) (xy 299.71492 -130.769106) (xy 299.71492 -130.777234) (xy 299.71443 -130.807202)
			(xy 299.706607 -130.866624) (xy 299.691094 -130.924517) (xy 299.668158 -130.97989) (xy 299.638191 -131.031796)
			(xy 299.601704 -131.079346) (xy 299.559324 -131.121726) (xy 299.511774 -131.158213) (xy 299.459868 -131.18818)
			(xy 299.404495 -131.211116) (xy 299.346602 -131.226629) (xy 299.28718 -131.234452) (xy 299.227244 -131.234452)
			(xy 299.167822 -131.226629) (xy 299.109929 -131.211116) (xy 299.054556 -131.18818) (xy 299.00265 -131.158213)
			(xy 298.9551 -131.121726) (xy 298.91272 -131.079346) (xy 298.876233 -131.031796) (xy 298.846266 -130.97989)
			(xy 298.82333 -130.924517) (xy 298.807817 -130.866624) (xy 298.799994 -130.807202) (xy 298.799504 -130.777234)
			(xy 286.754824 -130.777234) (xy 286.754824 -131.29641) (xy 286.754334 -131.326394) (xy 286.746506 -131.38585)
			(xy 286.730985 -131.443775) (xy 286.708036 -131.499179) (xy 286.678052 -131.551113) (xy 286.641546 -131.598689)
			(xy 286.599141 -131.641094) (xy 286.551565 -131.6776) (xy 286.499631 -131.707584) (xy 286.444227 -131.730533)
			(xy 286.386302 -131.746054) (xy 286.326846 -131.753882) (xy 286.266878 -131.753882) (xy 286.207422 -131.746054)
			(xy 286.149497 -131.730533) (xy 286.094093 -131.707584) (xy 286.042159 -131.6776) (xy 285.994583 -131.641094)
			(xy 285.952178 -131.598689) (xy 285.915672 -131.551113) (xy 285.885688 -131.499179) (xy 285.862739 -131.443775)
			(xy 285.847218 -131.38585) (xy 285.83939 -131.326394) (xy 285.8389 -131.29641) (xy 267.783564 -131.29641)
			(xy 267.783564 -131.297934) (xy 267.783074 -131.327918) (xy 267.775246 -131.387374) (xy 267.759725 -131.445299)
			(xy 267.736776 -131.500703) (xy 267.706792 -131.552637) (xy 267.670286 -131.600213) (xy 267.627881 -131.642618)
			(xy 267.580305 -131.679124) (xy 267.528371 -131.709108) (xy 267.472967 -131.732057) (xy 267.415042 -131.747578)
			(xy 267.355586 -131.755406) (xy 267.295618 -131.755406) (xy 267.236162 -131.747578) (xy 267.178237 -131.732057)
			(xy 267.122833 -131.709108) (xy 267.070899 -131.679124) (xy 267.023323 -131.642618) (xy 266.980918 -131.600213)
			(xy 266.944412 -131.552637) (xy 266.914428 -131.500703) (xy 266.891479 -131.445299) (xy 266.875958 -131.387374)
			(xy 266.86813 -131.327918) (xy 266.86764 -131.297934) (xy 200.469049 -131.297934) (xy 200.477084 -131.301262)
			(xy 200.52899 -131.331229) (xy 200.57654 -131.367716) (xy 200.61892 -131.410096) (xy 200.655407 -131.457646)
			(xy 200.685374 -131.509552) (xy 200.70831 -131.564925) (xy 200.723823 -131.622818) (xy 200.731646 -131.68224)
			(xy 200.732136 -131.712208) (xy 200.732136 -132.575808) (xy 200.731646 -132.605776) (xy 200.723823 -132.665198)
			(xy 200.70831 -132.723091) (xy 200.685374 -132.778464) (xy 200.655407 -132.83037) (xy 200.61892 -132.87792)
			(xy 200.57654 -132.9203) (xy 200.52899 -132.956787) (xy 200.477084 -132.986754) (xy 200.421711 -133.00969)
			(xy 200.363818 -133.025203) (xy 200.304396 -133.033026) (xy 200.24446 -133.033026) (xy 200.185038 -133.025203)
			(xy 200.127145 -133.00969) (xy 200.071772 -132.986754) (xy 200.019866 -132.956787) (xy 199.972316 -132.9203)
			(xy 199.929936 -132.87792) (xy 199.893449 -132.83037) (xy 199.863482 -132.778464) (xy 199.840546 -132.723091)
			(xy 199.825033 -132.665198) (xy 199.81721 -132.605776) (xy 199.81672 -132.575808) (xy 181.760876 -132.575808)
			(xy 181.760876 -132.577332) (xy 181.760386 -132.6073) (xy 181.752563 -132.666722) (xy 181.73705 -132.724615)
			(xy 181.714114 -132.779988) (xy 181.684147 -132.831894) (xy 181.64766 -132.879444) (xy 181.60528 -132.921824)
			(xy 181.55773 -132.958311) (xy 181.505824 -132.988278) (xy 181.450451 -133.011214) (xy 181.392558 -133.026727)
			(xy 181.333136 -133.03455) (xy 181.2732 -133.03455) (xy 181.213778 -133.026727) (xy 181.155885 -133.011214)
			(xy 181.100512 -132.988278) (xy 181.048606 -132.958311) (xy 181.001056 -132.921824) (xy 180.958676 -132.879444)
			(xy 180.922189 -132.831894) (xy 180.892222 -132.779988) (xy 180.869286 -132.724615) (xy 180.853773 -132.666722)
			(xy 180.84595 -132.6073) (xy 180.84546 -132.577332) (xy 168.80078 -132.577332) (xy 168.80078 -133.096508)
			(xy 168.80029 -133.126492) (xy 168.792462 -133.185948) (xy 168.776941 -133.243873) (xy 168.753992 -133.299277)
			(xy 168.724008 -133.351211) (xy 168.687502 -133.398787) (xy 168.645097 -133.441192) (xy 168.597521 -133.477698)
			(xy 168.545587 -133.507682) (xy 168.490183 -133.530631) (xy 168.432258 -133.546152) (xy 168.372802 -133.55398)
			(xy 168.312834 -133.55398) (xy 168.253378 -133.546152) (xy 168.195453 -133.530631) (xy 168.140049 -133.507682)
			(xy 168.088115 -133.477698) (xy 168.040539 -133.441192) (xy 167.998134 -133.398787) (xy 167.961628 -133.351211)
			(xy 167.931644 -133.299277) (xy 167.908695 -133.243873) (xy 167.893174 -133.185948) (xy 167.885346 -133.126492)
			(xy 167.884856 -133.096508) (xy 154.325828 -133.096508) (xy 154.325828 -133.104382) (xy 154.325338 -133.134366)
			(xy 154.31751 -133.193822) (xy 154.301989 -133.251747) (xy 154.27904 -133.307151) (xy 154.249056 -133.359085)
			(xy 154.21255 -133.406661) (xy 154.170145 -133.449066) (xy 154.122569 -133.485572) (xy 154.070635 -133.515556)
			(xy 154.015231 -133.538505) (xy 153.957306 -133.554026) (xy 153.89785 -133.561854) (xy 153.837882 -133.561854)
			(xy 153.778426 -133.554026) (xy 153.720501 -133.538505) (xy 153.665097 -133.515556) (xy 153.613163 -133.485572)
			(xy 153.565587 -133.449066) (xy 153.523182 -133.406661) (xy 153.486676 -133.359085) (xy 153.456692 -133.307151)
			(xy 153.433743 -133.251747) (xy 153.418222 -133.193822) (xy 153.410394 -133.134366) (xy 153.409904 -133.104382)
			(xy 81.752059 -133.104382) (xy 81.786925 -133.124512) (xy 81.834501 -133.161018) (xy 81.876906 -133.203423)
			(xy 81.913412 -133.250999) (xy 81.943396 -133.302933) (xy 81.966345 -133.358337) (xy 81.981866 -133.416262)
			(xy 81.989694 -133.475718) (xy 81.990184 -133.505702) (xy 81.990184 -134.369302) (xy 81.989694 -134.399286)
			(xy 81.981866 -134.458742) (xy 81.966345 -134.516667) (xy 81.943396 -134.572071) (xy 81.913412 -134.624005)
			(xy 81.876906 -134.671581) (xy 81.834501 -134.713986) (xy 81.786925 -134.750492) (xy 81.734991 -134.780476)
			(xy 81.679587 -134.803425) (xy 81.621662 -134.818946) (xy 81.562206 -134.826774) (xy 81.502238 -134.826774)
			(xy 81.442782 -134.818946) (xy 81.384857 -134.803425) (xy 81.329453 -134.780476) (xy 81.277519 -134.750492)
			(xy 81.229943 -134.713986) (xy 81.187538 -134.671581) (xy 81.151032 -134.624005) (xy 81.121048 -134.572071)
			(xy 81.098099 -134.516667) (xy 81.082578 -134.458742) (xy 81.07475 -134.399286) (xy 81.07426 -134.369302)
			(xy 67.515232 -134.369302) (xy 67.515232 -134.377176) (xy 67.514742 -134.40716) (xy 67.506914 -134.466616)
			(xy 67.491393 -134.524541) (xy 67.468444 -134.579945) (xy 67.43846 -134.631879) (xy 67.401954 -134.679455)
			(xy 67.359549 -134.72186) (xy 67.311973 -134.758366) (xy 67.260039 -134.78835) (xy 67.204635 -134.811299)
			(xy 67.14671 -134.82682) (xy 67.087254 -134.834648) (xy 67.027286 -134.834648) (xy 66.96783 -134.82682)
			(xy 66.909905 -134.811299) (xy 66.854501 -134.78835) (xy 66.802567 -134.758366) (xy 66.754991 -134.72186)
			(xy 66.712586 -134.679455) (xy 66.67608 -134.631879) (xy 66.646096 -134.579945) (xy 66.623147 -134.524541)
			(xy 66.607626 -134.466616) (xy 66.599798 -134.40716) (xy 66.599308 -134.377176) (xy 54.554628 -134.377176)
			(xy 54.554628 -134.896352) (xy 54.554138 -134.92632) (xy 54.546315 -134.985742) (xy 54.530802 -135.043635)
			(xy 54.507866 -135.099008) (xy 54.477899 -135.150914) (xy 54.441412 -135.198464) (xy 54.399032 -135.240844)
			(xy 54.351482 -135.277331) (xy 54.299576 -135.307298) (xy 54.244203 -135.330234) (xy 54.18631 -135.345747)
			(xy 54.126888 -135.35357) (xy 54.066952 -135.35357) (xy 54.00753 -135.345747) (xy 53.949637 -135.330234)
			(xy 53.894264 -135.307298) (xy 53.842358 -135.277331) (xy 53.794808 -135.240844) (xy 53.752428 -135.198464)
			(xy 53.715941 -135.150914) (xy 53.685974 -135.099008) (xy 53.663038 -135.043635) (xy 53.647525 -134.985742)
			(xy 53.639702 -134.92632) (xy 53.639212 -134.896352) (xy 35.583368 -134.896352) (xy 35.583368 -134.897876)
			(xy 35.582878 -134.927844) (xy 35.575055 -134.987266) (xy 35.559542 -135.045159) (xy 35.536606 -135.100532)
			(xy 35.506639 -135.152438) (xy 35.470152 -135.199988) (xy 35.427772 -135.242368) (xy 35.380222 -135.278855)
			(xy 35.328316 -135.308822) (xy 35.272943 -135.331758) (xy 35.21505 -135.347271) (xy 35.155628 -135.355094)
			(xy 35.095692 -135.355094) (xy 35.03627 -135.347271) (xy 34.978377 -135.331758) (xy 34.923004 -135.308822)
			(xy 34.871098 -135.278855) (xy 34.823548 -135.242368) (xy 34.781168 -135.199988) (xy 34.744681 -135.152438)
			(xy 34.714714 -135.100532) (xy 34.691778 -135.045159) (xy 34.676265 -134.987266) (xy 34.668442 -134.927844)
			(xy 34.667952 -134.897876) (xy 4.308094 -134.897876) (xy 4.308094 -136.704324) (xy 37.31006 -136.704324)
			(xy 37.31006 -135.840724) (xy 37.31055 -135.810756) (xy 37.318373 -135.751334) (xy 37.333886 -135.693441)
			(xy 37.356822 -135.638068) (xy 37.386789 -135.586162) (xy 37.423276 -135.538612) (xy 37.465656 -135.496232)
			(xy 37.513206 -135.459745) (xy 37.565112 -135.429778) (xy 37.620485 -135.406842) (xy 37.678378 -135.391329)
			(xy 37.7378 -135.383506) (xy 37.797736 -135.383506) (xy 37.857158 -135.391329) (xy 37.915051 -135.406842)
			(xy 37.970424 -135.429778) (xy 38.02233 -135.459745) (xy 38.06988 -135.496232) (xy 38.11226 -135.538612)
			(xy 38.148747 -135.586162) (xy 38.178714 -135.638068) (xy 38.20165 -135.693441) (xy 38.217163 -135.751334)
			(xy 38.224986 -135.810756) (xy 38.225476 -135.840724) (xy 38.225476 -136.69645) (xy 51.785012 -136.69645)
			(xy 51.785012 -135.83285) (xy 51.785502 -135.802882) (xy 51.793325 -135.74346) (xy 51.808838 -135.685567)
			(xy 51.831774 -135.630194) (xy 51.861741 -135.578288) (xy 51.898228 -135.530738) (xy 51.940608 -135.488358)
			(xy 51.988158 -135.451871) (xy 52.040064 -135.421904) (xy 52.095437 -135.398968) (xy 52.15333 -135.383455)
			(xy 52.212752 -135.375632) (xy 52.272688 -135.375632) (xy 52.33211 -135.383455) (xy 52.390003 -135.398968)
			(xy 52.445376 -135.421904) (xy 52.497282 -135.451871) (xy 52.544832 -135.488358) (xy 52.587212 -135.530738)
			(xy 52.623699 -135.578288) (xy 52.653666 -135.630194) (xy 52.676602 -135.685567) (xy 52.692115 -135.74346)
			(xy 52.699938 -135.802882) (xy 52.700428 -135.83285) (xy 52.700428 -136.177274) (xy 64.745108 -136.177274)
			(xy 64.745108 -135.313674) (xy 64.745598 -135.28369) (xy 64.753426 -135.224234) (xy 64.768947 -135.166309)
			(xy 64.791896 -135.110905) (xy 64.82188 -135.058971) (xy 64.858386 -135.011395) (xy 64.900791 -134.96899)
			(xy 64.948367 -134.932484) (xy 65.000301 -134.9025) (xy 65.055705 -134.879551) (xy 65.11363 -134.86403)
			(xy 65.173086 -134.856202) (xy 65.233054 -134.856202) (xy 65.29251 -134.86403) (xy 65.350435 -134.879551)
			(xy 65.405839 -134.9025) (xy 65.457773 -134.932484) (xy 65.505349 -134.96899) (xy 65.547754 -135.011395)
			(xy 65.58426 -135.058971) (xy 65.614244 -135.110905) (xy 65.637193 -135.166309) (xy 65.652714 -135.224234)
			(xy 65.660542 -135.28369) (xy 65.661032 -135.313674) (xy 65.661032 -136.17575) (xy 83.716368 -136.17575)
			(xy 83.716368 -135.31215) (xy 83.716858 -135.282166) (xy 83.724686 -135.22271) (xy 83.740207 -135.164785)
			(xy 83.763156 -135.109381) (xy 83.79314 -135.057447) (xy 83.829646 -135.009871) (xy 83.872051 -134.967466)
			(xy 83.919627 -134.93096) (xy 83.971561 -134.900976) (xy 84.026965 -134.878027) (xy 84.08489 -134.862506)
			(xy 84.144346 -134.854678) (xy 84.204314 -134.854678) (xy 84.26377 -134.862506) (xy 84.321695 -134.878027)
			(xy 84.369615 -134.897876) (xy 150.767796 -134.897876) (xy 150.767796 -134.034276) (xy 150.768286 -134.004292)
			(xy 150.776114 -133.944836) (xy 150.791635 -133.886911) (xy 150.814584 -133.831507) (xy 150.844568 -133.779573)
			(xy 150.881074 -133.731997) (xy 150.923479 -133.689592) (xy 150.971055 -133.653086) (xy 151.022989 -133.623102)
			(xy 151.078393 -133.600153) (xy 151.136318 -133.584632) (xy 151.195774 -133.576804) (xy 151.255742 -133.576804)
			(xy 151.315198 -133.584632) (xy 151.373123 -133.600153) (xy 151.428527 -133.623102) (xy 151.480461 -133.653086)
			(xy 151.528037 -133.689592) (xy 151.570442 -133.731997) (xy 151.606948 -133.779573) (xy 151.636932 -133.831507)
			(xy 151.659881 -133.886911) (xy 151.675402 -133.944836) (xy 151.68323 -134.004292) (xy 151.68372 -134.034276)
			(xy 151.68372 -134.896352) (xy 169.739056 -134.896352) (xy 169.739056 -134.032752) (xy 169.739546 -134.002768)
			(xy 169.747374 -133.943312) (xy 169.762895 -133.885387) (xy 169.785844 -133.829983) (xy 169.815828 -133.778049)
			(xy 169.852334 -133.730473) (xy 169.894739 -133.688068) (xy 169.942315 -133.651562) (xy 169.994249 -133.621578)
			(xy 170.049653 -133.598629) (xy 170.107578 -133.583108) (xy 170.167034 -133.57528) (xy 170.227002 -133.57528)
			(xy 170.286458 -133.583108) (xy 170.344383 -133.598629) (xy 170.399787 -133.621578) (xy 170.451721 -133.651562)
			(xy 170.499297 -133.688068) (xy 170.541702 -133.730473) (xy 170.578208 -133.778049) (xy 170.608192 -133.829983)
			(xy 170.631141 -133.885387) (xy 170.646662 -133.943312) (xy 170.65449 -134.002768) (xy 170.65498 -134.032752)
			(xy 170.65498 -134.377176) (xy 182.69966 -134.377176) (xy 182.69966 -133.513576) (xy 182.70015 -133.483608)
			(xy 182.707973 -133.424186) (xy 182.723486 -133.366293) (xy 182.746422 -133.31092) (xy 182.776389 -133.259014)
			(xy 182.812876 -133.211464) (xy 182.855256 -133.169084) (xy 182.902806 -133.132597) (xy 182.954712 -133.10263)
			(xy 183.010085 -133.079694) (xy 183.067978 -133.064181) (xy 183.1274 -133.056358) (xy 183.187336 -133.056358)
			(xy 183.246758 -133.064181) (xy 183.304651 -133.079694) (xy 183.360024 -133.10263) (xy 183.41193 -133.132597)
			(xy 183.45948 -133.169084) (xy 183.50186 -133.211464) (xy 183.538347 -133.259014) (xy 183.568314 -133.31092)
			(xy 183.59125 -133.366293) (xy 183.606763 -133.424186) (xy 183.614586 -133.483608) (xy 183.615076 -133.513576)
			(xy 183.615076 -134.369302) (xy 197.174612 -134.369302) (xy 197.174612 -133.505702) (xy 197.175102 -133.475734)
			(xy 197.182925 -133.416312) (xy 197.198438 -133.358419) (xy 197.221374 -133.303046) (xy 197.251341 -133.25114)
			(xy 197.287828 -133.20359) (xy 197.330208 -133.16121) (xy 197.377758 -133.124723) (xy 197.429664 -133.094756)
			(xy 197.485037 -133.07182) (xy 197.54293 -133.056307) (xy 197.602352 -133.048484) (xy 197.662288 -133.048484)
			(xy 197.72171 -133.056307) (xy 197.779603 -133.07182) (xy 197.834976 -133.094756) (xy 197.851649 -133.104382)
			(xy 269.509748 -133.104382) (xy 269.509748 -132.240782) (xy 269.510238 -132.210798) (xy 269.518066 -132.151342)
			(xy 269.533587 -132.093417) (xy 269.556536 -132.038013) (xy 269.58652 -131.986079) (xy 269.623026 -131.938503)
			(xy 269.665431 -131.896098) (xy 269.713007 -131.859592) (xy 269.764941 -131.829608) (xy 269.820345 -131.806659)
			(xy 269.87827 -131.791138) (xy 269.937726 -131.78331) (xy 269.997694 -131.78331) (xy 270.05715 -131.791138)
			(xy 270.115075 -131.806659) (xy 270.170479 -131.829608) (xy 270.222413 -131.859592) (xy 270.269989 -131.896098)
			(xy 270.312394 -131.938503) (xy 270.3489 -131.986079) (xy 270.378884 -132.038013) (xy 270.401833 -132.093417)
			(xy 270.417354 -132.151342) (xy 270.425182 -132.210798) (xy 270.425672 -132.240782) (xy 270.425672 -133.096508)
			(xy 283.9847 -133.096508) (xy 283.9847 -132.232908) (xy 283.98519 -132.202924) (xy 283.993018 -132.143468)
			(xy 284.008539 -132.085543) (xy 284.031488 -132.030139) (xy 284.061472 -131.978205) (xy 284.097978 -131.930629)
			(xy 284.140383 -131.888224) (xy 284.187959 -131.851718) (xy 284.239893 -131.821734) (xy 284.295297 -131.798785)
			(xy 284.353222 -131.783264) (xy 284.412678 -131.775436) (xy 284.472646 -131.775436) (xy 284.532102 -131.783264)
			(xy 284.590027 -131.798785) (xy 284.645431 -131.821734) (xy 284.697365 -131.851718) (xy 284.744941 -131.888224)
			(xy 284.787346 -131.930629) (xy 284.823852 -131.978205) (xy 284.853836 -132.030139) (xy 284.876785 -132.085543)
			(xy 284.892306 -132.143468) (xy 284.900134 -132.202924) (xy 284.900624 -132.232908) (xy 284.900624 -132.577332)
			(xy 296.945304 -132.577332) (xy 296.945304 -131.713732) (xy 296.945794 -131.683764) (xy 296.953617 -131.624342)
			(xy 296.96913 -131.566449) (xy 296.992066 -131.511076) (xy 297.022033 -131.45917) (xy 297.05852 -131.41162)
			(xy 297.1009 -131.36924) (xy 297.14845 -131.332753) (xy 297.200356 -131.302786) (xy 297.255729 -131.27985)
			(xy 297.313622 -131.264337) (xy 297.373044 -131.256514) (xy 297.43298 -131.256514) (xy 297.492402 -131.264337)
			(xy 297.550295 -131.27985) (xy 297.605668 -131.302786) (xy 297.657574 -131.332753) (xy 297.705124 -131.36924)
			(xy 297.747504 -131.41162) (xy 297.783991 -131.45917) (xy 297.813958 -131.511076) (xy 297.836894 -131.566449)
			(xy 297.852407 -131.624342) (xy 297.86023 -131.683764) (xy 297.86072 -131.713732) (xy 297.86072 -132.575808)
			(xy 315.916564 -132.575808) (xy 315.916564 -131.712208) (xy 315.917054 -131.68224) (xy 315.924877 -131.622818)
			(xy 315.94039 -131.564925) (xy 315.963326 -131.509552) (xy 315.993293 -131.457646) (xy 316.02978 -131.410096)
			(xy 316.07216 -131.367716) (xy 316.11971 -131.331229) (xy 316.171616 -131.301262) (xy 316.226989 -131.278326)
			(xy 316.284882 -131.262813) (xy 316.344304 -131.25499) (xy 316.40424 -131.25499) (xy 316.463662 -131.262813)
			(xy 316.521555 -131.278326) (xy 316.568893 -131.297934) (xy 382.967992 -131.297934) (xy 382.967992 -130.434334)
			(xy 382.968482 -130.404366) (xy 382.976305 -130.344944) (xy 382.991818 -130.287051) (xy 383.014754 -130.231678)
			(xy 383.044721 -130.179772) (xy 383.081208 -130.132222) (xy 383.123588 -130.089842) (xy 383.171138 -130.053355)
			(xy 383.223044 -130.023388) (xy 383.278417 -130.000452) (xy 383.33631 -129.984939) (xy 383.395732 -129.977116)
			(xy 383.455668 -129.977116) (xy 383.51509 -129.984939) (xy 383.572983 -130.000452) (xy 383.628356 -130.023388)
			(xy 383.680262 -130.053355) (xy 383.727812 -130.089842) (xy 383.770192 -130.132222) (xy 383.806679 -130.179772)
			(xy 383.836646 -130.231678) (xy 383.859582 -130.287051) (xy 383.875095 -130.344944) (xy 383.882918 -130.404366)
			(xy 383.883408 -130.434334) (xy 383.883408 -131.29641) (xy 401.939252 -131.29641) (xy 401.939252 -130.43281)
			(xy 401.939742 -130.402842) (xy 401.947565 -130.34342) (xy 401.963078 -130.285527) (xy 401.986014 -130.230154)
			(xy 402.015981 -130.178248) (xy 402.052468 -130.130698) (xy 402.094848 -130.088318) (xy 402.142398 -130.051831)
			(xy 402.194304 -130.021864) (xy 402.249677 -129.998928) (xy 402.30757 -129.983415) (xy 402.366992 -129.975592)
			(xy 402.426928 -129.975592) (xy 402.48635 -129.983415) (xy 402.544243 -129.998928) (xy 402.599616 -130.021864)
			(xy 402.651522 -130.051831) (xy 402.699072 -130.088318) (xy 402.741452 -130.130698) (xy 402.777939 -130.178248)
			(xy 402.807906 -130.230154) (xy 402.830842 -130.285527) (xy 402.846355 -130.34342) (xy 402.854178 -130.402842)
			(xy 402.854668 -130.43281) (xy 402.854668 -130.777234) (xy 414.899348 -130.777234) (xy 414.899348 -129.913634)
			(xy 414.899838 -129.88365) (xy 414.907666 -129.824194) (xy 414.923187 -129.766269) (xy 414.946136 -129.710865)
			(xy 414.97612 -129.658931) (xy 415.012626 -129.611355) (xy 415.055031 -129.56895) (xy 415.102607 -129.532444)
			(xy 415.154541 -129.50246) (xy 415.209945 -129.479511) (xy 415.26787 -129.46399) (xy 415.327326 -129.456162)
			(xy 415.387294 -129.456162) (xy 415.44675 -129.46399) (xy 415.504675 -129.479511) (xy 415.560079 -129.50246)
			(xy 415.612013 -129.532444) (xy 415.659589 -129.56895) (xy 415.701994 -129.611355) (xy 415.7385 -129.658931)
			(xy 415.768484 -129.710865) (xy 415.791433 -129.766269) (xy 415.806954 -129.824194) (xy 415.814782 -129.88365)
			(xy 415.815272 -129.913634) (xy 415.815272 -130.769106) (xy 429.3743 -130.769106) (xy 429.3743 -129.905506)
			(xy 429.37479 -129.875522) (xy 429.382618 -129.816066) (xy 429.398139 -129.758141) (xy 429.421088 -129.702737)
			(xy 429.451072 -129.650803) (xy 429.487578 -129.603227) (xy 429.529983 -129.560822) (xy 429.577559 -129.524316)
			(xy 429.629493 -129.494332) (xy 429.684897 -129.471383) (xy 429.742822 -129.455862) (xy 429.802278 -129.448034)
			(xy 429.862246 -129.448034) (xy 429.921702 -129.455862) (xy 429.979627 -129.471383) (xy 430.035031 -129.494332)
			(xy 430.086965 -129.524316) (xy 430.134541 -129.560822) (xy 430.176946 -129.603227) (xy 430.213452 -129.650803)
			(xy 430.243436 -129.702737) (xy 430.266385 -129.758141) (xy 430.281906 -129.816066) (xy 430.289734 -129.875522)
			(xy 430.290224 -129.905506) (xy 430.290224 -130.769106) (xy 430.289734 -130.79909) (xy 430.281906 -130.858546)
			(xy 430.266385 -130.916471) (xy 430.243436 -130.971875) (xy 430.213452 -131.023809) (xy 430.176946 -131.071385)
			(xy 430.134541 -131.11379) (xy 430.086965 -131.150296) (xy 430.035031 -131.18028) (xy 429.979627 -131.203229)
			(xy 429.921702 -131.21875) (xy 429.862246 -131.226578) (xy 429.802278 -131.226578) (xy 429.742822 -131.21875)
			(xy 429.684897 -131.203229) (xy 429.629493 -131.18028) (xy 429.577559 -131.150296) (xy 429.529983 -131.11379)
			(xy 429.487578 -131.071385) (xy 429.451072 -131.023809) (xy 429.421088 -130.971875) (xy 429.398139 -130.916471)
			(xy 429.382618 -130.858546) (xy 429.37479 -130.79909) (xy 429.3743 -130.769106) (xy 415.815272 -130.769106)
			(xy 415.815272 -130.777234) (xy 415.814782 -130.807218) (xy 415.806954 -130.866674) (xy 415.791433 -130.924599)
			(xy 415.768484 -130.980003) (xy 415.7385 -131.031937) (xy 415.701994 -131.079513) (xy 415.659589 -131.121918)
			(xy 415.612013 -131.158424) (xy 415.560079 -131.188408) (xy 415.504675 -131.211357) (xy 415.44675 -131.226878)
			(xy 415.387294 -131.234706) (xy 415.327326 -131.234706) (xy 415.26787 -131.226878) (xy 415.209945 -131.211357)
			(xy 415.154541 -131.188408) (xy 415.102607 -131.158424) (xy 415.055031 -131.121918) (xy 415.012626 -131.079513)
			(xy 414.97612 -131.031937) (xy 414.946136 -130.980003) (xy 414.923187 -130.924599) (xy 414.907666 -130.866674)
			(xy 414.899838 -130.807218) (xy 414.899348 -130.777234) (xy 402.854668 -130.777234) (xy 402.854668 -131.29641)
			(xy 402.854178 -131.326378) (xy 402.846355 -131.3858) (xy 402.830842 -131.443693) (xy 402.807906 -131.499066)
			(xy 402.777939 -131.550972) (xy 402.741452 -131.598522) (xy 402.699072 -131.640902) (xy 402.651522 -131.677389)
			(xy 402.599616 -131.707356) (xy 402.544243 -131.730292) (xy 402.48635 -131.745805) (xy 402.426928 -131.753628)
			(xy 402.366992 -131.753628) (xy 402.30757 -131.745805) (xy 402.249677 -131.730292) (xy 402.194304 -131.707356)
			(xy 402.142398 -131.677389) (xy 402.094848 -131.640902) (xy 402.052468 -131.598522) (xy 402.015981 -131.550972)
			(xy 401.986014 -131.499066) (xy 401.963078 -131.443693) (xy 401.947565 -131.3858) (xy 401.939742 -131.326378)
			(xy 401.939252 -131.29641) (xy 383.883408 -131.29641) (xy 383.883408 -131.297934) (xy 383.882918 -131.327902)
			(xy 383.875095 -131.387324) (xy 383.859582 -131.445217) (xy 383.836646 -131.50059) (xy 383.806679 -131.552496)
			(xy 383.770192 -131.600046) (xy 383.727812 -131.642426) (xy 383.680262 -131.678913) (xy 383.628356 -131.70888)
			(xy 383.572983 -131.731816) (xy 383.51509 -131.747329) (xy 383.455668 -131.755152) (xy 383.395732 -131.755152)
			(xy 383.33631 -131.747329) (xy 383.278417 -131.731816) (xy 383.223044 -131.70888) (xy 383.171138 -131.678913)
			(xy 383.123588 -131.642426) (xy 383.081208 -131.600046) (xy 383.044721 -131.552496) (xy 383.014754 -131.50059)
			(xy 382.991818 -131.445217) (xy 382.976305 -131.387324) (xy 382.968482 -131.327902) (xy 382.967992 -131.297934)
			(xy 316.568893 -131.297934) (xy 316.576928 -131.301262) (xy 316.628834 -131.331229) (xy 316.676384 -131.367716)
			(xy 316.718764 -131.410096) (xy 316.755251 -131.457646) (xy 316.785218 -131.509552) (xy 316.808154 -131.564925)
			(xy 316.823667 -131.622818) (xy 316.83149 -131.68224) (xy 316.83198 -131.712208) (xy 316.83198 -132.575808)
			(xy 316.83149 -132.605776) (xy 316.823667 -132.665198) (xy 316.808154 -132.723091) (xy 316.785218 -132.778464)
			(xy 316.755251 -132.83037) (xy 316.718764 -132.87792) (xy 316.676384 -132.9203) (xy 316.628834 -132.956787)
			(xy 316.576928 -132.986754) (xy 316.521555 -133.00969) (xy 316.463662 -133.025203) (xy 316.40424 -133.033026)
			(xy 316.344304 -133.033026) (xy 316.284882 -133.025203) (xy 316.226989 -133.00969) (xy 316.171616 -132.986754)
			(xy 316.11971 -132.956787) (xy 316.07216 -132.9203) (xy 316.02978 -132.87792) (xy 315.993293 -132.83037)
			(xy 315.963326 -132.778464) (xy 315.94039 -132.723091) (xy 315.924877 -132.665198) (xy 315.917054 -132.605776)
			(xy 315.916564 -132.575808) (xy 297.86072 -132.575808) (xy 297.86072 -132.577332) (xy 297.86023 -132.6073)
			(xy 297.852407 -132.666722) (xy 297.836894 -132.724615) (xy 297.813958 -132.779988) (xy 297.783991 -132.831894)
			(xy 297.747504 -132.879444) (xy 297.705124 -132.921824) (xy 297.657574 -132.958311) (xy 297.605668 -132.988278)
			(xy 297.550295 -133.011214) (xy 297.492402 -133.026727) (xy 297.43298 -133.03455) (xy 297.373044 -133.03455)
			(xy 297.313622 -133.026727) (xy 297.255729 -133.011214) (xy 297.200356 -132.988278) (xy 297.14845 -132.958311)
			(xy 297.1009 -132.921824) (xy 297.05852 -132.879444) (xy 297.022033 -132.831894) (xy 296.992066 -132.779988)
			(xy 296.96913 -132.724615) (xy 296.953617 -132.666722) (xy 296.945794 -132.6073) (xy 296.945304 -132.577332)
			(xy 284.900624 -132.577332) (xy 284.900624 -133.096508) (xy 284.900134 -133.126492) (xy 284.892306 -133.185948)
			(xy 284.876785 -133.243873) (xy 284.853836 -133.299277) (xy 284.823852 -133.351211) (xy 284.787346 -133.398787)
			(xy 284.744941 -133.441192) (xy 284.697365 -133.477698) (xy 284.645431 -133.507682) (xy 284.590027 -133.530631)
			(xy 284.532102 -133.546152) (xy 284.472646 -133.55398) (xy 284.412678 -133.55398) (xy 284.353222 -133.546152)
			(xy 284.295297 -133.530631) (xy 284.239893 -133.507682) (xy 284.187959 -133.477698) (xy 284.140383 -133.441192)
			(xy 284.097978 -133.398787) (xy 284.061472 -133.351211) (xy 284.031488 -133.299277) (xy 284.008539 -133.243873)
			(xy 283.993018 -133.185948) (xy 283.98519 -133.126492) (xy 283.9847 -133.096508) (xy 270.425672 -133.096508)
			(xy 270.425672 -133.104382) (xy 270.425182 -133.134366) (xy 270.417354 -133.193822) (xy 270.401833 -133.251747)
			(xy 270.378884 -133.307151) (xy 270.3489 -133.359085) (xy 270.312394 -133.406661) (xy 270.269989 -133.449066)
			(xy 270.222413 -133.485572) (xy 270.170479 -133.515556) (xy 270.115075 -133.538505) (xy 270.05715 -133.554026)
			(xy 269.997694 -133.561854) (xy 269.937726 -133.561854) (xy 269.87827 -133.554026) (xy 269.820345 -133.538505)
			(xy 269.764941 -133.515556) (xy 269.713007 -133.485572) (xy 269.665431 -133.449066) (xy 269.623026 -133.406661)
			(xy 269.58652 -133.359085) (xy 269.556536 -133.307151) (xy 269.533587 -133.251747) (xy 269.518066 -133.193822)
			(xy 269.510238 -133.134366) (xy 269.509748 -133.104382) (xy 197.851649 -133.104382) (xy 197.886882 -133.124723)
			(xy 197.934432 -133.16121) (xy 197.976812 -133.20359) (xy 198.013299 -133.25114) (xy 198.043266 -133.303046)
			(xy 198.066202 -133.358419) (xy 198.081715 -133.416312) (xy 198.089538 -133.475734) (xy 198.090028 -133.505702)
			(xy 198.090028 -134.369302) (xy 198.089538 -134.39927) (xy 198.081715 -134.458692) (xy 198.066202 -134.516585)
			(xy 198.043266 -134.571958) (xy 198.013299 -134.623864) (xy 197.976812 -134.671414) (xy 197.934432 -134.713794)
			(xy 197.886882 -134.750281) (xy 197.834976 -134.780248) (xy 197.779603 -134.803184) (xy 197.72171 -134.818697)
			(xy 197.662288 -134.82652) (xy 197.602352 -134.82652) (xy 197.54293 -134.818697) (xy 197.485037 -134.803184)
			(xy 197.429664 -134.780248) (xy 197.377758 -134.750281) (xy 197.330208 -134.713794) (xy 197.287828 -134.671414)
			(xy 197.251341 -134.623864) (xy 197.221374 -134.571958) (xy 197.198438 -134.516585) (xy 197.182925 -134.458692)
			(xy 197.175102 -134.39927) (xy 197.174612 -134.369302) (xy 183.615076 -134.369302) (xy 183.615076 -134.377176)
			(xy 183.614586 -134.407144) (xy 183.606763 -134.466566) (xy 183.59125 -134.524459) (xy 183.568314 -134.579832)
			(xy 183.538347 -134.631738) (xy 183.50186 -134.679288) (xy 183.45948 -134.721668) (xy 183.41193 -134.758155)
			(xy 183.360024 -134.788122) (xy 183.304651 -134.811058) (xy 183.246758 -134.826571) (xy 183.187336 -134.834394)
			(xy 183.1274 -134.834394) (xy 183.067978 -134.826571) (xy 183.010085 -134.811058) (xy 182.954712 -134.788122)
			(xy 182.902806 -134.758155) (xy 182.855256 -134.721668) (xy 182.812876 -134.679288) (xy 182.776389 -134.631738)
			(xy 182.746422 -134.579832) (xy 182.723486 -134.524459) (xy 182.707973 -134.466566) (xy 182.70015 -134.407144)
			(xy 182.69966 -134.377176) (xy 170.65498 -134.377176) (xy 170.65498 -134.896352) (xy 170.65449 -134.926336)
			(xy 170.646662 -134.985792) (xy 170.631141 -135.043717) (xy 170.608192 -135.099121) (xy 170.578208 -135.151055)
			(xy 170.541702 -135.198631) (xy 170.499297 -135.241036) (xy 170.451721 -135.277542) (xy 170.399787 -135.307526)
			(xy 170.344383 -135.330475) (xy 170.286458 -135.345996) (xy 170.227002 -135.353824) (xy 170.167034 -135.353824)
			(xy 170.107578 -135.345996) (xy 170.049653 -135.330475) (xy 169.994249 -135.307526) (xy 169.942315 -135.277542)
			(xy 169.894739 -135.241036) (xy 169.852334 -135.198631) (xy 169.815828 -135.151055) (xy 169.785844 -135.099121)
			(xy 169.762895 -135.043717) (xy 169.747374 -134.985792) (xy 169.739546 -134.926336) (xy 169.739056 -134.896352)
			(xy 151.68372 -134.896352) (xy 151.68372 -134.897876) (xy 151.68323 -134.92786) (xy 151.675402 -134.987316)
			(xy 151.659881 -135.045241) (xy 151.636932 -135.100645) (xy 151.606948 -135.152579) (xy 151.570442 -135.200155)
			(xy 151.528037 -135.24256) (xy 151.480461 -135.279066) (xy 151.428527 -135.30905) (xy 151.373123 -135.331999)
			(xy 151.315198 -135.34752) (xy 151.255742 -135.355348) (xy 151.195774 -135.355348) (xy 151.136318 -135.34752)
			(xy 151.078393 -135.331999) (xy 151.022989 -135.30905) (xy 150.971055 -135.279066) (xy 150.923479 -135.24256)
			(xy 150.881074 -135.200155) (xy 150.844568 -135.152579) (xy 150.814584 -135.100645) (xy 150.791635 -135.045241)
			(xy 150.776114 -134.987316) (xy 150.768286 -134.92786) (xy 150.767796 -134.897876) (xy 84.369615 -134.897876)
			(xy 84.377099 -134.900976) (xy 84.429033 -134.93096) (xy 84.476609 -134.967466) (xy 84.519014 -135.009871)
			(xy 84.55552 -135.057447) (xy 84.585504 -135.109381) (xy 84.608453 -135.164785) (xy 84.623974 -135.22271)
			(xy 84.631802 -135.282166) (xy 84.632292 -135.31215) (xy 84.632292 -136.17575) (xy 84.631802 -136.205734)
			(xy 84.623974 -136.26519) (xy 84.608453 -136.323115) (xy 84.585504 -136.378519) (xy 84.55552 -136.430453)
			(xy 84.519014 -136.478029) (xy 84.476609 -136.520434) (xy 84.429033 -136.55694) (xy 84.377099 -136.586924)
			(xy 84.321695 -136.609873) (xy 84.26377 -136.625394) (xy 84.204314 -136.633222) (xy 84.144346 -136.633222)
			(xy 84.08489 -136.625394) (xy 84.026965 -136.609873) (xy 83.971561 -136.586924) (xy 83.919627 -136.55694)
			(xy 83.872051 -136.520434) (xy 83.829646 -136.478029) (xy 83.79314 -136.430453) (xy 83.763156 -136.378519)
			(xy 83.740207 -136.323115) (xy 83.724686 -136.26519) (xy 83.716858 -136.205734) (xy 83.716368 -136.17575)
			(xy 65.661032 -136.17575) (xy 65.661032 -136.177274) (xy 65.660542 -136.207258) (xy 65.652714 -136.266714)
			(xy 65.637193 -136.324639) (xy 65.614244 -136.380043) (xy 65.58426 -136.431977) (xy 65.547754 -136.479553)
			(xy 65.505349 -136.521958) (xy 65.457773 -136.558464) (xy 65.405839 -136.588448) (xy 65.350435 -136.611397)
			(xy 65.29251 -136.626918) (xy 65.233054 -136.634746) (xy 65.173086 -136.634746) (xy 65.11363 -136.626918)
			(xy 65.055705 -136.611397) (xy 65.000301 -136.588448) (xy 64.948367 -136.558464) (xy 64.900791 -136.521958)
			(xy 64.858386 -136.479553) (xy 64.82188 -136.431977) (xy 64.791896 -136.380043) (xy 64.768947 -136.324639)
			(xy 64.753426 -136.266714) (xy 64.745598 -136.207258) (xy 64.745108 -136.177274) (xy 52.700428 -136.177274)
			(xy 52.700428 -136.69645) (xy 52.700299 -136.704324) (xy 153.409904 -136.704324) (xy 153.409904 -135.840724)
			(xy 153.410394 -135.81074) (xy 153.418222 -135.751284) (xy 153.433743 -135.693359) (xy 153.456692 -135.637955)
			(xy 153.486676 -135.586021) (xy 153.523182 -135.538445) (xy 153.565587 -135.49604) (xy 153.613163 -135.459534)
			(xy 153.665097 -135.42955) (xy 153.720501 -135.406601) (xy 153.778426 -135.39108) (xy 153.837882 -135.383252)
			(xy 153.89785 -135.383252) (xy 153.957306 -135.39108) (xy 154.015231 -135.406601) (xy 154.070635 -135.42955)
			(xy 154.122569 -135.459534) (xy 154.170145 -135.49604) (xy 154.21255 -135.538445) (xy 154.249056 -135.586021)
			(xy 154.27904 -135.637955) (xy 154.301989 -135.693359) (xy 154.31751 -135.751284) (xy 154.325338 -135.81074)
			(xy 154.325828 -135.840724) (xy 154.325828 -136.69645) (xy 167.884856 -136.69645) (xy 167.884856 -135.83285)
			(xy 167.885346 -135.802866) (xy 167.893174 -135.74341) (xy 167.908695 -135.685485) (xy 167.931644 -135.630081)
			(xy 167.961628 -135.578147) (xy 167.998134 -135.530571) (xy 168.040539 -135.488166) (xy 168.088115 -135.45166)
			(xy 168.140049 -135.421676) (xy 168.195453 -135.398727) (xy 168.253378 -135.383206) (xy 168.312834 -135.375378)
			(xy 168.372802 -135.375378) (xy 168.432258 -135.383206) (xy 168.490183 -135.398727) (xy 168.545587 -135.421676)
			(xy 168.597521 -135.45166) (xy 168.645097 -135.488166) (xy 168.687502 -135.530571) (xy 168.724008 -135.578147)
			(xy 168.753992 -135.630081) (xy 168.776941 -135.685485) (xy 168.792462 -135.74341) (xy 168.80029 -135.802866)
			(xy 168.80078 -135.83285) (xy 168.80078 -136.177274) (xy 180.84546 -136.177274) (xy 180.84546 -135.313674)
			(xy 180.84595 -135.283706) (xy 180.853773 -135.224284) (xy 180.869286 -135.166391) (xy 180.892222 -135.111018)
			(xy 180.922189 -135.059112) (xy 180.958676 -135.011562) (xy 181.001056 -134.969182) (xy 181.048606 -134.932695)
			(xy 181.100512 -134.902728) (xy 181.155885 -134.879792) (xy 181.213778 -134.864279) (xy 181.2732 -134.856456)
			(xy 181.333136 -134.856456) (xy 181.392558 -134.864279) (xy 181.450451 -134.879792) (xy 181.505824 -134.902728)
			(xy 181.55773 -134.932695) (xy 181.60528 -134.969182) (xy 181.64766 -135.011562) (xy 181.684147 -135.059112)
			(xy 181.714114 -135.111018) (xy 181.73705 -135.166391) (xy 181.752563 -135.224284) (xy 181.760386 -135.283706)
			(xy 181.760876 -135.313674) (xy 181.760876 -136.17575) (xy 199.81672 -136.17575) (xy 199.81672 -135.31215)
			(xy 199.81721 -135.282182) (xy 199.825033 -135.22276) (xy 199.840546 -135.164867) (xy 199.863482 -135.109494)
			(xy 199.893449 -135.057588) (xy 199.929936 -135.010038) (xy 199.972316 -134.967658) (xy 200.019866 -134.931171)
			(xy 200.071772 -134.901204) (xy 200.127145 -134.878268) (xy 200.185038 -134.862755) (xy 200.24446 -134.854932)
			(xy 200.304396 -134.854932) (xy 200.363818 -134.862755) (xy 200.421711 -134.878268) (xy 200.469049 -134.897876)
			(xy 266.86764 -134.897876) (xy 266.86764 -134.034276) (xy 266.86813 -134.004292) (xy 266.875958 -133.944836)
			(xy 266.891479 -133.886911) (xy 266.914428 -133.831507) (xy 266.944412 -133.779573) (xy 266.980918 -133.731997)
			(xy 267.023323 -133.689592) (xy 267.070899 -133.653086) (xy 267.122833 -133.623102) (xy 267.178237 -133.600153)
			(xy 267.236162 -133.584632) (xy 267.295618 -133.576804) (xy 267.355586 -133.576804) (xy 267.415042 -133.584632)
			(xy 267.472967 -133.600153) (xy 267.528371 -133.623102) (xy 267.580305 -133.653086) (xy 267.627881 -133.689592)
			(xy 267.670286 -133.731997) (xy 267.706792 -133.779573) (xy 267.736776 -133.831507) (xy 267.759725 -133.886911)
			(xy 267.775246 -133.944836) (xy 267.783074 -134.004292) (xy 267.783564 -134.034276) (xy 267.783564 -134.896352)
			(xy 285.8389 -134.896352) (xy 285.8389 -134.032752) (xy 285.83939 -134.002768) (xy 285.847218 -133.943312)
			(xy 285.862739 -133.885387) (xy 285.885688 -133.829983) (xy 285.915672 -133.778049) (xy 285.952178 -133.730473)
			(xy 285.994583 -133.688068) (xy 286.042159 -133.651562) (xy 286.094093 -133.621578) (xy 286.149497 -133.598629)
			(xy 286.207422 -133.583108) (xy 286.266878 -133.57528) (xy 286.326846 -133.57528) (xy 286.386302 -133.583108)
			(xy 286.444227 -133.598629) (xy 286.499631 -133.621578) (xy 286.551565 -133.651562) (xy 286.599141 -133.688068)
			(xy 286.641546 -133.730473) (xy 286.678052 -133.778049) (xy 286.708036 -133.829983) (xy 286.730985 -133.885387)
			(xy 286.746506 -133.943312) (xy 286.754334 -134.002768) (xy 286.754824 -134.032752) (xy 286.754824 -134.377176)
			(xy 298.799504 -134.377176) (xy 298.799504 -133.513576) (xy 298.799994 -133.483608) (xy 298.807817 -133.424186)
			(xy 298.82333 -133.366293) (xy 298.846266 -133.31092) (xy 298.876233 -133.259014) (xy 298.91272 -133.211464)
			(xy 298.9551 -133.169084) (xy 299.00265 -133.132597) (xy 299.054556 -133.10263) (xy 299.109929 -133.079694)
			(xy 299.167822 -133.064181) (xy 299.227244 -133.056358) (xy 299.28718 -133.056358) (xy 299.346602 -133.064181)
			(xy 299.404495 -133.079694) (xy 299.459868 -133.10263) (xy 299.511774 -133.132597) (xy 299.559324 -133.169084)
			(xy 299.601704 -133.211464) (xy 299.638191 -133.259014) (xy 299.668158 -133.31092) (xy 299.691094 -133.366293)
			(xy 299.706607 -133.424186) (xy 299.71443 -133.483608) (xy 299.71492 -133.513576) (xy 299.71492 -134.369302)
			(xy 313.274456 -134.369302) (xy 313.274456 -133.505702) (xy 313.274946 -133.475734) (xy 313.282769 -133.416312)
			(xy 313.298282 -133.358419) (xy 313.321218 -133.303046) (xy 313.351185 -133.25114) (xy 313.387672 -133.20359)
			(xy 313.430052 -133.16121) (xy 313.477602 -133.124723) (xy 313.529508 -133.094756) (xy 313.584881 -133.07182)
			(xy 313.642774 -133.056307) (xy 313.702196 -133.048484) (xy 313.762132 -133.048484) (xy 313.821554 -133.056307)
			(xy 313.879447 -133.07182) (xy 313.93482 -133.094756) (xy 313.951493 -133.104382) (xy 385.6101 -133.104382)
			(xy 385.6101 -132.240782) (xy 385.61059 -132.210814) (xy 385.618413 -132.151392) (xy 385.633926 -132.093499)
			(xy 385.656862 -132.038126) (xy 385.686829 -131.98622) (xy 385.723316 -131.93867) (xy 385.765696 -131.89629)
			(xy 385.813246 -131.859803) (xy 385.865152 -131.829836) (xy 385.920525 -131.8069) (xy 385.978418 -131.791387)
			(xy 386.03784 -131.783564) (xy 386.097776 -131.783564) (xy 386.157198 -131.791387) (xy 386.215091 -131.8069)
			(xy 386.270464 -131.829836) (xy 386.32237 -131.859803) (xy 386.36992 -131.89629) (xy 386.4123 -131.93867)
			(xy 386.448787 -131.98622) (xy 386.478754 -132.038126) (xy 386.50169 -132.093499) (xy 386.517203 -132.151392)
			(xy 386.525026 -132.210814) (xy 386.525516 -132.240782) (xy 386.525516 -133.096508) (xy 400.085052 -133.096508)
			(xy 400.085052 -132.232908) (xy 400.085542 -132.20294) (xy 400.093365 -132.143518) (xy 400.108878 -132.085625)
			(xy 400.131814 -132.030252) (xy 400.161781 -131.978346) (xy 400.198268 -131.930796) (xy 400.240648 -131.888416)
			(xy 400.288198 -131.851929) (xy 400.340104 -131.821962) (xy 400.395477 -131.799026) (xy 400.45337 -131.783513)
			(xy 400.512792 -131.77569) (xy 400.572728 -131.77569) (xy 400.63215 -131.783513) (xy 400.690043 -131.799026)
			(xy 400.745416 -131.821962) (xy 400.797322 -131.851929) (xy 400.844872 -131.888416) (xy 400.887252 -131.930796)
			(xy 400.923739 -131.978346) (xy 400.953706 -132.030252) (xy 400.976642 -132.085625) (xy 400.992155 -132.143518)
			(xy 400.999978 -132.20294) (xy 401.000468 -132.232908) (xy 401.000468 -132.577332) (xy 413.045148 -132.577332)
			(xy 413.045148 -131.713732) (xy 413.045638 -131.683748) (xy 413.053466 -131.624292) (xy 413.068987 -131.566367)
			(xy 413.091936 -131.510963) (xy 413.12192 -131.459029) (xy 413.158426 -131.411453) (xy 413.200831 -131.369048)
			(xy 413.248407 -131.332542) (xy 413.300341 -131.302558) (xy 413.355745 -131.279609) (xy 413.41367 -131.264088)
			(xy 413.473126 -131.25626) (xy 413.533094 -131.25626) (xy 413.59255 -131.264088) (xy 413.650475 -131.279609)
			(xy 413.705879 -131.302558) (xy 413.757813 -131.332542) (xy 413.805389 -131.369048) (xy 413.847794 -131.411453)
			(xy 413.8843 -131.459029) (xy 413.914284 -131.510963) (xy 413.937233 -131.566367) (xy 413.952754 -131.624292)
			(xy 413.960582 -131.683748) (xy 413.961072 -131.713732) (xy 413.961072 -132.575808) (xy 432.016408 -132.575808)
			(xy 432.016408 -131.712208) (xy 432.016898 -131.682224) (xy 432.024726 -131.622768) (xy 432.040247 -131.564843)
			(xy 432.063196 -131.509439) (xy 432.09318 -131.457505) (xy 432.129686 -131.409929) (xy 432.172091 -131.367524)
			(xy 432.219667 -131.331018) (xy 432.271601 -131.301034) (xy 432.327005 -131.278085) (xy 432.38493 -131.262564)
			(xy 432.444386 -131.254736) (xy 432.504354 -131.254736) (xy 432.56381 -131.262564) (xy 432.621735 -131.278085)
			(xy 432.677139 -131.301034) (xy 432.729073 -131.331018) (xy 432.776649 -131.367524) (xy 432.819054 -131.409929)
			(xy 432.85556 -131.457505) (xy 432.885544 -131.509439) (xy 432.908493 -131.564843) (xy 432.924014 -131.622768)
			(xy 432.931842 -131.682224) (xy 432.932332 -131.712208) (xy 432.932332 -132.575808) (xy 432.931842 -132.605792)
			(xy 432.924014 -132.665248) (xy 432.908493 -132.723173) (xy 432.885544 -132.778577) (xy 432.85556 -132.830511)
			(xy 432.819054 -132.878087) (xy 432.776649 -132.920492) (xy 432.729073 -132.956998) (xy 432.677139 -132.986982)
			(xy 432.621735 -133.009931) (xy 432.56381 -133.025452) (xy 432.504354 -133.03328) (xy 432.444386 -133.03328)
			(xy 432.38493 -133.025452) (xy 432.327005 -133.009931) (xy 432.271601 -132.986982) (xy 432.219667 -132.956998)
			(xy 432.172091 -132.920492) (xy 432.129686 -132.878087) (xy 432.09318 -132.830511) (xy 432.063196 -132.778577)
			(xy 432.040247 -132.723173) (xy 432.024726 -132.665248) (xy 432.016898 -132.605792) (xy 432.016408 -132.575808)
			(xy 413.961072 -132.575808) (xy 413.961072 -132.577332) (xy 413.960582 -132.607316) (xy 413.952754 -132.666772)
			(xy 413.937233 -132.724697) (xy 413.914284 -132.780101) (xy 413.8843 -132.832035) (xy 413.847794 -132.879611)
			(xy 413.805389 -132.922016) (xy 413.757813 -132.958522) (xy 413.705879 -132.988506) (xy 413.650475 -133.011455)
			(xy 413.59255 -133.026976) (xy 413.533094 -133.034804) (xy 413.473126 -133.034804) (xy 413.41367 -133.026976)
			(xy 413.355745 -133.011455) (xy 413.300341 -132.988506) (xy 413.248407 -132.958522) (xy 413.200831 -132.922016)
			(xy 413.158426 -132.879611) (xy 413.12192 -132.832035) (xy 413.091936 -132.780101) (xy 413.068987 -132.724697)
			(xy 413.053466 -132.666772) (xy 413.045638 -132.607316) (xy 413.045148 -132.577332) (xy 401.000468 -132.577332)
			(xy 401.000468 -133.096508) (xy 400.999978 -133.126476) (xy 400.992155 -133.185898) (xy 400.976642 -133.243791)
			(xy 400.953706 -133.299164) (xy 400.923739 -133.35107) (xy 400.887252 -133.39862) (xy 400.844872 -133.441)
			(xy 400.797322 -133.477487) (xy 400.745416 -133.507454) (xy 400.690043 -133.53039) (xy 400.63215 -133.545903)
			(xy 400.572728 -133.553726) (xy 400.512792 -133.553726) (xy 400.45337 -133.545903) (xy 400.395477 -133.53039)
			(xy 400.340104 -133.507454) (xy 400.288198 -133.477487) (xy 400.240648 -133.441) (xy 400.198268 -133.39862)
			(xy 400.161781 -133.35107) (xy 400.131814 -133.299164) (xy 400.108878 -133.243791) (xy 400.093365 -133.185898)
			(xy 400.085542 -133.126476) (xy 400.085052 -133.096508) (xy 386.525516 -133.096508) (xy 386.525516 -133.104382)
			(xy 386.525026 -133.13435) (xy 386.517203 -133.193772) (xy 386.50169 -133.251665) (xy 386.478754 -133.307038)
			(xy 386.448787 -133.358944) (xy 386.4123 -133.406494) (xy 386.36992 -133.448874) (xy 386.32237 -133.485361)
			(xy 386.270464 -133.515328) (xy 386.215091 -133.538264) (xy 386.157198 -133.553777) (xy 386.097776 -133.5616)
			(xy 386.03784 -133.5616) (xy 385.978418 -133.553777) (xy 385.920525 -133.538264) (xy 385.865152 -133.515328)
			(xy 385.813246 -133.485361) (xy 385.765696 -133.448874) (xy 385.723316 -133.406494) (xy 385.686829 -133.358944)
			(xy 385.656862 -133.307038) (xy 385.633926 -133.251665) (xy 385.618413 -133.193772) (xy 385.61059 -133.13435)
			(xy 385.6101 -133.104382) (xy 313.951493 -133.104382) (xy 313.986726 -133.124723) (xy 314.034276 -133.16121)
			(xy 314.076656 -133.20359) (xy 314.113143 -133.25114) (xy 314.14311 -133.303046) (xy 314.166046 -133.358419)
			(xy 314.181559 -133.416312) (xy 314.189382 -133.475734) (xy 314.189872 -133.505702) (xy 314.189872 -134.369302)
			(xy 314.189382 -134.39927) (xy 314.181559 -134.458692) (xy 314.166046 -134.516585) (xy 314.14311 -134.571958)
			(xy 314.113143 -134.623864) (xy 314.076656 -134.671414) (xy 314.034276 -134.713794) (xy 313.986726 -134.750281)
			(xy 313.93482 -134.780248) (xy 313.879447 -134.803184) (xy 313.821554 -134.818697) (xy 313.762132 -134.82652)
			(xy 313.702196 -134.82652) (xy 313.642774 -134.818697) (xy 313.584881 -134.803184) (xy 313.529508 -134.780248)
			(xy 313.477602 -134.750281) (xy 313.430052 -134.713794) (xy 313.387672 -134.671414) (xy 313.351185 -134.623864)
			(xy 313.321218 -134.571958) (xy 313.298282 -134.516585) (xy 313.282769 -134.458692) (xy 313.274946 -134.39927)
			(xy 313.274456 -134.369302) (xy 299.71492 -134.369302) (xy 299.71492 -134.377176) (xy 299.71443 -134.407144)
			(xy 299.706607 -134.466566) (xy 299.691094 -134.524459) (xy 299.668158 -134.579832) (xy 299.638191 -134.631738)
			(xy 299.601704 -134.679288) (xy 299.559324 -134.721668) (xy 299.511774 -134.758155) (xy 299.459868 -134.788122)
			(xy 299.404495 -134.811058) (xy 299.346602 -134.826571) (xy 299.28718 -134.834394) (xy 299.227244 -134.834394)
			(xy 299.167822 -134.826571) (xy 299.109929 -134.811058) (xy 299.054556 -134.788122) (xy 299.00265 -134.758155)
			(xy 298.9551 -134.721668) (xy 298.91272 -134.679288) (xy 298.876233 -134.631738) (xy 298.846266 -134.579832)
			(xy 298.82333 -134.524459) (xy 298.807817 -134.466566) (xy 298.799994 -134.407144) (xy 298.799504 -134.377176)
			(xy 286.754824 -134.377176) (xy 286.754824 -134.896352) (xy 286.754334 -134.926336) (xy 286.746506 -134.985792)
			(xy 286.730985 -135.043717) (xy 286.708036 -135.099121) (xy 286.678052 -135.151055) (xy 286.641546 -135.198631)
			(xy 286.599141 -135.241036) (xy 286.551565 -135.277542) (xy 286.499631 -135.307526) (xy 286.444227 -135.330475)
			(xy 286.386302 -135.345996) (xy 286.326846 -135.353824) (xy 286.266878 -135.353824) (xy 286.207422 -135.345996)
			(xy 286.149497 -135.330475) (xy 286.094093 -135.307526) (xy 286.042159 -135.277542) (xy 285.994583 -135.241036)
			(xy 285.952178 -135.198631) (xy 285.915672 -135.151055) (xy 285.885688 -135.099121) (xy 285.862739 -135.043717)
			(xy 285.847218 -134.985792) (xy 285.83939 -134.926336) (xy 285.8389 -134.896352) (xy 267.783564 -134.896352)
			(xy 267.783564 -134.897876) (xy 267.783074 -134.92786) (xy 267.775246 -134.987316) (xy 267.759725 -135.045241)
			(xy 267.736776 -135.100645) (xy 267.706792 -135.152579) (xy 267.670286 -135.200155) (xy 267.627881 -135.24256)
			(xy 267.580305 -135.279066) (xy 267.528371 -135.30905) (xy 267.472967 -135.331999) (xy 267.415042 -135.34752)
			(xy 267.355586 -135.355348) (xy 267.295618 -135.355348) (xy 267.236162 -135.34752) (xy 267.178237 -135.331999)
			(xy 267.122833 -135.30905) (xy 267.070899 -135.279066) (xy 267.023323 -135.24256) (xy 266.980918 -135.200155)
			(xy 266.944412 -135.152579) (xy 266.914428 -135.100645) (xy 266.891479 -135.045241) (xy 266.875958 -134.987316)
			(xy 266.86813 -134.92786) (xy 266.86764 -134.897876) (xy 200.469049 -134.897876) (xy 200.477084 -134.901204)
			(xy 200.52899 -134.931171) (xy 200.57654 -134.967658) (xy 200.61892 -135.010038) (xy 200.655407 -135.057588)
			(xy 200.685374 -135.109494) (xy 200.70831 -135.164867) (xy 200.723823 -135.22276) (xy 200.731646 -135.282182)
			(xy 200.732136 -135.31215) (xy 200.732136 -136.17575) (xy 200.731646 -136.205718) (xy 200.723823 -136.26514)
			(xy 200.70831 -136.323033) (xy 200.685374 -136.378406) (xy 200.655407 -136.430312) (xy 200.61892 -136.477862)
			(xy 200.57654 -136.520242) (xy 200.52899 -136.556729) (xy 200.477084 -136.586696) (xy 200.421711 -136.609632)
			(xy 200.363818 -136.625145) (xy 200.304396 -136.632968) (xy 200.24446 -136.632968) (xy 200.185038 -136.625145)
			(xy 200.127145 -136.609632) (xy 200.071772 -136.586696) (xy 200.019866 -136.556729) (xy 199.972316 -136.520242)
			(xy 199.929936 -136.477862) (xy 199.893449 -136.430312) (xy 199.863482 -136.378406) (xy 199.840546 -136.323033)
			(xy 199.825033 -136.26514) (xy 199.81721 -136.205718) (xy 199.81672 -136.17575) (xy 181.760876 -136.17575)
			(xy 181.760876 -136.177274) (xy 181.760386 -136.207242) (xy 181.752563 -136.266664) (xy 181.73705 -136.324557)
			(xy 181.714114 -136.37993) (xy 181.684147 -136.431836) (xy 181.64766 -136.479386) (xy 181.60528 -136.521766)
			(xy 181.55773 -136.558253) (xy 181.505824 -136.58822) (xy 181.450451 -136.611156) (xy 181.392558 -136.626669)
			(xy 181.333136 -136.634492) (xy 181.2732 -136.634492) (xy 181.213778 -136.626669) (xy 181.155885 -136.611156)
			(xy 181.100512 -136.58822) (xy 181.048606 -136.558253) (xy 181.001056 -136.521766) (xy 180.958676 -136.479386)
			(xy 180.922189 -136.431836) (xy 180.892222 -136.37993) (xy 180.869286 -136.324557) (xy 180.853773 -136.266664)
			(xy 180.84595 -136.207242) (xy 180.84546 -136.177274) (xy 168.80078 -136.177274) (xy 168.80078 -136.69645)
			(xy 168.800651 -136.704324) (xy 269.509748 -136.704324) (xy 269.509748 -135.840724) (xy 269.510238 -135.81074)
			(xy 269.518066 -135.751284) (xy 269.533587 -135.693359) (xy 269.556536 -135.637955) (xy 269.58652 -135.586021)
			(xy 269.623026 -135.538445) (xy 269.665431 -135.49604) (xy 269.713007 -135.459534) (xy 269.764941 -135.42955)
			(xy 269.820345 -135.406601) (xy 269.87827 -135.39108) (xy 269.937726 -135.383252) (xy 269.997694 -135.383252)
			(xy 270.05715 -135.39108) (xy 270.115075 -135.406601) (xy 270.170479 -135.42955) (xy 270.222413 -135.459534)
			(xy 270.269989 -135.49604) (xy 270.312394 -135.538445) (xy 270.3489 -135.586021) (xy 270.378884 -135.637955)
			(xy 270.401833 -135.693359) (xy 270.417354 -135.751284) (xy 270.425182 -135.81074) (xy 270.425672 -135.840724)
			(xy 270.425672 -136.69645) (xy 283.9847 -136.69645) (xy 283.9847 -135.83285) (xy 283.98519 -135.802866)
			(xy 283.993018 -135.74341) (xy 284.008539 -135.685485) (xy 284.031488 -135.630081) (xy 284.061472 -135.578147)
			(xy 284.097978 -135.530571) (xy 284.140383 -135.488166) (xy 284.187959 -135.45166) (xy 284.239893 -135.421676)
			(xy 284.295297 -135.398727) (xy 284.353222 -135.383206) (xy 284.412678 -135.375378) (xy 284.472646 -135.375378)
			(xy 284.532102 -135.383206) (xy 284.590027 -135.398727) (xy 284.645431 -135.421676) (xy 284.697365 -135.45166)
			(xy 284.744941 -135.488166) (xy 284.787346 -135.530571) (xy 284.823852 -135.578147) (xy 284.853836 -135.630081)
			(xy 284.876785 -135.685485) (xy 284.892306 -135.74341) (xy 284.900134 -135.802866) (xy 284.900624 -135.83285)
			(xy 284.900624 -136.177274) (xy 296.945304 -136.177274) (xy 296.945304 -135.313674) (xy 296.945794 -135.283706)
			(xy 296.953617 -135.224284) (xy 296.96913 -135.166391) (xy 296.992066 -135.111018) (xy 297.022033 -135.059112)
			(xy 297.05852 -135.011562) (xy 297.1009 -134.969182) (xy 297.14845 -134.932695) (xy 297.200356 -134.902728)
			(xy 297.255729 -134.879792) (xy 297.313622 -134.864279) (xy 297.373044 -134.856456) (xy 297.43298 -134.856456)
			(xy 297.492402 -134.864279) (xy 297.550295 -134.879792) (xy 297.605668 -134.902728) (xy 297.657574 -134.932695)
			(xy 297.705124 -134.969182) (xy 297.747504 -135.011562) (xy 297.783991 -135.059112) (xy 297.813958 -135.111018)
			(xy 297.836894 -135.166391) (xy 297.852407 -135.224284) (xy 297.86023 -135.283706) (xy 297.86072 -135.313674)
			(xy 297.86072 -136.17575) (xy 315.916564 -136.17575) (xy 315.916564 -135.31215) (xy 315.917054 -135.282182)
			(xy 315.924877 -135.22276) (xy 315.94039 -135.164867) (xy 315.963326 -135.109494) (xy 315.993293 -135.057588)
			(xy 316.02978 -135.010038) (xy 316.07216 -134.967658) (xy 316.11971 -134.931171) (xy 316.171616 -134.901204)
			(xy 316.226989 -134.878268) (xy 316.284882 -134.862755) (xy 316.344304 -134.854932) (xy 316.40424 -134.854932)
			(xy 316.463662 -134.862755) (xy 316.521555 -134.878268) (xy 316.568893 -134.897876) (xy 382.967992 -134.897876)
			(xy 382.967992 -134.034276) (xy 382.968482 -134.004308) (xy 382.976305 -133.944886) (xy 382.991818 -133.886993)
			(xy 383.014754 -133.83162) (xy 383.044721 -133.779714) (xy 383.081208 -133.732164) (xy 383.123588 -133.689784)
			(xy 383.171138 -133.653297) (xy 383.223044 -133.62333) (xy 383.278417 -133.600394) (xy 383.33631 -133.584881)
			(xy 383.395732 -133.577058) (xy 383.455668 -133.577058) (xy 383.51509 -133.584881) (xy 383.572983 -133.600394)
			(xy 383.628356 -133.62333) (xy 383.680262 -133.653297) (xy 383.727812 -133.689784) (xy 383.770192 -133.732164)
			(xy 383.806679 -133.779714) (xy 383.836646 -133.83162) (xy 383.859582 -133.886993) (xy 383.875095 -133.944886)
			(xy 383.882918 -134.004308) (xy 383.883408 -134.034276) (xy 383.883408 -134.896352) (xy 401.939252 -134.896352)
			(xy 401.939252 -134.032752) (xy 401.939742 -134.002784) (xy 401.947565 -133.943362) (xy 401.963078 -133.885469)
			(xy 401.986014 -133.830096) (xy 402.015981 -133.77819) (xy 402.052468 -133.73064) (xy 402.094848 -133.68826)
			(xy 402.142398 -133.651773) (xy 402.194304 -133.621806) (xy 402.249677 -133.59887) (xy 402.30757 -133.583357)
			(xy 402.366992 -133.575534) (xy 402.426928 -133.575534) (xy 402.48635 -133.583357) (xy 402.544243 -133.59887)
			(xy 402.599616 -133.621806) (xy 402.651522 -133.651773) (xy 402.699072 -133.68826) (xy 402.741452 -133.73064)
			(xy 402.777939 -133.77819) (xy 402.807906 -133.830096) (xy 402.830842 -133.885469) (xy 402.846355 -133.943362)
			(xy 402.854178 -134.002784) (xy 402.854668 -134.032752) (xy 402.854668 -134.377176) (xy 414.899348 -134.377176)
			(xy 414.899348 -133.513576) (xy 414.899838 -133.483592) (xy 414.907666 -133.424136) (xy 414.923187 -133.366211)
			(xy 414.946136 -133.310807) (xy 414.97612 -133.258873) (xy 415.012626 -133.211297) (xy 415.055031 -133.168892)
			(xy 415.102607 -133.132386) (xy 415.154541 -133.102402) (xy 415.209945 -133.079453) (xy 415.26787 -133.063932)
			(xy 415.327326 -133.056104) (xy 415.387294 -133.056104) (xy 415.44675 -133.063932) (xy 415.504675 -133.079453)
			(xy 415.560079 -133.102402) (xy 415.612013 -133.132386) (xy 415.659589 -133.168892) (xy 415.701994 -133.211297)
			(xy 415.7385 -133.258873) (xy 415.768484 -133.310807) (xy 415.791433 -133.366211) (xy 415.806954 -133.424136)
			(xy 415.814782 -133.483592) (xy 415.815272 -133.513576) (xy 415.815272 -134.369302) (xy 429.3743 -134.369302)
			(xy 429.3743 -133.505702) (xy 429.37479 -133.475718) (xy 429.382618 -133.416262) (xy 429.398139 -133.358337)
			(xy 429.421088 -133.302933) (xy 429.451072 -133.250999) (xy 429.487578 -133.203423) (xy 429.529983 -133.161018)
			(xy 429.577559 -133.124512) (xy 429.629493 -133.094528) (xy 429.684897 -133.071579) (xy 429.742822 -133.056058)
			(xy 429.802278 -133.04823) (xy 429.862246 -133.04823) (xy 429.921702 -133.056058) (xy 429.979627 -133.071579)
			(xy 430.035031 -133.094528) (xy 430.086965 -133.124512) (xy 430.134541 -133.161018) (xy 430.176946 -133.203423)
			(xy 430.213452 -133.250999) (xy 430.243436 -133.302933) (xy 430.266385 -133.358337) (xy 430.281906 -133.416262)
			(xy 430.289734 -133.475718) (xy 430.290224 -133.505702) (xy 430.290224 -134.369302) (xy 430.289734 -134.399286)
			(xy 430.281906 -134.458742) (xy 430.266385 -134.516667) (xy 430.243436 -134.572071) (xy 430.213452 -134.624005)
			(xy 430.176946 -134.671581) (xy 430.134541 -134.713986) (xy 430.086965 -134.750492) (xy 430.035031 -134.780476)
			(xy 429.979627 -134.803425) (xy 429.921702 -134.818946) (xy 429.862246 -134.826774) (xy 429.802278 -134.826774)
			(xy 429.742822 -134.818946) (xy 429.684897 -134.803425) (xy 429.629493 -134.780476) (xy 429.577559 -134.750492)
			(xy 429.529983 -134.713986) (xy 429.487578 -134.671581) (xy 429.451072 -134.624005) (xy 429.421088 -134.572071)
			(xy 429.398139 -134.516667) (xy 429.382618 -134.458742) (xy 429.37479 -134.399286) (xy 429.3743 -134.369302)
			(xy 415.815272 -134.369302) (xy 415.815272 -134.377176) (xy 415.814782 -134.40716) (xy 415.806954 -134.466616)
			(xy 415.791433 -134.524541) (xy 415.768484 -134.579945) (xy 415.7385 -134.631879) (xy 415.701994 -134.679455)
			(xy 415.659589 -134.72186) (xy 415.612013 -134.758366) (xy 415.560079 -134.78835) (xy 415.504675 -134.811299)
			(xy 415.44675 -134.82682) (xy 415.387294 -134.834648) (xy 415.327326 -134.834648) (xy 415.26787 -134.82682)
			(xy 415.209945 -134.811299) (xy 415.154541 -134.78835) (xy 415.102607 -134.758366) (xy 415.055031 -134.72186)
			(xy 415.012626 -134.679455) (xy 414.97612 -134.631879) (xy 414.946136 -134.579945) (xy 414.923187 -134.524541)
			(xy 414.907666 -134.466616) (xy 414.899838 -134.40716) (xy 414.899348 -134.377176) (xy 402.854668 -134.377176)
			(xy 402.854668 -134.896352) (xy 402.854178 -134.92632) (xy 402.846355 -134.985742) (xy 402.830842 -135.043635)
			(xy 402.807906 -135.099008) (xy 402.777939 -135.150914) (xy 402.741452 -135.198464) (xy 402.699072 -135.240844)
			(xy 402.651522 -135.277331) (xy 402.599616 -135.307298) (xy 402.544243 -135.330234) (xy 402.48635 -135.345747)
			(xy 402.426928 -135.35357) (xy 402.366992 -135.35357) (xy 402.30757 -135.345747) (xy 402.249677 -135.330234)
			(xy 402.194304 -135.307298) (xy 402.142398 -135.277331) (xy 402.094848 -135.240844) (xy 402.052468 -135.198464)
			(xy 402.015981 -135.150914) (xy 401.986014 -135.099008) (xy 401.963078 -135.043635) (xy 401.947565 -134.985742)
			(xy 401.939742 -134.92632) (xy 401.939252 -134.896352) (xy 383.883408 -134.896352) (xy 383.883408 -134.897876)
			(xy 383.882918 -134.927844) (xy 383.875095 -134.987266) (xy 383.859582 -135.045159) (xy 383.836646 -135.100532)
			(xy 383.806679 -135.152438) (xy 383.770192 -135.199988) (xy 383.727812 -135.242368) (xy 383.680262 -135.278855)
			(xy 383.628356 -135.308822) (xy 383.572983 -135.331758) (xy 383.51509 -135.347271) (xy 383.455668 -135.355094)
			(xy 383.395732 -135.355094) (xy 383.33631 -135.347271) (xy 383.278417 -135.331758) (xy 383.223044 -135.308822)
			(xy 383.171138 -135.278855) (xy 383.123588 -135.242368) (xy 383.081208 -135.199988) (xy 383.044721 -135.152438)
			(xy 383.014754 -135.100532) (xy 382.991818 -135.045159) (xy 382.976305 -134.987266) (xy 382.968482 -134.927844)
			(xy 382.967992 -134.897876) (xy 316.568893 -134.897876) (xy 316.576928 -134.901204) (xy 316.628834 -134.931171)
			(xy 316.676384 -134.967658) (xy 316.718764 -135.010038) (xy 316.755251 -135.057588) (xy 316.785218 -135.109494)
			(xy 316.808154 -135.164867) (xy 316.823667 -135.22276) (xy 316.83149 -135.282182) (xy 316.83198 -135.31215)
			(xy 316.83198 -136.17575) (xy 316.83149 -136.205718) (xy 316.823667 -136.26514) (xy 316.808154 -136.323033)
			(xy 316.785218 -136.378406) (xy 316.755251 -136.430312) (xy 316.718764 -136.477862) (xy 316.676384 -136.520242)
			(xy 316.628834 -136.556729) (xy 316.576928 -136.586696) (xy 316.521555 -136.609632) (xy 316.463662 -136.625145)
			(xy 316.40424 -136.632968) (xy 316.344304 -136.632968) (xy 316.284882 -136.625145) (xy 316.226989 -136.609632)
			(xy 316.171616 -136.586696) (xy 316.11971 -136.556729) (xy 316.07216 -136.520242) (xy 316.02978 -136.477862)
			(xy 315.993293 -136.430312) (xy 315.963326 -136.378406) (xy 315.94039 -136.323033) (xy 315.924877 -136.26514)
			(xy 315.917054 -136.205718) (xy 315.916564 -136.17575) (xy 297.86072 -136.17575) (xy 297.86072 -136.177274)
			(xy 297.86023 -136.207242) (xy 297.852407 -136.266664) (xy 297.836894 -136.324557) (xy 297.813958 -136.37993)
			(xy 297.783991 -136.431836) (xy 297.747504 -136.479386) (xy 297.705124 -136.521766) (xy 297.657574 -136.558253)
			(xy 297.605668 -136.58822) (xy 297.550295 -136.611156) (xy 297.492402 -136.626669) (xy 297.43298 -136.634492)
			(xy 297.373044 -136.634492) (xy 297.313622 -136.626669) (xy 297.255729 -136.611156) (xy 297.200356 -136.58822)
			(xy 297.14845 -136.558253) (xy 297.1009 -136.521766) (xy 297.05852 -136.479386) (xy 297.022033 -136.431836)
			(xy 296.992066 -136.37993) (xy 296.96913 -136.324557) (xy 296.953617 -136.266664) (xy 296.945794 -136.207242)
			(xy 296.945304 -136.177274) (xy 284.900624 -136.177274) (xy 284.900624 -136.69645) (xy 284.900495 -136.704324)
			(xy 385.6101 -136.704324) (xy 385.6101 -135.840724) (xy 385.61059 -135.810756) (xy 385.618413 -135.751334)
			(xy 385.633926 -135.693441) (xy 385.656862 -135.638068) (xy 385.686829 -135.586162) (xy 385.723316 -135.538612)
			(xy 385.765696 -135.496232) (xy 385.813246 -135.459745) (xy 385.865152 -135.429778) (xy 385.920525 -135.406842)
			(xy 385.978418 -135.391329) (xy 386.03784 -135.383506) (xy 386.097776 -135.383506) (xy 386.157198 -135.391329)
			(xy 386.215091 -135.406842) (xy 386.270464 -135.429778) (xy 386.32237 -135.459745) (xy 386.36992 -135.496232)
			(xy 386.4123 -135.538612) (xy 386.448787 -135.586162) (xy 386.478754 -135.638068) (xy 386.50169 -135.693441)
			(xy 386.517203 -135.751334) (xy 386.525026 -135.810756) (xy 386.525516 -135.840724) (xy 386.525516 -136.69645)
			(xy 400.085052 -136.69645) (xy 400.085052 -135.83285) (xy 400.085542 -135.802882) (xy 400.093365 -135.74346)
			(xy 400.108878 -135.685567) (xy 400.131814 -135.630194) (xy 400.161781 -135.578288) (xy 400.198268 -135.530738)
			(xy 400.240648 -135.488358) (xy 400.288198 -135.451871) (xy 400.340104 -135.421904) (xy 400.395477 -135.398968)
			(xy 400.45337 -135.383455) (xy 400.512792 -135.375632) (xy 400.572728 -135.375632) (xy 400.63215 -135.383455)
			(xy 400.690043 -135.398968) (xy 400.745416 -135.421904) (xy 400.797322 -135.451871) (xy 400.844872 -135.488358)
			(xy 400.887252 -135.530738) (xy 400.923739 -135.578288) (xy 400.953706 -135.630194) (xy 400.976642 -135.685567)
			(xy 400.992155 -135.74346) (xy 400.999978 -135.802882) (xy 401.000468 -135.83285) (xy 401.000468 -136.177274)
			(xy 413.045148 -136.177274) (xy 413.045148 -135.313674) (xy 413.045638 -135.28369) (xy 413.053466 -135.224234)
			(xy 413.068987 -135.166309) (xy 413.091936 -135.110905) (xy 413.12192 -135.058971) (xy 413.158426 -135.011395)
			(xy 413.200831 -134.96899) (xy 413.248407 -134.932484) (xy 413.300341 -134.9025) (xy 413.355745 -134.879551)
			(xy 413.41367 -134.86403) (xy 413.473126 -134.856202) (xy 413.533094 -134.856202) (xy 413.59255 -134.86403)
			(xy 413.650475 -134.879551) (xy 413.705879 -134.9025) (xy 413.757813 -134.932484) (xy 413.805389 -134.96899)
			(xy 413.847794 -135.011395) (xy 413.8843 -135.058971) (xy 413.914284 -135.110905) (xy 413.937233 -135.166309)
			(xy 413.952754 -135.224234) (xy 413.960582 -135.28369) (xy 413.961072 -135.313674) (xy 413.961072 -136.17575)
			(xy 432.016408 -136.17575) (xy 432.016408 -135.31215) (xy 432.016898 -135.282166) (xy 432.024726 -135.22271)
			(xy 432.040247 -135.164785) (xy 432.063196 -135.109381) (xy 432.09318 -135.057447) (xy 432.129686 -135.009871)
			(xy 432.172091 -134.967466) (xy 432.219667 -134.93096) (xy 432.271601 -134.900976) (xy 432.327005 -134.878027)
			(xy 432.38493 -134.862506) (xy 432.444386 -134.854678) (xy 432.504354 -134.854678) (xy 432.56381 -134.862506)
			(xy 432.621735 -134.878027) (xy 432.677139 -134.900976) (xy 432.729073 -134.93096) (xy 432.776649 -134.967466)
			(xy 432.819054 -135.009871) (xy 432.85556 -135.057447) (xy 432.885544 -135.109381) (xy 432.908493 -135.164785)
			(xy 432.924014 -135.22271) (xy 432.931842 -135.282166) (xy 432.932332 -135.31215) (xy 432.932332 -136.17575)
			(xy 432.931842 -136.205734) (xy 432.924014 -136.26519) (xy 432.908493 -136.323115) (xy 432.885544 -136.378519)
			(xy 432.85556 -136.430453) (xy 432.819054 -136.478029) (xy 432.776649 -136.520434) (xy 432.729073 -136.55694)
			(xy 432.677139 -136.586924) (xy 432.621735 -136.609873) (xy 432.56381 -136.625394) (xy 432.504354 -136.633222)
			(xy 432.444386 -136.633222) (xy 432.38493 -136.625394) (xy 432.327005 -136.609873) (xy 432.271601 -136.586924)
			(xy 432.219667 -136.55694) (xy 432.172091 -136.520434) (xy 432.129686 -136.478029) (xy 432.09318 -136.430453)
			(xy 432.063196 -136.378519) (xy 432.040247 -136.323115) (xy 432.024726 -136.26519) (xy 432.016898 -136.205734)
			(xy 432.016408 -136.17575) (xy 413.961072 -136.17575) (xy 413.961072 -136.177274) (xy 413.960582 -136.207258)
			(xy 413.952754 -136.266714) (xy 413.937233 -136.324639) (xy 413.914284 -136.380043) (xy 413.8843 -136.431977)
			(xy 413.847794 -136.479553) (xy 413.805389 -136.521958) (xy 413.757813 -136.558464) (xy 413.705879 -136.588448)
			(xy 413.650475 -136.611397) (xy 413.59255 -136.626918) (xy 413.533094 -136.634746) (xy 413.473126 -136.634746)
			(xy 413.41367 -136.626918) (xy 413.355745 -136.611397) (xy 413.300341 -136.588448) (xy 413.248407 -136.558464)
			(xy 413.200831 -136.521958) (xy 413.158426 -136.479553) (xy 413.12192 -136.431977) (xy 413.091936 -136.380043)
			(xy 413.068987 -136.324639) (xy 413.053466 -136.266714) (xy 413.045638 -136.207258) (xy 413.045148 -136.177274)
			(xy 401.000468 -136.177274) (xy 401.000468 -136.69645) (xy 400.999978 -136.726418) (xy 400.992155 -136.78584)
			(xy 400.976642 -136.843733) (xy 400.953706 -136.899106) (xy 400.923739 -136.951012) (xy 400.887252 -136.998562)
			(xy 400.844872 -137.040942) (xy 400.797322 -137.077429) (xy 400.745416 -137.107396) (xy 400.690043 -137.130332)
			(xy 400.63215 -137.145845) (xy 400.572728 -137.153668) (xy 400.512792 -137.153668) (xy 400.45337 -137.145845)
			(xy 400.395477 -137.130332) (xy 400.340104 -137.107396) (xy 400.288198 -137.077429) (xy 400.240648 -137.040942)
			(xy 400.198268 -136.998562) (xy 400.161781 -136.951012) (xy 400.131814 -136.899106) (xy 400.108878 -136.843733)
			(xy 400.093365 -136.78584) (xy 400.085542 -136.726418) (xy 400.085052 -136.69645) (xy 386.525516 -136.69645)
			(xy 386.525516 -136.704324) (xy 386.525026 -136.734292) (xy 386.517203 -136.793714) (xy 386.50169 -136.851607)
			(xy 386.478754 -136.90698) (xy 386.448787 -136.958886) (xy 386.4123 -137.006436) (xy 386.36992 -137.048816)
			(xy 386.32237 -137.085303) (xy 386.270464 -137.11527) (xy 386.215091 -137.138206) (xy 386.157198 -137.153719)
			(xy 386.097776 -137.161542) (xy 386.03784 -137.161542) (xy 385.978418 -137.153719) (xy 385.920525 -137.138206)
			(xy 385.865152 -137.11527) (xy 385.813246 -137.085303) (xy 385.765696 -137.048816) (xy 385.723316 -137.006436)
			(xy 385.686829 -136.958886) (xy 385.656862 -136.90698) (xy 385.633926 -136.851607) (xy 385.618413 -136.793714)
			(xy 385.61059 -136.734292) (xy 385.6101 -136.704324) (xy 284.900495 -136.704324) (xy 284.900134 -136.726434)
			(xy 284.892306 -136.78589) (xy 284.876785 -136.843815) (xy 284.853836 -136.899219) (xy 284.823852 -136.951153)
			(xy 284.787346 -136.998729) (xy 284.744941 -137.041134) (xy 284.697365 -137.07764) (xy 284.645431 -137.107624)
			(xy 284.590027 -137.130573) (xy 284.532102 -137.146094) (xy 284.472646 -137.153922) (xy 284.412678 -137.153922)
			(xy 284.353222 -137.146094) (xy 284.295297 -137.130573) (xy 284.239893 -137.107624) (xy 284.187959 -137.07764)
			(xy 284.140383 -137.041134) (xy 284.097978 -136.998729) (xy 284.061472 -136.951153) (xy 284.031488 -136.899219)
			(xy 284.008539 -136.843815) (xy 283.993018 -136.78589) (xy 283.98519 -136.726434) (xy 283.9847 -136.69645)
			(xy 270.425672 -136.69645) (xy 270.425672 -136.704324) (xy 270.425182 -136.734308) (xy 270.417354 -136.793764)
			(xy 270.401833 -136.851689) (xy 270.378884 -136.907093) (xy 270.3489 -136.959027) (xy 270.312394 -137.006603)
			(xy 270.269989 -137.049008) (xy 270.222413 -137.085514) (xy 270.170479 -137.115498) (xy 270.115075 -137.138447)
			(xy 270.05715 -137.153968) (xy 269.997694 -137.161796) (xy 269.937726 -137.161796) (xy 269.87827 -137.153968)
			(xy 269.820345 -137.138447) (xy 269.764941 -137.115498) (xy 269.713007 -137.085514) (xy 269.665431 -137.049008)
			(xy 269.623026 -137.006603) (xy 269.58652 -136.959027) (xy 269.556536 -136.907093) (xy 269.533587 -136.851689)
			(xy 269.518066 -136.793764) (xy 269.510238 -136.734308) (xy 269.509748 -136.704324) (xy 168.800651 -136.704324)
			(xy 168.80029 -136.726434) (xy 168.792462 -136.78589) (xy 168.776941 -136.843815) (xy 168.753992 -136.899219)
			(xy 168.724008 -136.951153) (xy 168.687502 -136.998729) (xy 168.645097 -137.041134) (xy 168.597521 -137.07764)
			(xy 168.545587 -137.107624) (xy 168.490183 -137.130573) (xy 168.432258 -137.146094) (xy 168.372802 -137.153922)
			(xy 168.312834 -137.153922) (xy 168.253378 -137.146094) (xy 168.195453 -137.130573) (xy 168.140049 -137.107624)
			(xy 168.088115 -137.07764) (xy 168.040539 -137.041134) (xy 167.998134 -136.998729) (xy 167.961628 -136.951153)
			(xy 167.931644 -136.899219) (xy 167.908695 -136.843815) (xy 167.893174 -136.78589) (xy 167.885346 -136.726434)
			(xy 167.884856 -136.69645) (xy 154.325828 -136.69645) (xy 154.325828 -136.704324) (xy 154.325338 -136.734308)
			(xy 154.31751 -136.793764) (xy 154.301989 -136.851689) (xy 154.27904 -136.907093) (xy 154.249056 -136.959027)
			(xy 154.21255 -137.006603) (xy 154.170145 -137.049008) (xy 154.122569 -137.085514) (xy 154.070635 -137.115498)
			(xy 154.015231 -137.138447) (xy 153.957306 -137.153968) (xy 153.89785 -137.161796) (xy 153.837882 -137.161796)
			(xy 153.778426 -137.153968) (xy 153.720501 -137.138447) (xy 153.665097 -137.115498) (xy 153.613163 -137.085514)
			(xy 153.565587 -137.049008) (xy 153.523182 -137.006603) (xy 153.486676 -136.959027) (xy 153.456692 -136.907093)
			(xy 153.433743 -136.851689) (xy 153.418222 -136.793764) (xy 153.410394 -136.734308) (xy 153.409904 -136.704324)
			(xy 52.700299 -136.704324) (xy 52.699938 -136.726418) (xy 52.692115 -136.78584) (xy 52.676602 -136.843733)
			(xy 52.653666 -136.899106) (xy 52.623699 -136.951012) (xy 52.587212 -136.998562) (xy 52.544832 -137.040942)
			(xy 52.497282 -137.077429) (xy 52.445376 -137.107396) (xy 52.390003 -137.130332) (xy 52.33211 -137.145845)
			(xy 52.272688 -137.153668) (xy 52.212752 -137.153668) (xy 52.15333 -137.145845) (xy 52.095437 -137.130332)
			(xy 52.040064 -137.107396) (xy 51.988158 -137.077429) (xy 51.940608 -137.040942) (xy 51.898228 -136.998562)
			(xy 51.861741 -136.951012) (xy 51.831774 -136.899106) (xy 51.808838 -136.843733) (xy 51.793325 -136.78584)
			(xy 51.785502 -136.726418) (xy 51.785012 -136.69645) (xy 38.225476 -136.69645) (xy 38.225476 -136.704324)
			(xy 38.224986 -136.734292) (xy 38.217163 -136.793714) (xy 38.20165 -136.851607) (xy 38.178714 -136.90698)
			(xy 38.148747 -136.958886) (xy 38.11226 -137.006436) (xy 38.06988 -137.048816) (xy 38.02233 -137.085303)
			(xy 37.970424 -137.11527) (xy 37.915051 -137.138206) (xy 37.857158 -137.153719) (xy 37.797736 -137.161542)
			(xy 37.7378 -137.161542) (xy 37.678378 -137.153719) (xy 37.620485 -137.138206) (xy 37.565112 -137.11527)
			(xy 37.513206 -137.085303) (xy 37.465656 -137.048816) (xy 37.423276 -137.006436) (xy 37.386789 -136.958886)
			(xy 37.356822 -136.90698) (xy 37.333886 -136.851607) (xy 37.318373 -136.793714) (xy 37.31055 -136.734292)
			(xy 37.31006 -136.704324) (xy 4.308094 -136.704324) (xy 4.308094 -138.496548) (xy 43.97248 -138.496548)
			(xy 43.97248 -137.632948) (xy 43.97297 -137.602964) (xy 43.980798 -137.543508) (xy 43.996319 -137.485583)
			(xy 44.019268 -137.430179) (xy 44.049252 -137.378245) (xy 44.085758 -137.330669) (xy 44.128163 -137.288264)
			(xy 44.175739 -137.251758) (xy 44.227673 -137.221774) (xy 44.283077 -137.198825) (xy 44.341002 -137.183304)
			(xy 44.400458 -137.175476) (xy 44.460426 -137.175476) (xy 44.519882 -137.183304) (xy 44.577807 -137.198825)
			(xy 44.633211 -137.221774) (xy 44.685145 -137.251758) (xy 44.732721 -137.288264) (xy 44.775126 -137.330669)
			(xy 44.811632 -137.378245) (xy 44.841616 -137.430179) (xy 44.864565 -137.485583) (xy 44.880086 -137.543508)
			(xy 44.887914 -137.602964) (xy 44.888404 -137.632948) (xy 44.888404 -138.496548) (xy 160.072324 -138.496548)
			(xy 160.072324 -137.632948) (xy 160.072814 -137.602964) (xy 160.080642 -137.543508) (xy 160.096163 -137.485583)
			(xy 160.119112 -137.430179) (xy 160.149096 -137.378245) (xy 160.185602 -137.330669) (xy 160.228007 -137.288264)
			(xy 160.275583 -137.251758) (xy 160.327517 -137.221774) (xy 160.382921 -137.198825) (xy 160.440846 -137.183304)
			(xy 160.500302 -137.175476) (xy 160.56027 -137.175476) (xy 160.619726 -137.183304) (xy 160.677651 -137.198825)
			(xy 160.733055 -137.221774) (xy 160.784989 -137.251758) (xy 160.832565 -137.288264) (xy 160.87497 -137.330669)
			(xy 160.911476 -137.378245) (xy 160.94146 -137.430179) (xy 160.964409 -137.485583) (xy 160.97993 -137.543508)
			(xy 160.987758 -137.602964) (xy 160.988248 -137.632948) (xy 160.988248 -138.496548) (xy 276.172676 -138.496548)
			(xy 276.172676 -137.632948) (xy 276.173166 -137.60298) (xy 276.180989 -137.543558) (xy 276.196502 -137.485665)
			(xy 276.219438 -137.430292) (xy 276.249405 -137.378386) (xy 276.285892 -137.330836) (xy 276.328272 -137.288456)
			(xy 276.375822 -137.251969) (xy 276.427728 -137.222002) (xy 276.483101 -137.199066) (xy 276.540994 -137.183553)
			(xy 276.600416 -137.17573) (xy 276.660352 -137.17573) (xy 276.719774 -137.183553) (xy 276.777667 -137.199066)
			(xy 276.83304 -137.222002) (xy 276.884946 -137.251969) (xy 276.932496 -137.288456) (xy 276.974876 -137.330836)
			(xy 277.011363 -137.378386) (xy 277.04133 -137.430292) (xy 277.064266 -137.485665) (xy 277.079779 -137.543558)
			(xy 277.087602 -137.60298) (xy 277.088092 -137.632948) (xy 277.088092 -138.496548) (xy 277.088084 -138.497056)
			(xy 392.27252 -138.497056) (xy 392.27252 -137.633456) (xy 392.27301 -137.603472) (xy 392.280838 -137.544016)
			(xy 392.296359 -137.486091) (xy 392.319308 -137.430687) (xy 392.349292 -137.378753) (xy 392.385798 -137.331177)
			(xy 392.428203 -137.288772) (xy 392.475779 -137.252266) (xy 392.527713 -137.222282) (xy 392.583117 -137.199333)
			(xy 392.641042 -137.183812) (xy 392.700498 -137.175984) (xy 392.760466 -137.175984) (xy 392.819922 -137.183812)
			(xy 392.877847 -137.199333) (xy 392.933251 -137.222282) (xy 392.985185 -137.252266) (xy 393.032761 -137.288772)
			(xy 393.075166 -137.331177) (xy 393.111672 -137.378753) (xy 393.141656 -137.430687) (xy 393.164605 -137.486091)
			(xy 393.180126 -137.544016) (xy 393.187954 -137.603472) (xy 393.188444 -137.633456) (xy 393.188444 -138.497056)
			(xy 393.187954 -138.52704) (xy 393.180126 -138.586496) (xy 393.164605 -138.644421) (xy 393.141656 -138.699825)
			(xy 393.111672 -138.751759) (xy 393.075166 -138.799335) (xy 393.032761 -138.84174) (xy 392.985185 -138.878246)
			(xy 392.933251 -138.90823) (xy 392.877847 -138.931179) (xy 392.819922 -138.9467) (xy 392.760466 -138.954528)
			(xy 392.700498 -138.954528) (xy 392.641042 -138.9467) (xy 392.583117 -138.931179) (xy 392.527713 -138.90823)
			(xy 392.475779 -138.878246) (xy 392.428203 -138.84174) (xy 392.385798 -138.799335) (xy 392.349292 -138.751759)
			(xy 392.319308 -138.699825) (xy 392.296359 -138.644421) (xy 392.280838 -138.586496) (xy 392.27301 -138.52704)
			(xy 392.27252 -138.497056) (xy 277.088084 -138.497056) (xy 277.087602 -138.526516) (xy 277.079779 -138.585938)
			(xy 277.064266 -138.643831) (xy 277.04133 -138.699204) (xy 277.011363 -138.75111) (xy 276.974876 -138.79866)
			(xy 276.932496 -138.84104) (xy 276.884946 -138.877527) (xy 276.83304 -138.907494) (xy 276.777667 -138.93043)
			(xy 276.719774 -138.945943) (xy 276.660352 -138.953766) (xy 276.600416 -138.953766) (xy 276.540994 -138.945943)
			(xy 276.483101 -138.93043) (xy 276.427728 -138.907494) (xy 276.375822 -138.877527) (xy 276.328272 -138.84104)
			(xy 276.285892 -138.79866) (xy 276.249405 -138.75111) (xy 276.219438 -138.699204) (xy 276.196502 -138.643831)
			(xy 276.180989 -138.585938) (xy 276.173166 -138.526516) (xy 276.172676 -138.496548) (xy 160.988248 -138.496548)
			(xy 160.987758 -138.526532) (xy 160.97993 -138.585988) (xy 160.964409 -138.643913) (xy 160.94146 -138.699317)
			(xy 160.911476 -138.751251) (xy 160.87497 -138.798827) (xy 160.832565 -138.841232) (xy 160.784989 -138.877738)
			(xy 160.733055 -138.907722) (xy 160.677651 -138.930671) (xy 160.619726 -138.946192) (xy 160.56027 -138.95402)
			(xy 160.500302 -138.95402) (xy 160.440846 -138.946192) (xy 160.382921 -138.930671) (xy 160.327517 -138.907722)
			(xy 160.275583 -138.877738) (xy 160.228007 -138.841232) (xy 160.185602 -138.798827) (xy 160.149096 -138.751251)
			(xy 160.119112 -138.699317) (xy 160.096163 -138.643913) (xy 160.080642 -138.585988) (xy 160.072814 -138.526532)
			(xy 160.072324 -138.496548) (xy 44.888404 -138.496548) (xy 44.887914 -138.526532) (xy 44.880086 -138.585988)
			(xy 44.864565 -138.643913) (xy 44.841616 -138.699317) (xy 44.811632 -138.751251) (xy 44.775126 -138.798827)
			(xy 44.732721 -138.841232) (xy 44.685145 -138.877738) (xy 44.633211 -138.907722) (xy 44.577807 -138.930671)
			(xy 44.519882 -138.946192) (xy 44.460426 -138.95402) (xy 44.400458 -138.95402) (xy 44.341002 -138.946192)
			(xy 44.283077 -138.930671) (xy 44.227673 -138.907722) (xy 44.175739 -138.877738) (xy 44.128163 -138.841232)
			(xy 44.085758 -138.798827) (xy 44.049252 -138.751251) (xy 44.019268 -138.699317) (xy 43.996319 -138.643913)
			(xy 43.980798 -138.585988) (xy 43.97297 -138.526532) (xy 43.97248 -138.496548) (xy 4.308094 -138.496548)
			(xy 4.308094 -143.48714) (xy 66.599308 -143.48714) (xy 66.599308 -142.62354) (xy 66.599798 -142.593556)
			(xy 66.607626 -142.5341) (xy 66.623147 -142.476175) (xy 66.646096 -142.420771) (xy 66.67608 -142.368837)
			(xy 66.712586 -142.321261) (xy 66.754991 -142.278856) (xy 66.802567 -142.24235) (xy 66.854501 -142.212366)
			(xy 66.909905 -142.189417) (xy 66.96783 -142.173896) (xy 67.027286 -142.166068) (xy 67.087254 -142.166068)
			(xy 67.14671 -142.173896) (xy 67.204635 -142.189417) (xy 67.260039 -142.212366) (xy 67.311973 -142.24235)
			(xy 67.359549 -142.278856) (xy 67.401954 -142.321261) (xy 67.43846 -142.368837) (xy 67.468444 -142.420771)
			(xy 67.491393 -142.476175) (xy 67.506914 -142.5341) (xy 67.514742 -142.593556) (xy 67.515232 -142.62354)
			(xy 67.515232 -143.479266) (xy 81.07426 -143.479266) (xy 81.07426 -142.615666) (xy 81.07475 -142.585682)
			(xy 81.082578 -142.526226) (xy 81.098099 -142.468301) (xy 81.121048 -142.412897) (xy 81.151032 -142.360963)
			(xy 81.187538 -142.313387) (xy 81.229943 -142.270982) (xy 81.277519 -142.234476) (xy 81.329453 -142.204492)
			(xy 81.384857 -142.181543) (xy 81.442782 -142.166022) (xy 81.502238 -142.158194) (xy 81.562206 -142.158194)
			(xy 81.621662 -142.166022) (xy 81.679587 -142.181543) (xy 81.734991 -142.204492) (xy 81.786925 -142.234476)
			(xy 81.834501 -142.270982) (xy 81.876906 -142.313387) (xy 81.913412 -142.360963) (xy 81.943396 -142.412897)
			(xy 81.966345 -142.468301) (xy 81.981866 -142.526226) (xy 81.989694 -142.585682) (xy 81.990184 -142.615666)
			(xy 81.990184 -143.479266) (xy 81.990055 -143.48714) (xy 182.69966 -143.48714) (xy 182.69966 -142.62354)
			(xy 182.70015 -142.593572) (xy 182.707973 -142.53415) (xy 182.723486 -142.476257) (xy 182.746422 -142.420884)
			(xy 182.776389 -142.368978) (xy 182.812876 -142.321428) (xy 182.855256 -142.279048) (xy 182.902806 -142.242561)
			(xy 182.954712 -142.212594) (xy 183.010085 -142.189658) (xy 183.067978 -142.174145) (xy 183.1274 -142.166322)
			(xy 183.187336 -142.166322) (xy 183.246758 -142.174145) (xy 183.304651 -142.189658) (xy 183.360024 -142.212594)
			(xy 183.41193 -142.242561) (xy 183.45948 -142.279048) (xy 183.50186 -142.321428) (xy 183.538347 -142.368978)
			(xy 183.568314 -142.420884) (xy 183.59125 -142.476257) (xy 183.606763 -142.53415) (xy 183.614586 -142.593572)
			(xy 183.615076 -142.62354) (xy 183.615076 -143.479266) (xy 197.174612 -143.479266) (xy 197.174612 -142.615666)
			(xy 197.175102 -142.585698) (xy 197.182925 -142.526276) (xy 197.198438 -142.468383) (xy 197.221374 -142.41301)
			(xy 197.251341 -142.361104) (xy 197.287828 -142.313554) (xy 197.330208 -142.271174) (xy 197.377758 -142.234687)
			(xy 197.429664 -142.20472) (xy 197.485037 -142.181784) (xy 197.54293 -142.166271) (xy 197.602352 -142.158448)
			(xy 197.662288 -142.158448) (xy 197.72171 -142.166271) (xy 197.779603 -142.181784) (xy 197.834976 -142.20472)
			(xy 197.886882 -142.234687) (xy 197.934432 -142.271174) (xy 197.976812 -142.313554) (xy 198.013299 -142.361104)
			(xy 198.043266 -142.41301) (xy 198.066202 -142.468383) (xy 198.081715 -142.526276) (xy 198.089538 -142.585698)
			(xy 198.090028 -142.615666) (xy 198.090028 -143.479266) (xy 198.089899 -143.48714) (xy 298.799504 -143.48714)
			(xy 298.799504 -142.62354) (xy 298.799994 -142.593572) (xy 298.807817 -142.53415) (xy 298.82333 -142.476257)
			(xy 298.846266 -142.420884) (xy 298.876233 -142.368978) (xy 298.91272 -142.321428) (xy 298.9551 -142.279048)
			(xy 299.00265 -142.242561) (xy 299.054556 -142.212594) (xy 299.109929 -142.189658) (xy 299.167822 -142.174145)
			(xy 299.227244 -142.166322) (xy 299.28718 -142.166322) (xy 299.346602 -142.174145) (xy 299.404495 -142.189658)
			(xy 299.459868 -142.212594) (xy 299.511774 -142.242561) (xy 299.559324 -142.279048) (xy 299.601704 -142.321428)
			(xy 299.638191 -142.368978) (xy 299.668158 -142.420884) (xy 299.691094 -142.476257) (xy 299.706607 -142.53415)
			(xy 299.71443 -142.593572) (xy 299.71492 -142.62354) (xy 299.71492 -143.479266) (xy 313.274456 -143.479266)
			(xy 313.274456 -142.615666) (xy 313.274946 -142.585698) (xy 313.282769 -142.526276) (xy 313.298282 -142.468383)
			(xy 313.321218 -142.41301) (xy 313.351185 -142.361104) (xy 313.387672 -142.313554) (xy 313.430052 -142.271174)
			(xy 313.477602 -142.234687) (xy 313.529508 -142.20472) (xy 313.584881 -142.181784) (xy 313.642774 -142.166271)
			(xy 313.702196 -142.158448) (xy 313.762132 -142.158448) (xy 313.821554 -142.166271) (xy 313.879447 -142.181784)
			(xy 313.93482 -142.20472) (xy 313.986726 -142.234687) (xy 314.034276 -142.271174) (xy 314.076656 -142.313554)
			(xy 314.113143 -142.361104) (xy 314.14311 -142.41301) (xy 314.166046 -142.468383) (xy 314.181559 -142.526276)
			(xy 314.189382 -142.585698) (xy 314.189872 -142.615666) (xy 314.189872 -143.479266) (xy 314.189743 -143.48714)
			(xy 414.899348 -143.48714) (xy 414.899348 -142.62354) (xy 414.899838 -142.593556) (xy 414.907666 -142.5341)
			(xy 414.923187 -142.476175) (xy 414.946136 -142.420771) (xy 414.97612 -142.368837) (xy 415.012626 -142.321261)
			(xy 415.055031 -142.278856) (xy 415.102607 -142.24235) (xy 415.154541 -142.212366) (xy 415.209945 -142.189417)
			(xy 415.26787 -142.173896) (xy 415.327326 -142.166068) (xy 415.387294 -142.166068) (xy 415.44675 -142.173896)
			(xy 415.504675 -142.189417) (xy 415.560079 -142.212366) (xy 415.612013 -142.24235) (xy 415.659589 -142.278856)
			(xy 415.701994 -142.321261) (xy 415.7385 -142.368837) (xy 415.768484 -142.420771) (xy 415.791433 -142.476175)
			(xy 415.806954 -142.5341) (xy 415.814782 -142.593556) (xy 415.815272 -142.62354) (xy 415.815272 -143.479266)
			(xy 429.3743 -143.479266) (xy 429.3743 -142.615666) (xy 429.37479 -142.585682) (xy 429.382618 -142.526226)
			(xy 429.398139 -142.468301) (xy 429.421088 -142.412897) (xy 429.451072 -142.360963) (xy 429.487578 -142.313387)
			(xy 429.529983 -142.270982) (xy 429.577559 -142.234476) (xy 429.629493 -142.204492) (xy 429.684897 -142.181543)
			(xy 429.742822 -142.166022) (xy 429.802278 -142.158194) (xy 429.862246 -142.158194) (xy 429.921702 -142.166022)
			(xy 429.979627 -142.181543) (xy 430.035031 -142.204492) (xy 430.086965 -142.234476) (xy 430.134541 -142.270982)
			(xy 430.176946 -142.313387) (xy 430.213452 -142.360963) (xy 430.243436 -142.412897) (xy 430.266385 -142.468301)
			(xy 430.281906 -142.526226) (xy 430.289734 -142.585682) (xy 430.290224 -142.615666) (xy 430.290224 -143.479266)
			(xy 430.289734 -143.50925) (xy 430.281906 -143.568706) (xy 430.266385 -143.626631) (xy 430.243436 -143.682035)
			(xy 430.213452 -143.733969) (xy 430.176946 -143.781545) (xy 430.134541 -143.82395) (xy 430.086965 -143.860456)
			(xy 430.035031 -143.89044) (xy 429.979627 -143.913389) (xy 429.921702 -143.92891) (xy 429.862246 -143.936738)
			(xy 429.802278 -143.936738) (xy 429.742822 -143.92891) (xy 429.684897 -143.913389) (xy 429.629493 -143.89044)
			(xy 429.577559 -143.860456) (xy 429.529983 -143.82395) (xy 429.487578 -143.781545) (xy 429.451072 -143.733969)
			(xy 429.421088 -143.682035) (xy 429.398139 -143.626631) (xy 429.382618 -143.568706) (xy 429.37479 -143.50925)
			(xy 429.3743 -143.479266) (xy 415.815272 -143.479266) (xy 415.815272 -143.48714) (xy 415.814782 -143.517124)
			(xy 415.806954 -143.57658) (xy 415.791433 -143.634505) (xy 415.768484 -143.689909) (xy 415.7385 -143.741843)
			(xy 415.701994 -143.789419) (xy 415.659589 -143.831824) (xy 415.612013 -143.86833) (xy 415.560079 -143.898314)
			(xy 415.504675 -143.921263) (xy 415.44675 -143.936784) (xy 415.387294 -143.944612) (xy 415.327326 -143.944612)
			(xy 415.26787 -143.936784) (xy 415.209945 -143.921263) (xy 415.154541 -143.898314) (xy 415.102607 -143.86833)
			(xy 415.055031 -143.831824) (xy 415.012626 -143.789419) (xy 414.97612 -143.741843) (xy 414.946136 -143.689909)
			(xy 414.923187 -143.634505) (xy 414.907666 -143.57658) (xy 414.899838 -143.517124) (xy 414.899348 -143.48714)
			(xy 314.189743 -143.48714) (xy 314.189382 -143.509234) (xy 314.181559 -143.568656) (xy 314.166046 -143.626549)
			(xy 314.14311 -143.681922) (xy 314.113143 -143.733828) (xy 314.076656 -143.781378) (xy 314.034276 -143.823758)
			(xy 313.986726 -143.860245) (xy 313.93482 -143.890212) (xy 313.879447 -143.913148) (xy 313.821554 -143.928661)
			(xy 313.762132 -143.936484) (xy 313.702196 -143.936484) (xy 313.642774 -143.928661) (xy 313.584881 -143.913148)
			(xy 313.529508 -143.890212) (xy 313.477602 -143.860245) (xy 313.430052 -143.823758) (xy 313.387672 -143.781378)
			(xy 313.351185 -143.733828) (xy 313.321218 -143.681922) (xy 313.298282 -143.626549) (xy 313.282769 -143.568656)
			(xy 313.274946 -143.509234) (xy 313.274456 -143.479266) (xy 299.71492 -143.479266) (xy 299.71492 -143.48714)
			(xy 299.71443 -143.517108) (xy 299.706607 -143.57653) (xy 299.691094 -143.634423) (xy 299.668158 -143.689796)
			(xy 299.638191 -143.741702) (xy 299.601704 -143.789252) (xy 299.559324 -143.831632) (xy 299.511774 -143.868119)
			(xy 299.459868 -143.898086) (xy 299.404495 -143.921022) (xy 299.346602 -143.936535) (xy 299.28718 -143.944358)
			(xy 299.227244 -143.944358) (xy 299.167822 -143.936535) (xy 299.109929 -143.921022) (xy 299.054556 -143.898086)
			(xy 299.00265 -143.868119) (xy 298.9551 -143.831632) (xy 298.91272 -143.789252) (xy 298.876233 -143.741702)
			(xy 298.846266 -143.689796) (xy 298.82333 -143.634423) (xy 298.807817 -143.57653) (xy 298.799994 -143.517108)
			(xy 298.799504 -143.48714) (xy 198.089899 -143.48714) (xy 198.089538 -143.509234) (xy 198.081715 -143.568656)
			(xy 198.066202 -143.626549) (xy 198.043266 -143.681922) (xy 198.013299 -143.733828) (xy 197.976812 -143.781378)
			(xy 197.934432 -143.823758) (xy 197.886882 -143.860245) (xy 197.834976 -143.890212) (xy 197.779603 -143.913148)
			(xy 197.72171 -143.928661) (xy 197.662288 -143.936484) (xy 197.602352 -143.936484) (xy 197.54293 -143.928661)
			(xy 197.485037 -143.913148) (xy 197.429664 -143.890212) (xy 197.377758 -143.860245) (xy 197.330208 -143.823758)
			(xy 197.287828 -143.781378) (xy 197.251341 -143.733828) (xy 197.221374 -143.681922) (xy 197.198438 -143.626549)
			(xy 197.182925 -143.568656) (xy 197.175102 -143.509234) (xy 197.174612 -143.479266) (xy 183.615076 -143.479266)
			(xy 183.615076 -143.48714) (xy 183.614586 -143.517108) (xy 183.606763 -143.57653) (xy 183.59125 -143.634423)
			(xy 183.568314 -143.689796) (xy 183.538347 -143.741702) (xy 183.50186 -143.789252) (xy 183.45948 -143.831632)
			(xy 183.41193 -143.868119) (xy 183.360024 -143.898086) (xy 183.304651 -143.921022) (xy 183.246758 -143.936535)
			(xy 183.187336 -143.944358) (xy 183.1274 -143.944358) (xy 183.067978 -143.936535) (xy 183.010085 -143.921022)
			(xy 182.954712 -143.898086) (xy 182.902806 -143.868119) (xy 182.855256 -143.831632) (xy 182.812876 -143.789252)
			(xy 182.776389 -143.741702) (xy 182.746422 -143.689796) (xy 182.723486 -143.634423) (xy 182.707973 -143.57653)
			(xy 182.70015 -143.517108) (xy 182.69966 -143.48714) (xy 81.990055 -143.48714) (xy 81.989694 -143.50925)
			(xy 81.981866 -143.568706) (xy 81.966345 -143.626631) (xy 81.943396 -143.682035) (xy 81.913412 -143.733969)
			(xy 81.876906 -143.781545) (xy 81.834501 -143.82395) (xy 81.786925 -143.860456) (xy 81.734991 -143.89044)
			(xy 81.679587 -143.913389) (xy 81.621662 -143.92891) (xy 81.562206 -143.936738) (xy 81.502238 -143.936738)
			(xy 81.442782 -143.92891) (xy 81.384857 -143.913389) (xy 81.329453 -143.89044) (xy 81.277519 -143.860456)
			(xy 81.229943 -143.82395) (xy 81.187538 -143.781545) (xy 81.151032 -143.733969) (xy 81.121048 -143.682035)
			(xy 81.098099 -143.626631) (xy 81.082578 -143.568706) (xy 81.07475 -143.50925) (xy 81.07426 -143.479266)
			(xy 67.515232 -143.479266) (xy 67.515232 -143.48714) (xy 67.514742 -143.517124) (xy 67.506914 -143.57658)
			(xy 67.491393 -143.634505) (xy 67.468444 -143.689909) (xy 67.43846 -143.741843) (xy 67.401954 -143.789419)
			(xy 67.359549 -143.831824) (xy 67.311973 -143.86833) (xy 67.260039 -143.898314) (xy 67.204635 -143.921263)
			(xy 67.14671 -143.936784) (xy 67.087254 -143.944612) (xy 67.027286 -143.944612) (xy 66.96783 -143.936784)
			(xy 66.909905 -143.921263) (xy 66.854501 -143.898314) (xy 66.802567 -143.86833) (xy 66.754991 -143.831824)
			(xy 66.712586 -143.789419) (xy 66.67608 -143.741843) (xy 66.646096 -143.689909) (xy 66.623147 -143.634505)
			(xy 66.607626 -143.57658) (xy 66.599798 -143.517124) (xy 66.599308 -143.48714) (xy 4.308094 -143.48714)
			(xy 4.308094 -145.287238) (xy 64.745108 -145.287238) (xy 64.745108 -144.423638) (xy 64.745598 -144.393654)
			(xy 64.753426 -144.334198) (xy 64.768947 -144.276273) (xy 64.791896 -144.220869) (xy 64.82188 -144.168935)
			(xy 64.858386 -144.121359) (xy 64.900791 -144.078954) (xy 64.948367 -144.042448) (xy 65.000301 -144.012464)
			(xy 65.055705 -143.989515) (xy 65.11363 -143.973994) (xy 65.173086 -143.966166) (xy 65.233054 -143.966166)
			(xy 65.29251 -143.973994) (xy 65.350435 -143.989515) (xy 65.405839 -144.012464) (xy 65.457773 -144.042448)
			(xy 65.505349 -144.078954) (xy 65.547754 -144.121359) (xy 65.58426 -144.168935) (xy 65.614244 -144.220869)
			(xy 65.637193 -144.276273) (xy 65.652714 -144.334198) (xy 65.660542 -144.393654) (xy 65.661032 -144.423638)
			(xy 65.661032 -145.285714) (xy 83.716368 -145.285714) (xy 83.716368 -144.422114) (xy 83.716858 -144.39213)
			(xy 83.724686 -144.332674) (xy 83.740207 -144.274749) (xy 83.763156 -144.219345) (xy 83.79314 -144.167411)
			(xy 83.829646 -144.119835) (xy 83.872051 -144.07743) (xy 83.919627 -144.040924) (xy 83.971561 -144.01094)
			(xy 84.026965 -143.987991) (xy 84.08489 -143.97247) (xy 84.144346 -143.964642) (xy 84.204314 -143.964642)
			(xy 84.26377 -143.97247) (xy 84.321695 -143.987991) (xy 84.377099 -144.01094) (xy 84.429033 -144.040924)
			(xy 84.476609 -144.07743) (xy 84.519014 -144.119835) (xy 84.55552 -144.167411) (xy 84.585504 -144.219345)
			(xy 84.608453 -144.274749) (xy 84.623974 -144.332674) (xy 84.631802 -144.39213) (xy 84.632292 -144.422114)
			(xy 84.632292 -145.285714) (xy 84.632267 -145.287238) (xy 180.84546 -145.287238) (xy 180.84546 -144.423638)
			(xy 180.84595 -144.39367) (xy 180.853773 -144.334248) (xy 180.869286 -144.276355) (xy 180.892222 -144.220982)
			(xy 180.922189 -144.169076) (xy 180.958676 -144.121526) (xy 181.001056 -144.079146) (xy 181.048606 -144.042659)
			(xy 181.100512 -144.012692) (xy 181.155885 -143.989756) (xy 181.213778 -143.974243) (xy 181.2732 -143.96642)
			(xy 181.333136 -143.96642) (xy 181.392558 -143.974243) (xy 181.450451 -143.989756) (xy 181.505824 -144.012692)
			(xy 181.55773 -144.042659) (xy 181.60528 -144.079146) (xy 181.64766 -144.121526) (xy 181.684147 -144.169076)
			(xy 181.714114 -144.220982) (xy 181.73705 -144.276355) (xy 181.752563 -144.334248) (xy 181.760386 -144.39367)
			(xy 181.760876 -144.423638) (xy 181.760876 -145.285714) (xy 199.81672 -145.285714) (xy 199.81672 -144.422114)
			(xy 199.81721 -144.392146) (xy 199.825033 -144.332724) (xy 199.840546 -144.274831) (xy 199.863482 -144.219458)
			(xy 199.893449 -144.167552) (xy 199.929936 -144.120002) (xy 199.972316 -144.077622) (xy 200.019866 -144.041135)
			(xy 200.071772 -144.011168) (xy 200.127145 -143.988232) (xy 200.185038 -143.972719) (xy 200.24446 -143.964896)
			(xy 200.304396 -143.964896) (xy 200.363818 -143.972719) (xy 200.421711 -143.988232) (xy 200.477084 -144.011168)
			(xy 200.52899 -144.041135) (xy 200.57654 -144.077622) (xy 200.61892 -144.120002) (xy 200.655407 -144.167552)
			(xy 200.685374 -144.219458) (xy 200.70831 -144.274831) (xy 200.723823 -144.332724) (xy 200.731646 -144.392146)
			(xy 200.732136 -144.422114) (xy 200.732136 -145.285714) (xy 200.732111 -145.287238) (xy 296.945304 -145.287238)
			(xy 296.945304 -144.423638) (xy 296.945794 -144.39367) (xy 296.953617 -144.334248) (xy 296.96913 -144.276355)
			(xy 296.992066 -144.220982) (xy 297.022033 -144.169076) (xy 297.05852 -144.121526) (xy 297.1009 -144.079146)
			(xy 297.14845 -144.042659) (xy 297.200356 -144.012692) (xy 297.255729 -143.989756) (xy 297.313622 -143.974243)
			(xy 297.373044 -143.96642) (xy 297.43298 -143.96642) (xy 297.492402 -143.974243) (xy 297.550295 -143.989756)
			(xy 297.605668 -144.012692) (xy 297.657574 -144.042659) (xy 297.705124 -144.079146) (xy 297.747504 -144.121526)
			(xy 297.783991 -144.169076) (xy 297.813958 -144.220982) (xy 297.836894 -144.276355) (xy 297.852407 -144.334248)
			(xy 297.86023 -144.39367) (xy 297.86072 -144.423638) (xy 297.86072 -145.285714) (xy 315.916564 -145.285714)
			(xy 315.916564 -144.422114) (xy 315.917054 -144.392146) (xy 315.924877 -144.332724) (xy 315.94039 -144.274831)
			(xy 315.963326 -144.219458) (xy 315.993293 -144.167552) (xy 316.02978 -144.120002) (xy 316.07216 -144.077622)
			(xy 316.11971 -144.041135) (xy 316.171616 -144.011168) (xy 316.226989 -143.988232) (xy 316.284882 -143.972719)
			(xy 316.344304 -143.964896) (xy 316.40424 -143.964896) (xy 316.463662 -143.972719) (xy 316.521555 -143.988232)
			(xy 316.576928 -144.011168) (xy 316.628834 -144.041135) (xy 316.676384 -144.077622) (xy 316.718764 -144.120002)
			(xy 316.755251 -144.167552) (xy 316.785218 -144.219458) (xy 316.808154 -144.274831) (xy 316.823667 -144.332724)
			(xy 316.83149 -144.392146) (xy 316.83198 -144.422114) (xy 316.83198 -145.285714) (xy 316.831955 -145.287238)
			(xy 413.045148 -145.287238) (xy 413.045148 -144.423638) (xy 413.045638 -144.393654) (xy 413.053466 -144.334198)
			(xy 413.068987 -144.276273) (xy 413.091936 -144.220869) (xy 413.12192 -144.168935) (xy 413.158426 -144.121359)
			(xy 413.200831 -144.078954) (xy 413.248407 -144.042448) (xy 413.300341 -144.012464) (xy 413.355745 -143.989515)
			(xy 413.41367 -143.973994) (xy 413.473126 -143.966166) (xy 413.533094 -143.966166) (xy 413.59255 -143.973994)
			(xy 413.650475 -143.989515) (xy 413.705879 -144.012464) (xy 413.757813 -144.042448) (xy 413.805389 -144.078954)
			(xy 413.847794 -144.121359) (xy 413.8843 -144.168935) (xy 413.914284 -144.220869) (xy 413.937233 -144.276273)
			(xy 413.952754 -144.334198) (xy 413.960582 -144.393654) (xy 413.961072 -144.423638) (xy 413.961072 -145.285714)
			(xy 432.016408 -145.285714) (xy 432.016408 -144.422114) (xy 432.016898 -144.39213) (xy 432.024726 -144.332674)
			(xy 432.040247 -144.274749) (xy 432.063196 -144.219345) (xy 432.09318 -144.167411) (xy 432.129686 -144.119835)
			(xy 432.172091 -144.07743) (xy 432.219667 -144.040924) (xy 432.271601 -144.01094) (xy 432.327005 -143.987991)
			(xy 432.38493 -143.97247) (xy 432.444386 -143.964642) (xy 432.504354 -143.964642) (xy 432.56381 -143.97247)
			(xy 432.621735 -143.987991) (xy 432.677139 -144.01094) (xy 432.729073 -144.040924) (xy 432.776649 -144.07743)
			(xy 432.819054 -144.119835) (xy 432.85556 -144.167411) (xy 432.885544 -144.219345) (xy 432.908493 -144.274749)
			(xy 432.924014 -144.332674) (xy 432.931842 -144.39213) (xy 432.932332 -144.422114) (xy 432.932332 -145.285714)
			(xy 432.931842 -145.315698) (xy 432.924014 -145.375154) (xy 432.908493 -145.433079) (xy 432.885544 -145.488483)
			(xy 432.85556 -145.540417) (xy 432.819054 -145.587993) (xy 432.776649 -145.630398) (xy 432.729073 -145.666904)
			(xy 432.677139 -145.696888) (xy 432.621735 -145.719837) (xy 432.56381 -145.735358) (xy 432.504354 -145.743186)
			(xy 432.444386 -145.743186) (xy 432.38493 -145.735358) (xy 432.327005 -145.719837) (xy 432.271601 -145.696888)
			(xy 432.219667 -145.666904) (xy 432.172091 -145.630398) (xy 432.129686 -145.587993) (xy 432.09318 -145.540417)
			(xy 432.063196 -145.488483) (xy 432.040247 -145.433079) (xy 432.024726 -145.375154) (xy 432.016898 -145.315698)
			(xy 432.016408 -145.285714) (xy 413.961072 -145.285714) (xy 413.961072 -145.287238) (xy 413.960582 -145.317222)
			(xy 413.952754 -145.376678) (xy 413.937233 -145.434603) (xy 413.914284 -145.490007) (xy 413.8843 -145.541941)
			(xy 413.847794 -145.589517) (xy 413.805389 -145.631922) (xy 413.757813 -145.668428) (xy 413.705879 -145.698412)
			(xy 413.650475 -145.721361) (xy 413.59255 -145.736882) (xy 413.533094 -145.74471) (xy 413.473126 -145.74471)
			(xy 413.41367 -145.736882) (xy 413.355745 -145.721361) (xy 413.300341 -145.698412) (xy 413.248407 -145.668428)
			(xy 413.200831 -145.631922) (xy 413.158426 -145.589517) (xy 413.12192 -145.541941) (xy 413.091936 -145.490007)
			(xy 413.068987 -145.434603) (xy 413.053466 -145.376678) (xy 413.045638 -145.317222) (xy 413.045148 -145.287238)
			(xy 316.831955 -145.287238) (xy 316.83149 -145.315682) (xy 316.823667 -145.375104) (xy 316.808154 -145.432997)
			(xy 316.785218 -145.48837) (xy 316.755251 -145.540276) (xy 316.718764 -145.587826) (xy 316.676384 -145.630206)
			(xy 316.628834 -145.666693) (xy 316.576928 -145.69666) (xy 316.521555 -145.719596) (xy 316.463662 -145.735109)
			(xy 316.40424 -145.742932) (xy 316.344304 -145.742932) (xy 316.284882 -145.735109) (xy 316.226989 -145.719596)
			(xy 316.171616 -145.69666) (xy 316.11971 -145.666693) (xy 316.07216 -145.630206) (xy 316.02978 -145.587826)
			(xy 315.993293 -145.540276) (xy 315.963326 -145.48837) (xy 315.94039 -145.432997) (xy 315.924877 -145.375104)
			(xy 315.917054 -145.315682) (xy 315.916564 -145.285714) (xy 297.86072 -145.285714) (xy 297.86072 -145.287238)
			(xy 297.86023 -145.317206) (xy 297.852407 -145.376628) (xy 297.836894 -145.434521) (xy 297.813958 -145.489894)
			(xy 297.783991 -145.5418) (xy 297.747504 -145.58935) (xy 297.705124 -145.63173) (xy 297.657574 -145.668217)
			(xy 297.605668 -145.698184) (xy 297.550295 -145.72112) (xy 297.492402 -145.736633) (xy 297.43298 -145.744456)
			(xy 297.373044 -145.744456) (xy 297.313622 -145.736633) (xy 297.255729 -145.72112) (xy 297.200356 -145.698184)
			(xy 297.14845 -145.668217) (xy 297.1009 -145.63173) (xy 297.05852 -145.58935) (xy 297.022033 -145.5418)
			(xy 296.992066 -145.489894) (xy 296.96913 -145.434521) (xy 296.953617 -145.376628) (xy 296.945794 -145.317206)
			(xy 296.945304 -145.287238) (xy 200.732111 -145.287238) (xy 200.731646 -145.315682) (xy 200.723823 -145.375104)
			(xy 200.70831 -145.432997) (xy 200.685374 -145.48837) (xy 200.655407 -145.540276) (xy 200.61892 -145.587826)
			(xy 200.57654 -145.630206) (xy 200.52899 -145.666693) (xy 200.477084 -145.69666) (xy 200.421711 -145.719596)
			(xy 200.363818 -145.735109) (xy 200.304396 -145.742932) (xy 200.24446 -145.742932) (xy 200.185038 -145.735109)
			(xy 200.127145 -145.719596) (xy 200.071772 -145.69666) (xy 200.019866 -145.666693) (xy 199.972316 -145.630206)
			(xy 199.929936 -145.587826) (xy 199.893449 -145.540276) (xy 199.863482 -145.48837) (xy 199.840546 -145.432997)
			(xy 199.825033 -145.375104) (xy 199.81721 -145.315682) (xy 199.81672 -145.285714) (xy 181.760876 -145.285714)
			(xy 181.760876 -145.287238) (xy 181.760386 -145.317206) (xy 181.752563 -145.376628) (xy 181.73705 -145.434521)
			(xy 181.714114 -145.489894) (xy 181.684147 -145.5418) (xy 181.64766 -145.58935) (xy 181.60528 -145.63173)
			(xy 181.55773 -145.668217) (xy 181.505824 -145.698184) (xy 181.450451 -145.72112) (xy 181.392558 -145.736633)
			(xy 181.333136 -145.744456) (xy 181.2732 -145.744456) (xy 181.213778 -145.736633) (xy 181.155885 -145.72112)
			(xy 181.100512 -145.698184) (xy 181.048606 -145.668217) (xy 181.001056 -145.63173) (xy 180.958676 -145.58935)
			(xy 180.922189 -145.5418) (xy 180.892222 -145.489894) (xy 180.869286 -145.434521) (xy 180.853773 -145.376628)
			(xy 180.84595 -145.317206) (xy 180.84546 -145.287238) (xy 84.632267 -145.287238) (xy 84.631802 -145.315698)
			(xy 84.623974 -145.375154) (xy 84.608453 -145.433079) (xy 84.585504 -145.488483) (xy 84.55552 -145.540417)
			(xy 84.519014 -145.587993) (xy 84.476609 -145.630398) (xy 84.429033 -145.666904) (xy 84.377099 -145.696888)
			(xy 84.321695 -145.719837) (xy 84.26377 -145.735358) (xy 84.204314 -145.743186) (xy 84.144346 -145.743186)
			(xy 84.08489 -145.735358) (xy 84.026965 -145.719837) (xy 83.971561 -145.696888) (xy 83.919627 -145.666904)
			(xy 83.872051 -145.630398) (xy 83.829646 -145.587993) (xy 83.79314 -145.540417) (xy 83.763156 -145.488483)
			(xy 83.740207 -145.433079) (xy 83.724686 -145.375154) (xy 83.716858 -145.315698) (xy 83.716368 -145.285714)
			(xy 65.661032 -145.285714) (xy 65.661032 -145.287238) (xy 65.660542 -145.317222) (xy 65.652714 -145.376678)
			(xy 65.637193 -145.434603) (xy 65.614244 -145.490007) (xy 65.58426 -145.541941) (xy 65.547754 -145.589517)
			(xy 65.505349 -145.631922) (xy 65.457773 -145.668428) (xy 65.405839 -145.698412) (xy 65.350435 -145.721361)
			(xy 65.29251 -145.736882) (xy 65.233054 -145.74471) (xy 65.173086 -145.74471) (xy 65.11363 -145.736882)
			(xy 65.055705 -145.721361) (xy 65.000301 -145.698412) (xy 64.948367 -145.668428) (xy 64.900791 -145.631922)
			(xy 64.858386 -145.589517) (xy 64.82188 -145.541941) (xy 64.791896 -145.490007) (xy 64.768947 -145.434603)
			(xy 64.753426 -145.376678) (xy 64.745598 -145.317222) (xy 64.745108 -145.287238) (xy 4.308094 -145.287238)
			(xy 4.308094 -147.087336) (xy 66.599308 -147.087336) (xy 66.599308 -146.223736) (xy 66.599798 -146.193752)
			(xy 66.607626 -146.134296) (xy 66.623147 -146.076371) (xy 66.646096 -146.020967) (xy 66.67608 -145.969033)
			(xy 66.712586 -145.921457) (xy 66.754991 -145.879052) (xy 66.802567 -145.842546) (xy 66.854501 -145.812562)
			(xy 66.909905 -145.789613) (xy 66.96783 -145.774092) (xy 67.027286 -145.766264) (xy 67.087254 -145.766264)
			(xy 67.14671 -145.774092) (xy 67.204635 -145.789613) (xy 67.260039 -145.812562) (xy 67.311973 -145.842546)
			(xy 67.359549 -145.879052) (xy 67.401954 -145.921457) (xy 67.43846 -145.969033) (xy 67.468444 -146.020967)
			(xy 67.491393 -146.076371) (xy 67.506914 -146.134296) (xy 67.514742 -146.193752) (xy 67.515232 -146.223736)
			(xy 67.515232 -147.079208) (xy 81.07426 -147.079208) (xy 81.07426 -146.215608) (xy 81.07475 -146.185624)
			(xy 81.082578 -146.126168) (xy 81.098099 -146.068243) (xy 81.121048 -146.012839) (xy 81.151032 -145.960905)
			(xy 81.187538 -145.913329) (xy 81.229943 -145.870924) (xy 81.277519 -145.834418) (xy 81.329453 -145.804434)
			(xy 81.384857 -145.781485) (xy 81.442782 -145.765964) (xy 81.502238 -145.758136) (xy 81.562206 -145.758136)
			(xy 81.621662 -145.765964) (xy 81.679587 -145.781485) (xy 81.734991 -145.804434) (xy 81.786925 -145.834418)
			(xy 81.834501 -145.870924) (xy 81.876906 -145.913329) (xy 81.913412 -145.960905) (xy 81.943396 -146.012839)
			(xy 81.966345 -146.068243) (xy 81.981866 -146.126168) (xy 81.989694 -146.185624) (xy 81.990184 -146.215608)
			(xy 81.990184 -147.079208) (xy 81.990051 -147.087336) (xy 182.69966 -147.087336) (xy 182.69966 -146.223736)
			(xy 182.70015 -146.193768) (xy 182.707973 -146.134346) (xy 182.723486 -146.076453) (xy 182.746422 -146.02108)
			(xy 182.776389 -145.969174) (xy 182.812876 -145.921624) (xy 182.855256 -145.879244) (xy 182.902806 -145.842757)
			(xy 182.954712 -145.81279) (xy 183.010085 -145.789854) (xy 183.067978 -145.774341) (xy 183.1274 -145.766518)
			(xy 183.187336 -145.766518) (xy 183.246758 -145.774341) (xy 183.304651 -145.789854) (xy 183.360024 -145.81279)
			(xy 183.41193 -145.842757) (xy 183.45948 -145.879244) (xy 183.50186 -145.921624) (xy 183.538347 -145.969174)
			(xy 183.568314 -146.02108) (xy 183.59125 -146.076453) (xy 183.606763 -146.134346) (xy 183.614586 -146.193768)
			(xy 183.615076 -146.223736) (xy 183.615076 -147.079208) (xy 197.174612 -147.079208) (xy 197.174612 -146.215608)
			(xy 197.175102 -146.18564) (xy 197.182925 -146.126218) (xy 197.198438 -146.068325) (xy 197.221374 -146.012952)
			(xy 197.251341 -145.961046) (xy 197.287828 -145.913496) (xy 197.330208 -145.871116) (xy 197.377758 -145.834629)
			(xy 197.429664 -145.804662) (xy 197.485037 -145.781726) (xy 197.54293 -145.766213) (xy 197.602352 -145.75839)
			(xy 197.662288 -145.75839) (xy 197.72171 -145.766213) (xy 197.779603 -145.781726) (xy 197.834976 -145.804662)
			(xy 197.886882 -145.834629) (xy 197.934432 -145.871116) (xy 197.976812 -145.913496) (xy 198.013299 -145.961046)
			(xy 198.043266 -146.012952) (xy 198.066202 -146.068325) (xy 198.081715 -146.126218) (xy 198.089538 -146.18564)
			(xy 198.090028 -146.215608) (xy 198.090028 -147.079208) (xy 198.089895 -147.087336) (xy 298.799504 -147.087336)
			(xy 298.799504 -146.223736) (xy 298.799994 -146.193768) (xy 298.807817 -146.134346) (xy 298.82333 -146.076453)
			(xy 298.846266 -146.02108) (xy 298.876233 -145.969174) (xy 298.91272 -145.921624) (xy 298.9551 -145.879244)
			(xy 299.00265 -145.842757) (xy 299.054556 -145.81279) (xy 299.109929 -145.789854) (xy 299.167822 -145.774341)
			(xy 299.227244 -145.766518) (xy 299.28718 -145.766518) (xy 299.346602 -145.774341) (xy 299.404495 -145.789854)
			(xy 299.459868 -145.81279) (xy 299.511774 -145.842757) (xy 299.559324 -145.879244) (xy 299.601704 -145.921624)
			(xy 299.638191 -145.969174) (xy 299.668158 -146.02108) (xy 299.691094 -146.076453) (xy 299.706607 -146.134346)
			(xy 299.71443 -146.193768) (xy 299.71492 -146.223736) (xy 299.71492 -147.079208) (xy 313.274456 -147.079208)
			(xy 313.274456 -146.215608) (xy 313.274946 -146.18564) (xy 313.282769 -146.126218) (xy 313.298282 -146.068325)
			(xy 313.321218 -146.012952) (xy 313.351185 -145.961046) (xy 313.387672 -145.913496) (xy 313.430052 -145.871116)
			(xy 313.477602 -145.834629) (xy 313.529508 -145.804662) (xy 313.584881 -145.781726) (xy 313.642774 -145.766213)
			(xy 313.702196 -145.75839) (xy 313.762132 -145.75839) (xy 313.821554 -145.766213) (xy 313.879447 -145.781726)
			(xy 313.93482 -145.804662) (xy 313.986726 -145.834629) (xy 314.034276 -145.871116) (xy 314.076656 -145.913496)
			(xy 314.113143 -145.961046) (xy 314.14311 -146.012952) (xy 314.166046 -146.068325) (xy 314.181559 -146.126218)
			(xy 314.189382 -146.18564) (xy 314.189872 -146.215608) (xy 314.189872 -147.079208) (xy 314.189739 -147.087336)
			(xy 414.899348 -147.087336) (xy 414.899348 -146.223736) (xy 414.899838 -146.193752) (xy 414.907666 -146.134296)
			(xy 414.923187 -146.076371) (xy 414.946136 -146.020967) (xy 414.97612 -145.969033) (xy 415.012626 -145.921457)
			(xy 415.055031 -145.879052) (xy 415.102607 -145.842546) (xy 415.154541 -145.812562) (xy 415.209945 -145.789613)
			(xy 415.26787 -145.774092) (xy 415.327326 -145.766264) (xy 415.387294 -145.766264) (xy 415.44675 -145.774092)
			(xy 415.504675 -145.789613) (xy 415.560079 -145.812562) (xy 415.612013 -145.842546) (xy 415.659589 -145.879052)
			(xy 415.701994 -145.921457) (xy 415.7385 -145.969033) (xy 415.768484 -146.020967) (xy 415.791433 -146.076371)
			(xy 415.806954 -146.134296) (xy 415.814782 -146.193752) (xy 415.815272 -146.223736) (xy 415.815272 -147.079208)
			(xy 429.3743 -147.079208) (xy 429.3743 -146.215608) (xy 429.37479 -146.185624) (xy 429.382618 -146.126168)
			(xy 429.398139 -146.068243) (xy 429.421088 -146.012839) (xy 429.451072 -145.960905) (xy 429.487578 -145.913329)
			(xy 429.529983 -145.870924) (xy 429.577559 -145.834418) (xy 429.629493 -145.804434) (xy 429.684897 -145.781485)
			(xy 429.742822 -145.765964) (xy 429.802278 -145.758136) (xy 429.862246 -145.758136) (xy 429.921702 -145.765964)
			(xy 429.979627 -145.781485) (xy 430.035031 -145.804434) (xy 430.086965 -145.834418) (xy 430.134541 -145.870924)
			(xy 430.176946 -145.913329) (xy 430.213452 -145.960905) (xy 430.243436 -146.012839) (xy 430.266385 -146.068243)
			(xy 430.281906 -146.126168) (xy 430.289734 -146.185624) (xy 430.290224 -146.215608) (xy 430.290224 -147.079208)
			(xy 430.289734 -147.109192) (xy 430.281906 -147.168648) (xy 430.266385 -147.226573) (xy 430.243436 -147.281977)
			(xy 430.213452 -147.333911) (xy 430.176946 -147.381487) (xy 430.134541 -147.423892) (xy 430.086965 -147.460398)
			(xy 430.035031 -147.490382) (xy 429.979627 -147.513331) (xy 429.921702 -147.528852) (xy 429.862246 -147.53668)
			(xy 429.802278 -147.53668) (xy 429.742822 -147.528852) (xy 429.684897 -147.513331) (xy 429.629493 -147.490382)
			(xy 429.577559 -147.460398) (xy 429.529983 -147.423892) (xy 429.487578 -147.381487) (xy 429.451072 -147.333911)
			(xy 429.421088 -147.281977) (xy 429.398139 -147.226573) (xy 429.382618 -147.168648) (xy 429.37479 -147.109192)
			(xy 429.3743 -147.079208) (xy 415.815272 -147.079208) (xy 415.815272 -147.087336) (xy 415.814782 -147.11732)
			(xy 415.806954 -147.176776) (xy 415.791433 -147.234701) (xy 415.768484 -147.290105) (xy 415.7385 -147.342039)
			(xy 415.701994 -147.389615) (xy 415.659589 -147.43202) (xy 415.612013 -147.468526) (xy 415.560079 -147.49851)
			(xy 415.504675 -147.521459) (xy 415.44675 -147.53698) (xy 415.387294 -147.544808) (xy 415.327326 -147.544808)
			(xy 415.26787 -147.53698) (xy 415.209945 -147.521459) (xy 415.154541 -147.49851) (xy 415.102607 -147.468526)
			(xy 415.055031 -147.43202) (xy 415.012626 -147.389615) (xy 414.97612 -147.342039) (xy 414.946136 -147.290105)
			(xy 414.923187 -147.234701) (xy 414.907666 -147.176776) (xy 414.899838 -147.11732) (xy 414.899348 -147.087336)
			(xy 314.189739 -147.087336) (xy 314.189382 -147.109176) (xy 314.181559 -147.168598) (xy 314.166046 -147.226491)
			(xy 314.14311 -147.281864) (xy 314.113143 -147.33377) (xy 314.076656 -147.38132) (xy 314.034276 -147.4237)
			(xy 313.986726 -147.460187) (xy 313.93482 -147.490154) (xy 313.879447 -147.51309) (xy 313.821554 -147.528603)
			(xy 313.762132 -147.536426) (xy 313.702196 -147.536426) (xy 313.642774 -147.528603) (xy 313.584881 -147.51309)
			(xy 313.529508 -147.490154) (xy 313.477602 -147.460187) (xy 313.430052 -147.4237) (xy 313.387672 -147.38132)
			(xy 313.351185 -147.33377) (xy 313.321218 -147.281864) (xy 313.298282 -147.226491) (xy 313.282769 -147.168598)
			(xy 313.274946 -147.109176) (xy 313.274456 -147.079208) (xy 299.71492 -147.079208) (xy 299.71492 -147.087336)
			(xy 299.71443 -147.117304) (xy 299.706607 -147.176726) (xy 299.691094 -147.234619) (xy 299.668158 -147.289992)
			(xy 299.638191 -147.341898) (xy 299.601704 -147.389448) (xy 299.559324 -147.431828) (xy 299.511774 -147.468315)
			(xy 299.459868 -147.498282) (xy 299.404495 -147.521218) (xy 299.346602 -147.536731) (xy 299.28718 -147.544554)
			(xy 299.227244 -147.544554) (xy 299.167822 -147.536731) (xy 299.109929 -147.521218) (xy 299.054556 -147.498282)
			(xy 299.00265 -147.468315) (xy 298.9551 -147.431828) (xy 298.91272 -147.389448) (xy 298.876233 -147.341898)
			(xy 298.846266 -147.289992) (xy 298.82333 -147.234619) (xy 298.807817 -147.176726) (xy 298.799994 -147.117304)
			(xy 298.799504 -147.087336) (xy 198.089895 -147.087336) (xy 198.089538 -147.109176) (xy 198.081715 -147.168598)
			(xy 198.066202 -147.226491) (xy 198.043266 -147.281864) (xy 198.013299 -147.33377) (xy 197.976812 -147.38132)
			(xy 197.934432 -147.4237) (xy 197.886882 -147.460187) (xy 197.834976 -147.490154) (xy 197.779603 -147.51309)
			(xy 197.72171 -147.528603) (xy 197.662288 -147.536426) (xy 197.602352 -147.536426) (xy 197.54293 -147.528603)
			(xy 197.485037 -147.51309) (xy 197.429664 -147.490154) (xy 197.377758 -147.460187) (xy 197.330208 -147.4237)
			(xy 197.287828 -147.38132) (xy 197.251341 -147.33377) (xy 197.221374 -147.281864) (xy 197.198438 -147.226491)
			(xy 197.182925 -147.168598) (xy 197.175102 -147.109176) (xy 197.174612 -147.079208) (xy 183.615076 -147.079208)
			(xy 183.615076 -147.087336) (xy 183.614586 -147.117304) (xy 183.606763 -147.176726) (xy 183.59125 -147.234619)
			(xy 183.568314 -147.289992) (xy 183.538347 -147.341898) (xy 183.50186 -147.389448) (xy 183.45948 -147.431828)
			(xy 183.41193 -147.468315) (xy 183.360024 -147.498282) (xy 183.304651 -147.521218) (xy 183.246758 -147.536731)
			(xy 183.187336 -147.544554) (xy 183.1274 -147.544554) (xy 183.067978 -147.536731) (xy 183.010085 -147.521218)
			(xy 182.954712 -147.498282) (xy 182.902806 -147.468315) (xy 182.855256 -147.431828) (xy 182.812876 -147.389448)
			(xy 182.776389 -147.341898) (xy 182.746422 -147.289992) (xy 182.723486 -147.234619) (xy 182.707973 -147.176726)
			(xy 182.70015 -147.117304) (xy 182.69966 -147.087336) (xy 81.990051 -147.087336) (xy 81.989694 -147.109192)
			(xy 81.981866 -147.168648) (xy 81.966345 -147.226573) (xy 81.943396 -147.281977) (xy 81.913412 -147.333911)
			(xy 81.876906 -147.381487) (xy 81.834501 -147.423892) (xy 81.786925 -147.460398) (xy 81.734991 -147.490382)
			(xy 81.679587 -147.513331) (xy 81.621662 -147.528852) (xy 81.562206 -147.53668) (xy 81.502238 -147.53668)
			(xy 81.442782 -147.528852) (xy 81.384857 -147.513331) (xy 81.329453 -147.490382) (xy 81.277519 -147.460398)
			(xy 81.229943 -147.423892) (xy 81.187538 -147.381487) (xy 81.151032 -147.333911) (xy 81.121048 -147.281977)
			(xy 81.098099 -147.226573) (xy 81.082578 -147.168648) (xy 81.07475 -147.109192) (xy 81.07426 -147.079208)
			(xy 67.515232 -147.079208) (xy 67.515232 -147.087336) (xy 67.514742 -147.11732) (xy 67.506914 -147.176776)
			(xy 67.491393 -147.234701) (xy 67.468444 -147.290105) (xy 67.43846 -147.342039) (xy 67.401954 -147.389615)
			(xy 67.359549 -147.43202) (xy 67.311973 -147.468526) (xy 67.260039 -147.49851) (xy 67.204635 -147.521459)
			(xy 67.14671 -147.53698) (xy 67.087254 -147.544808) (xy 67.027286 -147.544808) (xy 66.96783 -147.53698)
			(xy 66.909905 -147.521459) (xy 66.854501 -147.49851) (xy 66.802567 -147.468526) (xy 66.754991 -147.43202)
			(xy 66.712586 -147.389615) (xy 66.67608 -147.342039) (xy 66.646096 -147.290105) (xy 66.623147 -147.234701)
			(xy 66.607626 -147.176776) (xy 66.599798 -147.11732) (xy 66.599308 -147.087336) (xy 4.308094 -147.087336)
			(xy 4.308094 -148.887434) (xy 64.745108 -148.887434) (xy 64.745108 -148.023834) (xy 64.745598 -147.99385)
			(xy 64.753426 -147.934394) (xy 64.768947 -147.876469) (xy 64.791896 -147.821065) (xy 64.82188 -147.769131)
			(xy 64.858386 -147.721555) (xy 64.900791 -147.67915) (xy 64.948367 -147.642644) (xy 65.000301 -147.61266)
			(xy 65.055705 -147.589711) (xy 65.11363 -147.57419) (xy 65.173086 -147.566362) (xy 65.233054 -147.566362)
			(xy 65.29251 -147.57419) (xy 65.350435 -147.589711) (xy 65.405839 -147.61266) (xy 65.457773 -147.642644)
			(xy 65.505349 -147.67915) (xy 65.547754 -147.721555) (xy 65.58426 -147.769131) (xy 65.614244 -147.821065)
			(xy 65.637193 -147.876469) (xy 65.652714 -147.934394) (xy 65.660542 -147.99385) (xy 65.661032 -148.023834)
			(xy 65.661032 -148.88591) (xy 83.716368 -148.88591) (xy 83.716368 -148.02231) (xy 83.716858 -147.992326)
			(xy 83.724686 -147.93287) (xy 83.740207 -147.874945) (xy 83.763156 -147.819541) (xy 83.79314 -147.767607)
			(xy 83.829646 -147.720031) (xy 83.872051 -147.677626) (xy 83.919627 -147.64112) (xy 83.971561 -147.611136)
			(xy 84.026965 -147.588187) (xy 84.08489 -147.572666) (xy 84.144346 -147.564838) (xy 84.204314 -147.564838)
			(xy 84.26377 -147.572666) (xy 84.321695 -147.588187) (xy 84.377099 -147.611136) (xy 84.429033 -147.64112)
			(xy 84.476609 -147.677626) (xy 84.519014 -147.720031) (xy 84.55552 -147.767607) (xy 84.585504 -147.819541)
			(xy 84.608453 -147.874945) (xy 84.623974 -147.93287) (xy 84.631802 -147.992326) (xy 84.632292 -148.02231)
			(xy 84.632292 -148.88591) (xy 84.632267 -148.887434) (xy 180.84546 -148.887434) (xy 180.84546 -148.023834)
			(xy 180.84595 -147.993866) (xy 180.853773 -147.934444) (xy 180.869286 -147.876551) (xy 180.892222 -147.821178)
			(xy 180.922189 -147.769272) (xy 180.958676 -147.721722) (xy 181.001056 -147.679342) (xy 181.048606 -147.642855)
			(xy 181.100512 -147.612888) (xy 181.155885 -147.589952) (xy 181.213778 -147.574439) (xy 181.2732 -147.566616)
			(xy 181.333136 -147.566616) (xy 181.392558 -147.574439) (xy 181.450451 -147.589952) (xy 181.505824 -147.612888)
			(xy 181.55773 -147.642855) (xy 181.60528 -147.679342) (xy 181.64766 -147.721722) (xy 181.684147 -147.769272)
			(xy 181.714114 -147.821178) (xy 181.73705 -147.876551) (xy 181.752563 -147.934444) (xy 181.760386 -147.993866)
			(xy 181.760876 -148.023834) (xy 181.760876 -148.88591) (xy 199.81672 -148.88591) (xy 199.81672 -148.02231)
			(xy 199.81721 -147.992342) (xy 199.825033 -147.93292) (xy 199.840546 -147.875027) (xy 199.863482 -147.819654)
			(xy 199.893449 -147.767748) (xy 199.929936 -147.720198) (xy 199.972316 -147.677818) (xy 200.019866 -147.641331)
			(xy 200.071772 -147.611364) (xy 200.127145 -147.588428) (xy 200.185038 -147.572915) (xy 200.24446 -147.565092)
			(xy 200.304396 -147.565092) (xy 200.363818 -147.572915) (xy 200.421711 -147.588428) (xy 200.477084 -147.611364)
			(xy 200.52899 -147.641331) (xy 200.57654 -147.677818) (xy 200.61892 -147.720198) (xy 200.655407 -147.767748)
			(xy 200.685374 -147.819654) (xy 200.70831 -147.875027) (xy 200.723823 -147.93292) (xy 200.731646 -147.992342)
			(xy 200.732136 -148.02231) (xy 200.732136 -148.88591) (xy 200.731646 -148.915878) (xy 200.723823 -148.9753)
			(xy 200.70831 -149.033193) (xy 200.685374 -149.088566) (xy 200.655407 -149.140472) (xy 200.61892 -149.188022)
			(xy 200.57654 -149.230402) (xy 200.52899 -149.266889) (xy 200.477084 -149.296856) (xy 200.421711 -149.319792)
			(xy 200.363818 -149.335305) (xy 200.304396 -149.343128) (xy 200.24446 -149.343128) (xy 200.185038 -149.335305)
			(xy 200.127145 -149.319792) (xy 200.071772 -149.296856) (xy 200.019866 -149.266889) (xy 199.972316 -149.230402)
			(xy 199.929936 -149.188022) (xy 199.893449 -149.140472) (xy 199.863482 -149.088566) (xy 199.840546 -149.033193)
			(xy 199.825033 -148.9753) (xy 199.81721 -148.915878) (xy 199.81672 -148.88591) (xy 181.760876 -148.88591)
			(xy 181.760876 -148.887434) (xy 181.760386 -148.917402) (xy 181.752563 -148.976824) (xy 181.73705 -149.034717)
			(xy 181.714114 -149.09009) (xy 181.684147 -149.141996) (xy 181.64766 -149.189546) (xy 181.60528 -149.231926)
			(xy 181.55773 -149.268413) (xy 181.505824 -149.29838) (xy 181.450451 -149.321316) (xy 181.392558 -149.336829)
			(xy 181.333136 -149.344652) (xy 181.2732 -149.344652) (xy 181.213778 -149.336829) (xy 181.155885 -149.321316)
			(xy 181.100512 -149.29838) (xy 181.048606 -149.268413) (xy 181.001056 -149.231926) (xy 180.958676 -149.189546)
			(xy 180.922189 -149.141996) (xy 180.892222 -149.09009) (xy 180.869286 -149.034717) (xy 180.853773 -148.976824)
			(xy 180.84595 -148.917402) (xy 180.84546 -148.887434) (xy 84.632267 -148.887434) (xy 84.631802 -148.915894)
			(xy 84.623974 -148.97535) (xy 84.608453 -149.033275) (xy 84.585504 -149.088679) (xy 84.55552 -149.140613)
			(xy 84.519014 -149.188189) (xy 84.476609 -149.230594) (xy 84.429033 -149.2671) (xy 84.377099 -149.297084)
			(xy 84.321695 -149.320033) (xy 84.26377 -149.335554) (xy 84.204314 -149.343382) (xy 84.144346 -149.343382)
			(xy 84.08489 -149.335554) (xy 84.026965 -149.320033) (xy 83.971561 -149.297084) (xy 83.919627 -149.2671)
			(xy 83.872051 -149.230594) (xy 83.829646 -149.188189) (xy 83.79314 -149.140613) (xy 83.763156 -149.088679)
			(xy 83.740207 -149.033275) (xy 83.724686 -148.97535) (xy 83.716858 -148.915894) (xy 83.716368 -148.88591)
			(xy 65.661032 -148.88591) (xy 65.661032 -148.887434) (xy 65.660542 -148.917418) (xy 65.652714 -148.976874)
			(xy 65.637193 -149.034799) (xy 65.614244 -149.090203) (xy 65.58426 -149.142137) (xy 65.547754 -149.189713)
			(xy 65.505349 -149.232118) (xy 65.457773 -149.268624) (xy 65.405839 -149.298608) (xy 65.350435 -149.321557)
			(xy 65.29251 -149.337078) (xy 65.233054 -149.344906) (xy 65.173086 -149.344906) (xy 65.11363 -149.337078)
			(xy 65.055705 -149.321557) (xy 65.000301 -149.298608) (xy 64.948367 -149.268624) (xy 64.900791 -149.232118)
			(xy 64.858386 -149.189713) (xy 64.82188 -149.142137) (xy 64.791896 -149.090203) (xy 64.768947 -149.034799)
			(xy 64.753426 -148.976874) (xy 64.745598 -148.917418) (xy 64.745108 -148.887434) (xy 4.308094 -148.887434)
			(xy 4.308094 -150.687278) (xy 66.599308 -150.687278) (xy 66.599308 -149.823678) (xy 66.599798 -149.793694)
			(xy 66.607626 -149.734238) (xy 66.623147 -149.676313) (xy 66.646096 -149.620909) (xy 66.67608 -149.568975)
			(xy 66.712586 -149.521399) (xy 66.754991 -149.478994) (xy 66.802567 -149.442488) (xy 66.854501 -149.412504)
			(xy 66.909905 -149.389555) (xy 66.96783 -149.374034) (xy 67.027286 -149.366206) (xy 67.087254 -149.366206)
			(xy 67.14671 -149.374034) (xy 67.204635 -149.389555) (xy 67.260039 -149.412504) (xy 67.311973 -149.442488)
			(xy 67.359549 -149.478994) (xy 67.401954 -149.521399) (xy 67.43846 -149.568975) (xy 67.468444 -149.620909)
			(xy 67.491393 -149.676313) (xy 67.506914 -149.734238) (xy 67.514742 -149.793694) (xy 67.515232 -149.823678)
			(xy 67.515232 -150.67915) (xy 81.07426 -150.67915) (xy 81.07426 -149.81555) (xy 81.07475 -149.785566)
			(xy 81.082578 -149.72611) (xy 81.098099 -149.668185) (xy 81.121048 -149.612781) (xy 81.151032 -149.560847)
			(xy 81.187538 -149.513271) (xy 81.229943 -149.470866) (xy 81.277519 -149.43436) (xy 81.329453 -149.404376)
			(xy 81.384857 -149.381427) (xy 81.442782 -149.365906) (xy 81.502238 -149.358078) (xy 81.562206 -149.358078)
			(xy 81.621662 -149.365906) (xy 81.679587 -149.381427) (xy 81.734991 -149.404376) (xy 81.786925 -149.43436)
			(xy 81.834501 -149.470866) (xy 81.876906 -149.513271) (xy 81.913412 -149.560847) (xy 81.943396 -149.612781)
			(xy 81.966345 -149.668185) (xy 81.981866 -149.72611) (xy 81.989694 -149.785566) (xy 81.990184 -149.81555)
			(xy 81.990184 -150.67915) (xy 81.990051 -150.687278) (xy 182.69966 -150.687278) (xy 182.69966 -149.823678)
			(xy 182.70015 -149.79371) (xy 182.707973 -149.734288) (xy 182.723486 -149.676395) (xy 182.746422 -149.621022)
			(xy 182.776389 -149.569116) (xy 182.812876 -149.521566) (xy 182.855256 -149.479186) (xy 182.902806 -149.442699)
			(xy 182.954712 -149.412732) (xy 183.010085 -149.389796) (xy 183.067978 -149.374283) (xy 183.1274 -149.36646)
			(xy 183.187336 -149.36646) (xy 183.246758 -149.374283) (xy 183.304651 -149.389796) (xy 183.360024 -149.412732)
			(xy 183.41193 -149.442699) (xy 183.45948 -149.479186) (xy 183.50186 -149.521566) (xy 183.538347 -149.569116)
			(xy 183.568314 -149.621022) (xy 183.59125 -149.676395) (xy 183.606763 -149.734288) (xy 183.614586 -149.79371)
			(xy 183.615076 -149.823678) (xy 183.615076 -150.67915) (xy 197.174612 -150.67915) (xy 197.174612 -149.81555)
			(xy 197.175102 -149.785582) (xy 197.182925 -149.72616) (xy 197.198438 -149.668267) (xy 197.221374 -149.612894)
			(xy 197.251341 -149.560988) (xy 197.287828 -149.513438) (xy 197.330208 -149.471058) (xy 197.377758 -149.434571)
			(xy 197.429664 -149.404604) (xy 197.485037 -149.381668) (xy 197.54293 -149.366155) (xy 197.602352 -149.358332)
			(xy 197.662288 -149.358332) (xy 197.72171 -149.366155) (xy 197.779603 -149.381668) (xy 197.834976 -149.404604)
			(xy 197.886882 -149.434571) (xy 197.934432 -149.471058) (xy 197.976812 -149.513438) (xy 198.013299 -149.560988)
			(xy 198.043266 -149.612894) (xy 198.066202 -149.668267) (xy 198.072386 -149.691344) (xy 236.708188 -149.691344)
			(xy 236.708188 -148.827744) (xy 236.708678 -148.79776) (xy 236.716506 -148.738304) (xy 236.732027 -148.680379)
			(xy 236.754976 -148.624975) (xy 236.78496 -148.573041) (xy 236.821466 -148.525465) (xy 236.863871 -148.48306)
			(xy 236.911447 -148.446554) (xy 236.963381 -148.41657) (xy 237.018785 -148.393621) (xy 237.07671 -148.3781)
			(xy 237.136166 -148.370272) (xy 237.196134 -148.370272) (xy 237.25559 -148.3781) (xy 237.313515 -148.393621)
			(xy 237.368919 -148.41657) (xy 237.420853 -148.446554) (xy 237.468429 -148.48306) (xy 237.510834 -148.525465)
			(xy 237.54734 -148.573041) (xy 237.577324 -148.624975) (xy 237.600273 -148.680379) (xy 237.615794 -148.738304)
			(xy 237.623622 -148.79776) (xy 237.624112 -148.827744) (xy 237.624112 -148.887434) (xy 296.945304 -148.887434)
			(xy 296.945304 -148.023834) (xy 296.945794 -147.993866) (xy 296.953617 -147.934444) (xy 296.96913 -147.876551)
			(xy 296.992066 -147.821178) (xy 297.022033 -147.769272) (xy 297.05852 -147.721722) (xy 297.1009 -147.679342)
			(xy 297.14845 -147.642855) (xy 297.200356 -147.612888) (xy 297.255729 -147.589952) (xy 297.313622 -147.574439)
			(xy 297.373044 -147.566616) (xy 297.43298 -147.566616) (xy 297.492402 -147.574439) (xy 297.550295 -147.589952)
			(xy 297.605668 -147.612888) (xy 297.657574 -147.642855) (xy 297.705124 -147.679342) (xy 297.747504 -147.721722)
			(xy 297.783991 -147.769272) (xy 297.813958 -147.821178) (xy 297.836894 -147.876551) (xy 297.852407 -147.934444)
			(xy 297.86023 -147.993866) (xy 297.86072 -148.023834) (xy 297.86072 -148.88591) (xy 315.916564 -148.88591)
			(xy 315.916564 -148.02231) (xy 315.917054 -147.992342) (xy 315.924877 -147.93292) (xy 315.94039 -147.875027)
			(xy 315.963326 -147.819654) (xy 315.993293 -147.767748) (xy 316.02978 -147.720198) (xy 316.07216 -147.677818)
			(xy 316.11971 -147.641331) (xy 316.171616 -147.611364) (xy 316.226989 -147.588428) (xy 316.284882 -147.572915)
			(xy 316.344304 -147.565092) (xy 316.40424 -147.565092) (xy 316.463662 -147.572915) (xy 316.521555 -147.588428)
			(xy 316.576928 -147.611364) (xy 316.628834 -147.641331) (xy 316.676384 -147.677818) (xy 316.718764 -147.720198)
			(xy 316.755251 -147.767748) (xy 316.785218 -147.819654) (xy 316.808154 -147.875027) (xy 316.823667 -147.93292)
			(xy 316.83149 -147.992342) (xy 316.83198 -148.02231) (xy 316.83198 -148.88591) (xy 316.831955 -148.887434)
			(xy 413.045148 -148.887434) (xy 413.045148 -148.023834) (xy 413.045638 -147.99385) (xy 413.053466 -147.934394)
			(xy 413.068987 -147.876469) (xy 413.091936 -147.821065) (xy 413.12192 -147.769131) (xy 413.158426 -147.721555)
			(xy 413.200831 -147.67915) (xy 413.248407 -147.642644) (xy 413.300341 -147.61266) (xy 413.355745 -147.589711)
			(xy 413.41367 -147.57419) (xy 413.473126 -147.566362) (xy 413.533094 -147.566362) (xy 413.59255 -147.57419)
			(xy 413.650475 -147.589711) (xy 413.705879 -147.61266) (xy 413.757813 -147.642644) (xy 413.805389 -147.67915)
			(xy 413.847794 -147.721555) (xy 413.8843 -147.769131) (xy 413.914284 -147.821065) (xy 413.937233 -147.876469)
			(xy 413.952754 -147.934394) (xy 413.960582 -147.99385) (xy 413.961072 -148.023834) (xy 413.961072 -148.88591)
			(xy 432.016408 -148.88591) (xy 432.016408 -148.02231) (xy 432.016898 -147.992326) (xy 432.024726 -147.93287)
			(xy 432.040247 -147.874945) (xy 432.063196 -147.819541) (xy 432.09318 -147.767607) (xy 432.129686 -147.720031)
			(xy 432.172091 -147.677626) (xy 432.219667 -147.64112) (xy 432.271601 -147.611136) (xy 432.327005 -147.588187)
			(xy 432.38493 -147.572666) (xy 432.444386 -147.564838) (xy 432.504354 -147.564838) (xy 432.56381 -147.572666)
			(xy 432.621735 -147.588187) (xy 432.677139 -147.611136) (xy 432.729073 -147.64112) (xy 432.776649 -147.677626)
			(xy 432.819054 -147.720031) (xy 432.85556 -147.767607) (xy 432.885544 -147.819541) (xy 432.908493 -147.874945)
			(xy 432.924014 -147.93287) (xy 432.931842 -147.992326) (xy 432.932332 -148.02231) (xy 432.932332 -148.88591)
			(xy 432.931842 -148.915894) (xy 432.924014 -148.97535) (xy 432.908493 -149.033275) (xy 432.885544 -149.088679)
			(xy 432.85556 -149.140613) (xy 432.819054 -149.188189) (xy 432.776649 -149.230594) (xy 432.729073 -149.2671)
			(xy 432.677139 -149.297084) (xy 432.621735 -149.320033) (xy 432.56381 -149.335554) (xy 432.504354 -149.343382)
			(xy 432.444386 -149.343382) (xy 432.38493 -149.335554) (xy 432.327005 -149.320033) (xy 432.271601 -149.297084)
			(xy 432.219667 -149.2671) (xy 432.172091 -149.230594) (xy 432.129686 -149.188189) (xy 432.09318 -149.140613)
			(xy 432.063196 -149.088679) (xy 432.040247 -149.033275) (xy 432.024726 -148.97535) (xy 432.016898 -148.915894)
			(xy 432.016408 -148.88591) (xy 413.961072 -148.88591) (xy 413.961072 -148.887434) (xy 413.960582 -148.917418)
			(xy 413.952754 -148.976874) (xy 413.937233 -149.034799) (xy 413.914284 -149.090203) (xy 413.8843 -149.142137)
			(xy 413.847794 -149.189713) (xy 413.805389 -149.232118) (xy 413.757813 -149.268624) (xy 413.705879 -149.298608)
			(xy 413.650475 -149.321557) (xy 413.59255 -149.337078) (xy 413.533094 -149.344906) (xy 413.473126 -149.344906)
			(xy 413.41367 -149.337078) (xy 413.355745 -149.321557) (xy 413.300341 -149.298608) (xy 413.248407 -149.268624)
			(xy 413.200831 -149.232118) (xy 413.158426 -149.189713) (xy 413.12192 -149.142137) (xy 413.091936 -149.090203)
			(xy 413.068987 -149.034799) (xy 413.053466 -148.976874) (xy 413.045638 -148.917418) (xy 413.045148 -148.887434)
			(xy 316.831955 -148.887434) (xy 316.83149 -148.915878) (xy 316.823667 -148.9753) (xy 316.808154 -149.033193)
			(xy 316.785218 -149.088566) (xy 316.755251 -149.140472) (xy 316.718764 -149.188022) (xy 316.676384 -149.230402)
			(xy 316.628834 -149.266889) (xy 316.576928 -149.296856) (xy 316.521555 -149.319792) (xy 316.463662 -149.335305)
			(xy 316.40424 -149.343128) (xy 316.344304 -149.343128) (xy 316.284882 -149.335305) (xy 316.226989 -149.319792)
			(xy 316.171616 -149.296856) (xy 316.11971 -149.266889) (xy 316.07216 -149.230402) (xy 316.02978 -149.188022)
			(xy 315.993293 -149.140472) (xy 315.963326 -149.088566) (xy 315.94039 -149.033193) (xy 315.924877 -148.9753)
			(xy 315.917054 -148.915878) (xy 315.916564 -148.88591) (xy 297.86072 -148.88591) (xy 297.86072 -148.887434)
			(xy 297.86023 -148.917402) (xy 297.852407 -148.976824) (xy 297.836894 -149.034717) (xy 297.813958 -149.09009)
			(xy 297.783991 -149.141996) (xy 297.747504 -149.189546) (xy 297.705124 -149.231926) (xy 297.657574 -149.268413)
			(xy 297.605668 -149.29838) (xy 297.550295 -149.321316) (xy 297.492402 -149.336829) (xy 297.43298 -149.344652)
			(xy 297.373044 -149.344652) (xy 297.313622 -149.336829) (xy 297.255729 -149.321316) (xy 297.200356 -149.29838)
			(xy 297.14845 -149.268413) (xy 297.1009 -149.231926) (xy 297.05852 -149.189546) (xy 297.022033 -149.141996)
			(xy 296.992066 -149.09009) (xy 296.96913 -149.034717) (xy 296.953617 -148.976824) (xy 296.945794 -148.917402)
			(xy 296.945304 -148.887434) (xy 237.624112 -148.887434) (xy 237.624112 -149.691344) (xy 237.623622 -149.721328)
			(xy 237.615794 -149.780784) (xy 237.600273 -149.838709) (xy 237.577324 -149.894113) (xy 237.54734 -149.946047)
			(xy 237.510834 -149.993623) (xy 237.468429 -150.036028) (xy 237.420853 -150.072534) (xy 237.368919 -150.102518)
			(xy 237.313515 -150.125467) (xy 237.25559 -150.140988) (xy 237.196134 -150.148816) (xy 237.136166 -150.148816)
			(xy 237.07671 -150.140988) (xy 237.018785 -150.125467) (xy 236.963381 -150.102518) (xy 236.911447 -150.072534)
			(xy 236.863871 -150.036028) (xy 236.821466 -149.993623) (xy 236.78496 -149.946047) (xy 236.754976 -149.894113)
			(xy 236.732027 -149.838709) (xy 236.716506 -149.780784) (xy 236.708678 -149.721328) (xy 236.708188 -149.691344)
			(xy 198.072386 -149.691344) (xy 198.081715 -149.72616) (xy 198.089538 -149.785582) (xy 198.090028 -149.81555)
			(xy 198.090028 -150.67915) (xy 198.089538 -150.709118) (xy 198.081715 -150.76854) (xy 198.066202 -150.826433)
			(xy 198.043266 -150.881806) (xy 198.013299 -150.933712) (xy 197.976812 -150.981262) (xy 197.934432 -151.023642)
			(xy 197.886882 -151.060129) (xy 197.834976 -151.090096) (xy 197.779603 -151.113032) (xy 197.72171 -151.128545)
			(xy 197.662288 -151.136368) (xy 197.602352 -151.136368) (xy 197.54293 -151.128545) (xy 197.485037 -151.113032)
			(xy 197.429664 -151.090096) (xy 197.377758 -151.060129) (xy 197.330208 -151.023642) (xy 197.287828 -150.981262)
			(xy 197.251341 -150.933712) (xy 197.221374 -150.881806) (xy 197.198438 -150.826433) (xy 197.182925 -150.76854)
			(xy 197.175102 -150.709118) (xy 197.174612 -150.67915) (xy 183.615076 -150.67915) (xy 183.615076 -150.687278)
			(xy 183.614586 -150.717246) (xy 183.606763 -150.776668) (xy 183.59125 -150.834561) (xy 183.568314 -150.889934)
			(xy 183.538347 -150.94184) (xy 183.50186 -150.98939) (xy 183.45948 -151.03177) (xy 183.41193 -151.068257)
			(xy 183.360024 -151.098224) (xy 183.304651 -151.12116) (xy 183.246758 -151.136673) (xy 183.187336 -151.144496)
			(xy 183.1274 -151.144496) (xy 183.067978 -151.136673) (xy 183.010085 -151.12116) (xy 182.954712 -151.098224)
			(xy 182.902806 -151.068257) (xy 182.855256 -151.03177) (xy 182.812876 -150.98939) (xy 182.776389 -150.94184)
			(xy 182.746422 -150.889934) (xy 182.723486 -150.834561) (xy 182.707973 -150.776668) (xy 182.70015 -150.717246)
			(xy 182.69966 -150.687278) (xy 81.990051 -150.687278) (xy 81.989694 -150.709134) (xy 81.981866 -150.76859)
			(xy 81.966345 -150.826515) (xy 81.943396 -150.881919) (xy 81.913412 -150.933853) (xy 81.876906 -150.981429)
			(xy 81.834501 -151.023834) (xy 81.786925 -151.06034) (xy 81.734991 -151.090324) (xy 81.679587 -151.113273)
			(xy 81.621662 -151.128794) (xy 81.562206 -151.136622) (xy 81.502238 -151.136622) (xy 81.442782 -151.128794)
			(xy 81.384857 -151.113273) (xy 81.329453 -151.090324) (xy 81.277519 -151.06034) (xy 81.229943 -151.023834)
			(xy 81.187538 -150.981429) (xy 81.151032 -150.933853) (xy 81.121048 -150.881919) (xy 81.098099 -150.826515)
			(xy 81.082578 -150.76859) (xy 81.07475 -150.709134) (xy 81.07426 -150.67915) (xy 67.515232 -150.67915)
			(xy 67.515232 -150.687278) (xy 67.514742 -150.717262) (xy 67.506914 -150.776718) (xy 67.491393 -150.834643)
			(xy 67.468444 -150.890047) (xy 67.43846 -150.941981) (xy 67.401954 -150.989557) (xy 67.359549 -151.031962)
			(xy 67.311973 -151.068468) (xy 67.260039 -151.098452) (xy 67.204635 -151.121401) (xy 67.14671 -151.136922)
			(xy 67.087254 -151.14475) (xy 67.027286 -151.14475) (xy 66.96783 -151.136922) (xy 66.909905 -151.121401)
			(xy 66.854501 -151.098452) (xy 66.802567 -151.068468) (xy 66.754991 -151.031962) (xy 66.712586 -150.989557)
			(xy 66.67608 -150.941981) (xy 66.646096 -150.890047) (xy 66.623147 -150.834643) (xy 66.607626 -150.776718)
			(xy 66.599798 -150.717262) (xy 66.599308 -150.687278) (xy 4.308094 -150.687278) (xy 4.308094 -152.487376)
			(xy 64.745108 -152.487376) (xy 64.745108 -151.623776) (xy 64.745598 -151.593792) (xy 64.753426 -151.534336)
			(xy 64.768947 -151.476411) (xy 64.791896 -151.421007) (xy 64.82188 -151.369073) (xy 64.858386 -151.321497)
			(xy 64.900791 -151.279092) (xy 64.948367 -151.242586) (xy 65.000301 -151.212602) (xy 65.055705 -151.189653)
			(xy 65.11363 -151.174132) (xy 65.173086 -151.166304) (xy 65.233054 -151.166304) (xy 65.29251 -151.174132)
			(xy 65.350435 -151.189653) (xy 65.405839 -151.212602) (xy 65.457773 -151.242586) (xy 65.505349 -151.279092)
			(xy 65.547754 -151.321497) (xy 65.58426 -151.369073) (xy 65.614244 -151.421007) (xy 65.637193 -151.476411)
			(xy 65.652714 -151.534336) (xy 65.660542 -151.593792) (xy 65.661032 -151.623776) (xy 65.661032 -152.485852)
			(xy 83.716368 -152.485852) (xy 83.716368 -151.622252) (xy 83.716858 -151.592268) (xy 83.724686 -151.532812)
			(xy 83.740207 -151.474887) (xy 83.763156 -151.419483) (xy 83.79314 -151.367549) (xy 83.829646 -151.319973)
			(xy 83.872051 -151.277568) (xy 83.919627 -151.241062) (xy 83.971561 -151.211078) (xy 84.026965 -151.188129)
			(xy 84.08489 -151.172608) (xy 84.144346 -151.16478) (xy 84.204314 -151.16478) (xy 84.26377 -151.172608)
			(xy 84.321695 -151.188129) (xy 84.377099 -151.211078) (xy 84.429033 -151.241062) (xy 84.476609 -151.277568)
			(xy 84.519014 -151.319973) (xy 84.55552 -151.367549) (xy 84.585504 -151.419483) (xy 84.608453 -151.474887)
			(xy 84.623974 -151.532812) (xy 84.631802 -151.592268) (xy 84.632292 -151.622252) (xy 84.632292 -152.485852)
			(xy 84.632267 -152.487376) (xy 180.84546 -152.487376) (xy 180.84546 -151.623776) (xy 180.84595 -151.593808)
			(xy 180.853773 -151.534386) (xy 180.869286 -151.476493) (xy 180.892222 -151.42112) (xy 180.922189 -151.369214)
			(xy 180.958676 -151.321664) (xy 181.001056 -151.279284) (xy 181.048606 -151.242797) (xy 181.100512 -151.21283)
			(xy 181.155885 -151.189894) (xy 181.213778 -151.174381) (xy 181.2732 -151.166558) (xy 181.333136 -151.166558)
			(xy 181.392558 -151.174381) (xy 181.450451 -151.189894) (xy 181.505824 -151.21283) (xy 181.55773 -151.242797)
			(xy 181.60528 -151.279284) (xy 181.64766 -151.321664) (xy 181.684147 -151.369214) (xy 181.714114 -151.42112)
			(xy 181.73705 -151.476493) (xy 181.752563 -151.534386) (xy 181.760386 -151.593808) (xy 181.760876 -151.623776)
			(xy 181.760876 -152.485852) (xy 199.81672 -152.485852) (xy 199.81672 -151.622252) (xy 199.81721 -151.592284)
			(xy 199.825033 -151.532862) (xy 199.840546 -151.474969) (xy 199.863482 -151.419596) (xy 199.893449 -151.36769)
			(xy 199.929936 -151.32014) (xy 199.972316 -151.27776) (xy 200.019866 -151.241273) (xy 200.071772 -151.211306)
			(xy 200.127145 -151.18837) (xy 200.185038 -151.172857) (xy 200.24446 -151.165034) (xy 200.304396 -151.165034)
			(xy 200.363818 -151.172857) (xy 200.421711 -151.18837) (xy 200.477084 -151.211306) (xy 200.52899 -151.241273)
			(xy 200.57654 -151.27776) (xy 200.61892 -151.32014) (xy 200.655407 -151.36769) (xy 200.685374 -151.419596)
			(xy 200.70831 -151.474969) (xy 200.723823 -151.532862) (xy 200.731646 -151.592284) (xy 200.732136 -151.622252)
			(xy 200.732136 -151.914098) (xy 236.712252 -151.914098) (xy 236.712252 -151.050498) (xy 236.712742 -151.020514)
			(xy 236.72057 -150.961058) (xy 236.736091 -150.903133) (xy 236.75904 -150.847729) (xy 236.789024 -150.795795)
			(xy 236.82553 -150.748219) (xy 236.867935 -150.705814) (xy 236.915511 -150.669308) (xy 236.967445 -150.639324)
			(xy 237.022849 -150.616375) (xy 237.080774 -150.600854) (xy 237.14023 -150.593026) (xy 237.200198 -150.593026)
			(xy 237.259654 -150.600854) (xy 237.317579 -150.616375) (xy 237.372983 -150.639324) (xy 237.424917 -150.669308)
			(xy 237.448336 -150.687278) (xy 298.799504 -150.687278) (xy 298.799504 -149.823678) (xy 298.799994 -149.79371)
			(xy 298.807817 -149.734288) (xy 298.82333 -149.676395) (xy 298.846266 -149.621022) (xy 298.876233 -149.569116)
			(xy 298.91272 -149.521566) (xy 298.9551 -149.479186) (xy 299.00265 -149.442699) (xy 299.054556 -149.412732)
			(xy 299.109929 -149.389796) (xy 299.167822 -149.374283) (xy 299.227244 -149.36646) (xy 299.28718 -149.36646)
			(xy 299.346602 -149.374283) (xy 299.404495 -149.389796) (xy 299.459868 -149.412732) (xy 299.511774 -149.442699)
			(xy 299.559324 -149.479186) (xy 299.601704 -149.521566) (xy 299.638191 -149.569116) (xy 299.668158 -149.621022)
			(xy 299.691094 -149.676395) (xy 299.706607 -149.734288) (xy 299.71443 -149.79371) (xy 299.71492 -149.823678)
			(xy 299.71492 -150.67915) (xy 313.274456 -150.67915) (xy 313.274456 -149.81555) (xy 313.274946 -149.785582)
			(xy 313.282769 -149.72616) (xy 313.298282 -149.668267) (xy 313.321218 -149.612894) (xy 313.351185 -149.560988)
			(xy 313.387672 -149.513438) (xy 313.430052 -149.471058) (xy 313.477602 -149.434571) (xy 313.529508 -149.404604)
			(xy 313.584881 -149.381668) (xy 313.642774 -149.366155) (xy 313.702196 -149.358332) (xy 313.762132 -149.358332)
			(xy 313.821554 -149.366155) (xy 313.879447 -149.381668) (xy 313.93482 -149.404604) (xy 313.986726 -149.434571)
			(xy 314.034276 -149.471058) (xy 314.076656 -149.513438) (xy 314.113143 -149.560988) (xy 314.14311 -149.612894)
			(xy 314.166046 -149.668267) (xy 314.181559 -149.72616) (xy 314.189382 -149.785582) (xy 314.189872 -149.81555)
			(xy 314.189872 -150.67915) (xy 314.189739 -150.687278) (xy 414.899348 -150.687278) (xy 414.899348 -149.823678)
			(xy 414.899838 -149.793694) (xy 414.907666 -149.734238) (xy 414.923187 -149.676313) (xy 414.946136 -149.620909)
			(xy 414.97612 -149.568975) (xy 415.012626 -149.521399) (xy 415.055031 -149.478994) (xy 415.102607 -149.442488)
			(xy 415.154541 -149.412504) (xy 415.209945 -149.389555) (xy 415.26787 -149.374034) (xy 415.327326 -149.366206)
			(xy 415.387294 -149.366206) (xy 415.44675 -149.374034) (xy 415.504675 -149.389555) (xy 415.560079 -149.412504)
			(xy 415.612013 -149.442488) (xy 415.659589 -149.478994) (xy 415.701994 -149.521399) (xy 415.7385 -149.568975)
			(xy 415.768484 -149.620909) (xy 415.791433 -149.676313) (xy 415.806954 -149.734238) (xy 415.814782 -149.793694)
			(xy 415.815272 -149.823678) (xy 415.815272 -150.67915) (xy 429.3743 -150.67915) (xy 429.3743 -149.81555)
			(xy 429.37479 -149.785566) (xy 429.382618 -149.72611) (xy 429.398139 -149.668185) (xy 429.421088 -149.612781)
			(xy 429.451072 -149.560847) (xy 429.487578 -149.513271) (xy 429.529983 -149.470866) (xy 429.577559 -149.43436)
			(xy 429.629493 -149.404376) (xy 429.684897 -149.381427) (xy 429.742822 -149.365906) (xy 429.802278 -149.358078)
			(xy 429.862246 -149.358078) (xy 429.921702 -149.365906) (xy 429.979627 -149.381427) (xy 430.035031 -149.404376)
			(xy 430.086965 -149.43436) (xy 430.134541 -149.470866) (xy 430.176946 -149.513271) (xy 430.213452 -149.560847)
			(xy 430.243436 -149.612781) (xy 430.266385 -149.668185) (xy 430.281906 -149.72611) (xy 430.289734 -149.785566)
			(xy 430.290224 -149.81555) (xy 430.290224 -150.67915) (xy 430.289734 -150.709134) (xy 430.281906 -150.76859)
			(xy 430.266385 -150.826515) (xy 430.243436 -150.881919) (xy 430.213452 -150.933853) (xy 430.176946 -150.981429)
			(xy 430.134541 -151.023834) (xy 430.086965 -151.06034) (xy 430.035031 -151.090324) (xy 429.979627 -151.113273)
			(xy 429.921702 -151.128794) (xy 429.862246 -151.136622) (xy 429.802278 -151.136622) (xy 429.742822 -151.128794)
			(xy 429.684897 -151.113273) (xy 429.629493 -151.090324) (xy 429.577559 -151.06034) (xy 429.529983 -151.023834)
			(xy 429.487578 -150.981429) (xy 429.451072 -150.933853) (xy 429.421088 -150.881919) (xy 429.398139 -150.826515)
			(xy 429.382618 -150.76859) (xy 429.37479 -150.709134) (xy 429.3743 -150.67915) (xy 415.815272 -150.67915)
			(xy 415.815272 -150.687278) (xy 415.814782 -150.717262) (xy 415.806954 -150.776718) (xy 415.791433 -150.834643)
			(xy 415.768484 -150.890047) (xy 415.7385 -150.941981) (xy 415.701994 -150.989557) (xy 415.659589 -151.031962)
			(xy 415.612013 -151.068468) (xy 415.560079 -151.098452) (xy 415.504675 -151.121401) (xy 415.44675 -151.136922)
			(xy 415.387294 -151.14475) (xy 415.327326 -151.14475) (xy 415.26787 -151.136922) (xy 415.209945 -151.121401)
			(xy 415.154541 -151.098452) (xy 415.102607 -151.068468) (xy 415.055031 -151.031962) (xy 415.012626 -150.989557)
			(xy 414.97612 -150.941981) (xy 414.946136 -150.890047) (xy 414.923187 -150.834643) (xy 414.907666 -150.776718)
			(xy 414.899838 -150.717262) (xy 414.899348 -150.687278) (xy 314.189739 -150.687278) (xy 314.189382 -150.709118)
			(xy 314.181559 -150.76854) (xy 314.166046 -150.826433) (xy 314.14311 -150.881806) (xy 314.113143 -150.933712)
			(xy 314.076656 -150.981262) (xy 314.034276 -151.023642) (xy 313.986726 -151.060129) (xy 313.93482 -151.090096)
			(xy 313.879447 -151.113032) (xy 313.821554 -151.128545) (xy 313.762132 -151.136368) (xy 313.702196 -151.136368)
			(xy 313.642774 -151.128545) (xy 313.584881 -151.113032) (xy 313.529508 -151.090096) (xy 313.477602 -151.060129)
			(xy 313.430052 -151.023642) (xy 313.387672 -150.981262) (xy 313.351185 -150.933712) (xy 313.321218 -150.881806)
			(xy 313.298282 -150.826433) (xy 313.282769 -150.76854) (xy 313.274946 -150.709118) (xy 313.274456 -150.67915)
			(xy 299.71492 -150.67915) (xy 299.71492 -150.687278) (xy 299.71443 -150.717246) (xy 299.706607 -150.776668)
			(xy 299.691094 -150.834561) (xy 299.668158 -150.889934) (xy 299.638191 -150.94184) (xy 299.601704 -150.98939)
			(xy 299.559324 -151.03177) (xy 299.511774 -151.068257) (xy 299.459868 -151.098224) (xy 299.404495 -151.12116)
			(xy 299.346602 -151.136673) (xy 299.28718 -151.144496) (xy 299.227244 -151.144496) (xy 299.167822 -151.136673)
			(xy 299.109929 -151.12116) (xy 299.054556 -151.098224) (xy 299.00265 -151.068257) (xy 298.9551 -151.03177)
			(xy 298.91272 -150.98939) (xy 298.876233 -150.94184) (xy 298.846266 -150.889934) (xy 298.82333 -150.834561)
			(xy 298.807817 -150.776668) (xy 298.799994 -150.717246) (xy 298.799504 -150.687278) (xy 237.448336 -150.687278)
			(xy 237.472493 -150.705814) (xy 237.514898 -150.748219) (xy 237.551404 -150.795795) (xy 237.581388 -150.847729)
			(xy 237.604337 -150.903133) (xy 237.619858 -150.961058) (xy 237.627686 -151.020514) (xy 237.628176 -151.050498)
			(xy 237.628176 -151.914098) (xy 237.627686 -151.944082) (xy 237.619858 -152.003538) (xy 237.604337 -152.061463)
			(xy 237.581388 -152.116867) (xy 237.551404 -152.168801) (xy 237.514898 -152.216377) (xy 237.472493 -152.258782)
			(xy 237.424917 -152.295288) (xy 237.372983 -152.325272) (xy 237.317579 -152.348221) (xy 237.259654 -152.363742)
			(xy 237.200198 -152.37157) (xy 237.14023 -152.37157) (xy 237.080774 -152.363742) (xy 237.022849 -152.348221)
			(xy 236.967445 -152.325272) (xy 236.915511 -152.295288) (xy 236.867935 -152.258782) (xy 236.82553 -152.216377)
			(xy 236.789024 -152.168801) (xy 236.75904 -152.116867) (xy 236.736091 -152.061463) (xy 236.72057 -152.003538)
			(xy 236.712742 -151.944082) (xy 236.712252 -151.914098) (xy 200.732136 -151.914098) (xy 200.732136 -152.485852)
			(xy 200.732111 -152.487376) (xy 296.945304 -152.487376) (xy 296.945304 -151.623776) (xy 296.945794 -151.593808)
			(xy 296.953617 -151.534386) (xy 296.96913 -151.476493) (xy 296.992066 -151.42112) (xy 297.022033 -151.369214)
			(xy 297.05852 -151.321664) (xy 297.1009 -151.279284) (xy 297.14845 -151.242797) (xy 297.200356 -151.21283)
			(xy 297.255729 -151.189894) (xy 297.313622 -151.174381) (xy 297.373044 -151.166558) (xy 297.43298 -151.166558)
			(xy 297.492402 -151.174381) (xy 297.550295 -151.189894) (xy 297.605668 -151.21283) (xy 297.657574 -151.242797)
			(xy 297.705124 -151.279284) (xy 297.747504 -151.321664) (xy 297.783991 -151.369214) (xy 297.813958 -151.42112)
			(xy 297.836894 -151.476493) (xy 297.852407 -151.534386) (xy 297.86023 -151.593808) (xy 297.86072 -151.623776)
			(xy 297.86072 -152.485852) (xy 315.916564 -152.485852) (xy 315.916564 -151.622252) (xy 315.917054 -151.592284)
			(xy 315.924877 -151.532862) (xy 315.94039 -151.474969) (xy 315.963326 -151.419596) (xy 315.993293 -151.36769)
			(xy 316.02978 -151.32014) (xy 316.07216 -151.27776) (xy 316.11971 -151.241273) (xy 316.171616 -151.211306)
			(xy 316.226989 -151.18837) (xy 316.284882 -151.172857) (xy 316.344304 -151.165034) (xy 316.40424 -151.165034)
			(xy 316.463662 -151.172857) (xy 316.521555 -151.18837) (xy 316.576928 -151.211306) (xy 316.628834 -151.241273)
			(xy 316.676384 -151.27776) (xy 316.718764 -151.32014) (xy 316.755251 -151.36769) (xy 316.785218 -151.419596)
			(xy 316.808154 -151.474969) (xy 316.823667 -151.532862) (xy 316.83149 -151.592284) (xy 316.83198 -151.622252)
			(xy 316.83198 -152.485852) (xy 316.831955 -152.487376) (xy 413.045148 -152.487376) (xy 413.045148 -151.623776)
			(xy 413.045638 -151.593792) (xy 413.053466 -151.534336) (xy 413.068987 -151.476411) (xy 413.091936 -151.421007)
			(xy 413.12192 -151.369073) (xy 413.158426 -151.321497) (xy 413.200831 -151.279092) (xy 413.248407 -151.242586)
			(xy 413.300341 -151.212602) (xy 413.355745 -151.189653) (xy 413.41367 -151.174132) (xy 413.473126 -151.166304)
			(xy 413.533094 -151.166304) (xy 413.59255 -151.174132) (xy 413.650475 -151.189653) (xy 413.705879 -151.212602)
			(xy 413.757813 -151.242586) (xy 413.805389 -151.279092) (xy 413.847794 -151.321497) (xy 413.8843 -151.369073)
			(xy 413.914284 -151.421007) (xy 413.937233 -151.476411) (xy 413.952754 -151.534336) (xy 413.960582 -151.593792)
			(xy 413.961072 -151.623776) (xy 413.961072 -152.485852) (xy 432.016408 -152.485852) (xy 432.016408 -151.622252)
			(xy 432.016898 -151.592268) (xy 432.024726 -151.532812) (xy 432.040247 -151.474887) (xy 432.063196 -151.419483)
			(xy 432.09318 -151.367549) (xy 432.129686 -151.319973) (xy 432.172091 -151.277568) (xy 432.219667 -151.241062)
			(xy 432.271601 -151.211078) (xy 432.327005 -151.188129) (xy 432.38493 -151.172608) (xy 432.444386 -151.16478)
			(xy 432.504354 -151.16478) (xy 432.56381 -151.172608) (xy 432.621735 -151.188129) (xy 432.677139 -151.211078)
			(xy 432.729073 -151.241062) (xy 432.776649 -151.277568) (xy 432.819054 -151.319973) (xy 432.85556 -151.367549)
			(xy 432.885544 -151.419483) (xy 432.908493 -151.474887) (xy 432.924014 -151.532812) (xy 432.931842 -151.592268)
			(xy 432.932332 -151.622252) (xy 432.932332 -152.485852) (xy 432.931842 -152.515836) (xy 432.924014 -152.575292)
			(xy 432.908493 -152.633217) (xy 432.885544 -152.688621) (xy 432.85556 -152.740555) (xy 432.819054 -152.788131)
			(xy 432.776649 -152.830536) (xy 432.729073 -152.867042) (xy 432.677139 -152.897026) (xy 432.621735 -152.919975)
			(xy 432.56381 -152.935496) (xy 432.504354 -152.943324) (xy 432.444386 -152.943324) (xy 432.38493 -152.935496)
			(xy 432.327005 -152.919975) (xy 432.271601 -152.897026) (xy 432.219667 -152.867042) (xy 432.172091 -152.830536)
			(xy 432.129686 -152.788131) (xy 432.09318 -152.740555) (xy 432.063196 -152.688621) (xy 432.040247 -152.633217)
			(xy 432.024726 -152.575292) (xy 432.016898 -152.515836) (xy 432.016408 -152.485852) (xy 413.961072 -152.485852)
			(xy 413.961072 -152.487376) (xy 413.960582 -152.51736) (xy 413.952754 -152.576816) (xy 413.937233 -152.634741)
			(xy 413.914284 -152.690145) (xy 413.8843 -152.742079) (xy 413.847794 -152.789655) (xy 413.805389 -152.83206)
			(xy 413.757813 -152.868566) (xy 413.705879 -152.89855) (xy 413.650475 -152.921499) (xy 413.59255 -152.93702)
			(xy 413.533094 -152.944848) (xy 413.473126 -152.944848) (xy 413.41367 -152.93702) (xy 413.355745 -152.921499)
			(xy 413.300341 -152.89855) (xy 413.248407 -152.868566) (xy 413.200831 -152.83206) (xy 413.158426 -152.789655)
			(xy 413.12192 -152.742079) (xy 413.091936 -152.690145) (xy 413.068987 -152.634741) (xy 413.053466 -152.576816)
			(xy 413.045638 -152.51736) (xy 413.045148 -152.487376) (xy 316.831955 -152.487376) (xy 316.83149 -152.51582)
			(xy 316.823667 -152.575242) (xy 316.808154 -152.633135) (xy 316.785218 -152.688508) (xy 316.755251 -152.740414)
			(xy 316.718764 -152.787964) (xy 316.676384 -152.830344) (xy 316.628834 -152.866831) (xy 316.576928 -152.896798)
			(xy 316.521555 -152.919734) (xy 316.463662 -152.935247) (xy 316.40424 -152.94307) (xy 316.344304 -152.94307)
			(xy 316.284882 -152.935247) (xy 316.226989 -152.919734) (xy 316.171616 -152.896798) (xy 316.11971 -152.866831)
			(xy 316.07216 -152.830344) (xy 316.02978 -152.787964) (xy 315.993293 -152.740414) (xy 315.963326 -152.688508)
			(xy 315.94039 -152.633135) (xy 315.924877 -152.575242) (xy 315.917054 -152.51582) (xy 315.916564 -152.485852)
			(xy 297.86072 -152.485852) (xy 297.86072 -152.487376) (xy 297.86023 -152.517344) (xy 297.852407 -152.576766)
			(xy 297.836894 -152.634659) (xy 297.813958 -152.690032) (xy 297.783991 -152.741938) (xy 297.747504 -152.789488)
			(xy 297.705124 -152.831868) (xy 297.657574 -152.868355) (xy 297.605668 -152.898322) (xy 297.550295 -152.921258)
			(xy 297.492402 -152.936771) (xy 297.43298 -152.944594) (xy 297.373044 -152.944594) (xy 297.313622 -152.936771)
			(xy 297.255729 -152.921258) (xy 297.200356 -152.898322) (xy 297.14845 -152.868355) (xy 297.1009 -152.831868)
			(xy 297.05852 -152.789488) (xy 297.022033 -152.741938) (xy 296.992066 -152.690032) (xy 296.96913 -152.634659)
			(xy 296.953617 -152.576766) (xy 296.945794 -152.517344) (xy 296.945304 -152.487376) (xy 200.732111 -152.487376)
			(xy 200.731646 -152.51582) (xy 200.723823 -152.575242) (xy 200.70831 -152.633135) (xy 200.685374 -152.688508)
			(xy 200.655407 -152.740414) (xy 200.61892 -152.787964) (xy 200.57654 -152.830344) (xy 200.52899 -152.866831)
			(xy 200.477084 -152.896798) (xy 200.421711 -152.919734) (xy 200.363818 -152.935247) (xy 200.304396 -152.94307)
			(xy 200.24446 -152.94307) (xy 200.185038 -152.935247) (xy 200.127145 -152.919734) (xy 200.071772 -152.896798)
			(xy 200.019866 -152.866831) (xy 199.972316 -152.830344) (xy 199.929936 -152.787964) (xy 199.893449 -152.740414)
			(xy 199.863482 -152.688508) (xy 199.840546 -152.633135) (xy 199.825033 -152.575242) (xy 199.81721 -152.51582)
			(xy 199.81672 -152.485852) (xy 181.760876 -152.485852) (xy 181.760876 -152.487376) (xy 181.760386 -152.517344)
			(xy 181.752563 -152.576766) (xy 181.73705 -152.634659) (xy 181.714114 -152.690032) (xy 181.684147 -152.741938)
			(xy 181.64766 -152.789488) (xy 181.60528 -152.831868) (xy 181.55773 -152.868355) (xy 181.505824 -152.898322)
			(xy 181.450451 -152.921258) (xy 181.392558 -152.936771) (xy 181.333136 -152.944594) (xy 181.2732 -152.944594)
			(xy 181.213778 -152.936771) (xy 181.155885 -152.921258) (xy 181.100512 -152.898322) (xy 181.048606 -152.868355)
			(xy 181.001056 -152.831868) (xy 180.958676 -152.789488) (xy 180.922189 -152.741938) (xy 180.892222 -152.690032)
			(xy 180.869286 -152.634659) (xy 180.853773 -152.576766) (xy 180.84595 -152.517344) (xy 180.84546 -152.487376)
			(xy 84.632267 -152.487376) (xy 84.631802 -152.515836) (xy 84.623974 -152.575292) (xy 84.608453 -152.633217)
			(xy 84.585504 -152.688621) (xy 84.55552 -152.740555) (xy 84.519014 -152.788131) (xy 84.476609 -152.830536)
			(xy 84.429033 -152.867042) (xy 84.377099 -152.897026) (xy 84.321695 -152.919975) (xy 84.26377 -152.935496)
			(xy 84.204314 -152.943324) (xy 84.144346 -152.943324) (xy 84.08489 -152.935496) (xy 84.026965 -152.919975)
			(xy 83.971561 -152.897026) (xy 83.919627 -152.867042) (xy 83.872051 -152.830536) (xy 83.829646 -152.788131)
			(xy 83.79314 -152.740555) (xy 83.763156 -152.688621) (xy 83.740207 -152.633217) (xy 83.724686 -152.575292)
			(xy 83.716858 -152.515836) (xy 83.716368 -152.485852) (xy 65.661032 -152.485852) (xy 65.661032 -152.487376)
			(xy 65.660542 -152.51736) (xy 65.652714 -152.576816) (xy 65.637193 -152.634741) (xy 65.614244 -152.690145)
			(xy 65.58426 -152.742079) (xy 65.547754 -152.789655) (xy 65.505349 -152.83206) (xy 65.457773 -152.868566)
			(xy 65.405839 -152.89855) (xy 65.350435 -152.921499) (xy 65.29251 -152.93702) (xy 65.233054 -152.944848)
			(xy 65.173086 -152.944848) (xy 65.11363 -152.93702) (xy 65.055705 -152.921499) (xy 65.000301 -152.89855)
			(xy 64.948367 -152.868566) (xy 64.900791 -152.83206) (xy 64.858386 -152.789655) (xy 64.82188 -152.742079)
			(xy 64.791896 -152.690145) (xy 64.768947 -152.634741) (xy 64.753426 -152.576816) (xy 64.745598 -152.51736)
			(xy 64.745108 -152.487376) (xy 4.308094 -152.487376) (xy 4.308094 -154.28722) (xy 66.599308 -154.28722)
			(xy 66.599308 -153.42362) (xy 66.599798 -153.393636) (xy 66.607626 -153.33418) (xy 66.623147 -153.276255)
			(xy 66.646096 -153.220851) (xy 66.67608 -153.168917) (xy 66.712586 -153.121341) (xy 66.754991 -153.078936)
			(xy 66.802567 -153.04243) (xy 66.854501 -153.012446) (xy 66.909905 -152.989497) (xy 66.96783 -152.973976)
			(xy 67.027286 -152.966148) (xy 67.087254 -152.966148) (xy 67.14671 -152.973976) (xy 67.204635 -152.989497)
			(xy 67.260039 -153.012446) (xy 67.311973 -153.04243) (xy 67.359549 -153.078936) (xy 67.401954 -153.121341)
			(xy 67.43846 -153.168917) (xy 67.468444 -153.220851) (xy 67.491393 -153.276255) (xy 67.506914 -153.33418)
			(xy 67.514742 -153.393636) (xy 67.515232 -153.42362) (xy 67.515232 -154.279346) (xy 81.07426 -154.279346)
			(xy 81.07426 -153.415746) (xy 81.07475 -153.385762) (xy 81.082578 -153.326306) (xy 81.098099 -153.268381)
			(xy 81.121048 -153.212977) (xy 81.151032 -153.161043) (xy 81.187538 -153.113467) (xy 81.229943 -153.071062)
			(xy 81.277519 -153.034556) (xy 81.329453 -153.004572) (xy 81.384857 -152.981623) (xy 81.442782 -152.966102)
			(xy 81.502238 -152.958274) (xy 81.562206 -152.958274) (xy 81.621662 -152.966102) (xy 81.679587 -152.981623)
			(xy 81.734991 -153.004572) (xy 81.786925 -153.034556) (xy 81.834501 -153.071062) (xy 81.876906 -153.113467)
			(xy 81.913412 -153.161043) (xy 81.943396 -153.212977) (xy 81.966345 -153.268381) (xy 81.981866 -153.326306)
			(xy 81.989694 -153.385762) (xy 81.990184 -153.415746) (xy 81.990184 -154.279346) (xy 81.990055 -154.28722)
			(xy 182.69966 -154.28722) (xy 182.69966 -153.42362) (xy 182.70015 -153.393652) (xy 182.707973 -153.33423)
			(xy 182.723486 -153.276337) (xy 182.746422 -153.220964) (xy 182.776389 -153.169058) (xy 182.812876 -153.121508)
			(xy 182.855256 -153.079128) (xy 182.902806 -153.042641) (xy 182.954712 -153.012674) (xy 183.010085 -152.989738)
			(xy 183.067978 -152.974225) (xy 183.1274 -152.966402) (xy 183.187336 -152.966402) (xy 183.246758 -152.974225)
			(xy 183.304651 -152.989738) (xy 183.360024 -153.012674) (xy 183.41193 -153.042641) (xy 183.45948 -153.079128)
			(xy 183.50186 -153.121508) (xy 183.538347 -153.169058) (xy 183.568314 -153.220964) (xy 183.59125 -153.276337)
			(xy 183.606763 -153.33423) (xy 183.614586 -153.393652) (xy 183.615076 -153.42362) (xy 183.615076 -154.279346)
			(xy 197.174612 -154.279346) (xy 197.174612 -153.415746) (xy 197.175102 -153.385778) (xy 197.182925 -153.326356)
			(xy 197.198438 -153.268463) (xy 197.221374 -153.21309) (xy 197.251341 -153.161184) (xy 197.287828 -153.113634)
			(xy 197.330208 -153.071254) (xy 197.377758 -153.034767) (xy 197.429664 -153.0048) (xy 197.485037 -152.981864)
			(xy 197.54293 -152.966351) (xy 197.602352 -152.958528) (xy 197.662288 -152.958528) (xy 197.72171 -152.966351)
			(xy 197.779603 -152.981864) (xy 197.834976 -153.0048) (xy 197.886882 -153.034767) (xy 197.934432 -153.071254)
			(xy 197.976812 -153.113634) (xy 198.013299 -153.161184) (xy 198.043266 -153.21309) (xy 198.066202 -153.268463)
			(xy 198.081715 -153.326356) (xy 198.089538 -153.385778) (xy 198.090028 -153.415746) (xy 198.090028 -154.279346)
			(xy 198.089899 -154.28722) (xy 298.799504 -154.28722) (xy 298.799504 -153.42362) (xy 298.799994 -153.393652)
			(xy 298.807817 -153.33423) (xy 298.82333 -153.276337) (xy 298.846266 -153.220964) (xy 298.876233 -153.169058)
			(xy 298.91272 -153.121508) (xy 298.9551 -153.079128) (xy 299.00265 -153.042641) (xy 299.054556 -153.012674)
			(xy 299.109929 -152.989738) (xy 299.167822 -152.974225) (xy 299.227244 -152.966402) (xy 299.28718 -152.966402)
			(xy 299.346602 -152.974225) (xy 299.404495 -152.989738) (xy 299.459868 -153.012674) (xy 299.511774 -153.042641)
			(xy 299.559324 -153.079128) (xy 299.601704 -153.121508) (xy 299.638191 -153.169058) (xy 299.668158 -153.220964)
			(xy 299.691094 -153.276337) (xy 299.706607 -153.33423) (xy 299.71443 -153.393652) (xy 299.71492 -153.42362)
			(xy 299.71492 -154.279346) (xy 313.274456 -154.279346) (xy 313.274456 -153.415746) (xy 313.274946 -153.385778)
			(xy 313.282769 -153.326356) (xy 313.298282 -153.268463) (xy 313.321218 -153.21309) (xy 313.351185 -153.161184)
			(xy 313.387672 -153.113634) (xy 313.430052 -153.071254) (xy 313.477602 -153.034767) (xy 313.529508 -153.0048)
			(xy 313.584881 -152.981864) (xy 313.642774 -152.966351) (xy 313.702196 -152.958528) (xy 313.762132 -152.958528)
			(xy 313.821554 -152.966351) (xy 313.879447 -152.981864) (xy 313.93482 -153.0048) (xy 313.986726 -153.034767)
			(xy 314.034276 -153.071254) (xy 314.076656 -153.113634) (xy 314.113143 -153.161184) (xy 314.14311 -153.21309)
			(xy 314.166046 -153.268463) (xy 314.181559 -153.326356) (xy 314.189382 -153.385778) (xy 314.189872 -153.415746)
			(xy 314.189872 -154.279346) (xy 314.189743 -154.28722) (xy 414.899348 -154.28722) (xy 414.899348 -153.42362)
			(xy 414.899838 -153.393636) (xy 414.907666 -153.33418) (xy 414.923187 -153.276255) (xy 414.946136 -153.220851)
			(xy 414.97612 -153.168917) (xy 415.012626 -153.121341) (xy 415.055031 -153.078936) (xy 415.102607 -153.04243)
			(xy 415.154541 -153.012446) (xy 415.209945 -152.989497) (xy 415.26787 -152.973976) (xy 415.327326 -152.966148)
			(xy 415.387294 -152.966148) (xy 415.44675 -152.973976) (xy 415.504675 -152.989497) (xy 415.560079 -153.012446)
			(xy 415.612013 -153.04243) (xy 415.659589 -153.078936) (xy 415.701994 -153.121341) (xy 415.7385 -153.168917)
			(xy 415.768484 -153.220851) (xy 415.791433 -153.276255) (xy 415.806954 -153.33418) (xy 415.814782 -153.393636)
			(xy 415.815272 -153.42362) (xy 415.815272 -154.279346) (xy 429.3743 -154.279346) (xy 429.3743 -153.415746)
			(xy 429.37479 -153.385762) (xy 429.382618 -153.326306) (xy 429.398139 -153.268381) (xy 429.421088 -153.212977)
			(xy 429.451072 -153.161043) (xy 429.487578 -153.113467) (xy 429.529983 -153.071062) (xy 429.577559 -153.034556)
			(xy 429.629493 -153.004572) (xy 429.684897 -152.981623) (xy 429.742822 -152.966102) (xy 429.802278 -152.958274)
			(xy 429.862246 -152.958274) (xy 429.921702 -152.966102) (xy 429.979627 -152.981623) (xy 430.035031 -153.004572)
			(xy 430.086965 -153.034556) (xy 430.134541 -153.071062) (xy 430.176946 -153.113467) (xy 430.213452 -153.161043)
			(xy 430.243436 -153.212977) (xy 430.266385 -153.268381) (xy 430.281906 -153.326306) (xy 430.289734 -153.385762)
			(xy 430.290224 -153.415746) (xy 430.290224 -154.279346) (xy 430.289734 -154.30933) (xy 430.281906 -154.368786)
			(xy 430.266385 -154.426711) (xy 430.243436 -154.482115) (xy 430.213452 -154.534049) (xy 430.176946 -154.581625)
			(xy 430.134541 -154.62403) (xy 430.086965 -154.660536) (xy 430.035031 -154.69052) (xy 429.979627 -154.713469)
			(xy 429.921702 -154.72899) (xy 429.862246 -154.736818) (xy 429.802278 -154.736818) (xy 429.742822 -154.72899)
			(xy 429.684897 -154.713469) (xy 429.629493 -154.69052) (xy 429.577559 -154.660536) (xy 429.529983 -154.62403)
			(xy 429.487578 -154.581625) (xy 429.451072 -154.534049) (xy 429.421088 -154.482115) (xy 429.398139 -154.426711)
			(xy 429.382618 -154.368786) (xy 429.37479 -154.30933) (xy 429.3743 -154.279346) (xy 415.815272 -154.279346)
			(xy 415.815272 -154.28722) (xy 415.814782 -154.317204) (xy 415.806954 -154.37666) (xy 415.791433 -154.434585)
			(xy 415.768484 -154.489989) (xy 415.7385 -154.541923) (xy 415.701994 -154.589499) (xy 415.659589 -154.631904)
			(xy 415.612013 -154.66841) (xy 415.560079 -154.698394) (xy 415.504675 -154.721343) (xy 415.44675 -154.736864)
			(xy 415.387294 -154.744692) (xy 415.327326 -154.744692) (xy 415.26787 -154.736864) (xy 415.209945 -154.721343)
			(xy 415.154541 -154.698394) (xy 415.102607 -154.66841) (xy 415.055031 -154.631904) (xy 415.012626 -154.589499)
			(xy 414.97612 -154.541923) (xy 414.946136 -154.489989) (xy 414.923187 -154.434585) (xy 414.907666 -154.37666)
			(xy 414.899838 -154.317204) (xy 414.899348 -154.28722) (xy 314.189743 -154.28722) (xy 314.189382 -154.309314)
			(xy 314.181559 -154.368736) (xy 314.166046 -154.426629) (xy 314.14311 -154.482002) (xy 314.113143 -154.533908)
			(xy 314.076656 -154.581458) (xy 314.034276 -154.623838) (xy 313.986726 -154.660325) (xy 313.93482 -154.690292)
			(xy 313.879447 -154.713228) (xy 313.821554 -154.728741) (xy 313.762132 -154.736564) (xy 313.702196 -154.736564)
			(xy 313.642774 -154.728741) (xy 313.584881 -154.713228) (xy 313.529508 -154.690292) (xy 313.477602 -154.660325)
			(xy 313.430052 -154.623838) (xy 313.387672 -154.581458) (xy 313.351185 -154.533908) (xy 313.321218 -154.482002)
			(xy 313.298282 -154.426629) (xy 313.282769 -154.368736) (xy 313.274946 -154.309314) (xy 313.274456 -154.279346)
			(xy 299.71492 -154.279346) (xy 299.71492 -154.28722) (xy 299.71443 -154.317188) (xy 299.706607 -154.37661)
			(xy 299.691094 -154.434503) (xy 299.668158 -154.489876) (xy 299.638191 -154.541782) (xy 299.601704 -154.589332)
			(xy 299.559324 -154.631712) (xy 299.511774 -154.668199) (xy 299.459868 -154.698166) (xy 299.404495 -154.721102)
			(xy 299.346602 -154.736615) (xy 299.28718 -154.744438) (xy 299.227244 -154.744438) (xy 299.167822 -154.736615)
			(xy 299.109929 -154.721102) (xy 299.054556 -154.698166) (xy 299.00265 -154.668199) (xy 298.9551 -154.631712)
			(xy 298.91272 -154.589332) (xy 298.876233 -154.541782) (xy 298.846266 -154.489876) (xy 298.82333 -154.434503)
			(xy 298.807817 -154.37661) (xy 298.799994 -154.317188) (xy 298.799504 -154.28722) (xy 198.089899 -154.28722)
			(xy 198.089538 -154.309314) (xy 198.081715 -154.368736) (xy 198.066202 -154.426629) (xy 198.043266 -154.482002)
			(xy 198.013299 -154.533908) (xy 197.976812 -154.581458) (xy 197.934432 -154.623838) (xy 197.886882 -154.660325)
			(xy 197.834976 -154.690292) (xy 197.779603 -154.713228) (xy 197.72171 -154.728741) (xy 197.662288 -154.736564)
			(xy 197.602352 -154.736564) (xy 197.54293 -154.728741) (xy 197.485037 -154.713228) (xy 197.429664 -154.690292)
			(xy 197.377758 -154.660325) (xy 197.330208 -154.623838) (xy 197.287828 -154.581458) (xy 197.251341 -154.533908)
			(xy 197.221374 -154.482002) (xy 197.198438 -154.426629) (xy 197.182925 -154.368736) (xy 197.175102 -154.309314)
			(xy 197.174612 -154.279346) (xy 183.615076 -154.279346) (xy 183.615076 -154.28722) (xy 183.614586 -154.317188)
			(xy 183.606763 -154.37661) (xy 183.59125 -154.434503) (xy 183.568314 -154.489876) (xy 183.538347 -154.541782)
			(xy 183.50186 -154.589332) (xy 183.45948 -154.631712) (xy 183.41193 -154.668199) (xy 183.360024 -154.698166)
			(xy 183.304651 -154.721102) (xy 183.246758 -154.736615) (xy 183.187336 -154.744438) (xy 183.1274 -154.744438)
			(xy 183.067978 -154.736615) (xy 183.010085 -154.721102) (xy 182.954712 -154.698166) (xy 182.902806 -154.668199)
			(xy 182.855256 -154.631712) (xy 182.812876 -154.589332) (xy 182.776389 -154.541782) (xy 182.746422 -154.489876)
			(xy 182.723486 -154.434503) (xy 182.707973 -154.37661) (xy 182.70015 -154.317188) (xy 182.69966 -154.28722)
			(xy 81.990055 -154.28722) (xy 81.989694 -154.30933) (xy 81.981866 -154.368786) (xy 81.966345 -154.426711)
			(xy 81.943396 -154.482115) (xy 81.913412 -154.534049) (xy 81.876906 -154.581625) (xy 81.834501 -154.62403)
			(xy 81.786925 -154.660536) (xy 81.734991 -154.69052) (xy 81.679587 -154.713469) (xy 81.621662 -154.72899)
			(xy 81.562206 -154.736818) (xy 81.502238 -154.736818) (xy 81.442782 -154.72899) (xy 81.384857 -154.713469)
			(xy 81.329453 -154.69052) (xy 81.277519 -154.660536) (xy 81.229943 -154.62403) (xy 81.187538 -154.581625)
			(xy 81.151032 -154.534049) (xy 81.121048 -154.482115) (xy 81.098099 -154.426711) (xy 81.082578 -154.368786)
			(xy 81.07475 -154.30933) (xy 81.07426 -154.279346) (xy 67.515232 -154.279346) (xy 67.515232 -154.28722)
			(xy 67.514742 -154.317204) (xy 67.506914 -154.37666) (xy 67.491393 -154.434585) (xy 67.468444 -154.489989)
			(xy 67.43846 -154.541923) (xy 67.401954 -154.589499) (xy 67.359549 -154.631904) (xy 67.311973 -154.66841)
			(xy 67.260039 -154.698394) (xy 67.204635 -154.721343) (xy 67.14671 -154.736864) (xy 67.087254 -154.744692)
			(xy 67.027286 -154.744692) (xy 66.96783 -154.736864) (xy 66.909905 -154.721343) (xy 66.854501 -154.698394)
			(xy 66.802567 -154.66841) (xy 66.754991 -154.631904) (xy 66.712586 -154.589499) (xy 66.67608 -154.541923)
			(xy 66.646096 -154.489989) (xy 66.623147 -154.434585) (xy 66.607626 -154.37666) (xy 66.599798 -154.317204)
			(xy 66.599308 -154.28722) (xy 4.308094 -154.28722) (xy 4.308094 -156.087318) (xy 64.745108 -156.087318)
			(xy 64.745108 -155.223718) (xy 64.745598 -155.193734) (xy 64.753426 -155.134278) (xy 64.768947 -155.076353)
			(xy 64.791896 -155.020949) (xy 64.82188 -154.969015) (xy 64.858386 -154.921439) (xy 64.900791 -154.879034)
			(xy 64.948367 -154.842528) (xy 65.000301 -154.812544) (xy 65.055705 -154.789595) (xy 65.11363 -154.774074)
			(xy 65.173086 -154.766246) (xy 65.233054 -154.766246) (xy 65.29251 -154.774074) (xy 65.350435 -154.789595)
			(xy 65.405839 -154.812544) (xy 65.457773 -154.842528) (xy 65.505349 -154.879034) (xy 65.547754 -154.921439)
			(xy 65.58426 -154.969015) (xy 65.614244 -155.020949) (xy 65.637193 -155.076353) (xy 65.652714 -155.134278)
			(xy 65.660542 -155.193734) (xy 65.661032 -155.223718) (xy 65.661032 -156.085794) (xy 83.716368 -156.085794)
			(xy 83.716368 -155.222194) (xy 83.716858 -155.19221) (xy 83.724686 -155.132754) (xy 83.740207 -155.074829)
			(xy 83.763156 -155.019425) (xy 83.79314 -154.967491) (xy 83.829646 -154.919915) (xy 83.872051 -154.87751)
			(xy 83.919627 -154.841004) (xy 83.971561 -154.81102) (xy 84.026965 -154.788071) (xy 84.08489 -154.77255)
			(xy 84.144346 -154.764722) (xy 84.204314 -154.764722) (xy 84.26377 -154.77255) (xy 84.321695 -154.788071)
			(xy 84.377099 -154.81102) (xy 84.429033 -154.841004) (xy 84.476609 -154.87751) (xy 84.519014 -154.919915)
			(xy 84.55552 -154.967491) (xy 84.585504 -155.019425) (xy 84.608453 -155.074829) (xy 84.623974 -155.132754)
			(xy 84.631802 -155.19221) (xy 84.632292 -155.222194) (xy 84.632292 -156.085794) (xy 84.632267 -156.087318)
			(xy 180.84546 -156.087318) (xy 180.84546 -155.223718) (xy 180.84595 -155.19375) (xy 180.853773 -155.134328)
			(xy 180.869286 -155.076435) (xy 180.892222 -155.021062) (xy 180.922189 -154.969156) (xy 180.958676 -154.921606)
			(xy 181.001056 -154.879226) (xy 181.048606 -154.842739) (xy 181.100512 -154.812772) (xy 181.155885 -154.789836)
			(xy 181.213778 -154.774323) (xy 181.2732 -154.7665) (xy 181.333136 -154.7665) (xy 181.392558 -154.774323)
			(xy 181.450451 -154.789836) (xy 181.505824 -154.812772) (xy 181.55773 -154.842739) (xy 181.60528 -154.879226)
			(xy 181.64766 -154.921606) (xy 181.684147 -154.969156) (xy 181.714114 -155.021062) (xy 181.73705 -155.076435)
			(xy 181.752563 -155.134328) (xy 181.760386 -155.19375) (xy 181.760876 -155.223718) (xy 181.760876 -156.085794)
			(xy 199.81672 -156.085794) (xy 199.81672 -155.222194) (xy 199.81721 -155.192226) (xy 199.825033 -155.132804)
			(xy 199.840546 -155.074911) (xy 199.863482 -155.019538) (xy 199.893449 -154.967632) (xy 199.929936 -154.920082)
			(xy 199.972316 -154.877702) (xy 200.019866 -154.841215) (xy 200.071772 -154.811248) (xy 200.127145 -154.788312)
			(xy 200.185038 -154.772799) (xy 200.24446 -154.764976) (xy 200.304396 -154.764976) (xy 200.363818 -154.772799)
			(xy 200.421711 -154.788312) (xy 200.477084 -154.811248) (xy 200.52899 -154.841215) (xy 200.57654 -154.877702)
			(xy 200.61892 -154.920082) (xy 200.655407 -154.967632) (xy 200.685374 -155.019538) (xy 200.70831 -155.074911)
			(xy 200.723823 -155.132804) (xy 200.731646 -155.192226) (xy 200.732136 -155.222194) (xy 200.732136 -156.085794)
			(xy 200.732111 -156.087318) (xy 296.945304 -156.087318) (xy 296.945304 -155.223718) (xy 296.945794 -155.19375)
			(xy 296.953617 -155.134328) (xy 296.96913 -155.076435) (xy 296.992066 -155.021062) (xy 297.022033 -154.969156)
			(xy 297.05852 -154.921606) (xy 297.1009 -154.879226) (xy 297.14845 -154.842739) (xy 297.200356 -154.812772)
			(xy 297.255729 -154.789836) (xy 297.313622 -154.774323) (xy 297.373044 -154.7665) (xy 297.43298 -154.7665)
			(xy 297.492402 -154.774323) (xy 297.550295 -154.789836) (xy 297.605668 -154.812772) (xy 297.657574 -154.842739)
			(xy 297.705124 -154.879226) (xy 297.747504 -154.921606) (xy 297.783991 -154.969156) (xy 297.813958 -155.021062)
			(xy 297.836894 -155.076435) (xy 297.852407 -155.134328) (xy 297.86023 -155.19375) (xy 297.86072 -155.223718)
			(xy 297.86072 -156.085794) (xy 315.916564 -156.085794) (xy 315.916564 -155.222194) (xy 315.917054 -155.192226)
			(xy 315.924877 -155.132804) (xy 315.94039 -155.074911) (xy 315.963326 -155.019538) (xy 315.993293 -154.967632)
			(xy 316.02978 -154.920082) (xy 316.07216 -154.877702) (xy 316.11971 -154.841215) (xy 316.171616 -154.811248)
			(xy 316.226989 -154.788312) (xy 316.284882 -154.772799) (xy 316.344304 -154.764976) (xy 316.40424 -154.764976)
			(xy 316.463662 -154.772799) (xy 316.521555 -154.788312) (xy 316.576928 -154.811248) (xy 316.628834 -154.841215)
			(xy 316.676384 -154.877702) (xy 316.718764 -154.920082) (xy 316.755251 -154.967632) (xy 316.785218 -155.019538)
			(xy 316.808154 -155.074911) (xy 316.823667 -155.132804) (xy 316.83149 -155.192226) (xy 316.83198 -155.222194)
			(xy 316.83198 -156.085794) (xy 316.831955 -156.087318) (xy 413.045148 -156.087318) (xy 413.045148 -155.223718)
			(xy 413.045638 -155.193734) (xy 413.053466 -155.134278) (xy 413.068987 -155.076353) (xy 413.091936 -155.020949)
			(xy 413.12192 -154.969015) (xy 413.158426 -154.921439) (xy 413.200831 -154.879034) (xy 413.248407 -154.842528)
			(xy 413.300341 -154.812544) (xy 413.355745 -154.789595) (xy 413.41367 -154.774074) (xy 413.473126 -154.766246)
			(xy 413.533094 -154.766246) (xy 413.59255 -154.774074) (xy 413.650475 -154.789595) (xy 413.705879 -154.812544)
			(xy 413.757813 -154.842528) (xy 413.805389 -154.879034) (xy 413.847794 -154.921439) (xy 413.8843 -154.969015)
			(xy 413.914284 -155.020949) (xy 413.937233 -155.076353) (xy 413.952754 -155.134278) (xy 413.960582 -155.193734)
			(xy 413.961072 -155.223718) (xy 413.961072 -156.085794) (xy 432.016408 -156.085794) (xy 432.016408 -155.222194)
			(xy 432.016898 -155.19221) (xy 432.024726 -155.132754) (xy 432.040247 -155.074829) (xy 432.063196 -155.019425)
			(xy 432.09318 -154.967491) (xy 432.129686 -154.919915) (xy 432.172091 -154.87751) (xy 432.219667 -154.841004)
			(xy 432.271601 -154.81102) (xy 432.327005 -154.788071) (xy 432.38493 -154.77255) (xy 432.444386 -154.764722)
			(xy 432.504354 -154.764722) (xy 432.56381 -154.77255) (xy 432.621735 -154.788071) (xy 432.677139 -154.81102)
			(xy 432.729073 -154.841004) (xy 432.776649 -154.87751) (xy 432.819054 -154.919915) (xy 432.85556 -154.967491)
			(xy 432.885544 -155.019425) (xy 432.908493 -155.074829) (xy 432.924014 -155.132754) (xy 432.931842 -155.19221)
			(xy 432.932332 -155.222194) (xy 432.932332 -156.085794) (xy 432.931842 -156.115778) (xy 432.924014 -156.175234)
			(xy 432.908493 -156.233159) (xy 432.885544 -156.288563) (xy 432.85556 -156.340497) (xy 432.819054 -156.388073)
			(xy 432.776649 -156.430478) (xy 432.729073 -156.466984) (xy 432.677139 -156.496968) (xy 432.621735 -156.519917)
			(xy 432.56381 -156.535438) (xy 432.504354 -156.543266) (xy 432.444386 -156.543266) (xy 432.38493 -156.535438)
			(xy 432.327005 -156.519917) (xy 432.271601 -156.496968) (xy 432.219667 -156.466984) (xy 432.172091 -156.430478)
			(xy 432.129686 -156.388073) (xy 432.09318 -156.340497) (xy 432.063196 -156.288563) (xy 432.040247 -156.233159)
			(xy 432.024726 -156.175234) (xy 432.016898 -156.115778) (xy 432.016408 -156.085794) (xy 413.961072 -156.085794)
			(xy 413.961072 -156.087318) (xy 413.960582 -156.117302) (xy 413.952754 -156.176758) (xy 413.937233 -156.234683)
			(xy 413.914284 -156.290087) (xy 413.8843 -156.342021) (xy 413.847794 -156.389597) (xy 413.805389 -156.432002)
			(xy 413.757813 -156.468508) (xy 413.705879 -156.498492) (xy 413.650475 -156.521441) (xy 413.59255 -156.536962)
			(xy 413.533094 -156.54479) (xy 413.473126 -156.54479) (xy 413.41367 -156.536962) (xy 413.355745 -156.521441)
			(xy 413.300341 -156.498492) (xy 413.248407 -156.468508) (xy 413.200831 -156.432002) (xy 413.158426 -156.389597)
			(xy 413.12192 -156.342021) (xy 413.091936 -156.290087) (xy 413.068987 -156.234683) (xy 413.053466 -156.176758)
			(xy 413.045638 -156.117302) (xy 413.045148 -156.087318) (xy 316.831955 -156.087318) (xy 316.83149 -156.115762)
			(xy 316.823667 -156.175184) (xy 316.808154 -156.233077) (xy 316.785218 -156.28845) (xy 316.755251 -156.340356)
			(xy 316.718764 -156.387906) (xy 316.676384 -156.430286) (xy 316.628834 -156.466773) (xy 316.576928 -156.49674)
			(xy 316.521555 -156.519676) (xy 316.463662 -156.535189) (xy 316.40424 -156.543012) (xy 316.344304 -156.543012)
			(xy 316.284882 -156.535189) (xy 316.226989 -156.519676) (xy 316.171616 -156.49674) (xy 316.11971 -156.466773)
			(xy 316.07216 -156.430286) (xy 316.02978 -156.387906) (xy 315.993293 -156.340356) (xy 315.963326 -156.28845)
			(xy 315.94039 -156.233077) (xy 315.924877 -156.175184) (xy 315.917054 -156.115762) (xy 315.916564 -156.085794)
			(xy 297.86072 -156.085794) (xy 297.86072 -156.087318) (xy 297.86023 -156.117286) (xy 297.852407 -156.176708)
			(xy 297.836894 -156.234601) (xy 297.813958 -156.289974) (xy 297.783991 -156.34188) (xy 297.747504 -156.38943)
			(xy 297.705124 -156.43181) (xy 297.657574 -156.468297) (xy 297.605668 -156.498264) (xy 297.550295 -156.5212)
			(xy 297.492402 -156.536713) (xy 297.43298 -156.544536) (xy 297.373044 -156.544536) (xy 297.313622 -156.536713)
			(xy 297.255729 -156.5212) (xy 297.200356 -156.498264) (xy 297.14845 -156.468297) (xy 297.1009 -156.43181)
			(xy 297.05852 -156.38943) (xy 297.022033 -156.34188) (xy 296.992066 -156.289974) (xy 296.96913 -156.234601)
			(xy 296.953617 -156.176708) (xy 296.945794 -156.117286) (xy 296.945304 -156.087318) (xy 200.732111 -156.087318)
			(xy 200.731646 -156.115762) (xy 200.723823 -156.175184) (xy 200.70831 -156.233077) (xy 200.685374 -156.28845)
			(xy 200.655407 -156.340356) (xy 200.61892 -156.387906) (xy 200.57654 -156.430286) (xy 200.52899 -156.466773)
			(xy 200.477084 -156.49674) (xy 200.421711 -156.519676) (xy 200.363818 -156.535189) (xy 200.304396 -156.543012)
			(xy 200.24446 -156.543012) (xy 200.185038 -156.535189) (xy 200.127145 -156.519676) (xy 200.071772 -156.49674)
			(xy 200.019866 -156.466773) (xy 199.972316 -156.430286) (xy 199.929936 -156.387906) (xy 199.893449 -156.340356)
			(xy 199.863482 -156.28845) (xy 199.840546 -156.233077) (xy 199.825033 -156.175184) (xy 199.81721 -156.115762)
			(xy 199.81672 -156.085794) (xy 181.760876 -156.085794) (xy 181.760876 -156.087318) (xy 181.760386 -156.117286)
			(xy 181.752563 -156.176708) (xy 181.73705 -156.234601) (xy 181.714114 -156.289974) (xy 181.684147 -156.34188)
			(xy 181.64766 -156.38943) (xy 181.60528 -156.43181) (xy 181.55773 -156.468297) (xy 181.505824 -156.498264)
			(xy 181.450451 -156.5212) (xy 181.392558 -156.536713) (xy 181.333136 -156.544536) (xy 181.2732 -156.544536)
			(xy 181.213778 -156.536713) (xy 181.155885 -156.5212) (xy 181.100512 -156.498264) (xy 181.048606 -156.468297)
			(xy 181.001056 -156.43181) (xy 180.958676 -156.38943) (xy 180.922189 -156.34188) (xy 180.892222 -156.289974)
			(xy 180.869286 -156.234601) (xy 180.853773 -156.176708) (xy 180.84595 -156.117286) (xy 180.84546 -156.087318)
			(xy 84.632267 -156.087318) (xy 84.631802 -156.115778) (xy 84.623974 -156.175234) (xy 84.608453 -156.233159)
			(xy 84.585504 -156.288563) (xy 84.55552 -156.340497) (xy 84.519014 -156.388073) (xy 84.476609 -156.430478)
			(xy 84.429033 -156.466984) (xy 84.377099 -156.496968) (xy 84.321695 -156.519917) (xy 84.26377 -156.535438)
			(xy 84.204314 -156.543266) (xy 84.144346 -156.543266) (xy 84.08489 -156.535438) (xy 84.026965 -156.519917)
			(xy 83.971561 -156.496968) (xy 83.919627 -156.466984) (xy 83.872051 -156.430478) (xy 83.829646 -156.388073)
			(xy 83.79314 -156.340497) (xy 83.763156 -156.288563) (xy 83.740207 -156.233159) (xy 83.724686 -156.175234)
			(xy 83.716858 -156.115778) (xy 83.716368 -156.085794) (xy 65.661032 -156.085794) (xy 65.661032 -156.087318)
			(xy 65.660542 -156.117302) (xy 65.652714 -156.176758) (xy 65.637193 -156.234683) (xy 65.614244 -156.290087)
			(xy 65.58426 -156.342021) (xy 65.547754 -156.389597) (xy 65.505349 -156.432002) (xy 65.457773 -156.468508)
			(xy 65.405839 -156.498492) (xy 65.350435 -156.521441) (xy 65.29251 -156.536962) (xy 65.233054 -156.54479)
			(xy 65.173086 -156.54479) (xy 65.11363 -156.536962) (xy 65.055705 -156.521441) (xy 65.000301 -156.498492)
			(xy 64.948367 -156.468508) (xy 64.900791 -156.432002) (xy 64.858386 -156.389597) (xy 64.82188 -156.342021)
			(xy 64.791896 -156.290087) (xy 64.768947 -156.234683) (xy 64.753426 -156.176758) (xy 64.745598 -156.117302)
			(xy 64.745108 -156.087318) (xy 4.308094 -156.087318) (xy 4.308094 -157.900066) (xy 228.314505 -157.900066)
			(xy 228.314505 -157.840134) (xy 228.322328 -157.780714) (xy 228.33784 -157.722823) (xy 228.360775 -157.667453)
			(xy 228.390741 -157.61555) (xy 228.427226 -157.568002) (xy 228.469605 -157.525624) (xy 228.517153 -157.489139)
			(xy 228.569056 -157.459173) (xy 228.624427 -157.436238) (xy 228.682318 -157.420727) (xy 228.741738 -157.412905)
			(xy 228.771704 -157.412436) (xy 229.635304 -157.412436) (xy 229.665274 -157.412838) (xy 229.724702 -157.420663)
			(xy 229.7826 -157.436177) (xy 229.837978 -157.459116) (xy 229.889888 -157.489086) (xy 229.937442 -157.525576)
			(xy 229.979827 -157.567961) (xy 230.016316 -157.615515) (xy 230.046286 -157.667425) (xy 230.069224 -157.722803)
			(xy 230.084738 -157.780702) (xy 230.092562 -157.84013) (xy 230.092562 -157.90007) (xy 230.089876 -157.920473)
			(xy 230.557725 -157.920473) (xy 230.557725 -157.860527) (xy 230.56555 -157.801095) (xy 230.581066 -157.743192)
			(xy 230.604007 -157.68781) (xy 230.633981 -157.635897) (xy 230.670475 -157.58834) (xy 230.712864 -157.545953)
			(xy 230.760423 -157.509463) (xy 230.812339 -157.479493) (xy 230.867722 -157.456555) (xy 230.925626 -157.441044)
			(xy 230.985059 -157.433223) (xy 231.015032 -157.432756) (xy 231.878632 -157.432756) (xy 231.908596 -157.43332)
			(xy 231.968011 -157.441146) (xy 232.025896 -157.45666) (xy 232.081261 -157.479596) (xy 232.133158 -157.509563)
			(xy 232.180701 -157.546046) (xy 232.223075 -157.588423) (xy 232.259555 -157.635968) (xy 232.289518 -157.687868)
			(xy 232.31245 -157.743235) (xy 232.32796 -157.801121) (xy 232.335782 -157.860536) (xy 232.335782 -157.920464)
			(xy 232.32796 -157.979879) (xy 232.31245 -158.037765) (xy 232.289518 -158.093132) (xy 232.259555 -158.145032)
			(xy 232.223075 -158.192577) (xy 232.180701 -158.234954) (xy 232.133158 -158.271437) (xy 232.081261 -158.301404)
			(xy 232.025896 -158.32434) (xy 231.968011 -158.339854) (xy 231.908596 -158.34768) (xy 231.878632 -158.348172)
			(xy 231.015032 -158.348172) (xy 230.985059 -158.347777) (xy 230.925626 -158.339956) (xy 230.867722 -158.324445)
			(xy 230.812339 -158.301507) (xy 230.760423 -158.271537) (xy 230.712864 -158.235047) (xy 230.670475 -158.19266)
			(xy 230.633981 -158.145103) (xy 230.604007 -158.09319) (xy 230.581066 -158.037808) (xy 230.56555 -157.979905)
			(xy 230.557725 -157.920473) (xy 230.089876 -157.920473) (xy 230.084738 -157.959498) (xy 230.069224 -158.017397)
			(xy 230.046286 -158.072775) (xy 230.016316 -158.124685) (xy 229.979827 -158.172239) (xy 229.937442 -158.214624)
			(xy 229.889888 -158.251114) (xy 229.837978 -158.281084) (xy 229.7826 -158.304023) (xy 229.724702 -158.319537)
			(xy 229.665274 -158.327362) (xy 229.635304 -158.327852) (xy 228.771704 -158.327852) (xy 228.741738 -158.327295)
			(xy 228.682318 -158.319473) (xy 228.624427 -158.303962) (xy 228.569056 -158.281027) (xy 228.517153 -158.251061)
			(xy 228.469605 -158.214576) (xy 228.427226 -158.172198) (xy 228.390741 -158.12465) (xy 228.360775 -158.072747)
			(xy 228.33784 -158.017377) (xy 228.322328 -157.959486) (xy 228.314505 -157.900066) (xy 4.308094 -157.900066)
			(xy 4.308094 -160.1851) (xy 45.524179 -160.1851) (xy 45.528134 -160.093263) (xy 45.539969 -160.002106)
			(xy 45.559596 -159.912303) (xy 45.58687 -159.824521) (xy 45.62159 -159.739407) (xy 45.663498 -159.657594)
			(xy 45.712284 -159.579686) (xy 45.767587 -159.506261) (xy 45.828997 -159.437861) (xy 45.896059 -159.374994)
			(xy 45.968278 -159.318124) (xy 46.045118 -159.267673) (xy 46.126011 -159.224014) (xy 46.210357 -159.187471)
			(xy 46.297533 -159.158314) (xy 46.386892 -159.13676) (xy 46.477773 -159.122966) (xy 46.569504 -159.117036)
			(xy 46.661405 -159.119014) (xy 46.752796 -159.128885) (xy 46.843 -159.146575) (xy 46.931349 -159.171955)
			(xy 47.017189 -159.204835) (xy 47.099885 -159.244973) (xy 47.178825 -159.292072) (xy 47.253423 -159.345782)
			(xy 47.323129 -159.405706) (xy 47.387424 -159.4714) (xy 47.445835 -159.542378) (xy 47.497927 -159.618115)
			(xy 47.543316 -159.69805) (xy 47.581666 -159.78159) (xy 47.612691 -159.868118) (xy 47.636164 -159.956993)
			(xy 47.65191 -160.047557) (xy 47.659812 -160.139139) (xy 47.660306 -160.1851) (xy 69.888875 -160.1851)
			(xy 69.892831 -160.093241) (xy 69.904668 -160.002062) (xy 69.9243 -159.912238) (xy 69.951581 -159.824435)
			(xy 69.986309 -159.739302) (xy 70.028227 -159.657469) (xy 70.077025 -159.579542) (xy 70.13234 -159.506099)
			(xy 70.193765 -159.437683) (xy 70.260844 -159.374801) (xy 70.333079 -159.317918) (xy 70.409938 -159.267455)
			(xy 70.49085 -159.223786) (xy 70.575216 -159.187234) (xy 70.662412 -159.15807) (xy 70.751793 -159.13651)
			(xy 70.842696 -159.122714) (xy 70.934449 -159.116782) (xy 71.026371 -159.118761) (xy 71.117784 -159.128634)
			(xy 71.208009 -159.146329) (xy 71.29638 -159.171714) (xy 71.38224 -159.204602) (xy 71.464956 -159.24475)
			(xy 71.543914 -159.291859) (xy 71.618531 -159.345582) (xy 71.688252 -159.40552) (xy 71.752563 -159.47123)
			(xy 71.810988 -159.542226) (xy 71.863093 -159.61798) (xy 71.908492 -159.697934) (xy 71.946851 -159.781494)
			(xy 71.977884 -159.868043) (xy 72.001362 -159.956939) (xy 72.017112 -160.047524) (xy 72.025016 -160.139128)
			(xy 72.02551 -160.1851) (xy 161.624277 -160.1851) (xy 161.628232 -160.093263) (xy 161.640067 -160.002106)
			(xy 161.659694 -159.912303) (xy 161.686968 -159.824521) (xy 161.721688 -159.739407) (xy 161.763596 -159.657594)
			(xy 161.812382 -159.579686) (xy 161.867685 -159.506261) (xy 161.929095 -159.437861) (xy 161.996157 -159.374994)
			(xy 162.068376 -159.318124) (xy 162.145216 -159.267673) (xy 162.226109 -159.224014) (xy 162.310455 -159.187471)
			(xy 162.397631 -159.158314) (xy 162.48699 -159.13676) (xy 162.577871 -159.122966) (xy 162.669602 -159.117036)
			(xy 162.761503 -159.119014) (xy 162.852894 -159.128885) (xy 162.943098 -159.146575) (xy 163.031447 -159.171955)
			(xy 163.117287 -159.204835) (xy 163.199983 -159.244973) (xy 163.278923 -159.292072) (xy 163.353521 -159.345782)
			(xy 163.423227 -159.405706) (xy 163.487522 -159.4714) (xy 163.545933 -159.542378) (xy 163.598025 -159.618115)
			(xy 163.643414 -159.69805) (xy 163.681764 -159.78159) (xy 163.712789 -159.868118) (xy 163.736262 -159.956993)
			(xy 163.752008 -160.047557) (xy 163.75991 -160.139139) (xy 163.760404 -160.1851) (xy 185.988973 -160.1851)
			(xy 185.992929 -160.093241) (xy 186.004766 -160.002062) (xy 186.024398 -159.912238) (xy 186.051679 -159.824435)
			(xy 186.086407 -159.739302) (xy 186.128325 -159.657469) (xy 186.177123 -159.579542) (xy 186.232438 -159.506099)
			(xy 186.293863 -159.437683) (xy 186.360942 -159.374801) (xy 186.433177 -159.317918) (xy 186.510036 -159.267455)
			(xy 186.590948 -159.223786) (xy 186.675314 -159.187234) (xy 186.76251 -159.15807) (xy 186.851891 -159.13651)
			(xy 186.942794 -159.122714) (xy 187.034547 -159.116782) (xy 187.126469 -159.118761) (xy 187.217882 -159.128634)
			(xy 187.308107 -159.146329) (xy 187.396478 -159.171714) (xy 187.482338 -159.204602) (xy 187.565054 -159.24475)
			(xy 187.644012 -159.291859) (xy 187.718629 -159.345582) (xy 187.78835 -159.40552) (xy 187.852661 -159.47123)
			(xy 187.911086 -159.542226) (xy 187.963191 -159.61798) (xy 188.00859 -159.697934) (xy 188.046949 -159.781494)
			(xy 188.077982 -159.868043) (xy 188.10146 -159.956939) (xy 188.11721 -160.047524) (xy 188.125114 -160.139128)
			(xy 188.125608 -160.1851) (xy 277.724121 -160.1851) (xy 277.728076 -160.093263) (xy 277.739911 -160.002106)
			(xy 277.759538 -159.912303) (xy 277.786812 -159.824521) (xy 277.821532 -159.739407) (xy 277.86344 -159.657594)
			(xy 277.912226 -159.579686) (xy 277.967529 -159.506261) (xy 278.028939 -159.437861) (xy 278.096001 -159.374994)
			(xy 278.16822 -159.318124) (xy 278.24506 -159.267673) (xy 278.325953 -159.224014) (xy 278.410299 -159.187471)
			(xy 278.497475 -159.158314) (xy 278.586834 -159.13676) (xy 278.677715 -159.122966) (xy 278.769446 -159.117036)
			(xy 278.861347 -159.119014) (xy 278.952738 -159.128885) (xy 279.042942 -159.146575) (xy 279.131291 -159.171955)
			(xy 279.217131 -159.204835) (xy 279.299827 -159.244973) (xy 279.378767 -159.292072) (xy 279.453365 -159.345782)
			(xy 279.523071 -159.405706) (xy 279.587366 -159.4714) (xy 279.645777 -159.542378) (xy 279.697869 -159.618115)
			(xy 279.743258 -159.69805) (xy 279.781608 -159.78159) (xy 279.812633 -159.868118) (xy 279.836106 -159.956993)
			(xy 279.851852 -160.047557) (xy 279.859754 -160.139139) (xy 279.860248 -160.1851) (xy 302.088817 -160.1851)
			(xy 302.092773 -160.093241) (xy 302.10461 -160.002062) (xy 302.124242 -159.912238) (xy 302.151523 -159.824435)
			(xy 302.186251 -159.739302) (xy 302.228169 -159.657469) (xy 302.276967 -159.579542) (xy 302.332282 -159.506099)
			(xy 302.393707 -159.437683) (xy 302.460786 -159.374801) (xy 302.533021 -159.317918) (xy 302.60988 -159.267455)
			(xy 302.690792 -159.223786) (xy 302.775158 -159.187234) (xy 302.862354 -159.15807) (xy 302.951735 -159.13651)
			(xy 303.042638 -159.122714) (xy 303.134391 -159.116782) (xy 303.226313 -159.118761) (xy 303.317726 -159.128634)
			(xy 303.407951 -159.146329) (xy 303.496322 -159.171714) (xy 303.582182 -159.204602) (xy 303.664898 -159.24475)
			(xy 303.743856 -159.291859) (xy 303.818473 -159.345582) (xy 303.888194 -159.40552) (xy 303.952505 -159.47123)
			(xy 304.01093 -159.542226) (xy 304.063035 -159.61798) (xy 304.108434 -159.697934) (xy 304.146793 -159.781494)
			(xy 304.177826 -159.868043) (xy 304.201304 -159.956939) (xy 304.217054 -160.047524) (xy 304.224958 -160.139128)
			(xy 304.225452 -160.1851) (xy 393.824219 -160.1851) (xy 393.828174 -160.093263) (xy 393.840009 -160.002106)
			(xy 393.859636 -159.912303) (xy 393.88691 -159.824521) (xy 393.92163 -159.739407) (xy 393.963538 -159.657594)
			(xy 394.012324 -159.579686) (xy 394.067627 -159.506261) (xy 394.129037 -159.437861) (xy 394.196099 -159.374994)
			(xy 394.268318 -159.318124) (xy 394.345158 -159.267673) (xy 394.426051 -159.224014) (xy 394.510397 -159.187471)
			(xy 394.597573 -159.158314) (xy 394.686932 -159.13676) (xy 394.777813 -159.122966) (xy 394.869544 -159.117036)
			(xy 394.961445 -159.119014) (xy 395.052836 -159.128885) (xy 395.14304 -159.146575) (xy 395.231389 -159.171955)
			(xy 395.317229 -159.204835) (xy 395.399925 -159.244973) (xy 395.478865 -159.292072) (xy 395.553463 -159.345782)
			(xy 395.623169 -159.405706) (xy 395.687464 -159.4714) (xy 395.745875 -159.542378) (xy 395.797967 -159.618115)
			(xy 395.843356 -159.69805) (xy 395.881706 -159.78159) (xy 395.912731 -159.868118) (xy 395.936204 -159.956993)
			(xy 395.95195 -160.047557) (xy 395.959852 -160.139139) (xy 395.960346 -160.1851) (xy 418.188915 -160.1851)
			(xy 418.192871 -160.093241) (xy 418.204708 -160.002062) (xy 418.22434 -159.912238) (xy 418.251621 -159.824435)
			(xy 418.286349 -159.739302) (xy 418.328267 -159.657469) (xy 418.377065 -159.579542) (xy 418.43238 -159.506099)
			(xy 418.493805 -159.437683) (xy 418.560884 -159.374801) (xy 418.633119 -159.317918) (xy 418.709978 -159.267455)
			(xy 418.79089 -159.223786) (xy 418.875256 -159.187234) (xy 418.962452 -159.15807) (xy 419.051833 -159.13651)
			(xy 419.142736 -159.122714) (xy 419.234489 -159.116782) (xy 419.326411 -159.118761) (xy 419.417824 -159.128634)
			(xy 419.508049 -159.146329) (xy 419.59642 -159.171714) (xy 419.68228 -159.204602) (xy 419.764996 -159.24475)
			(xy 419.843954 -159.291859) (xy 419.918571 -159.345582) (xy 419.988292 -159.40552) (xy 420.052603 -159.47123)
			(xy 420.111028 -159.542226) (xy 420.163133 -159.61798) (xy 420.208532 -159.697934) (xy 420.246891 -159.781494)
			(xy 420.277924 -159.868043) (xy 420.301402 -159.956939) (xy 420.317152 -160.047524) (xy 420.325056 -160.139128)
			(xy 420.32555 -160.1851) (xy 420.325056 -160.231072) (xy 420.317152 -160.322676) (xy 420.301402 -160.413261)
			(xy 420.277924 -160.502157) (xy 420.246891 -160.588706) (xy 420.208532 -160.672266) (xy 420.163133 -160.75222)
			(xy 420.111028 -160.827974) (xy 420.052603 -160.89897) (xy 419.988292 -160.96468) (xy 419.918571 -161.024618)
			(xy 419.843954 -161.078341) (xy 419.764996 -161.12545) (xy 419.68228 -161.165598) (xy 419.59642 -161.198486)
			(xy 419.508049 -161.223871) (xy 419.417824 -161.241566) (xy 419.326411 -161.251439) (xy 419.234489 -161.253418)
			(xy 419.142736 -161.247486) (xy 419.051833 -161.23369) (xy 418.962452 -161.21213) (xy 418.875256 -161.182966)
			(xy 418.79089 -161.146414) (xy 418.709978 -161.102745) (xy 418.633119 -161.052282) (xy 418.560884 -160.995399)
			(xy 418.493805 -160.932517) (xy 418.43238 -160.864101) (xy 418.377065 -160.790658) (xy 418.328267 -160.712731)
			(xy 418.286349 -160.630898) (xy 418.251621 -160.545765) (xy 418.22434 -160.457962) (xy 418.204708 -160.368138)
			(xy 418.192871 -160.276959) (xy 418.188915 -160.1851) (xy 395.960346 -160.1851) (xy 395.959852 -160.231061)
			(xy 395.95195 -160.322643) (xy 395.936204 -160.413207) (xy 395.912731 -160.502082) (xy 395.881706 -160.58861)
			(xy 395.843356 -160.67215) (xy 395.797967 -160.752085) (xy 395.745875 -160.827822) (xy 395.687464 -160.8988)
			(xy 395.623169 -160.964494) (xy 395.553463 -161.024418) (xy 395.478865 -161.078128) (xy 395.399925 -161.125227)
			(xy 395.317229 -161.165365) (xy 395.231389 -161.198245) (xy 395.14304 -161.223625) (xy 395.052836 -161.241315)
			(xy 394.961445 -161.251186) (xy 394.869544 -161.253164) (xy 394.777813 -161.247234) (xy 394.686932 -161.23344)
			(xy 394.597573 -161.211886) (xy 394.510397 -161.182729) (xy 394.426051 -161.146186) (xy 394.345158 -161.102527)
			(xy 394.268318 -161.052076) (xy 394.196099 -160.995206) (xy 394.129037 -160.932339) (xy 394.067627 -160.863939)
			(xy 394.012324 -160.790514) (xy 393.963538 -160.712606) (xy 393.92163 -160.630793) (xy 393.88691 -160.545679)
			(xy 393.859636 -160.457897) (xy 393.840009 -160.368094) (xy 393.828174 -160.276937) (xy 393.824219 -160.1851)
			(xy 304.225452 -160.1851) (xy 304.224958 -160.231072) (xy 304.217054 -160.322676) (xy 304.201304 -160.413261)
			(xy 304.177826 -160.502157) (xy 304.146793 -160.588706) (xy 304.108434 -160.672266) (xy 304.063035 -160.75222)
			(xy 304.01093 -160.827974) (xy 303.952505 -160.89897) (xy 303.888194 -160.96468) (xy 303.818473 -161.024618)
			(xy 303.743856 -161.078341) (xy 303.664898 -161.12545) (xy 303.582182 -161.165598) (xy 303.496322 -161.198486)
			(xy 303.407951 -161.223871) (xy 303.317726 -161.241566) (xy 303.226313 -161.251439) (xy 303.134391 -161.253418)
			(xy 303.042638 -161.247486) (xy 302.951735 -161.23369) (xy 302.862354 -161.21213) (xy 302.775158 -161.182966)
			(xy 302.690792 -161.146414) (xy 302.60988 -161.102745) (xy 302.533021 -161.052282) (xy 302.460786 -160.995399)
			(xy 302.393707 -160.932517) (xy 302.332282 -160.864101) (xy 302.276967 -160.790658) (xy 302.228169 -160.712731)
			(xy 302.186251 -160.630898) (xy 302.151523 -160.545765) (xy 302.124242 -160.457962) (xy 302.10461 -160.368138)
			(xy 302.092773 -160.276959) (xy 302.088817 -160.1851) (xy 279.860248 -160.1851) (xy 279.859754 -160.231061)
			(xy 279.851852 -160.322643) (xy 279.836106 -160.413207) (xy 279.812633 -160.502082) (xy 279.781608 -160.58861)
			(xy 279.743258 -160.67215) (xy 279.697869 -160.752085) (xy 279.645777 -160.827822) (xy 279.587366 -160.8988)
			(xy 279.523071 -160.964494) (xy 279.453365 -161.024418) (xy 279.378767 -161.078128) (xy 279.299827 -161.125227)
			(xy 279.217131 -161.165365) (xy 279.131291 -161.198245) (xy 279.042942 -161.223625) (xy 278.952738 -161.241315)
			(xy 278.861347 -161.251186) (xy 278.769446 -161.253164) (xy 278.677715 -161.247234) (xy 278.586834 -161.23344)
			(xy 278.497475 -161.211886) (xy 278.410299 -161.182729) (xy 278.325953 -161.146186) (xy 278.24506 -161.102527)
			(xy 278.16822 -161.052076) (xy 278.096001 -160.995206) (xy 278.028939 -160.932339) (xy 277.967529 -160.863939)
			(xy 277.912226 -160.790514) (xy 277.86344 -160.712606) (xy 277.821532 -160.630793) (xy 277.786812 -160.545679)
			(xy 277.759538 -160.457897) (xy 277.739911 -160.368094) (xy 277.728076 -160.276937) (xy 277.724121 -160.1851)
			(xy 188.125608 -160.1851) (xy 188.125114 -160.231072) (xy 188.11721 -160.322676) (xy 188.10146 -160.413261)
			(xy 188.077982 -160.502157) (xy 188.046949 -160.588706) (xy 188.00859 -160.672266) (xy 187.963191 -160.75222)
			(xy 187.911086 -160.827974) (xy 187.852661 -160.89897) (xy 187.78835 -160.96468) (xy 187.718629 -161.024618)
			(xy 187.644012 -161.078341) (xy 187.565054 -161.12545) (xy 187.482338 -161.165598) (xy 187.396478 -161.198486)
			(xy 187.308107 -161.223871) (xy 187.217882 -161.241566) (xy 187.126469 -161.251439) (xy 187.034547 -161.253418)
			(xy 186.942794 -161.247486) (xy 186.851891 -161.23369) (xy 186.76251 -161.21213) (xy 186.675314 -161.182966)
			(xy 186.590948 -161.146414) (xy 186.510036 -161.102745) (xy 186.433177 -161.052282) (xy 186.360942 -160.995399)
			(xy 186.293863 -160.932517) (xy 186.232438 -160.864101) (xy 186.177123 -160.790658) (xy 186.128325 -160.712731)
			(xy 186.086407 -160.630898) (xy 186.051679 -160.545765) (xy 186.024398 -160.457962) (xy 186.004766 -160.368138)
			(xy 185.992929 -160.276959) (xy 185.988973 -160.1851) (xy 163.760404 -160.1851) (xy 163.75991 -160.231061)
			(xy 163.752008 -160.322643) (xy 163.736262 -160.413207) (xy 163.712789 -160.502082) (xy 163.681764 -160.58861)
			(xy 163.643414 -160.67215) (xy 163.598025 -160.752085) (xy 163.545933 -160.827822) (xy 163.487522 -160.8988)
			(xy 163.423227 -160.964494) (xy 163.353521 -161.024418) (xy 163.278923 -161.078128) (xy 163.199983 -161.125227)
			(xy 163.117287 -161.165365) (xy 163.031447 -161.198245) (xy 162.943098 -161.223625) (xy 162.852894 -161.241315)
			(xy 162.761503 -161.251186) (xy 162.669602 -161.253164) (xy 162.577871 -161.247234) (xy 162.48699 -161.23344)
			(xy 162.397631 -161.211886) (xy 162.310455 -161.182729) (xy 162.226109 -161.146186) (xy 162.145216 -161.102527)
			(xy 162.068376 -161.052076) (xy 161.996157 -160.995206) (xy 161.929095 -160.932339) (xy 161.867685 -160.863939)
			(xy 161.812382 -160.790514) (xy 161.763596 -160.712606) (xy 161.721688 -160.630793) (xy 161.686968 -160.545679)
			(xy 161.659694 -160.457897) (xy 161.640067 -160.368094) (xy 161.628232 -160.276937) (xy 161.624277 -160.1851)
			(xy 72.02551 -160.1851) (xy 72.025016 -160.231072) (xy 72.017112 -160.322676) (xy 72.001362 -160.413261)
			(xy 71.977884 -160.502157) (xy 71.946851 -160.588706) (xy 71.908492 -160.672266) (xy 71.863093 -160.75222)
			(xy 71.810988 -160.827974) (xy 71.752563 -160.89897) (xy 71.688252 -160.96468) (xy 71.618531 -161.024618)
			(xy 71.543914 -161.078341) (xy 71.464956 -161.12545) (xy 71.38224 -161.165598) (xy 71.29638 -161.198486)
			(xy 71.208009 -161.223871) (xy 71.117784 -161.241566) (xy 71.026371 -161.251439) (xy 70.934449 -161.253418)
			(xy 70.842696 -161.247486) (xy 70.751793 -161.23369) (xy 70.662412 -161.21213) (xy 70.575216 -161.182966)
			(xy 70.49085 -161.146414) (xy 70.409938 -161.102745) (xy 70.333079 -161.052282) (xy 70.260844 -160.995399)
			(xy 70.193765 -160.932517) (xy 70.13234 -160.864101) (xy 70.077025 -160.790658) (xy 70.028227 -160.712731)
			(xy 69.986309 -160.630898) (xy 69.951581 -160.545765) (xy 69.9243 -160.457962) (xy 69.904668 -160.368138)
			(xy 69.892831 -160.276959) (xy 69.888875 -160.1851) (xy 47.660306 -160.1851) (xy 47.659812 -160.231061)
			(xy 47.65191 -160.322643) (xy 47.636164 -160.413207) (xy 47.612691 -160.502082) (xy 47.581666 -160.58861)
			(xy 47.543316 -160.67215) (xy 47.497927 -160.752085) (xy 47.445835 -160.827822) (xy 47.387424 -160.8988)
			(xy 47.323129 -160.964494) (xy 47.253423 -161.024418) (xy 47.178825 -161.078128) (xy 47.099885 -161.125227)
			(xy 47.017189 -161.165365) (xy 46.931349 -161.198245) (xy 46.843 -161.223625) (xy 46.752796 -161.241315)
			(xy 46.661405 -161.251186) (xy 46.569504 -161.253164) (xy 46.477773 -161.247234) (xy 46.386892 -161.23344)
			(xy 46.297533 -161.211886) (xy 46.210357 -161.182729) (xy 46.126011 -161.146186) (xy 46.045118 -161.102527)
			(xy 45.968278 -161.052076) (xy 45.896059 -160.995206) (xy 45.828997 -160.932339) (xy 45.767587 -160.863939)
			(xy 45.712284 -160.790514) (xy 45.663498 -160.712606) (xy 45.62159 -160.630793) (xy 45.58687 -160.545679)
			(xy 45.559596 -160.457897) (xy 45.539969 -160.368094) (xy 45.528134 -160.276937) (xy 45.524179 -160.1851)
			(xy 4.308094 -160.1851) (xy 4.308094 -168.065164) (xy 135.245906 -168.065164) (xy 135.245906 -168.005236)
			(xy 135.253728 -167.94582) (xy 135.269237 -167.887933) (xy 135.29217 -167.832566) (xy 135.322132 -167.780665)
			(xy 135.358612 -167.733119) (xy 135.400986 -167.690742) (xy 135.448529 -167.654257) (xy 135.500426 -167.624289)
			(xy 135.555791 -167.601351) (xy 135.613677 -167.585836) (xy 135.673092 -167.578009) (xy 135.703056 -167.577516)
			(xy 136.566656 -167.577516) (xy 136.596628 -167.577934) (xy 136.656061 -167.585754) (xy 136.713965 -167.601264)
			(xy 136.769348 -167.6242) (xy 136.821264 -167.654169) (xy 136.868823 -167.690658) (xy 136.911213 -167.733044)
			(xy 136.947707 -167.7806) (xy 136.977681 -167.832512) (xy 137.000622 -167.887894) (xy 137.016138 -167.945796)
			(xy 137.023963 -168.005228) (xy 137.023963 -168.065172) (xy 137.016138 -168.124604) (xy 137.000622 -168.182506)
			(xy 136.977681 -168.237888) (xy 136.947707 -168.2898) (xy 136.911213 -168.337356) (xy 136.868823 -168.379742)
			(xy 136.821264 -168.416231) (xy 136.769348 -168.4462) (xy 136.713965 -168.469136) (xy 136.656061 -168.484646)
			(xy 136.596628 -168.492466) (xy 136.566656 -168.492932) (xy 135.703056 -168.492932) (xy 135.673092 -168.492391)
			(xy 135.613677 -168.484564) (xy 135.555791 -168.469049) (xy 135.500426 -168.446111) (xy 135.448529 -168.416143)
			(xy 135.400986 -168.379658) (xy 135.358612 -168.337281) (xy 135.322132 -168.289735) (xy 135.29217 -168.237834)
			(xy 135.269237 -168.182467) (xy 135.253728 -168.12458) (xy 135.245906 -168.065164) (xy 4.308094 -168.065164)
			(xy 4.308094 -168.700164) (xy 133.213906 -168.700164) (xy 133.213906 -168.640236) (xy 133.221728 -168.58082)
			(xy 133.237237 -168.522933) (xy 133.26017 -168.467566) (xy 133.290132 -168.415665) (xy 133.326612 -168.368119)
			(xy 133.368986 -168.325742) (xy 133.416529 -168.289257) (xy 133.468426 -168.259289) (xy 133.523791 -168.236351)
			(xy 133.581677 -168.220836) (xy 133.641092 -168.213009) (xy 133.671056 -168.212516) (xy 134.534656 -168.212516)
			(xy 134.564628 -168.212934) (xy 134.624061 -168.220754) (xy 134.681965 -168.236264) (xy 134.737348 -168.2592)
			(xy 134.789264 -168.289169) (xy 134.836823 -168.325658) (xy 134.879213 -168.368044) (xy 134.915707 -168.4156)
			(xy 134.945681 -168.467512) (xy 134.968622 -168.522894) (xy 134.984138 -168.580796) (xy 134.991963 -168.640228)
			(xy 134.991963 -168.700172) (xy 134.984138 -168.759604) (xy 134.968622 -168.817506) (xy 134.945681 -168.872888)
			(xy 134.915707 -168.9248) (xy 134.879213 -168.972356) (xy 134.836823 -169.014742) (xy 134.789264 -169.051231)
			(xy 134.737348 -169.0812) (xy 134.681965 -169.104136) (xy 134.624061 -169.119646) (xy 134.564628 -169.127466)
			(xy 134.534656 -169.127932) (xy 133.671056 -169.127932) (xy 133.641092 -169.127391) (xy 133.581677 -169.119564)
			(xy 133.523791 -169.104049) (xy 133.468426 -169.081111) (xy 133.416529 -169.051143) (xy 133.368986 -169.014658)
			(xy 133.326612 -168.972281) (xy 133.290132 -168.924735) (xy 133.26017 -168.872834) (xy 133.237237 -168.817467)
			(xy 133.221728 -168.75958) (xy 133.213906 -168.700164) (xy 4.308094 -168.700164) (xy 4.308094 -169.61389)
			(xy 245.108869 -169.61389) (xy 245.108869 -169.55391) (xy 245.116699 -169.494444) (xy 245.132223 -169.436508)
			(xy 245.155178 -169.381095) (xy 245.185169 -169.329152) (xy 245.221684 -169.281569) (xy 245.264097 -169.239158)
			(xy 245.311684 -169.202648) (xy 245.363629 -169.172661) (xy 245.419045 -169.149711) (xy 245.476981 -169.134191)
			(xy 245.536448 -169.126367) (xy 245.566438 -169.1259) (xy 246.430038 -169.1259) (xy 246.460018 -169.126468)
			(xy 246.519465 -169.134299) (xy 246.577381 -169.149822) (xy 246.632776 -169.172772) (xy 246.684702 -169.202755)
			(xy 246.73227 -169.239259) (xy 246.774667 -169.281659) (xy 246.811166 -169.32923) (xy 246.841145 -169.381158)
			(xy 246.86409 -169.436555) (xy 246.879608 -169.494472) (xy 246.887434 -169.55392) (xy 246.887434 -169.61388)
			(xy 246.879608 -169.673328) (xy 246.86409 -169.731245) (xy 246.841145 -169.786642) (xy 246.811166 -169.83857)
			(xy 246.774667 -169.886141) (xy 246.73227 -169.928541) (xy 246.684702 -169.965045) (xy 246.632776 -169.995028)
			(xy 246.577381 -170.017978) (xy 246.519465 -170.033501) (xy 246.460018 -170.041332) (xy 246.430038 -170.041824)
			(xy 245.566438 -170.041824) (xy 245.536448 -170.041433) (xy 245.476981 -170.033609) (xy 245.419045 -170.018089)
			(xy 245.363629 -169.995139) (xy 245.311684 -169.965152) (xy 245.264097 -169.928642) (xy 245.221684 -169.886231)
			(xy 245.185169 -169.838648) (xy 245.155178 -169.786705) (xy 245.132223 -169.731292) (xy 245.116699 -169.673356)
			(xy 245.108869 -169.61389) (xy 4.308094 -169.61389) (xy 4.308094 -174.805086) (xy 141.546072 -174.805086)
			(xy 141.546072 -173.941486) (xy 141.546562 -173.911518) (xy 141.554385 -173.852096) (xy 141.569898 -173.794203)
			(xy 141.592834 -173.73883) (xy 141.622801 -173.686924) (xy 141.659288 -173.639374) (xy 141.701668 -173.596994)
			(xy 141.749218 -173.560507) (xy 141.801124 -173.53054) (xy 141.856497 -173.507604) (xy 141.91439 -173.492091)
			(xy 141.973812 -173.484268) (xy 142.033748 -173.484268) (xy 142.09317 -173.492091) (xy 142.106698 -173.495716)
			(xy 257.519424 -173.495716) (xy 257.519424 -172.632116) (xy 257.519914 -172.602132) (xy 257.527742 -172.542676)
			(xy 257.543263 -172.484751) (xy 257.566212 -172.429347) (xy 257.596196 -172.377413) (xy 257.632702 -172.329837)
			(xy 257.675107 -172.287432) (xy 257.722683 -172.250926) (xy 257.774617 -172.220942) (xy 257.830021 -172.197993)
			(xy 257.887946 -172.182472) (xy 257.947402 -172.174644) (xy 258.00737 -172.174644) (xy 258.066826 -172.182472)
			(xy 258.124751 -172.197993) (xy 258.180155 -172.220942) (xy 258.232089 -172.250926) (xy 258.279665 -172.287432)
			(xy 258.32207 -172.329837) (xy 258.358576 -172.377413) (xy 258.38856 -172.429347) (xy 258.411509 -172.484751)
			(xy 258.42703 -172.542676) (xy 258.434858 -172.602132) (xy 258.435348 -172.632116) (xy 258.435348 -173.495716)
			(xy 258.434858 -173.5257) (xy 258.42703 -173.585156) (xy 258.411509 -173.643081) (xy 258.38856 -173.698485)
			(xy 258.358576 -173.750419) (xy 258.32207 -173.797995) (xy 258.279665 -173.8404) (xy 258.232089 -173.876906)
			(xy 258.180155 -173.90689) (xy 258.124751 -173.929839) (xy 258.066826 -173.94536) (xy 258.00737 -173.953188)
			(xy 257.947402 -173.953188) (xy 257.887946 -173.94536) (xy 257.830021 -173.929839) (xy 257.774617 -173.90689)
			(xy 257.722683 -173.876906) (xy 257.675107 -173.8404) (xy 257.632702 -173.797995) (xy 257.596196 -173.750419)
			(xy 257.566212 -173.698485) (xy 257.543263 -173.643081) (xy 257.527742 -173.585156) (xy 257.519914 -173.5257)
			(xy 257.519424 -173.495716) (xy 142.106698 -173.495716) (xy 142.151063 -173.507604) (xy 142.206436 -173.53054)
			(xy 142.258342 -173.560507) (xy 142.305892 -173.596994) (xy 142.348272 -173.639374) (xy 142.384759 -173.686924)
			(xy 142.414726 -173.73883) (xy 142.437662 -173.794203) (xy 142.453175 -173.852096) (xy 142.460998 -173.911518)
			(xy 142.461488 -173.941486) (xy 142.461488 -174.805086) (xy 142.460998 -174.835054) (xy 142.453175 -174.894476)
			(xy 142.437662 -174.952369) (xy 142.414726 -175.007742) (xy 142.384759 -175.059648) (xy 142.348272 -175.107198)
			(xy 142.305892 -175.149578) (xy 142.258342 -175.186065) (xy 142.206436 -175.216032) (xy 142.151063 -175.238968)
			(xy 142.09317 -175.254481) (xy 142.033748 -175.262304) (xy 141.973812 -175.262304) (xy 141.91439 -175.254481)
			(xy 141.856497 -175.238968) (xy 141.801124 -175.216032) (xy 141.749218 -175.186065) (xy 141.701668 -175.149578)
			(xy 141.659288 -175.107198) (xy 141.622801 -175.059648) (xy 141.592834 -175.007742) (xy 141.569898 -174.952369)
			(xy 141.554385 -174.894476) (xy 141.546562 -174.835054) (xy 141.546072 -174.805086) (xy 4.308094 -174.805086)
			(xy 4.308094 -176.837086) (xy 142.181072 -176.837086) (xy 142.181072 -175.973486) (xy 142.181562 -175.943518)
			(xy 142.189385 -175.884096) (xy 142.204898 -175.826203) (xy 142.227834 -175.77083) (xy 142.257801 -175.718924)
			(xy 142.294288 -175.671374) (xy 142.336668 -175.628994) (xy 142.384218 -175.592507) (xy 142.436124 -175.56254)
			(xy 142.491497 -175.539604) (xy 142.54939 -175.524091) (xy 142.608812 -175.516268) (xy 142.668748 -175.516268)
			(xy 142.72817 -175.524091) (xy 142.786063 -175.539604) (xy 142.841436 -175.56254) (xy 142.893342 -175.592507)
			(xy 142.940892 -175.628994) (xy 142.983272 -175.671374) (xy 143.019759 -175.718924) (xy 143.049726 -175.77083)
			(xy 143.072662 -175.826203) (xy 143.088175 -175.884096) (xy 143.095998 -175.943518) (xy 143.096488 -175.973486)
			(xy 143.096488 -176.837086) (xy 143.095998 -176.867054) (xy 143.088175 -176.926476) (xy 143.072662 -176.984369)
			(xy 143.049726 -177.039742) (xy 143.019759 -177.091648) (xy 142.983272 -177.139198) (xy 142.940892 -177.181578)
			(xy 142.893342 -177.218065) (xy 142.841436 -177.248032) (xy 142.786063 -177.270968) (xy 142.72817 -177.286481)
			(xy 142.668748 -177.294304) (xy 142.608812 -177.294304) (xy 142.54939 -177.286481) (xy 142.491497 -177.270968)
			(xy 142.436124 -177.248032) (xy 142.384218 -177.218065) (xy 142.336668 -177.181578) (xy 142.294288 -177.139198)
			(xy 142.257801 -177.091648) (xy 142.227834 -177.039742) (xy 142.204898 -176.984369) (xy 142.189385 -176.926476)
			(xy 142.181562 -176.867054) (xy 142.181072 -176.837086) (xy 4.308094 -176.837086) (xy 4.308094 -178.995324)
			(xy 123.198636 -178.995324) (xy 123.198636 -178.131724) (xy 123.199126 -178.10174) (xy 123.206954 -178.042284)
			(xy 123.222475 -177.984359) (xy 123.245424 -177.928955) (xy 123.275408 -177.877021) (xy 123.311914 -177.829445)
			(xy 123.354319 -177.78704) (xy 123.401895 -177.750534) (xy 123.453829 -177.72055) (xy 123.509233 -177.697601)
			(xy 123.567158 -177.68208) (xy 123.626614 -177.674252) (xy 123.686582 -177.674252) (xy 123.746038 -177.68208)
			(xy 123.803963 -177.697601) (xy 123.859367 -177.72055) (xy 123.911301 -177.750534) (xy 123.958877 -177.78704)
			(xy 124.001282 -177.829445) (xy 124.037788 -177.877021) (xy 124.067772 -177.928955) (xy 124.090721 -177.984359)
			(xy 124.106242 -178.042284) (xy 124.11407 -178.10174) (xy 124.11456 -178.131724) (xy 124.11456 -178.869086)
			(xy 141.546072 -178.869086) (xy 141.546072 -178.005486) (xy 141.546562 -177.975518) (xy 141.554385 -177.916096)
			(xy 141.569898 -177.858203) (xy 141.592834 -177.80283) (xy 141.622801 -177.750924) (xy 141.659288 -177.703374)
			(xy 141.701668 -177.660994) (xy 141.749218 -177.624507) (xy 141.801124 -177.59454) (xy 141.856497 -177.571604)
			(xy 141.91439 -177.556091) (xy 141.973812 -177.548268) (xy 142.033748 -177.548268) (xy 142.09317 -177.556091)
			(xy 142.151063 -177.571604) (xy 142.206436 -177.59454) (xy 142.258342 -177.624507) (xy 142.305892 -177.660994)
			(xy 142.348272 -177.703374) (xy 142.384759 -177.750924) (xy 142.414726 -177.80283) (xy 142.437662 -177.858203)
			(xy 142.453175 -177.916096) (xy 142.460998 -177.975518) (xy 142.461488 -178.005486) (xy 142.461488 -178.869086)
			(xy 142.460998 -178.899054) (xy 142.453175 -178.958476) (xy 142.437662 -179.016369) (xy 142.414726 -179.071742)
			(xy 142.384759 -179.123648) (xy 142.348272 -179.171198) (xy 142.305892 -179.213578) (xy 142.258342 -179.250065)
			(xy 142.206436 -179.280032) (xy 142.151063 -179.302968) (xy 142.09317 -179.318481) (xy 142.033748 -179.326304)
			(xy 141.973812 -179.326304) (xy 141.91439 -179.318481) (xy 141.856497 -179.302968) (xy 141.801124 -179.280032)
			(xy 141.749218 -179.250065) (xy 141.701668 -179.213578) (xy 141.659288 -179.171198) (xy 141.622801 -179.123648)
			(xy 141.592834 -179.071742) (xy 141.569898 -179.016369) (xy 141.554385 -178.958476) (xy 141.546562 -178.899054)
			(xy 141.546072 -178.869086) (xy 124.11456 -178.869086) (xy 124.11456 -178.995324) (xy 124.11407 -179.025308)
			(xy 124.106242 -179.084764) (xy 124.090721 -179.142689) (xy 124.067772 -179.198093) (xy 124.037788 -179.250027)
			(xy 124.001282 -179.297603) (xy 123.958877 -179.340008) (xy 123.911301 -179.376514) (xy 123.859367 -179.406498)
			(xy 123.803963 -179.429447) (xy 123.746038 -179.444968) (xy 123.686582 -179.452796) (xy 123.626614 -179.452796)
			(xy 123.567158 -179.444968) (xy 123.509233 -179.429447) (xy 123.453829 -179.406498) (xy 123.401895 -179.376514)
			(xy 123.354319 -179.340008) (xy 123.311914 -179.297603) (xy 123.275408 -179.250027) (xy 123.245424 -179.198093)
			(xy 123.222475 -179.142689) (xy 123.206954 -179.084764) (xy 123.199126 -179.025308) (xy 123.198636 -178.995324)
			(xy 4.308094 -178.995324) (xy 4.308094 -180.901086) (xy 142.181072 -180.901086) (xy 142.181072 -180.037486)
			(xy 142.181562 -180.007518) (xy 142.189385 -179.948096) (xy 142.204898 -179.890203) (xy 142.227834 -179.83483)
			(xy 142.257801 -179.782924) (xy 142.294288 -179.735374) (xy 142.336668 -179.692994) (xy 142.384218 -179.656507)
			(xy 142.436124 -179.62654) (xy 142.491497 -179.603604) (xy 142.54939 -179.588091) (xy 142.608812 -179.580268)
			(xy 142.668748 -179.580268) (xy 142.72817 -179.588091) (xy 142.786063 -179.603604) (xy 142.841436 -179.62654)
			(xy 142.893342 -179.656507) (xy 142.940892 -179.692994) (xy 142.983272 -179.735374) (xy 143.019759 -179.782924)
			(xy 143.049726 -179.83483) (xy 143.072662 -179.890203) (xy 143.088175 -179.948096) (xy 143.095998 -180.007518)
			(xy 143.096488 -180.037486) (xy 143.096488 -180.901086) (xy 143.095998 -180.931054) (xy 143.088175 -180.990476)
			(xy 143.072662 -181.048369) (xy 143.049726 -181.103742) (xy 143.019759 -181.155648) (xy 142.983272 -181.203198)
			(xy 142.940892 -181.245578) (xy 142.893342 -181.282065) (xy 142.841436 -181.312032) (xy 142.786063 -181.334968)
			(xy 142.72817 -181.350481) (xy 142.668748 -181.358304) (xy 142.608812 -181.358304) (xy 142.54939 -181.350481)
			(xy 142.491497 -181.334968) (xy 142.436124 -181.312032) (xy 142.384218 -181.282065) (xy 142.336668 -181.245578)
			(xy 142.294288 -181.203198) (xy 142.257801 -181.155648) (xy 142.227834 -181.103742) (xy 142.204898 -181.048369)
			(xy 142.189385 -180.990476) (xy 142.181562 -180.931054) (xy 142.181072 -180.901086) (xy 4.308094 -180.901086)
			(xy 4.308094 -182.933086) (xy 141.546072 -182.933086) (xy 141.546072 -182.069486) (xy 141.546562 -182.039518)
			(xy 141.554385 -181.980096) (xy 141.569898 -181.922203) (xy 141.592834 -181.86683) (xy 141.622801 -181.814924)
			(xy 141.659288 -181.767374) (xy 141.701668 -181.724994) (xy 141.749218 -181.688507) (xy 141.801124 -181.65854)
			(xy 141.856497 -181.635604) (xy 141.91439 -181.620091) (xy 141.973812 -181.612268) (xy 142.033748 -181.612268)
			(xy 142.09317 -181.620091) (xy 142.151063 -181.635604) (xy 142.206436 -181.65854) (xy 142.258342 -181.688507)
			(xy 142.305892 -181.724994) (xy 142.348272 -181.767374) (xy 142.384759 -181.814924) (xy 142.414726 -181.86683)
			(xy 142.437662 -181.922203) (xy 142.453175 -181.980096) (xy 142.460998 -182.039518) (xy 142.461488 -182.069486)
			(xy 142.461488 -182.933086) (xy 142.460998 -182.963054) (xy 142.453175 -183.022476) (xy 142.437662 -183.080369)
			(xy 142.414726 -183.135742) (xy 142.384759 -183.187648) (xy 142.348272 -183.235198) (xy 142.305892 -183.277578)
			(xy 142.258342 -183.314065) (xy 142.206436 -183.344032) (xy 142.151063 -183.366968) (xy 142.09317 -183.382481)
			(xy 142.033748 -183.390304) (xy 141.973812 -183.390304) (xy 141.91439 -183.382481) (xy 141.856497 -183.366968)
			(xy 141.801124 -183.344032) (xy 141.749218 -183.314065) (xy 141.701668 -183.277578) (xy 141.659288 -183.235198)
			(xy 141.622801 -183.187648) (xy 141.592834 -183.135742) (xy 141.569898 -183.080369) (xy 141.554385 -183.022476)
			(xy 141.546562 -182.963054) (xy 141.546072 -182.933086) (xy 4.308094 -182.933086) (xy 4.308094 -187.124582)
			(xy 135.58115 -187.124582) (xy 135.58115 -187.064618) (xy 135.588977 -187.005166) (xy 135.604497 -186.947244)
			(xy 135.627444 -186.891844) (xy 135.657426 -186.839912) (xy 135.69393 -186.792339) (xy 135.736331 -186.749937)
			(xy 135.783904 -186.713432) (xy 135.835835 -186.683448) (xy 135.891235 -186.6605) (xy 135.949156 -186.644979)
			(xy 136.008608 -186.637151) (xy 136.03859 -186.63666) (xy 136.90219 -186.63666) (xy 136.932178 -186.637085)
			(xy 136.99164 -186.644912) (xy 137.049571 -186.660433) (xy 137.104981 -186.683384) (xy 137.156922 -186.713371)
			(xy 137.204504 -186.749881) (xy 137.246913 -186.792289) (xy 137.283424 -186.83987) (xy 137.313412 -186.89181)
			(xy 137.336363 -186.947219) (xy 137.351886 -187.005151) (xy 137.359715 -187.064612) (xy 137.359715 -187.124588)
			(xy 137.351886 -187.184049) (xy 137.336363 -187.241981) (xy 137.313412 -187.29739) (xy 137.283424 -187.34933)
			(xy 137.246913 -187.396911) (xy 137.204504 -187.439319) (xy 137.156922 -187.475829) (xy 137.104981 -187.505816)
			(xy 137.049571 -187.528767) (xy 136.99164 -187.544288) (xy 136.932178 -187.552115) (xy 136.90219 -187.552584)
			(xy 136.03859 -187.552584) (xy 136.008608 -187.552049) (xy 135.949156 -187.544221) (xy 135.891235 -187.5287)
			(xy 135.835835 -187.505752) (xy 135.783904 -187.475768) (xy 135.736331 -187.439263) (xy 135.69393 -187.396861)
			(xy 135.657426 -187.349288) (xy 135.627444 -187.297356) (xy 135.604497 -187.241956) (xy 135.588977 -187.184034)
			(xy 135.58115 -187.124582) (xy 4.308094 -187.124582) (xy 4.308094 -188.252885) (xy 128.656818 -188.252885)
			(xy 128.656818 -188.192915) (xy 128.664646 -188.133459) (xy 128.680167 -188.075533) (xy 128.703116 -188.020128)
			(xy 128.733101 -187.968193) (xy 128.769608 -187.920615) (xy 128.812012 -187.87821) (xy 128.859589 -187.841703)
			(xy 128.911524 -187.811718) (xy 128.966929 -187.788768) (xy 129.024855 -187.773246) (xy 129.084311 -187.765418)
			(xy 129.114296 -187.764928) (xy 129.977896 -187.764928) (xy 130.007881 -187.765417) (xy 130.067339 -187.773244)
			(xy 130.125266 -187.788765) (xy 130.180671 -187.811714) (xy 130.232607 -187.841699) (xy 130.280185 -187.878207)
			(xy 130.322591 -187.920612) (xy 130.359098 -187.96819) (xy 130.389084 -188.020125) (xy 130.412034 -188.075531)
			(xy 130.427555 -188.133458) (xy 130.435383 -188.192915) (xy 130.435383 -188.252885) (xy 130.434185 -188.261981)
			(xy 131.046262 -188.261981) (xy 131.046262 -188.202019) (xy 131.054088 -188.14257) (xy 131.069607 -188.084651)
			(xy 131.092553 -188.029253) (xy 131.122533 -187.977324) (xy 131.159034 -187.929752) (xy 131.201432 -187.887351)
			(xy 131.249002 -187.850847) (xy 131.30093 -187.820864) (xy 131.356326 -187.797915) (xy 131.414244 -187.782393)
			(xy 131.473693 -187.774564) (xy 131.503674 -187.774072) (xy 132.367274 -187.774072) (xy 132.397263 -187.774472)
			(xy 132.456728 -187.782297) (xy 132.514663 -187.797818) (xy 132.570077 -187.820768) (xy 132.62202 -187.850755)
			(xy 132.669605 -187.887266) (xy 132.712017 -187.929675) (xy 132.74853 -187.977258) (xy 132.77852 -188.0292)
			(xy 132.801474 -188.084612) (xy 132.816998 -188.142546) (xy 132.824827 -188.202011) (xy 132.824827 -188.261989)
			(xy 132.816998 -188.321454) (xy 132.801474 -188.379388) (xy 132.79518 -188.394582) (xy 133.54915 -188.394582)
			(xy 133.54915 -188.334618) (xy 133.556977 -188.275166) (xy 133.572497 -188.217244) (xy 133.595444 -188.161844)
			(xy 133.625426 -188.109912) (xy 133.66193 -188.062339) (xy 133.704331 -188.019937) (xy 133.751904 -187.983432)
			(xy 133.803835 -187.953448) (xy 133.859235 -187.9305) (xy 133.917156 -187.914979) (xy 133.976608 -187.907151)
			(xy 134.00659 -187.90666) (xy 134.87019 -187.90666) (xy 134.900178 -187.907085) (xy 134.95964 -187.914912)
			(xy 135.017571 -187.930433) (xy 135.072981 -187.953384) (xy 135.124922 -187.983371) (xy 135.172504 -188.019881)
			(xy 135.214913 -188.062289) (xy 135.251424 -188.10987) (xy 135.281412 -188.16181) (xy 135.304363 -188.217219)
			(xy 135.319886 -188.275151) (xy 135.327715 -188.334612) (xy 135.327715 -188.394588) (xy 135.319886 -188.454049)
			(xy 135.304363 -188.511981) (xy 135.281412 -188.56739) (xy 135.251424 -188.61933) (xy 135.214913 -188.666911)
			(xy 135.172504 -188.709319) (xy 135.124922 -188.745829) (xy 135.072981 -188.775816) (xy 135.017571 -188.798767)
			(xy 134.95964 -188.814288) (xy 134.900178 -188.822115) (xy 134.87019 -188.822584) (xy 134.00659 -188.822584)
			(xy 133.976608 -188.822049) (xy 133.917156 -188.814221) (xy 133.859235 -188.7987) (xy 133.803835 -188.775752)
			(xy 133.751904 -188.745768) (xy 133.704331 -188.709263) (xy 133.66193 -188.666861) (xy 133.625426 -188.619288)
			(xy 133.595444 -188.567356) (xy 133.572497 -188.511956) (xy 133.556977 -188.454034) (xy 133.54915 -188.394582)
			(xy 132.79518 -188.394582) (xy 132.77852 -188.4348) (xy 132.74853 -188.486742) (xy 132.712017 -188.534325)
			(xy 132.669605 -188.576734) (xy 132.62202 -188.613245) (xy 132.570077 -188.643232) (xy 132.514663 -188.666182)
			(xy 132.456728 -188.681703) (xy 132.397263 -188.689528) (xy 132.367274 -188.689996) (xy 131.503674 -188.689996)
			(xy 131.473693 -188.689436) (xy 131.414244 -188.681607) (xy 131.356326 -188.666085) (xy 131.30093 -188.643136)
			(xy 131.249002 -188.613153) (xy 131.201432 -188.576649) (xy 131.159034 -188.534248) (xy 131.122533 -188.486676)
			(xy 131.092553 -188.434747) (xy 131.069607 -188.379349) (xy 131.054088 -188.32143) (xy 131.046262 -188.261981)
			(xy 130.434185 -188.261981) (xy 130.427555 -188.312342) (xy 130.412034 -188.370269) (xy 130.389084 -188.425675)
			(xy 130.359098 -188.47761) (xy 130.322591 -188.525188) (xy 130.280185 -188.567593) (xy 130.232607 -188.604101)
			(xy 130.180671 -188.634086) (xy 130.125266 -188.657035) (xy 130.067339 -188.672556) (xy 130.007881 -188.680383)
			(xy 129.977896 -188.680852) (xy 129.114296 -188.680852) (xy 129.084311 -188.680382) (xy 129.024855 -188.672554)
			(xy 128.966929 -188.657032) (xy 128.911524 -188.634082) (xy 128.859589 -188.604097) (xy 128.812012 -188.56759)
			(xy 128.769608 -188.525185) (xy 128.733101 -188.477607) (xy 128.703116 -188.425672) (xy 128.680167 -188.370267)
			(xy 128.664646 -188.312341) (xy 128.656818 -188.252885) (xy 4.308094 -188.252885) (xy 4.308094 -195.726088)
			(xy 126.922185 -195.726088) (xy 126.922185 -195.666112) (xy 126.930014 -195.606648) (xy 126.945538 -195.548715)
			(xy 126.968491 -195.493304) (xy 126.99848 -195.441364) (xy 127.034993 -195.393782) (xy 127.077404 -195.351373)
			(xy 127.124989 -195.314864) (xy 127.176931 -195.284878) (xy 127.232344 -195.261928) (xy 127.290278 -195.246408)
			(xy 127.349742 -195.238583) (xy 127.37973 -195.238116) (xy 128.24333 -195.238116) (xy 128.273312 -195.238652)
			(xy 128.332761 -195.246482) (xy 128.39068 -195.262005) (xy 128.446078 -195.284955) (xy 128.498007 -195.314939)
			(xy 128.545577 -195.351444) (xy 128.587976 -195.393845) (xy 128.624478 -195.441418) (xy 128.654459 -195.493349)
			(xy 128.677405 -195.548748) (xy 128.692924 -195.606668) (xy 128.70075 -195.666118) (xy 128.70075 -195.726082)
			(xy 128.692924 -195.785532) (xy 128.677405 -195.843452) (xy 128.654459 -195.898851) (xy 128.624478 -195.950782)
			(xy 128.587976 -195.998355) (xy 128.545577 -196.040756) (xy 128.498007 -196.077261) (xy 128.446078 -196.107245)
			(xy 128.39068 -196.130195) (xy 128.332761 -196.145718) (xy 128.273312 -196.153548) (xy 128.24333 -196.15404)
			(xy 127.37973 -196.15404) (xy 127.349742 -196.153617) (xy 127.290278 -196.145792) (xy 127.232344 -196.130272)
			(xy 127.176931 -196.107322) (xy 127.124989 -196.077336) (xy 127.077404 -196.040827) (xy 127.034993 -195.998418)
			(xy 126.99848 -195.950836) (xy 126.968491 -195.898896) (xy 126.945538 -195.843485) (xy 126.930014 -195.785552)
			(xy 126.922185 -195.726088) (xy 4.308094 -195.726088) (xy 4.308094 -198.543743) (xy 138.243774 -198.543743)
			(xy 138.24519 -198.489257) (xy 138.254343 -198.435528) (xy 138.271047 -198.383647) (xy 138.294963 -198.33467)
			(xy 138.325603 -198.289594) (xy 138.362344 -198.249336) (xy 138.40444 -198.214715) (xy 138.451033 -198.186434)
			(xy 138.501175 -198.165071) (xy 138.553847 -198.151058) (xy 138.607977 -198.144682) (xy 138.635232 -198.144892)
			(xy 138.636502 -198.144892) (xy 139.488672 -198.144892) (xy 139.515926 -198.145353) (xy 139.56988 -198.153107)
			(xy 139.622181 -198.168461) (xy 139.671765 -198.191102) (xy 139.717622 -198.220569) (xy 139.758818 -198.256263)
			(xy 139.794514 -198.297456) (xy 139.823985 -198.34331) (xy 139.846629 -198.392892) (xy 139.861987 -198.445192)
			(xy 139.869745 -198.499146) (xy 139.869745 -198.553654) (xy 139.861987 -198.607608) (xy 139.846629 -198.659908)
			(xy 139.823985 -198.70949) (xy 139.794514 -198.755344) (xy 139.758818 -198.796537) (xy 139.717622 -198.832231)
			(xy 139.671765 -198.861698) (xy 139.622181 -198.884339) (xy 139.56988 -198.899693) (xy 139.515926 -198.907447)
			(xy 139.488672 -198.907908) (xy 139.477343 -198.907862) (xy 139.454723 -198.90659) (xy 139.44346 -198.905368)
			(xy 139.440412 -198.90486) (xy 138.672824 -198.90486) (xy 138.669776 -198.905368) (xy 138.642662 -198.908134)
			(xy 138.588177 -198.906693) (xy 138.534452 -198.897514) (xy 138.482579 -198.880785) (xy 138.433613 -198.856847)
			(xy 138.388552 -198.826185) (xy 138.348311 -198.789424) (xy 138.31371 -198.747312) (xy 138.285452 -198.700706)
			(xy 138.264112 -198.650554) (xy 138.250125 -198.597875) (xy 138.243774 -198.543743) (xy 4.308094 -198.543743)
			(xy 4.308094 -201.379368) (xy 98.428551 -201.379368) (xy 98.428551 -201.324832) (xy 98.436313 -201.270851)
			(xy 98.451678 -201.218525) (xy 98.474333 -201.168917) (xy 98.503818 -201.123039) (xy 98.539531 -201.081824)
			(xy 98.580747 -201.046112) (xy 98.626626 -201.016628) (xy 98.676234 -200.993974) (xy 98.728561 -200.978611)
			(xy 98.782542 -200.970851) (xy 98.80981 -200.970388) (xy 99.67341 -200.970388) (xy 99.700682 -200.970775)
			(xy 99.754672 -200.978539) (xy 99.807007 -200.993907) (xy 99.856623 -201.016567) (xy 99.902508 -201.046057)
			(xy 99.94373 -201.081777) (xy 99.979449 -201.123) (xy 100.008938 -201.168886) (xy 100.031596 -201.218502)
			(xy 100.046963 -201.270838) (xy 100.054725 -201.324828) (xy 100.054725 -201.379372) (xy 100.046963 -201.433362)
			(xy 100.031596 -201.485698) (xy 100.008938 -201.535314) (xy 99.979449 -201.5812) (xy 99.94373 -201.622423)
			(xy 99.902508 -201.658143) (xy 99.856623 -201.687633) (xy 99.807007 -201.710293) (xy 99.754672 -201.725661)
			(xy 99.700682 -201.733425) (xy 99.67341 -201.733912) (xy 98.80981 -201.733912) (xy 98.782542 -201.733349)
			(xy 98.728561 -201.725589) (xy 98.676234 -201.710226) (xy 98.626626 -201.687572) (xy 98.580747 -201.658088)
			(xy 98.539531 -201.622376) (xy 98.503818 -201.581161) (xy 98.474333 -201.535283) (xy 98.451678 -201.485675)
			(xy 98.436313 -201.433349) (xy 98.428551 -201.379368) (xy 4.308094 -201.379368) (xy 4.308094 -209.380836)
			(xy 445.288416 -209.380836) (xy 445.288416 -208.517236) (xy 445.288906 -208.487268) (xy 445.296729 -208.427846)
			(xy 445.312242 -208.369953) (xy 445.335178 -208.31458) (xy 445.365145 -208.262674) (xy 445.401632 -208.215124)
			(xy 445.444012 -208.172744) (xy 445.491562 -208.136257) (xy 445.543468 -208.10629) (xy 445.598841 -208.083354)
			(xy 445.656734 -208.067841) (xy 445.716156 -208.060018) (xy 445.776092 -208.060018) (xy 445.835514 -208.067841)
			(xy 445.893407 -208.083354) (xy 445.94878 -208.10629) (xy 446.000686 -208.136257) (xy 446.048236 -208.172744)
			(xy 446.090616 -208.215124) (xy 446.127103 -208.262674) (xy 446.15707 -208.31458) (xy 446.180006 -208.369953)
			(xy 446.195519 -208.427846) (xy 446.203342 -208.487268) (xy 446.203832 -208.517236) (xy 446.203832 -209.380836)
			(xy 446.203342 -209.410804) (xy 446.195519 -209.470226) (xy 446.180006 -209.528119) (xy 446.15707 -209.583492)
			(xy 446.127103 -209.635398) (xy 446.090616 -209.682948) (xy 446.048236 -209.725328) (xy 446.000686 -209.761815)
			(xy 445.94878 -209.791782) (xy 445.893407 -209.814718) (xy 445.835514 -209.830231) (xy 445.776092 -209.838054)
			(xy 445.716156 -209.838054) (xy 445.656734 -209.830231) (xy 445.598841 -209.814718) (xy 445.543468 -209.791782)
			(xy 445.491562 -209.761815) (xy 445.444012 -209.725328) (xy 445.401632 -209.682948) (xy 445.365145 -209.635398)
			(xy 445.335178 -209.583492) (xy 445.312242 -209.528119) (xy 445.296729 -209.470226) (xy 445.288906 -209.410804)
			(xy 445.288416 -209.380836) (xy 4.308094 -209.380836) (xy 4.308094 -225.261473) (xy 239.822113 -225.261473)
			(xy 239.822113 -225.201527) (xy 239.829938 -225.142093) (xy 239.845454 -225.084189) (xy 239.868395 -225.028806)
			(xy 239.89837 -224.976891) (xy 239.934864 -224.929333) (xy 239.977254 -224.886945) (xy 240.024814 -224.850454)
			(xy 240.076731 -224.820483) (xy 240.132115 -224.797545) (xy 240.19002 -224.782032) (xy 240.249455 -224.774211)
			(xy 240.279428 -224.773744) (xy 241.143028 -224.773744) (xy 241.172991 -224.774332) (xy 241.232405 -224.782157)
			(xy 241.290289 -224.79767) (xy 241.345653 -224.820606) (xy 241.39755 -224.850571) (xy 241.445091 -224.887054)
			(xy 241.487465 -224.92943) (xy 241.523944 -224.976974) (xy 241.553907 -225.028872) (xy 241.576839 -225.084238)
			(xy 241.592348 -225.142123) (xy 241.60017 -225.201537) (xy 241.60017 -225.261463) (xy 241.592348 -225.320877)
			(xy 241.576839 -225.378762) (xy 241.553907 -225.434128) (xy 241.523944 -225.486026) (xy 241.487465 -225.53357)
			(xy 241.445091 -225.575946) (xy 241.39755 -225.612429) (xy 241.345653 -225.642394) (xy 241.290289 -225.66533)
			(xy 241.232405 -225.680843) (xy 241.172991 -225.688668) (xy 241.143028 -225.68916) (xy 240.279428 -225.68916)
			(xy 240.249455 -225.688789) (xy 240.19002 -225.680968) (xy 240.132115 -225.665455) (xy 240.076731 -225.642517)
			(xy 240.024814 -225.612546) (xy 239.977254 -225.576055) (xy 239.934864 -225.533667) (xy 239.89837 -225.486109)
			(xy 239.868395 -225.434194) (xy 239.845454 -225.378811) (xy 239.829938 -225.320907) (xy 239.822113 -225.261473)
			(xy 4.308094 -225.261473) (xy 4.308094 -230.903589) (xy 383.216061 -230.903589) (xy 383.216061 -230.843611)
			(xy 383.22389 -230.784147) (xy 383.239413 -230.726213) (xy 383.262366 -230.670801) (xy 383.292355 -230.618858)
			(xy 383.328867 -230.571275) (xy 383.371278 -230.528865) (xy 383.418862 -230.492353) (xy 383.470804 -230.462364)
			(xy 383.526216 -230.439412) (xy 383.584151 -230.423889) (xy 383.643615 -230.416061) (xy 383.673604 -230.415592)
			(xy 384.537204 -230.415592) (xy 384.567185 -230.416174) (xy 384.626634 -230.424001) (xy 384.684553 -230.439521)
			(xy 384.739951 -230.462468) (xy 384.79188 -230.492449) (xy 384.839451 -230.528952) (xy 384.88185 -230.571352)
			(xy 384.918353 -230.618924) (xy 384.948334 -230.670853) (xy 384.97128 -230.726251) (xy 384.986799 -230.78417)
			(xy 384.994626 -230.843619) (xy 384.994626 -230.903581) (xy 384.986799 -230.96303) (xy 384.97128 -231.020949)
			(xy 384.948334 -231.076347) (xy 384.918353 -231.128276) (xy 384.88185 -231.175848) (xy 384.839451 -231.218248)
			(xy 384.79188 -231.254751) (xy 384.739951 -231.284732) (xy 384.684553 -231.307679) (xy 384.626634 -231.323199)
			(xy 384.567185 -231.331026) (xy 384.537204 -231.331516) (xy 383.673604 -231.331516) (xy 383.643615 -231.331139)
			(xy 383.584151 -231.323311) (xy 383.526216 -231.307788) (xy 383.470804 -231.284836) (xy 383.418862 -231.254847)
			(xy 383.371278 -231.218335) (xy 383.328867 -231.175925) (xy 383.292355 -231.128342) (xy 383.262366 -231.076399)
			(xy 383.239413 -231.020987) (xy 383.22389 -230.963053) (xy 383.216061 -230.903589) (xy 4.308094 -230.903589)
			(xy 4.308094 -234.655869) (xy 448.021157 -234.655869) (xy 448.021157 -234.595931) (xy 448.028981 -234.536505)
			(xy 448.044494 -234.478608) (xy 448.067432 -234.423232) (xy 448.097401 -234.371324) (xy 448.13389 -234.323771)
			(xy 448.176273 -234.281388) (xy 448.223825 -234.2449) (xy 448.275734 -234.214931) (xy 448.33111 -234.191993)
			(xy 448.389007 -234.17648) (xy 448.448433 -234.168657) (xy 448.478402 -234.168188) (xy 449.342002 -234.168188)
			(xy 449.371969 -234.168686) (xy 449.431391 -234.176509) (xy 449.489283 -234.192022) (xy 449.544656 -234.214958)
			(xy 449.596561 -234.244925) (xy 449.64411 -234.281411) (xy 449.68649 -234.323792) (xy 449.722976 -234.371341)
			(xy 449.752943 -234.423246) (xy 449.775879 -234.478618) (xy 449.791391 -234.536511) (xy 449.799214 -234.595933)
			(xy 449.799214 -234.655867) (xy 449.791391 -234.715289) (xy 449.775879 -234.773182) (xy 449.752943 -234.828554)
			(xy 449.722976 -234.880459) (xy 449.68649 -234.928008) (xy 449.64411 -234.970389) (xy 449.596561 -235.006875)
			(xy 449.544656 -235.036842) (xy 449.489283 -235.059778) (xy 449.431391 -235.075291) (xy 449.371969 -235.083114)
			(xy 449.342002 -235.083604) (xy 448.478402 -235.083604) (xy 448.448433 -235.083143) (xy 448.389007 -235.07532)
			(xy 448.33111 -235.059807) (xy 448.275734 -235.036869) (xy 448.223825 -235.0069) (xy 448.176273 -234.970412)
			(xy 448.13389 -234.928029) (xy 448.097401 -234.880476) (xy 448.067432 -234.828568) (xy 448.044494 -234.773192)
			(xy 448.028981 -234.715295) (xy 448.021157 -234.655869) (xy 4.308094 -234.655869) (xy 4.308094 -239.07907)
			(xy 153.398934 -239.07907) (xy 153.398934 -239.01913) (xy 153.406758 -238.959703) (xy 153.422271 -238.901805)
			(xy 153.445208 -238.846427) (xy 153.475178 -238.794517) (xy 153.511666 -238.746963) (xy 153.554049 -238.704578)
			(xy 153.601602 -238.668088) (xy 153.653511 -238.638116) (xy 153.708888 -238.615177) (xy 153.766785 -238.599661)
			(xy 153.826212 -238.591835) (xy 153.856182 -238.591344) (xy 154.719782 -238.591344) (xy 154.749749 -238.591908)
			(xy 154.809169 -238.599729) (xy 154.867061 -238.615239) (xy 154.922433 -238.638172) (xy 154.974337 -238.668138)
			(xy 155.021886 -238.704622) (xy 155.064267 -238.747) (xy 155.100752 -238.794548) (xy 155.13072 -238.846451)
			(xy 155.153656 -238.901822) (xy 155.169168 -238.959713) (xy 155.176991 -239.019133) (xy 155.176991 -239.079067)
			(xy 155.169168 -239.138487) (xy 155.153656 -239.196378) (xy 155.13072 -239.251749) (xy 155.100752 -239.303652)
			(xy 155.064267 -239.3512) (xy 155.021886 -239.393578) (xy 154.974337 -239.430062) (xy 154.922433 -239.460028)
			(xy 154.867061 -239.482961) (xy 154.809169 -239.498471) (xy 154.749749 -239.506292) (xy 154.719782 -239.50676)
			(xy 153.856182 -239.50676) (xy 153.826212 -239.506365) (xy 153.766785 -239.498539) (xy 153.708888 -239.483023)
			(xy 153.653511 -239.460084) (xy 153.601602 -239.430112) (xy 153.554049 -239.393622) (xy 153.511666 -239.351237)
			(xy 153.475178 -239.303683) (xy 153.445208 -239.251773) (xy 153.422271 -239.196395) (xy 153.406758 -239.138497)
			(xy 153.398934 -239.07907) (xy 4.308094 -239.07907) (xy 4.308094 -241.031522) (xy 4.307605 -241.10188)
			(xy 4.299704 -241.242374) (xy 4.283937 -241.382205) (xy 4.260354 -241.52093) (xy 4.229028 -241.658116)
			(xy 4.190059 -241.793328) (xy 4.143568 -241.926143) (xy 4.089703 -242.056141) (xy 4.028633 -242.182915)
			(xy 3.960549 -242.306064) (xy 3.885667 -242.425201) (xy 3.804222 -242.539952) (xy 3.71647 -242.649955)
			(xy 3.622687 -242.754863) (xy 3.573272 -242.80495) (xy 0.94488 -245.433342) (xy 0.907568 -245.471336)
			(xy 0.837834 -245.55183) (xy 0.774017 -245.637091) (xy 0.716442 -245.726686) (xy 0.665403 -245.820159)
			(xy 0.62116 -245.917033) (xy 0.583936 -246.016815) (xy 0.553923 -246.118998) (xy 0.531273 -246.223061)
			(xy 0.5161 -246.328474) (xy 0.508483 -246.4347) (xy 0.508 -246.48795) (xy 0.508 -270.89989) (xy 26.882353 -270.89989)
			(xy 26.886342 -270.75135) (xy 26.898299 -270.603237) (xy 26.918189 -270.45598) (xy 26.945954 -270.310004)
			(xy 26.981515 -270.165727) (xy 27.024769 -270.023568) (xy 27.075591 -269.883935) (xy 27.133835 -269.747232)
			(xy 27.199333 -269.613852) (xy 27.271896 -269.48418) (xy 27.351314 -269.35859) (xy 27.437359 -269.237443)
			(xy 27.529783 -269.12109) (xy 27.628319 -269.009866) (xy 27.732683 -268.904091) (xy 27.842575 -268.804071)
			(xy 27.957676 -268.710093) (xy 28.077656 -268.622429) (xy 28.202169 -268.541332) (xy 28.330855 -268.467035)
			(xy 28.463344 -268.399753) (xy 28.599253 -268.339679) (xy 28.738191 -268.286987) (xy 28.879757 -268.241828)
			(xy 29.023543 -268.204333) (xy 29.169134 -268.174611) (xy 29.31611 -268.152746) (xy 29.464049 -268.138802)
			(xy 29.612522 -268.132818) (xy 29.761103 -268.134813) (xy 29.909362 -268.144781) (xy 30.056873 -268.162692)
			(xy 30.203209 -268.188495) (xy 30.34795 -268.222115) (xy 30.490677 -268.263457) (xy 30.63098 -268.3124)
			(xy 30.768453 -268.368803) (xy 30.9027 -268.432504) (xy 31.033335 -268.50332) (xy 31.15998 -268.581045)
			(xy 31.28227 -268.665456) (xy 31.399853 -268.756309) (xy 31.51239 -268.853343) (xy 31.619557 -268.956278)
			(xy 31.721044 -269.064817) (xy 31.816558 -269.178646) (xy 31.905825 -269.297439) (xy 31.988586 -269.420851)
			(xy 32.064604 -269.548529) (xy 32.133659 -269.680102) (xy 32.195552 -269.815193) (xy 32.250105 -269.95341)
			(xy 32.29716 -270.094357) (xy 32.336582 -270.237627) (xy 32.368256 -270.382806) (xy 32.392092 -270.529475)
			(xy 32.408021 -270.677213) (xy 32.415997 -270.825593) (xy 32.416496 -270.89989) (xy 86.882487 -270.89989)
			(xy 86.886476 -270.75135) (xy 86.898433 -270.603237) (xy 86.918323 -270.45598) (xy 86.946088 -270.310004)
			(xy 86.981649 -270.165727) (xy 87.024903 -270.023568) (xy 87.075725 -269.883935) (xy 87.133969 -269.747232)
			(xy 87.199467 -269.613852) (xy 87.27203 -269.48418) (xy 87.351448 -269.35859) (xy 87.437493 -269.237443)
			(xy 87.529917 -269.12109) (xy 87.628453 -269.009866) (xy 87.732817 -268.904091) (xy 87.842709 -268.804071)
			(xy 87.95781 -268.710093) (xy 88.07779 -268.622429) (xy 88.202303 -268.541332) (xy 88.330989 -268.467035)
			(xy 88.463478 -268.399753) (xy 88.599387 -268.339679) (xy 88.738325 -268.286987) (xy 88.879891 -268.241828)
			(xy 89.023677 -268.204333) (xy 89.169268 -268.174611) (xy 89.316244 -268.152746) (xy 89.464183 -268.138802)
			(xy 89.612656 -268.132818) (xy 89.761237 -268.134813) (xy 89.909496 -268.144781) (xy 90.057007 -268.162692)
			(xy 90.203343 -268.188495) (xy 90.348084 -268.222115) (xy 90.490811 -268.263457) (xy 90.631114 -268.3124)
			(xy 90.768587 -268.368803) (xy 90.902834 -268.432504) (xy 91.033469 -268.50332) (xy 91.160114 -268.581045)
			(xy 91.282404 -268.665456) (xy 91.399987 -268.756309) (xy 91.512524 -268.853343) (xy 91.619691 -268.956278)
			(xy 91.721178 -269.064817) (xy 91.816692 -269.178646) (xy 91.905959 -269.297439) (xy 91.98872 -269.420851)
			(xy 92.064738 -269.548529) (xy 92.133793 -269.680102) (xy 92.195686 -269.815193) (xy 92.250239 -269.95341)
			(xy 92.297294 -270.094357) (xy 92.336716 -270.237627) (xy 92.36839 -270.382806) (xy 92.392226 -270.529475)
			(xy 92.408155 -270.677213) (xy 92.416131 -270.825593) (xy 92.41663 -270.89989) (xy 142.982451 -270.89989)
			(xy 142.98644 -270.75135) (xy 142.998397 -270.603237) (xy 143.018287 -270.45598) (xy 143.046052 -270.310004)
			(xy 143.081613 -270.165727) (xy 143.124867 -270.023568) (xy 143.175689 -269.883935) (xy 143.233933 -269.747232)
			(xy 143.299431 -269.613852) (xy 143.371994 -269.48418) (xy 143.451412 -269.35859) (xy 143.537457 -269.237443)
			(xy 143.629881 -269.12109) (xy 143.728417 -269.009866) (xy 143.832781 -268.904091) (xy 143.942673 -268.804071)
			(xy 144.057774 -268.710093) (xy 144.177754 -268.622429) (xy 144.302267 -268.541332) (xy 144.430953 -268.467035)
			(xy 144.563442 -268.399753) (xy 144.699351 -268.339679) (xy 144.838289 -268.286987) (xy 144.979855 -268.241828)
			(xy 145.123641 -268.204333) (xy 145.269232 -268.174611) (xy 145.416208 -268.152746) (xy 145.564147 -268.138802)
			(xy 145.71262 -268.132818) (xy 145.861201 -268.134813) (xy 146.00946 -268.144781) (xy 146.156971 -268.162692)
			(xy 146.303307 -268.188495) (xy 146.448048 -268.222115) (xy 146.590775 -268.263457) (xy 146.731078 -268.3124)
			(xy 146.868551 -268.368803) (xy 147.002798 -268.432504) (xy 147.133433 -268.50332) (xy 147.260078 -268.581045)
			(xy 147.382368 -268.665456) (xy 147.499951 -268.756309) (xy 147.612488 -268.853343) (xy 147.719655 -268.956278)
			(xy 147.821142 -269.064817) (xy 147.916656 -269.178646) (xy 148.005923 -269.297439) (xy 148.088684 -269.420851)
			(xy 148.164702 -269.548529) (xy 148.233757 -269.680102) (xy 148.29565 -269.815193) (xy 148.350203 -269.95341)
			(xy 148.397258 -270.094357) (xy 148.43668 -270.237627) (xy 148.468354 -270.382806) (xy 148.49219 -270.529475)
			(xy 148.508119 -270.677213) (xy 148.516095 -270.825593) (xy 148.516594 -270.89989) (xy 202.982331 -270.89989)
			(xy 202.98632 -270.75135) (xy 202.998277 -270.603237) (xy 203.018167 -270.45598) (xy 203.045932 -270.310004)
			(xy 203.081493 -270.165727) (xy 203.124747 -270.023568) (xy 203.175569 -269.883935) (xy 203.233813 -269.747232)
			(xy 203.299311 -269.613852) (xy 203.371874 -269.48418) (xy 203.451292 -269.35859) (xy 203.537337 -269.237443)
			(xy 203.629761 -269.12109) (xy 203.728297 -269.009866) (xy 203.832661 -268.904091) (xy 203.942553 -268.804071)
			(xy 204.057654 -268.710093) (xy 204.177634 -268.622429) (xy 204.302147 -268.541332) (xy 204.430833 -268.467035)
			(xy 204.563322 -268.399753) (xy 204.699231 -268.339679) (xy 204.838169 -268.286987) (xy 204.979735 -268.241828)
			(xy 205.123521 -268.204333) (xy 205.269112 -268.174611) (xy 205.416088 -268.152746) (xy 205.564027 -268.138802)
			(xy 205.7125 -268.132818) (xy 205.861081 -268.134813) (xy 206.00934 -268.144781) (xy 206.156851 -268.162692)
			(xy 206.303187 -268.188495) (xy 206.447928 -268.222115) (xy 206.590655 -268.263457) (xy 206.730958 -268.3124)
			(xy 206.868431 -268.368803) (xy 207.002678 -268.432504) (xy 207.133313 -268.50332) (xy 207.259958 -268.581045)
			(xy 207.382248 -268.665456) (xy 207.499831 -268.756309) (xy 207.612368 -268.853343) (xy 207.719535 -268.956278)
			(xy 207.821022 -269.064817) (xy 207.916536 -269.178646) (xy 208.005803 -269.297439) (xy 208.088564 -269.420851)
			(xy 208.164582 -269.548529) (xy 208.233637 -269.680102) (xy 208.29553 -269.815193) (xy 208.350083 -269.95341)
			(xy 208.397138 -270.094357) (xy 208.43656 -270.237627) (xy 208.468234 -270.382806) (xy 208.49207 -270.529475)
			(xy 208.507999 -270.677213) (xy 208.515975 -270.825593) (xy 208.516474 -270.89989) (xy 259.082549 -270.89989)
			(xy 259.086538 -270.75135) (xy 259.098495 -270.603237) (xy 259.118385 -270.45598) (xy 259.14615 -270.310004)
			(xy 259.181711 -270.165727) (xy 259.224965 -270.023568) (xy 259.275787 -269.883935) (xy 259.334031 -269.747232)
			(xy 259.399529 -269.613852) (xy 259.472092 -269.48418) (xy 259.55151 -269.35859) (xy 259.637555 -269.237443)
			(xy 259.729979 -269.12109) (xy 259.828515 -269.009866) (xy 259.932879 -268.904091) (xy 260.042771 -268.804071)
			(xy 260.157872 -268.710093) (xy 260.277852 -268.622429) (xy 260.402365 -268.541332) (xy 260.531051 -268.467035)
			(xy 260.66354 -268.399753) (xy 260.799449 -268.339679) (xy 260.938387 -268.286987) (xy 261.079953 -268.241828)
			(xy 261.223739 -268.204333) (xy 261.36933 -268.174611) (xy 261.516306 -268.152746) (xy 261.664245 -268.138802)
			(xy 261.812718 -268.132818) (xy 261.961299 -268.134813) (xy 262.109558 -268.144781) (xy 262.257069 -268.162692)
			(xy 262.403405 -268.188495) (xy 262.548146 -268.222115) (xy 262.690873 -268.263457) (xy 262.831176 -268.3124)
			(xy 262.968649 -268.368803) (xy 263.102896 -268.432504) (xy 263.233531 -268.50332) (xy 263.360176 -268.581045)
			(xy 263.482466 -268.665456) (xy 263.600049 -268.756309) (xy 263.712586 -268.853343) (xy 263.819753 -268.956278)
			(xy 263.92124 -269.064817) (xy 264.016754 -269.178646) (xy 264.106021 -269.297439) (xy 264.188782 -269.420851)
			(xy 264.2648 -269.548529) (xy 264.333855 -269.680102) (xy 264.395748 -269.815193) (xy 264.450301 -269.95341)
			(xy 264.497356 -270.094357) (xy 264.536778 -270.237627) (xy 264.568452 -270.382806) (xy 264.592288 -270.529475)
			(xy 264.608217 -270.677213) (xy 264.616193 -270.825593) (xy 264.616692 -270.89989) (xy 319.082429 -270.89989)
			(xy 319.086418 -270.75135) (xy 319.098375 -270.603237) (xy 319.118265 -270.45598) (xy 319.14603 -270.310004)
			(xy 319.181591 -270.165727) (xy 319.224845 -270.023568) (xy 319.275667 -269.883935) (xy 319.333911 -269.747232)
			(xy 319.399409 -269.613852) (xy 319.471972 -269.48418) (xy 319.55139 -269.35859) (xy 319.637435 -269.237443)
			(xy 319.729859 -269.12109) (xy 319.828395 -269.009866) (xy 319.932759 -268.904091) (xy 320.042651 -268.804071)
			(xy 320.157752 -268.710093) (xy 320.277732 -268.622429) (xy 320.402245 -268.541332) (xy 320.530931 -268.467035)
			(xy 320.66342 -268.399753) (xy 320.799329 -268.339679) (xy 320.938267 -268.286987) (xy 321.079833 -268.241828)
			(xy 321.223619 -268.204333) (xy 321.36921 -268.174611) (xy 321.516186 -268.152746) (xy 321.664125 -268.138802)
			(xy 321.812598 -268.132818) (xy 321.961179 -268.134813) (xy 322.109438 -268.144781) (xy 322.256949 -268.162692)
			(xy 322.403285 -268.188495) (xy 322.548026 -268.222115) (xy 322.690753 -268.263457) (xy 322.831056 -268.3124)
			(xy 322.968529 -268.368803) (xy 323.102776 -268.432504) (xy 323.233411 -268.50332) (xy 323.360056 -268.581045)
			(xy 323.482346 -268.665456) (xy 323.599929 -268.756309) (xy 323.712466 -268.853343) (xy 323.819633 -268.956278)
			(xy 323.92112 -269.064817) (xy 324.016634 -269.178646) (xy 324.105901 -269.297439) (xy 324.188662 -269.420851)
			(xy 324.26468 -269.548529) (xy 324.333735 -269.680102) (xy 324.395628 -269.815193) (xy 324.450181 -269.95341)
			(xy 324.497236 -270.094357) (xy 324.536658 -270.237627) (xy 324.568332 -270.382806) (xy 324.592168 -270.529475)
			(xy 324.608097 -270.677213) (xy 324.616073 -270.825593) (xy 324.616572 -270.89989) (xy 375.182393 -270.89989)
			(xy 375.186382 -270.75135) (xy 375.198339 -270.603237) (xy 375.218229 -270.45598) (xy 375.245994 -270.310004)
			(xy 375.281555 -270.165727) (xy 375.324809 -270.023568) (xy 375.375631 -269.883935) (xy 375.433875 -269.747232)
			(xy 375.499373 -269.613852) (xy 375.571936 -269.48418) (xy 375.651354 -269.35859) (xy 375.737399 -269.237443)
			(xy 375.829823 -269.12109) (xy 375.928359 -269.009866) (xy 376.032723 -268.904091) (xy 376.142615 -268.804071)
			(xy 376.257716 -268.710093) (xy 376.377696 -268.622429) (xy 376.502209 -268.541332) (xy 376.630895 -268.467035)
			(xy 376.763384 -268.399753) (xy 376.899293 -268.339679) (xy 377.038231 -268.286987) (xy 377.179797 -268.241828)
			(xy 377.323583 -268.204333) (xy 377.469174 -268.174611) (xy 377.61615 -268.152746) (xy 377.764089 -268.138802)
			(xy 377.912562 -268.132818) (xy 378.061143 -268.134813) (xy 378.209402 -268.144781) (xy 378.356913 -268.162692)
			(xy 378.503249 -268.188495) (xy 378.64799 -268.222115) (xy 378.790717 -268.263457) (xy 378.93102 -268.3124)
			(xy 379.068493 -268.368803) (xy 379.20274 -268.432504) (xy 379.333375 -268.50332) (xy 379.46002 -268.581045)
			(xy 379.58231 -268.665456) (xy 379.699893 -268.756309) (xy 379.81243 -268.853343) (xy 379.919597 -268.956278)
			(xy 380.021084 -269.064817) (xy 380.116598 -269.178646) (xy 380.205865 -269.297439) (xy 380.288626 -269.420851)
			(xy 380.364644 -269.548529) (xy 380.433699 -269.680102) (xy 380.495592 -269.815193) (xy 380.550145 -269.95341)
			(xy 380.5972 -270.094357) (xy 380.636622 -270.237627) (xy 380.668296 -270.382806) (xy 380.692132 -270.529475)
			(xy 380.708061 -270.677213) (xy 380.716037 -270.825593) (xy 380.716536 -270.89989) (xy 435.182527 -270.89989)
			(xy 435.186516 -270.75135) (xy 435.198473 -270.603237) (xy 435.218363 -270.45598) (xy 435.246128 -270.310004)
			(xy 435.281689 -270.165727) (xy 435.324943 -270.023568) (xy 435.375765 -269.883935) (xy 435.434009 -269.747232)
			(xy 435.499507 -269.613852) (xy 435.57207 -269.48418) (xy 435.651488 -269.35859) (xy 435.737533 -269.237443)
			(xy 435.829957 -269.12109) (xy 435.928493 -269.009866) (xy 436.032857 -268.904091) (xy 436.142749 -268.804071)
			(xy 436.25785 -268.710093) (xy 436.37783 -268.622429) (xy 436.502343 -268.541332) (xy 436.631029 -268.467035)
			(xy 436.763518 -268.399753) (xy 436.899427 -268.339679) (xy 437.038365 -268.286987) (xy 437.179931 -268.241828)
			(xy 437.323717 -268.204333) (xy 437.469308 -268.174611) (xy 437.616284 -268.152746) (xy 437.764223 -268.138802)
			(xy 437.912696 -268.132818) (xy 438.061277 -268.134813) (xy 438.209536 -268.144781) (xy 438.357047 -268.162692)
			(xy 438.503383 -268.188495) (xy 438.648124 -268.222115) (xy 438.790851 -268.263457) (xy 438.931154 -268.3124)
			(xy 439.068627 -268.368803) (xy 439.202874 -268.432504) (xy 439.333509 -268.50332) (xy 439.460154 -268.581045)
			(xy 439.582444 -268.665456) (xy 439.700027 -268.756309) (xy 439.812564 -268.853343) (xy 439.919731 -268.956278)
			(xy 440.021218 -269.064817) (xy 440.116732 -269.178646) (xy 440.205999 -269.297439) (xy 440.28876 -269.420851)
			(xy 440.364778 -269.548529) (xy 440.433833 -269.680102) (xy 440.495726 -269.815193) (xy 440.550279 -269.95341)
			(xy 440.597334 -270.094357) (xy 440.636756 -270.237627) (xy 440.66843 -270.382806) (xy 440.692266 -270.529475)
			(xy 440.708195 -270.677213) (xy 440.716171 -270.825593) (xy 440.71667 -270.89989) (xy 440.716171 -270.974187)
			(xy 440.708195 -271.122567) (xy 440.692266 -271.270305) (xy 440.66843 -271.416974) (xy 440.636756 -271.562153)
			(xy 440.597334 -271.705423) (xy 440.550279 -271.84637) (xy 440.495726 -271.984587) (xy 440.433833 -272.119678)
			(xy 440.364778 -272.251251) (xy 440.28876 -272.378929) (xy 440.205999 -272.502341) (xy 440.116732 -272.621134)
			(xy 440.021218 -272.734963) (xy 439.919731 -272.843502) (xy 439.812564 -272.946437) (xy 439.700027 -273.043471)
			(xy 439.582444 -273.134324) (xy 439.460154 -273.218735) (xy 439.333509 -273.29646) (xy 439.202874 -273.367276)
			(xy 439.068627 -273.430977) (xy 438.931154 -273.48738) (xy 438.790851 -273.536323) (xy 438.648124 -273.577665)
			(xy 438.503383 -273.611285) (xy 438.357047 -273.637088) (xy 438.209536 -273.654999) (xy 438.061277 -273.664967)
			(xy 437.912696 -273.666962) (xy 437.764223 -273.660978) (xy 437.616284 -273.647034) (xy 437.469308 -273.625169)
			(xy 437.323717 -273.595447) (xy 437.179931 -273.557952) (xy 437.038365 -273.512793) (xy 436.899427 -273.460101)
			(xy 436.763518 -273.400027) (xy 436.631029 -273.332745) (xy 436.502343 -273.258448) (xy 436.37783 -273.177351)
			(xy 436.25785 -273.089687) (xy 436.142749 -272.995709) (xy 436.032857 -272.895689) (xy 435.928493 -272.789914)
			(xy 435.829957 -272.67869) (xy 435.737533 -272.562337) (xy 435.651488 -272.44119) (xy 435.57207 -272.3156)
			(xy 435.499507 -272.185928) (xy 435.434009 -272.052548) (xy 435.375765 -271.915845) (xy 435.324943 -271.776212)
			(xy 435.281689 -271.634053) (xy 435.246128 -271.489776) (xy 435.218363 -271.3438) (xy 435.198473 -271.196543)
			(xy 435.186516 -271.04843) (xy 435.182527 -270.89989) (xy 380.716536 -270.89989) (xy 380.716037 -270.974187)
			(xy 380.708061 -271.122567) (xy 380.692132 -271.270305) (xy 380.668296 -271.416974) (xy 380.636622 -271.562153)
			(xy 380.5972 -271.705423) (xy 380.550145 -271.84637) (xy 380.495592 -271.984587) (xy 380.433699 -272.119678)
			(xy 380.364644 -272.251251) (xy 380.288626 -272.378929) (xy 380.205865 -272.502341) (xy 380.116598 -272.621134)
			(xy 380.021084 -272.734963) (xy 379.919597 -272.843502) (xy 379.81243 -272.946437) (xy 379.699893 -273.043471)
			(xy 379.58231 -273.134324) (xy 379.46002 -273.218735) (xy 379.333375 -273.29646) (xy 379.20274 -273.367276)
			(xy 379.068493 -273.430977) (xy 378.93102 -273.48738) (xy 378.790717 -273.536323) (xy 378.64799 -273.577665)
			(xy 378.503249 -273.611285) (xy 378.356913 -273.637088) (xy 378.209402 -273.654999) (xy 378.061143 -273.664967)
			(xy 377.912562 -273.666962) (xy 377.764089 -273.660978) (xy 377.61615 -273.647034) (xy 377.469174 -273.625169)
			(xy 377.323583 -273.595447) (xy 377.179797 -273.557952) (xy 377.038231 -273.512793) (xy 376.899293 -273.460101)
			(xy 376.763384 -273.400027) (xy 376.630895 -273.332745) (xy 376.502209 -273.258448) (xy 376.377696 -273.177351)
			(xy 376.257716 -273.089687) (xy 376.142615 -272.995709) (xy 376.032723 -272.895689) (xy 375.928359 -272.789914)
			(xy 375.829823 -272.67869) (xy 375.737399 -272.562337) (xy 375.651354 -272.44119) (xy 375.571936 -272.3156)
			(xy 375.499373 -272.185928) (xy 375.433875 -272.052548) (xy 375.375631 -271.915845) (xy 375.324809 -271.776212)
			(xy 375.281555 -271.634053) (xy 375.245994 -271.489776) (xy 375.218229 -271.3438) (xy 375.198339 -271.196543)
			(xy 375.186382 -271.04843) (xy 375.182393 -270.89989) (xy 324.616572 -270.89989) (xy 324.616073 -270.974187)
			(xy 324.608097 -271.122567) (xy 324.592168 -271.270305) (xy 324.568332 -271.416974) (xy 324.536658 -271.562153)
			(xy 324.497236 -271.705423) (xy 324.450181 -271.84637) (xy 324.395628 -271.984587) (xy 324.333735 -272.119678)
			(xy 324.26468 -272.251251) (xy 324.188662 -272.378929) (xy 324.105901 -272.502341) (xy 324.016634 -272.621134)
			(xy 323.92112 -272.734963) (xy 323.819633 -272.843502) (xy 323.712466 -272.946437) (xy 323.599929 -273.043471)
			(xy 323.482346 -273.134324) (xy 323.360056 -273.218735) (xy 323.233411 -273.29646) (xy 323.102776 -273.367276)
			(xy 322.968529 -273.430977) (xy 322.831056 -273.48738) (xy 322.690753 -273.536323) (xy 322.548026 -273.577665)
			(xy 322.403285 -273.611285) (xy 322.256949 -273.637088) (xy 322.109438 -273.654999) (xy 321.961179 -273.664967)
			(xy 321.812598 -273.666962) (xy 321.664125 -273.660978) (xy 321.516186 -273.647034) (xy 321.36921 -273.625169)
			(xy 321.223619 -273.595447) (xy 321.079833 -273.557952) (xy 320.938267 -273.512793) (xy 320.799329 -273.460101)
			(xy 320.66342 -273.400027) (xy 320.530931 -273.332745) (xy 320.402245 -273.258448) (xy 320.277732 -273.177351)
			(xy 320.157752 -273.089687) (xy 320.042651 -272.995709) (xy 319.932759 -272.895689) (xy 319.828395 -272.789914)
			(xy 319.729859 -272.67869) (xy 319.637435 -272.562337) (xy 319.55139 -272.44119) (xy 319.471972 -272.3156)
			(xy 319.399409 -272.185928) (xy 319.333911 -272.052548) (xy 319.275667 -271.915845) (xy 319.224845 -271.776212)
			(xy 319.181591 -271.634053) (xy 319.14603 -271.489776) (xy 319.118265 -271.3438) (xy 319.098375 -271.196543)
			(xy 319.086418 -271.04843) (xy 319.082429 -270.89989) (xy 264.616692 -270.89989) (xy 264.616193 -270.974187)
			(xy 264.608217 -271.122567) (xy 264.592288 -271.270305) (xy 264.568452 -271.416974) (xy 264.536778 -271.562153)
			(xy 264.497356 -271.705423) (xy 264.450301 -271.84637) (xy 264.395748 -271.984587) (xy 264.333855 -272.119678)
			(xy 264.2648 -272.251251) (xy 264.188782 -272.378929) (xy 264.106021 -272.502341) (xy 264.016754 -272.621134)
			(xy 263.92124 -272.734963) (xy 263.819753 -272.843502) (xy 263.712586 -272.946437) (xy 263.600049 -273.043471)
			(xy 263.482466 -273.134324) (xy 263.360176 -273.218735) (xy 263.233531 -273.29646) (xy 263.102896 -273.367276)
			(xy 262.968649 -273.430977) (xy 262.831176 -273.48738) (xy 262.690873 -273.536323) (xy 262.548146 -273.577665)
			(xy 262.403405 -273.611285) (xy 262.257069 -273.637088) (xy 262.109558 -273.654999) (xy 261.961299 -273.664967)
			(xy 261.812718 -273.666962) (xy 261.664245 -273.660978) (xy 261.516306 -273.647034) (xy 261.36933 -273.625169)
			(xy 261.223739 -273.595447) (xy 261.079953 -273.557952) (xy 260.938387 -273.512793) (xy 260.799449 -273.460101)
			(xy 260.66354 -273.400027) (xy 260.531051 -273.332745) (xy 260.402365 -273.258448) (xy 260.277852 -273.177351)
			(xy 260.157872 -273.089687) (xy 260.042771 -272.995709) (xy 259.932879 -272.895689) (xy 259.828515 -272.789914)
			(xy 259.729979 -272.67869) (xy 259.637555 -272.562337) (xy 259.55151 -272.44119) (xy 259.472092 -272.3156)
			(xy 259.399529 -272.185928) (xy 259.334031 -272.052548) (xy 259.275787 -271.915845) (xy 259.224965 -271.776212)
			(xy 259.181711 -271.634053) (xy 259.14615 -271.489776) (xy 259.118385 -271.3438) (xy 259.098495 -271.196543)
			(xy 259.086538 -271.04843) (xy 259.082549 -270.89989) (xy 208.516474 -270.89989) (xy 208.515975 -270.974187)
			(xy 208.507999 -271.122567) (xy 208.49207 -271.270305) (xy 208.468234 -271.416974) (xy 208.43656 -271.562153)
			(xy 208.397138 -271.705423) (xy 208.350083 -271.84637) (xy 208.29553 -271.984587) (xy 208.233637 -272.119678)
			(xy 208.164582 -272.251251) (xy 208.088564 -272.378929) (xy 208.005803 -272.502341) (xy 207.916536 -272.621134)
			(xy 207.821022 -272.734963) (xy 207.719535 -272.843502) (xy 207.612368 -272.946437) (xy 207.499831 -273.043471)
			(xy 207.382248 -273.134324) (xy 207.259958 -273.218735) (xy 207.133313 -273.29646) (xy 207.002678 -273.367276)
			(xy 206.868431 -273.430977) (xy 206.730958 -273.48738) (xy 206.590655 -273.536323) (xy 206.447928 -273.577665)
			(xy 206.303187 -273.611285) (xy 206.156851 -273.637088) (xy 206.00934 -273.654999) (xy 205.861081 -273.664967)
			(xy 205.7125 -273.666962) (xy 205.564027 -273.660978) (xy 205.416088 -273.647034) (xy 205.269112 -273.625169)
			(xy 205.123521 -273.595447) (xy 204.979735 -273.557952) (xy 204.838169 -273.512793) (xy 204.699231 -273.460101)
			(xy 204.563322 -273.400027) (xy 204.430833 -273.332745) (xy 204.302147 -273.258448) (xy 204.177634 -273.177351)
			(xy 204.057654 -273.089687) (xy 203.942553 -272.995709) (xy 203.832661 -272.895689) (xy 203.728297 -272.789914)
			(xy 203.629761 -272.67869) (xy 203.537337 -272.562337) (xy 203.451292 -272.44119) (xy 203.371874 -272.3156)
			(xy 203.299311 -272.185928) (xy 203.233813 -272.052548) (xy 203.175569 -271.915845) (xy 203.124747 -271.776212)
			(xy 203.081493 -271.634053) (xy 203.045932 -271.489776) (xy 203.018167 -271.3438) (xy 202.998277 -271.196543)
			(xy 202.98632 -271.04843) (xy 202.982331 -270.89989) (xy 148.516594 -270.89989) (xy 148.516095 -270.974187)
			(xy 148.508119 -271.122567) (xy 148.49219 -271.270305) (xy 148.468354 -271.416974) (xy 148.43668 -271.562153)
			(xy 148.397258 -271.705423) (xy 148.350203 -271.84637) (xy 148.29565 -271.984587) (xy 148.233757 -272.119678)
			(xy 148.164702 -272.251251) (xy 148.088684 -272.378929) (xy 148.005923 -272.502341) (xy 147.916656 -272.621134)
			(xy 147.821142 -272.734963) (xy 147.719655 -272.843502) (xy 147.612488 -272.946437) (xy 147.499951 -273.043471)
			(xy 147.382368 -273.134324) (xy 147.260078 -273.218735) (xy 147.133433 -273.29646) (xy 147.002798 -273.367276)
			(xy 146.868551 -273.430977) (xy 146.731078 -273.48738) (xy 146.590775 -273.536323) (xy 146.448048 -273.577665)
			(xy 146.303307 -273.611285) (xy 146.156971 -273.637088) (xy 146.00946 -273.654999) (xy 145.861201 -273.664967)
			(xy 145.71262 -273.666962) (xy 145.564147 -273.660978) (xy 145.416208 -273.647034) (xy 145.269232 -273.625169)
			(xy 145.123641 -273.595447) (xy 144.979855 -273.557952) (xy 144.838289 -273.512793) (xy 144.699351 -273.460101)
			(xy 144.563442 -273.400027) (xy 144.430953 -273.332745) (xy 144.302267 -273.258448) (xy 144.177754 -273.177351)
			(xy 144.057774 -273.089687) (xy 143.942673 -272.995709) (xy 143.832781 -272.895689) (xy 143.728417 -272.789914)
			(xy 143.629881 -272.67869) (xy 143.537457 -272.562337) (xy 143.451412 -272.44119) (xy 143.371994 -272.3156)
			(xy 143.299431 -272.185928) (xy 143.233933 -272.052548) (xy 143.175689 -271.915845) (xy 143.124867 -271.776212)
			(xy 143.081613 -271.634053) (xy 143.046052 -271.489776) (xy 143.018287 -271.3438) (xy 142.998397 -271.196543)
			(xy 142.98644 -271.04843) (xy 142.982451 -270.89989) (xy 92.41663 -270.89989) (xy 92.416131 -270.974187)
			(xy 92.408155 -271.122567) (xy 92.392226 -271.270305) (xy 92.36839 -271.416974) (xy 92.336716 -271.562153)
			(xy 92.297294 -271.705423) (xy 92.250239 -271.84637) (xy 92.195686 -271.984587) (xy 92.133793 -272.119678)
			(xy 92.064738 -272.251251) (xy 91.98872 -272.378929) (xy 91.905959 -272.502341) (xy 91.816692 -272.621134)
			(xy 91.721178 -272.734963) (xy 91.619691 -272.843502) (xy 91.512524 -272.946437) (xy 91.399987 -273.043471)
			(xy 91.282404 -273.134324) (xy 91.160114 -273.218735) (xy 91.033469 -273.29646) (xy 90.902834 -273.367276)
			(xy 90.768587 -273.430977) (xy 90.631114 -273.48738) (xy 90.490811 -273.536323) (xy 90.348084 -273.577665)
			(xy 90.203343 -273.611285) (xy 90.057007 -273.637088) (xy 89.909496 -273.654999) (xy 89.761237 -273.664967)
			(xy 89.612656 -273.666962) (xy 89.464183 -273.660978) (xy 89.316244 -273.647034) (xy 89.169268 -273.625169)
			(xy 89.023677 -273.595447) (xy 88.879891 -273.557952) (xy 88.738325 -273.512793) (xy 88.599387 -273.460101)
			(xy 88.463478 -273.400027) (xy 88.330989 -273.332745) (xy 88.202303 -273.258448) (xy 88.07779 -273.177351)
			(xy 87.95781 -273.089687) (xy 87.842709 -272.995709) (xy 87.732817 -272.895689) (xy 87.628453 -272.789914)
			(xy 87.529917 -272.67869) (xy 87.437493 -272.562337) (xy 87.351448 -272.44119) (xy 87.27203 -272.3156)
			(xy 87.199467 -272.185928) (xy 87.133969 -272.052548) (xy 87.075725 -271.915845) (xy 87.024903 -271.776212)
			(xy 86.981649 -271.634053) (xy 86.946088 -271.489776) (xy 86.918323 -271.3438) (xy 86.898433 -271.196543)
			(xy 86.886476 -271.04843) (xy 86.882487 -270.89989) (xy 32.416496 -270.89989) (xy 32.415997 -270.974187)
			(xy 32.408021 -271.122567) (xy 32.392092 -271.270305) (xy 32.368256 -271.416974) (xy 32.336582 -271.562153)
			(xy 32.29716 -271.705423) (xy 32.250105 -271.84637) (xy 32.195552 -271.984587) (xy 32.133659 -272.119678)
			(xy 32.064604 -272.251251) (xy 31.988586 -272.378929) (xy 31.905825 -272.502341) (xy 31.816558 -272.621134)
			(xy 31.721044 -272.734963) (xy 31.619557 -272.843502) (xy 31.51239 -272.946437) (xy 31.399853 -273.043471)
			(xy 31.28227 -273.134324) (xy 31.15998 -273.218735) (xy 31.033335 -273.29646) (xy 30.9027 -273.367276)
			(xy 30.768453 -273.430977) (xy 30.63098 -273.48738) (xy 30.490677 -273.536323) (xy 30.34795 -273.577665)
			(xy 30.203209 -273.611285) (xy 30.056873 -273.637088) (xy 29.909362 -273.654999) (xy 29.761103 -273.664967)
			(xy 29.612522 -273.666962) (xy 29.464049 -273.660978) (xy 29.31611 -273.647034) (xy 29.169134 -273.625169)
			(xy 29.023543 -273.595447) (xy 28.879757 -273.557952) (xy 28.738191 -273.512793) (xy 28.599253 -273.460101)
			(xy 28.463344 -273.400027) (xy 28.330855 -273.332745) (xy 28.202169 -273.258448) (xy 28.077656 -273.177351)
			(xy 27.957676 -273.089687) (xy 27.842575 -272.995709) (xy 27.732683 -272.895689) (xy 27.628319 -272.789914)
			(xy 27.529783 -272.67869) (xy 27.437359 -272.562337) (xy 27.351314 -272.44119) (xy 27.271896 -272.3156)
			(xy 27.199333 -272.185928) (xy 27.133835 -272.052548) (xy 27.075591 -271.915845) (xy 27.024769 -271.776212)
			(xy 26.981515 -271.634053) (xy 26.945954 -271.489776) (xy 26.918189 -271.3438) (xy 26.898299 -271.196543)
			(xy 26.886342 -271.04843) (xy 26.882353 -270.89989) (xy 0.508 -270.89989) (xy 0.508 -276.899878)
			(xy 81.19416 -276.899878) (xy 81.19812 -276.850824) (xy 81.209897 -276.80304) (xy 81.229188 -276.757764)
			(xy 81.255491 -276.716168) (xy 81.288126 -276.679331) (xy 81.326247 -276.648206) (xy 81.368868 -276.623599)
			(xy 81.414884 -276.606147) (xy 81.463103 -276.596303) (xy 81.512278 -276.594322) (xy 81.561133 -276.600254)
			(xy 81.608404 -276.613946) (xy 81.652866 -276.635044) (xy 81.693369 -276.663) (xy 81.728862 -276.697092)
			(xy 81.758427 -276.736436) (xy 81.781298 -276.780013) (xy 81.796882 -276.826694) (xy 81.804777 -276.875271)
			(xy 81.805272 -276.899878) (xy 82.14412 -276.899878) (xy 82.14808 -276.850824) (xy 82.159857 -276.80304)
			(xy 82.179148 -276.757764) (xy 82.205451 -276.716168) (xy 82.238086 -276.679331) (xy 82.276207 -276.648206)
			(xy 82.318828 -276.623599) (xy 82.364844 -276.606147) (xy 82.413063 -276.596303) (xy 82.462238 -276.594322)
			(xy 82.511093 -276.600254) (xy 82.558364 -276.613946) (xy 82.602826 -276.635044) (xy 82.643329 -276.663)
			(xy 82.678822 -276.697092) (xy 82.708387 -276.736436) (xy 82.731258 -276.780013) (xy 82.746842 -276.826694)
			(xy 82.754737 -276.875271) (xy 82.755232 -276.899878) (xy 197.294258 -276.899878) (xy 197.298218 -276.850824)
			(xy 197.309995 -276.80304) (xy 197.329286 -276.757764) (xy 197.355589 -276.716168) (xy 197.388224 -276.679331)
			(xy 197.426345 -276.648206) (xy 197.468966 -276.623599) (xy 197.514982 -276.606147) (xy 197.563201 -276.596303)
			(xy 197.612376 -276.594322) (xy 197.661231 -276.600254) (xy 197.708502 -276.613946) (xy 197.752964 -276.635044)
			(xy 197.793467 -276.663) (xy 197.82896 -276.697092) (xy 197.858525 -276.736436) (xy 197.881396 -276.780013)
			(xy 197.89698 -276.826694) (xy 197.904875 -276.875271) (xy 197.90537 -276.899878) (xy 198.244218 -276.899878)
			(xy 198.248178 -276.850824) (xy 198.259955 -276.80304) (xy 198.279246 -276.757764) (xy 198.305549 -276.716168)
			(xy 198.338184 -276.679331) (xy 198.376305 -276.648206) (xy 198.418926 -276.623599) (xy 198.464942 -276.606147)
			(xy 198.513161 -276.596303) (xy 198.562336 -276.594322) (xy 198.611191 -276.600254) (xy 198.658462 -276.613946)
			(xy 198.702924 -276.635044) (xy 198.743427 -276.663) (xy 198.77892 -276.697092) (xy 198.808485 -276.736436)
			(xy 198.831356 -276.780013) (xy 198.84694 -276.826694) (xy 198.854835 -276.875271) (xy 198.85533 -276.899878)
			(xy 313.394102 -276.899878) (xy 313.398062 -276.850824) (xy 313.409839 -276.80304) (xy 313.42913 -276.757764)
			(xy 313.455433 -276.716168) (xy 313.488068 -276.679331) (xy 313.526189 -276.648206) (xy 313.56881 -276.623599)
			(xy 313.614826 -276.606147) (xy 313.663045 -276.596303) (xy 313.71222 -276.594322) (xy 313.761075 -276.600254)
			(xy 313.808346 -276.613946) (xy 313.852808 -276.635044) (xy 313.893311 -276.663) (xy 313.928804 -276.697092)
			(xy 313.958369 -276.736436) (xy 313.98124 -276.780013) (xy 313.996824 -276.826694) (xy 314.004719 -276.875271)
			(xy 314.005214 -276.899878) (xy 314.344062 -276.899878) (xy 314.348022 -276.850824) (xy 314.359799 -276.80304)
			(xy 314.37909 -276.757764) (xy 314.405393 -276.716168) (xy 314.438028 -276.679331) (xy 314.476149 -276.648206)
			(xy 314.51877 -276.623599) (xy 314.564786 -276.606147) (xy 314.613005 -276.596303) (xy 314.66218 -276.594322)
			(xy 314.711035 -276.600254) (xy 314.758306 -276.613946) (xy 314.802768 -276.635044) (xy 314.843271 -276.663)
			(xy 314.878764 -276.697092) (xy 314.908329 -276.736436) (xy 314.9312 -276.780013) (xy 314.946784 -276.826694)
			(xy 314.954679 -276.875271) (xy 314.955174 -276.899878) (xy 429.4942 -276.899878) (xy 429.49816 -276.850824)
			(xy 429.509937 -276.80304) (xy 429.529228 -276.757764) (xy 429.555531 -276.716168) (xy 429.588166 -276.679331)
			(xy 429.626287 -276.648206) (xy 429.668908 -276.623599) (xy 429.714924 -276.606147) (xy 429.763143 -276.596303)
			(xy 429.812318 -276.594322) (xy 429.861173 -276.600254) (xy 429.908444 -276.613946) (xy 429.952906 -276.635044)
			(xy 429.993409 -276.663) (xy 430.028902 -276.697092) (xy 430.058467 -276.736436) (xy 430.081338 -276.780013)
			(xy 430.096922 -276.826694) (xy 430.104817 -276.875271) (xy 430.105312 -276.899878) (xy 430.44416 -276.899878)
			(xy 430.44812 -276.850824) (xy 430.459897 -276.80304) (xy 430.479188 -276.757764) (xy 430.505491 -276.716168)
			(xy 430.538126 -276.679331) (xy 430.576247 -276.648206) (xy 430.618868 -276.623599) (xy 430.664884 -276.606147)
			(xy 430.713103 -276.596303) (xy 430.762278 -276.594322) (xy 430.811133 -276.600254) (xy 430.858404 -276.613946)
			(xy 430.902866 -276.635044) (xy 430.943369 -276.663) (xy 430.978862 -276.697092) (xy 431.008427 -276.736436)
			(xy 431.031298 -276.780013) (xy 431.046882 -276.826694) (xy 431.054777 -276.875271) (xy 431.055272 -276.899878)
			(xy 431.054777 -276.924485) (xy 431.046882 -276.973062) (xy 431.031298 -277.019743) (xy 431.008427 -277.06332)
			(xy 430.978862 -277.102664) (xy 430.943369 -277.136756) (xy 430.902866 -277.164712) (xy 430.858404 -277.18581)
			(xy 430.811133 -277.199502) (xy 430.762278 -277.205434) (xy 430.713103 -277.203453) (xy 430.664884 -277.193609)
			(xy 430.618868 -277.176157) (xy 430.576247 -277.15155) (xy 430.538126 -277.120425) (xy 430.505491 -277.083588)
			(xy 430.479188 -277.041992) (xy 430.459897 -276.996716) (xy 430.44812 -276.948932) (xy 430.44416 -276.899878)
			(xy 430.105312 -276.899878) (xy 430.104817 -276.924485) (xy 430.096922 -276.973062) (xy 430.081338 -277.019743)
			(xy 430.058467 -277.06332) (xy 430.028902 -277.102664) (xy 429.993409 -277.136756) (xy 429.952906 -277.164712)
			(xy 429.908444 -277.18581) (xy 429.861173 -277.199502) (xy 429.812318 -277.205434) (xy 429.763143 -277.203453)
			(xy 429.714924 -277.193609) (xy 429.668908 -277.176157) (xy 429.626287 -277.15155) (xy 429.588166 -277.120425)
			(xy 429.555531 -277.083588) (xy 429.529228 -277.041992) (xy 429.509937 -276.996716) (xy 429.49816 -276.948932)
			(xy 429.4942 -276.899878) (xy 314.955174 -276.899878) (xy 314.954679 -276.924485) (xy 314.946784 -276.973062)
			(xy 314.9312 -277.019743) (xy 314.908329 -277.06332) (xy 314.878764 -277.102664) (xy 314.843271 -277.136756)
			(xy 314.802768 -277.164712) (xy 314.758306 -277.18581) (xy 314.711035 -277.199502) (xy 314.66218 -277.205434)
			(xy 314.613005 -277.203453) (xy 314.564786 -277.193609) (xy 314.51877 -277.176157) (xy 314.476149 -277.15155)
			(xy 314.438028 -277.120425) (xy 314.405393 -277.083588) (xy 314.37909 -277.041992) (xy 314.359799 -276.996716)
			(xy 314.348022 -276.948932) (xy 314.344062 -276.899878) (xy 314.005214 -276.899878) (xy 314.004719 -276.924485)
			(xy 313.996824 -276.973062) (xy 313.98124 -277.019743) (xy 313.958369 -277.06332) (xy 313.928804 -277.102664)
			(xy 313.893311 -277.136756) (xy 313.852808 -277.164712) (xy 313.808346 -277.18581) (xy 313.761075 -277.199502)
			(xy 313.71222 -277.205434) (xy 313.663045 -277.203453) (xy 313.614826 -277.193609) (xy 313.56881 -277.176157)
			(xy 313.526189 -277.15155) (xy 313.488068 -277.120425) (xy 313.455433 -277.083588) (xy 313.42913 -277.041992)
			(xy 313.409839 -276.996716) (xy 313.398062 -276.948932) (xy 313.394102 -276.899878) (xy 198.85533 -276.899878)
			(xy 198.854835 -276.924485) (xy 198.84694 -276.973062) (xy 198.831356 -277.019743) (xy 198.808485 -277.06332)
			(xy 198.77892 -277.102664) (xy 198.743427 -277.136756) (xy 198.702924 -277.164712) (xy 198.658462 -277.18581)
			(xy 198.611191 -277.199502) (xy 198.562336 -277.205434) (xy 198.513161 -277.203453) (xy 198.464942 -277.193609)
			(xy 198.418926 -277.176157) (xy 198.376305 -277.15155) (xy 198.338184 -277.120425) (xy 198.305549 -277.083588)
			(xy 198.279246 -277.041992) (xy 198.259955 -276.996716) (xy 198.248178 -276.948932) (xy 198.244218 -276.899878)
			(xy 197.90537 -276.899878) (xy 197.904875 -276.924485) (xy 197.89698 -276.973062) (xy 197.881396 -277.019743)
			(xy 197.858525 -277.06332) (xy 197.82896 -277.102664) (xy 197.793467 -277.136756) (xy 197.752964 -277.164712)
			(xy 197.708502 -277.18581) (xy 197.661231 -277.199502) (xy 197.612376 -277.205434) (xy 197.563201 -277.203453)
			(xy 197.514982 -277.193609) (xy 197.468966 -277.176157) (xy 197.426345 -277.15155) (xy 197.388224 -277.120425)
			(xy 197.355589 -277.083588) (xy 197.329286 -277.041992) (xy 197.309995 -276.996716) (xy 197.298218 -276.948932)
			(xy 197.294258 -276.899878) (xy 82.755232 -276.899878) (xy 82.754737 -276.924485) (xy 82.746842 -276.973062)
			(xy 82.731258 -277.019743) (xy 82.708387 -277.06332) (xy 82.678822 -277.102664) (xy 82.643329 -277.136756)
			(xy 82.602826 -277.164712) (xy 82.558364 -277.18581) (xy 82.511093 -277.199502) (xy 82.462238 -277.205434)
			(xy 82.413063 -277.203453) (xy 82.364844 -277.193609) (xy 82.318828 -277.176157) (xy 82.276207 -277.15155)
			(xy 82.238086 -277.120425) (xy 82.205451 -277.083588) (xy 82.179148 -277.041992) (xy 82.159857 -276.996716)
			(xy 82.14808 -276.948932) (xy 82.14412 -276.899878) (xy 81.805272 -276.899878) (xy 81.804777 -276.924485)
			(xy 81.796882 -276.973062) (xy 81.781298 -277.019743) (xy 81.758427 -277.06332) (xy 81.728862 -277.102664)
			(xy 81.693369 -277.136756) (xy 81.652866 -277.164712) (xy 81.608404 -277.18581) (xy 81.561133 -277.199502)
			(xy 81.512278 -277.205434) (xy 81.463103 -277.203453) (xy 81.414884 -277.193609) (xy 81.368868 -277.176157)
			(xy 81.326247 -277.15155) (xy 81.288126 -277.120425) (xy 81.255491 -277.083588) (xy 81.229188 -277.041992)
			(xy 81.209897 -276.996716) (xy 81.19812 -276.948932) (xy 81.19416 -276.899878) (xy 0.508 -276.899878)
			(xy 0.508 -277.849838) (xy 44.143942 -277.849838) (xy 44.147902 -277.800784) (xy 44.159679 -277.753)
			(xy 44.17897 -277.707724) (xy 44.205273 -277.666128) (xy 44.237908 -277.629291) (xy 44.276029 -277.598166)
			(xy 44.31865 -277.573559) (xy 44.364666 -277.556107) (xy 44.412885 -277.546263) (xy 44.46206 -277.544282)
			(xy 44.510915 -277.550214) (xy 44.558186 -277.563906) (xy 44.602648 -277.585004) (xy 44.643151 -277.61296)
			(xy 44.678644 -277.647052) (xy 44.708209 -277.686396) (xy 44.73108 -277.729973) (xy 44.746664 -277.776654)
			(xy 44.754559 -277.825231) (xy 44.755054 -277.849838) (xy 46.044116 -277.849838) (xy 46.048076 -277.800784)
			(xy 46.059853 -277.753) (xy 46.079144 -277.707724) (xy 46.105447 -277.666128) (xy 46.138082 -277.629291)
			(xy 46.176203 -277.598166) (xy 46.218824 -277.573559) (xy 46.26484 -277.556107) (xy 46.313059 -277.546263)
			(xy 46.362234 -277.544282) (xy 46.411089 -277.550214) (xy 46.45836 -277.563906) (xy 46.502822 -277.585004)
			(xy 46.543325 -277.61296) (xy 46.578818 -277.647052) (xy 46.608383 -277.686396) (xy 46.631254 -277.729973)
			(xy 46.646838 -277.776654) (xy 46.654733 -277.825231) (xy 46.655228 -277.849838) (xy 47.944036 -277.849838)
			(xy 47.947996 -277.800784) (xy 47.959773 -277.753) (xy 47.979064 -277.707724) (xy 48.005367 -277.666128)
			(xy 48.038002 -277.629291) (xy 48.076123 -277.598166) (xy 48.118744 -277.573559) (xy 48.16476 -277.556107)
			(xy 48.212979 -277.546263) (xy 48.262154 -277.544282) (xy 48.311009 -277.550214) (xy 48.35828 -277.563906)
			(xy 48.402742 -277.585004) (xy 48.443245 -277.61296) (xy 48.478738 -277.647052) (xy 48.508303 -277.686396)
			(xy 48.531174 -277.729973) (xy 48.546758 -277.776654) (xy 48.554653 -277.825231) (xy 48.555148 -277.849838)
			(xy 49.843956 -277.849838) (xy 49.847916 -277.800784) (xy 49.859693 -277.753) (xy 49.878984 -277.707724)
			(xy 49.905287 -277.666128) (xy 49.937922 -277.629291) (xy 49.976043 -277.598166) (xy 50.018664 -277.573559)
			(xy 50.06468 -277.556107) (xy 50.112899 -277.546263) (xy 50.162074 -277.544282) (xy 50.210929 -277.550214)
			(xy 50.2582 -277.563906) (xy 50.302662 -277.585004) (xy 50.343165 -277.61296) (xy 50.378658 -277.647052)
			(xy 50.408223 -277.686396) (xy 50.431094 -277.729973) (xy 50.446678 -277.776654) (xy 50.454573 -277.825231)
			(xy 50.455068 -277.849838) (xy 51.74413 -277.849838) (xy 51.74809 -277.800784) (xy 51.759867 -277.753)
			(xy 51.779158 -277.707724) (xy 51.805461 -277.666128) (xy 51.838096 -277.629291) (xy 51.876217 -277.598166)
			(xy 51.918838 -277.573559) (xy 51.964854 -277.556107) (xy 52.013073 -277.546263) (xy 52.062248 -277.544282)
			(xy 52.111103 -277.550214) (xy 52.158374 -277.563906) (xy 52.202836 -277.585004) (xy 52.243339 -277.61296)
			(xy 52.278832 -277.647052) (xy 52.308397 -277.686396) (xy 52.331268 -277.729973) (xy 52.346852 -277.776654)
			(xy 52.354747 -277.825231) (xy 52.355242 -277.849838) (xy 53.64405 -277.849838) (xy 53.64801 -277.800784)
			(xy 53.659787 -277.753) (xy 53.679078 -277.707724) (xy 53.705381 -277.666128) (xy 53.738016 -277.629291)
			(xy 53.776137 -277.598166) (xy 53.818758 -277.573559) (xy 53.864774 -277.556107) (xy 53.912993 -277.546263)
			(xy 53.962168 -277.544282) (xy 54.011023 -277.550214) (xy 54.058294 -277.563906) (xy 54.102756 -277.585004)
			(xy 54.143259 -277.61296) (xy 54.178752 -277.647052) (xy 54.208317 -277.686396) (xy 54.231188 -277.729973)
			(xy 54.246772 -277.776654) (xy 54.254667 -277.825231) (xy 54.255162 -277.849838) (xy 55.54397 -277.849838)
			(xy 55.54793 -277.800784) (xy 55.559707 -277.753) (xy 55.578998 -277.707724) (xy 55.605301 -277.666128)
			(xy 55.637936 -277.629291) (xy 55.676057 -277.598166) (xy 55.718678 -277.573559) (xy 55.764694 -277.556107)
			(xy 55.812913 -277.546263) (xy 55.862088 -277.544282) (xy 55.910943 -277.550214) (xy 55.958214 -277.563906)
			(xy 56.002676 -277.585004) (xy 56.043179 -277.61296) (xy 56.078672 -277.647052) (xy 56.108237 -277.686396)
			(xy 56.131108 -277.729973) (xy 56.146692 -277.776654) (xy 56.154587 -277.825231) (xy 56.155082 -277.849838)
			(xy 57.444144 -277.849838) (xy 57.448104 -277.800784) (xy 57.459881 -277.753) (xy 57.479172 -277.707724)
			(xy 57.505475 -277.666128) (xy 57.53811 -277.629291) (xy 57.576231 -277.598166) (xy 57.618852 -277.573559)
			(xy 57.664868 -277.556107) (xy 57.713087 -277.546263) (xy 57.762262 -277.544282) (xy 57.811117 -277.550214)
			(xy 57.858388 -277.563906) (xy 57.90285 -277.585004) (xy 57.943353 -277.61296) (xy 57.978846 -277.647052)
			(xy 58.008411 -277.686396) (xy 58.031282 -277.729973) (xy 58.046866 -277.776654) (xy 58.054761 -277.825231)
			(xy 58.055256 -277.849838) (xy 59.34381 -277.849838) (xy 59.34777 -277.800784) (xy 59.359547 -277.753)
			(xy 59.378838 -277.707724) (xy 59.405141 -277.666128) (xy 59.437776 -277.629291) (xy 59.475897 -277.598166)
			(xy 59.518518 -277.573559) (xy 59.564534 -277.556107) (xy 59.612753 -277.546263) (xy 59.661928 -277.544282)
			(xy 59.710783 -277.550214) (xy 59.758054 -277.563906) (xy 59.802516 -277.585004) (xy 59.843019 -277.61296)
			(xy 59.878512 -277.647052) (xy 59.908077 -277.686396) (xy 59.930948 -277.729973) (xy 59.946532 -277.776654)
			(xy 59.954427 -277.825231) (xy 59.954922 -277.849838) (xy 61.24373 -277.849838) (xy 61.24769 -277.800784)
			(xy 61.259467 -277.753) (xy 61.278758 -277.707724) (xy 61.305061 -277.666128) (xy 61.337696 -277.629291)
			(xy 61.375817 -277.598166) (xy 61.418438 -277.573559) (xy 61.464454 -277.556107) (xy 61.512673 -277.546263)
			(xy 61.561848 -277.544282) (xy 61.610703 -277.550214) (xy 61.657974 -277.563906) (xy 61.702436 -277.585004)
			(xy 61.742939 -277.61296) (xy 61.778432 -277.647052) (xy 61.807997 -277.686396) (xy 61.830868 -277.729973)
			(xy 61.846452 -277.776654) (xy 61.854347 -277.825231) (xy 61.854842 -277.849838) (xy 63.143904 -277.849838)
			(xy 63.147864 -277.800784) (xy 63.159641 -277.753) (xy 63.178932 -277.707724) (xy 63.205235 -277.666128)
			(xy 63.23787 -277.629291) (xy 63.275991 -277.598166) (xy 63.318612 -277.573559) (xy 63.364628 -277.556107)
			(xy 63.412847 -277.546263) (xy 63.462022 -277.544282) (xy 63.510877 -277.550214) (xy 63.558148 -277.563906)
			(xy 63.60261 -277.585004) (xy 63.643113 -277.61296) (xy 63.678606 -277.647052) (xy 63.708171 -277.686396)
			(xy 63.731042 -277.729973) (xy 63.746626 -277.776654) (xy 63.754521 -277.825231) (xy 63.755016 -277.849838)
			(xy 65.043824 -277.849838) (xy 65.047784 -277.800784) (xy 65.059561 -277.753) (xy 65.078852 -277.707724)
			(xy 65.105155 -277.666128) (xy 65.13779 -277.629291) (xy 65.175911 -277.598166) (xy 65.218532 -277.573559)
			(xy 65.264548 -277.556107) (xy 65.312767 -277.546263) (xy 65.361942 -277.544282) (xy 65.410797 -277.550214)
			(xy 65.458068 -277.563906) (xy 65.50253 -277.585004) (xy 65.543033 -277.61296) (xy 65.578526 -277.647052)
			(xy 65.608091 -277.686396) (xy 65.630962 -277.729973) (xy 65.646546 -277.776654) (xy 65.654441 -277.825231)
			(xy 65.654936 -277.849838) (xy 66.943744 -277.849838) (xy 66.947704 -277.800784) (xy 66.959481 -277.753)
			(xy 66.978772 -277.707724) (xy 67.005075 -277.666128) (xy 67.03771 -277.629291) (xy 67.075831 -277.598166)
			(xy 67.118452 -277.573559) (xy 67.164468 -277.556107) (xy 67.212687 -277.546263) (xy 67.261862 -277.544282)
			(xy 67.310717 -277.550214) (xy 67.357988 -277.563906) (xy 67.40245 -277.585004) (xy 67.442953 -277.61296)
			(xy 67.478446 -277.647052) (xy 67.508011 -277.686396) (xy 67.530882 -277.729973) (xy 67.546466 -277.776654)
			(xy 67.554361 -277.825231) (xy 67.554856 -277.849838) (xy 68.843918 -277.849838) (xy 68.847878 -277.800784)
			(xy 68.859655 -277.753) (xy 68.878946 -277.707724) (xy 68.905249 -277.666128) (xy 68.937884 -277.629291)
			(xy 68.976005 -277.598166) (xy 69.018626 -277.573559) (xy 69.064642 -277.556107) (xy 69.112861 -277.546263)
			(xy 69.162036 -277.544282) (xy 69.210891 -277.550214) (xy 69.258162 -277.563906) (xy 69.302624 -277.585004)
			(xy 69.343127 -277.61296) (xy 69.37862 -277.647052) (xy 69.408185 -277.686396) (xy 69.431056 -277.729973)
			(xy 69.44664 -277.776654) (xy 69.454535 -277.825231) (xy 69.45503 -277.849838) (xy 70.743838 -277.849838)
			(xy 70.747798 -277.800784) (xy 70.759575 -277.753) (xy 70.778866 -277.707724) (xy 70.805169 -277.666128)
			(xy 70.837804 -277.629291) (xy 70.875925 -277.598166) (xy 70.918546 -277.573559) (xy 70.964562 -277.556107)
			(xy 71.012781 -277.546263) (xy 71.061956 -277.544282) (xy 71.110811 -277.550214) (xy 71.158082 -277.563906)
			(xy 71.202544 -277.585004) (xy 71.243047 -277.61296) (xy 71.27854 -277.647052) (xy 71.308105 -277.686396)
			(xy 71.330976 -277.729973) (xy 71.34656 -277.776654) (xy 71.354455 -277.825231) (xy 71.35495 -277.849838)
			(xy 72.643758 -277.849838) (xy 72.647718 -277.800784) (xy 72.659495 -277.753) (xy 72.678786 -277.707724)
			(xy 72.705089 -277.666128) (xy 72.737724 -277.629291) (xy 72.775845 -277.598166) (xy 72.818466 -277.573559)
			(xy 72.864482 -277.556107) (xy 72.912701 -277.546263) (xy 72.961876 -277.544282) (xy 73.010731 -277.550214)
			(xy 73.058002 -277.563906) (xy 73.102464 -277.585004) (xy 73.142967 -277.61296) (xy 73.17846 -277.647052)
			(xy 73.208025 -277.686396) (xy 73.230896 -277.729973) (xy 73.24648 -277.776654) (xy 73.254375 -277.825231)
			(xy 73.25487 -277.849838) (xy 74.543932 -277.849838) (xy 74.547892 -277.800784) (xy 74.559669 -277.753)
			(xy 74.57896 -277.707724) (xy 74.605263 -277.666128) (xy 74.637898 -277.629291) (xy 74.676019 -277.598166)
			(xy 74.71864 -277.573559) (xy 74.764656 -277.556107) (xy 74.812875 -277.546263) (xy 74.86205 -277.544282)
			(xy 74.910905 -277.550214) (xy 74.958176 -277.563906) (xy 75.002638 -277.585004) (xy 75.043141 -277.61296)
			(xy 75.078634 -277.647052) (xy 75.108199 -277.686396) (xy 75.13107 -277.729973) (xy 75.146654 -277.776654)
			(xy 75.154549 -277.825231) (xy 75.155044 -277.849838) (xy 76.443852 -277.849838) (xy 76.447812 -277.800784)
			(xy 76.459589 -277.753) (xy 76.47888 -277.707724) (xy 76.505183 -277.666128) (xy 76.537818 -277.629291)
			(xy 76.575939 -277.598166) (xy 76.61856 -277.573559) (xy 76.664576 -277.556107) (xy 76.712795 -277.546263)
			(xy 76.76197 -277.544282) (xy 76.810825 -277.550214) (xy 76.858096 -277.563906) (xy 76.902558 -277.585004)
			(xy 76.943061 -277.61296) (xy 76.978554 -277.647052) (xy 77.008119 -277.686396) (xy 77.03099 -277.729973)
			(xy 77.046574 -277.776654) (xy 77.054469 -277.825231) (xy 77.054964 -277.849838) (xy 78.343772 -277.849838)
			(xy 78.347732 -277.800784) (xy 78.359509 -277.753) (xy 78.3788 -277.707724) (xy 78.405103 -277.666128)
			(xy 78.437738 -277.629291) (xy 78.475859 -277.598166) (xy 78.51848 -277.573559) (xy 78.564496 -277.556107)
			(xy 78.612715 -277.546263) (xy 78.66189 -277.544282) (xy 78.710745 -277.550214) (xy 78.758016 -277.563906)
			(xy 78.802478 -277.585004) (xy 78.842981 -277.61296) (xy 78.878474 -277.647052) (xy 78.908039 -277.686396)
			(xy 78.93091 -277.729973) (xy 78.946494 -277.776654) (xy 78.954389 -277.825231) (xy 78.954884 -277.849838)
			(xy 80.243946 -277.849838) (xy 80.247906 -277.800784) (xy 80.259683 -277.753) (xy 80.278974 -277.707724)
			(xy 80.305277 -277.666128) (xy 80.337912 -277.629291) (xy 80.376033 -277.598166) (xy 80.418654 -277.573559)
			(xy 80.46467 -277.556107) (xy 80.512889 -277.546263) (xy 80.562064 -277.544282) (xy 80.610919 -277.550214)
			(xy 80.65819 -277.563906) (xy 80.702652 -277.585004) (xy 80.743155 -277.61296) (xy 80.778648 -277.647052)
			(xy 80.808213 -277.686396) (xy 80.831084 -277.729973) (xy 80.846668 -277.776654) (xy 80.854563 -277.825231)
			(xy 80.855058 -277.849838) (xy 160.24404 -277.849838) (xy 160.248 -277.800784) (xy 160.259777 -277.753)
			(xy 160.279068 -277.707724) (xy 160.305371 -277.666128) (xy 160.338006 -277.629291) (xy 160.376127 -277.598166)
			(xy 160.418748 -277.573559) (xy 160.464764 -277.556107) (xy 160.512983 -277.546263) (xy 160.562158 -277.544282)
			(xy 160.611013 -277.550214) (xy 160.658284 -277.563906) (xy 160.702746 -277.585004) (xy 160.743249 -277.61296)
			(xy 160.778742 -277.647052) (xy 160.808307 -277.686396) (xy 160.831178 -277.729973) (xy 160.846762 -277.776654)
			(xy 160.854657 -277.825231) (xy 160.855152 -277.849838) (xy 162.144214 -277.849838) (xy 162.148174 -277.800784)
			(xy 162.159951 -277.753) (xy 162.179242 -277.707724) (xy 162.205545 -277.666128) (xy 162.23818 -277.629291)
			(xy 162.276301 -277.598166) (xy 162.318922 -277.573559) (xy 162.364938 -277.556107) (xy 162.413157 -277.546263)
			(xy 162.462332 -277.544282) (xy 162.511187 -277.550214) (xy 162.558458 -277.563906) (xy 162.60292 -277.585004)
			(xy 162.643423 -277.61296) (xy 162.678916 -277.647052) (xy 162.708481 -277.686396) (xy 162.731352 -277.729973)
			(xy 162.746936 -277.776654) (xy 162.754831 -277.825231) (xy 162.755326 -277.849838) (xy 164.044134 -277.849838)
			(xy 164.048094 -277.800784) (xy 164.059871 -277.753) (xy 164.079162 -277.707724) (xy 164.105465 -277.666128)
			(xy 164.1381 -277.629291) (xy 164.176221 -277.598166) (xy 164.218842 -277.573559) (xy 164.264858 -277.556107)
			(xy 164.313077 -277.546263) (xy 164.362252 -277.544282) (xy 164.411107 -277.550214) (xy 164.458378 -277.563906)
			(xy 164.50284 -277.585004) (xy 164.543343 -277.61296) (xy 164.578836 -277.647052) (xy 164.608401 -277.686396)
			(xy 164.631272 -277.729973) (xy 164.646856 -277.776654) (xy 164.654751 -277.825231) (xy 164.655246 -277.849838)
			(xy 165.944054 -277.849838) (xy 165.948014 -277.800784) (xy 165.959791 -277.753) (xy 165.979082 -277.707724)
			(xy 166.005385 -277.666128) (xy 166.03802 -277.629291) (xy 166.076141 -277.598166) (xy 166.118762 -277.573559)
			(xy 166.164778 -277.556107) (xy 166.212997 -277.546263) (xy 166.262172 -277.544282) (xy 166.311027 -277.550214)
			(xy 166.358298 -277.563906) (xy 166.40276 -277.585004) (xy 166.443263 -277.61296) (xy 166.478756 -277.647052)
			(xy 166.508321 -277.686396) (xy 166.531192 -277.729973) (xy 166.546776 -277.776654) (xy 166.554671 -277.825231)
			(xy 166.555166 -277.849838) (xy 167.844228 -277.849838) (xy 167.848188 -277.800784) (xy 167.859965 -277.753)
			(xy 167.879256 -277.707724) (xy 167.905559 -277.666128) (xy 167.938194 -277.629291) (xy 167.976315 -277.598166)
			(xy 168.018936 -277.573559) (xy 168.064952 -277.556107) (xy 168.113171 -277.546263) (xy 168.162346 -277.544282)
			(xy 168.211201 -277.550214) (xy 168.258472 -277.563906) (xy 168.302934 -277.585004) (xy 168.343437 -277.61296)
			(xy 168.37893 -277.647052) (xy 168.408495 -277.686396) (xy 168.431366 -277.729973) (xy 168.44695 -277.776654)
			(xy 168.454845 -277.825231) (xy 168.45534 -277.849838) (xy 169.744148 -277.849838) (xy 169.748108 -277.800784)
			(xy 169.759885 -277.753) (xy 169.779176 -277.707724) (xy 169.805479 -277.666128) (xy 169.838114 -277.629291)
			(xy 169.876235 -277.598166) (xy 169.918856 -277.573559) (xy 169.964872 -277.556107) (xy 170.013091 -277.546263)
			(xy 170.062266 -277.544282) (xy 170.111121 -277.550214) (xy 170.158392 -277.563906) (xy 170.202854 -277.585004)
			(xy 170.243357 -277.61296) (xy 170.27885 -277.647052) (xy 170.308415 -277.686396) (xy 170.331286 -277.729973)
			(xy 170.34687 -277.776654) (xy 170.354765 -277.825231) (xy 170.35526 -277.849838) (xy 171.644068 -277.849838)
			(xy 171.648028 -277.800784) (xy 171.659805 -277.753) (xy 171.679096 -277.707724) (xy 171.705399 -277.666128)
			(xy 171.738034 -277.629291) (xy 171.776155 -277.598166) (xy 171.818776 -277.573559) (xy 171.864792 -277.556107)
			(xy 171.913011 -277.546263) (xy 171.962186 -277.544282) (xy 172.011041 -277.550214) (xy 172.058312 -277.563906)
			(xy 172.102774 -277.585004) (xy 172.143277 -277.61296) (xy 172.17877 -277.647052) (xy 172.208335 -277.686396)
			(xy 172.231206 -277.729973) (xy 172.24679 -277.776654) (xy 172.254685 -277.825231) (xy 172.25518 -277.849838)
			(xy 173.544242 -277.849838) (xy 173.548202 -277.800784) (xy 173.559979 -277.753) (xy 173.57927 -277.707724)
			(xy 173.605573 -277.666128) (xy 173.638208 -277.629291) (xy 173.676329 -277.598166) (xy 173.71895 -277.573559)
			(xy 173.764966 -277.556107) (xy 173.813185 -277.546263) (xy 173.86236 -277.544282) (xy 173.911215 -277.550214)
			(xy 173.958486 -277.563906) (xy 174.002948 -277.585004) (xy 174.043451 -277.61296) (xy 174.078944 -277.647052)
			(xy 174.108509 -277.686396) (xy 174.13138 -277.729973) (xy 174.146964 -277.776654) (xy 174.154859 -277.825231)
			(xy 174.155354 -277.849838) (xy 175.443908 -277.849838) (xy 175.447868 -277.800784) (xy 175.459645 -277.753)
			(xy 175.478936 -277.707724) (xy 175.505239 -277.666128) (xy 175.537874 -277.629291) (xy 175.575995 -277.598166)
			(xy 175.618616 -277.573559) (xy 175.664632 -277.556107) (xy 175.712851 -277.546263) (xy 175.762026 -277.544282)
			(xy 175.810881 -277.550214) (xy 175.858152 -277.563906) (xy 175.902614 -277.585004) (xy 175.943117 -277.61296)
			(xy 175.97861 -277.647052) (xy 176.008175 -277.686396) (xy 176.031046 -277.729973) (xy 176.04663 -277.776654)
			(xy 176.054525 -277.825231) (xy 176.05502 -277.849838) (xy 177.343828 -277.849838) (xy 177.347788 -277.800784)
			(xy 177.359565 -277.753) (xy 177.378856 -277.707724) (xy 177.405159 -277.666128) (xy 177.437794 -277.629291)
			(xy 177.475915 -277.598166) (xy 177.518536 -277.573559) (xy 177.564552 -277.556107) (xy 177.612771 -277.546263)
			(xy 177.661946 -277.544282) (xy 177.710801 -277.550214) (xy 177.758072 -277.563906) (xy 177.802534 -277.585004)
			(xy 177.843037 -277.61296) (xy 177.87853 -277.647052) (xy 177.908095 -277.686396) (xy 177.930966 -277.729973)
			(xy 177.94655 -277.776654) (xy 177.954445 -277.825231) (xy 177.95494 -277.849838) (xy 179.244002 -277.849838)
			(xy 179.247962 -277.800784) (xy 179.259739 -277.753) (xy 179.27903 -277.707724) (xy 179.305333 -277.666128)
			(xy 179.337968 -277.629291) (xy 179.376089 -277.598166) (xy 179.41871 -277.573559) (xy 179.464726 -277.556107)
			(xy 179.512945 -277.546263) (xy 179.56212 -277.544282) (xy 179.610975 -277.550214) (xy 179.658246 -277.563906)
			(xy 179.702708 -277.585004) (xy 179.743211 -277.61296) (xy 179.778704 -277.647052) (xy 179.808269 -277.686396)
			(xy 179.83114 -277.729973) (xy 179.846724 -277.776654) (xy 179.854619 -277.825231) (xy 179.855114 -277.849838)
			(xy 181.143922 -277.849838) (xy 181.147882 -277.800784) (xy 181.159659 -277.753) (xy 181.17895 -277.707724)
			(xy 181.205253 -277.666128) (xy 181.237888 -277.629291) (xy 181.276009 -277.598166) (xy 181.31863 -277.573559)
			(xy 181.364646 -277.556107) (xy 181.412865 -277.546263) (xy 181.46204 -277.544282) (xy 181.510895 -277.550214)
			(xy 181.558166 -277.563906) (xy 181.602628 -277.585004) (xy 181.643131 -277.61296) (xy 181.678624 -277.647052)
			(xy 181.708189 -277.686396) (xy 181.73106 -277.729973) (xy 181.746644 -277.776654) (xy 181.754539 -277.825231)
			(xy 181.755034 -277.849838) (xy 183.043842 -277.849838) (xy 183.047802 -277.800784) (xy 183.059579 -277.753)
			(xy 183.07887 -277.707724) (xy 183.105173 -277.666128) (xy 183.137808 -277.629291) (xy 183.175929 -277.598166)
			(xy 183.21855 -277.573559) (xy 183.264566 -277.556107) (xy 183.312785 -277.546263) (xy 183.36196 -277.544282)
			(xy 183.410815 -277.550214) (xy 183.458086 -277.563906) (xy 183.502548 -277.585004) (xy 183.543051 -277.61296)
			(xy 183.578544 -277.647052) (xy 183.608109 -277.686396) (xy 183.63098 -277.729973) (xy 183.646564 -277.776654)
			(xy 183.654459 -277.825231) (xy 183.654954 -277.849838) (xy 184.944016 -277.849838) (xy 184.947976 -277.800784)
			(xy 184.959753 -277.753) (xy 184.979044 -277.707724) (xy 185.005347 -277.666128) (xy 185.037982 -277.629291)
			(xy 185.076103 -277.598166) (xy 185.118724 -277.573559) (xy 185.16474 -277.556107) (xy 185.212959 -277.546263)
			(xy 185.262134 -277.544282) (xy 185.310989 -277.550214) (xy 185.35826 -277.563906) (xy 185.402722 -277.585004)
			(xy 185.443225 -277.61296) (xy 185.478718 -277.647052) (xy 185.508283 -277.686396) (xy 185.531154 -277.729973)
			(xy 185.546738 -277.776654) (xy 185.554633 -277.825231) (xy 185.555128 -277.849838) (xy 186.843936 -277.849838)
			(xy 186.847896 -277.800784) (xy 186.859673 -277.753) (xy 186.878964 -277.707724) (xy 186.905267 -277.666128)
			(xy 186.937902 -277.629291) (xy 186.976023 -277.598166) (xy 187.018644 -277.573559) (xy 187.06466 -277.556107)
			(xy 187.112879 -277.546263) (xy 187.162054 -277.544282) (xy 187.210909 -277.550214) (xy 187.25818 -277.563906)
			(xy 187.302642 -277.585004) (xy 187.343145 -277.61296) (xy 187.378638 -277.647052) (xy 187.408203 -277.686396)
			(xy 187.431074 -277.729973) (xy 187.446658 -277.776654) (xy 187.454553 -277.825231) (xy 187.455048 -277.849838)
			(xy 188.743856 -277.849838) (xy 188.747816 -277.800784) (xy 188.759593 -277.753) (xy 188.778884 -277.707724)
			(xy 188.805187 -277.666128) (xy 188.837822 -277.629291) (xy 188.875943 -277.598166) (xy 188.918564 -277.573559)
			(xy 188.96458 -277.556107) (xy 189.012799 -277.546263) (xy 189.061974 -277.544282) (xy 189.110829 -277.550214)
			(xy 189.1581 -277.563906) (xy 189.202562 -277.585004) (xy 189.243065 -277.61296) (xy 189.278558 -277.647052)
			(xy 189.308123 -277.686396) (xy 189.330994 -277.729973) (xy 189.346578 -277.776654) (xy 189.354473 -277.825231)
			(xy 189.354968 -277.849838) (xy 190.64403 -277.849838) (xy 190.64799 -277.800784) (xy 190.659767 -277.753)
			(xy 190.679058 -277.707724) (xy 190.705361 -277.666128) (xy 190.737996 -277.629291) (xy 190.776117 -277.598166)
			(xy 190.818738 -277.573559) (xy 190.864754 -277.556107) (xy 190.912973 -277.546263) (xy 190.962148 -277.544282)
			(xy 191.011003 -277.550214) (xy 191.058274 -277.563906) (xy 191.102736 -277.585004) (xy 191.143239 -277.61296)
			(xy 191.178732 -277.647052) (xy 191.208297 -277.686396) (xy 191.231168 -277.729973) (xy 191.246752 -277.776654)
			(xy 191.254647 -277.825231) (xy 191.255142 -277.849838) (xy 192.54395 -277.849838) (xy 192.54791 -277.800784)
			(xy 192.559687 -277.753) (xy 192.578978 -277.707724) (xy 192.605281 -277.666128) (xy 192.637916 -277.629291)
			(xy 192.676037 -277.598166) (xy 192.718658 -277.573559) (xy 192.764674 -277.556107) (xy 192.812893 -277.546263)
			(xy 192.862068 -277.544282) (xy 192.910923 -277.550214) (xy 192.958194 -277.563906) (xy 193.002656 -277.585004)
			(xy 193.043159 -277.61296) (xy 193.078652 -277.647052) (xy 193.108217 -277.686396) (xy 193.131088 -277.729973)
			(xy 193.146672 -277.776654) (xy 193.154567 -277.825231) (xy 193.155062 -277.849838) (xy 194.44387 -277.849838)
			(xy 194.44783 -277.800784) (xy 194.459607 -277.753) (xy 194.478898 -277.707724) (xy 194.505201 -277.666128)
			(xy 194.537836 -277.629291) (xy 194.575957 -277.598166) (xy 194.618578 -277.573559) (xy 194.664594 -277.556107)
			(xy 194.712813 -277.546263) (xy 194.761988 -277.544282) (xy 194.810843 -277.550214) (xy 194.858114 -277.563906)
			(xy 194.902576 -277.585004) (xy 194.943079 -277.61296) (xy 194.978572 -277.647052) (xy 195.008137 -277.686396)
			(xy 195.031008 -277.729973) (xy 195.046592 -277.776654) (xy 195.054487 -277.825231) (xy 195.054982 -277.849838)
			(xy 196.344044 -277.849838) (xy 196.348004 -277.800784) (xy 196.359781 -277.753) (xy 196.379072 -277.707724)
			(xy 196.405375 -277.666128) (xy 196.43801 -277.629291) (xy 196.476131 -277.598166) (xy 196.518752 -277.573559)
			(xy 196.564768 -277.556107) (xy 196.612987 -277.546263) (xy 196.662162 -277.544282) (xy 196.711017 -277.550214)
			(xy 196.758288 -277.563906) (xy 196.80275 -277.585004) (xy 196.843253 -277.61296) (xy 196.878746 -277.647052)
			(xy 196.908311 -277.686396) (xy 196.931182 -277.729973) (xy 196.946766 -277.776654) (xy 196.954661 -277.825231)
			(xy 196.955156 -277.849838) (xy 276.343884 -277.849838) (xy 276.347844 -277.800784) (xy 276.359621 -277.753)
			(xy 276.378912 -277.707724) (xy 276.405215 -277.666128) (xy 276.43785 -277.629291) (xy 276.475971 -277.598166)
			(xy 276.518592 -277.573559) (xy 276.564608 -277.556107) (xy 276.612827 -277.546263) (xy 276.662002 -277.544282)
			(xy 276.710857 -277.550214) (xy 276.758128 -277.563906) (xy 276.80259 -277.585004) (xy 276.843093 -277.61296)
			(xy 276.878586 -277.647052) (xy 276.908151 -277.686396) (xy 276.931022 -277.729973) (xy 276.946606 -277.776654)
			(xy 276.954501 -277.825231) (xy 276.954996 -277.849838) (xy 278.244058 -277.849838) (xy 278.248018 -277.800784)
			(xy 278.259795 -277.753) (xy 278.279086 -277.707724) (xy 278.305389 -277.666128) (xy 278.338024 -277.629291)
			(xy 278.376145 -277.598166) (xy 278.418766 -277.573559) (xy 278.464782 -277.556107) (xy 278.513001 -277.546263)
			(xy 278.562176 -277.544282) (xy 278.611031 -277.550214) (xy 278.658302 -277.563906) (xy 278.702764 -277.585004)
			(xy 278.743267 -277.61296) (xy 278.77876 -277.647052) (xy 278.808325 -277.686396) (xy 278.831196 -277.729973)
			(xy 278.84678 -277.776654) (xy 278.854675 -277.825231) (xy 278.85517 -277.849838) (xy 280.143978 -277.849838)
			(xy 280.147938 -277.800784) (xy 280.159715 -277.753) (xy 280.179006 -277.707724) (xy 280.205309 -277.666128)
			(xy 280.237944 -277.629291) (xy 280.276065 -277.598166) (xy 280.318686 -277.573559) (xy 280.364702 -277.556107)
			(xy 280.412921 -277.546263) (xy 280.462096 -277.544282) (xy 280.510951 -277.550214) (xy 280.558222 -277.563906)
			(xy 280.602684 -277.585004) (xy 280.643187 -277.61296) (xy 280.67868 -277.647052) (xy 280.708245 -277.686396)
			(xy 280.731116 -277.729973) (xy 280.7467 -277.776654) (xy 280.754595 -277.825231) (xy 280.75509 -277.849838)
			(xy 282.043898 -277.849838) (xy 282.047858 -277.800784) (xy 282.059635 -277.753) (xy 282.078926 -277.707724)
			(xy 282.105229 -277.666128) (xy 282.137864 -277.629291) (xy 282.175985 -277.598166) (xy 282.218606 -277.573559)
			(xy 282.264622 -277.556107) (xy 282.312841 -277.546263) (xy 282.362016 -277.544282) (xy 282.410871 -277.550214)
			(xy 282.458142 -277.563906) (xy 282.502604 -277.585004) (xy 282.543107 -277.61296) (xy 282.5786 -277.647052)
			(xy 282.608165 -277.686396) (xy 282.631036 -277.729973) (xy 282.64662 -277.776654) (xy 282.654515 -277.825231)
			(xy 282.65501 -277.849838) (xy 283.944072 -277.849838) (xy 283.948032 -277.800784) (xy 283.959809 -277.753)
			(xy 283.9791 -277.707724) (xy 284.005403 -277.666128) (xy 284.038038 -277.629291) (xy 284.076159 -277.598166)
			(xy 284.11878 -277.573559) (xy 284.164796 -277.556107) (xy 284.213015 -277.546263) (xy 284.26219 -277.544282)
			(xy 284.311045 -277.550214) (xy 284.358316 -277.563906) (xy 284.402778 -277.585004) (xy 284.443281 -277.61296)
			(xy 284.478774 -277.647052) (xy 284.508339 -277.686396) (xy 284.53121 -277.729973) (xy 284.546794 -277.776654)
			(xy 284.554689 -277.825231) (xy 284.555184 -277.849838) (xy 285.843992 -277.849838) (xy 285.847952 -277.800784)
			(xy 285.859729 -277.753) (xy 285.87902 -277.707724) (xy 285.905323 -277.666128) (xy 285.937958 -277.629291)
			(xy 285.976079 -277.598166) (xy 286.0187 -277.573559) (xy 286.064716 -277.556107) (xy 286.112935 -277.546263)
			(xy 286.16211 -277.544282) (xy 286.210965 -277.550214) (xy 286.258236 -277.563906) (xy 286.302698 -277.585004)
			(xy 286.343201 -277.61296) (xy 286.378694 -277.647052) (xy 286.408259 -277.686396) (xy 286.43113 -277.729973)
			(xy 286.446714 -277.776654) (xy 286.454609 -277.825231) (xy 286.455104 -277.849838) (xy 287.743912 -277.849838)
			(xy 287.747872 -277.800784) (xy 287.759649 -277.753) (xy 287.77894 -277.707724) (xy 287.805243 -277.666128)
			(xy 287.837878 -277.629291) (xy 287.875999 -277.598166) (xy 287.91862 -277.573559) (xy 287.964636 -277.556107)
			(xy 288.012855 -277.546263) (xy 288.06203 -277.544282) (xy 288.110885 -277.550214) (xy 288.158156 -277.563906)
			(xy 288.202618 -277.585004) (xy 288.243121 -277.61296) (xy 288.278614 -277.647052) (xy 288.308179 -277.686396)
			(xy 288.33105 -277.729973) (xy 288.346634 -277.776654) (xy 288.354529 -277.825231) (xy 288.355024 -277.849838)
			(xy 289.644086 -277.849838) (xy 289.648046 -277.800784) (xy 289.659823 -277.753) (xy 289.679114 -277.707724)
			(xy 289.705417 -277.666128) (xy 289.738052 -277.629291) (xy 289.776173 -277.598166) (xy 289.818794 -277.573559)
			(xy 289.86481 -277.556107) (xy 289.913029 -277.546263) (xy 289.962204 -277.544282) (xy 290.011059 -277.550214)
			(xy 290.05833 -277.563906) (xy 290.102792 -277.585004) (xy 290.143295 -277.61296) (xy 290.178788 -277.647052)
			(xy 290.208353 -277.686396) (xy 290.231224 -277.729973) (xy 290.246808 -277.776654) (xy 290.254703 -277.825231)
			(xy 290.255198 -277.849838) (xy 291.543752 -277.849838) (xy 291.547712 -277.800784) (xy 291.559489 -277.753)
			(xy 291.57878 -277.707724) (xy 291.605083 -277.666128) (xy 291.637718 -277.629291) (xy 291.675839 -277.598166)
			(xy 291.71846 -277.573559) (xy 291.764476 -277.556107) (xy 291.812695 -277.546263) (xy 291.86187 -277.544282)
			(xy 291.910725 -277.550214) (xy 291.957996 -277.563906) (xy 292.002458 -277.585004) (xy 292.042961 -277.61296)
			(xy 292.078454 -277.647052) (xy 292.108019 -277.686396) (xy 292.13089 -277.729973) (xy 292.146474 -277.776654)
			(xy 292.154369 -277.825231) (xy 292.154864 -277.849838) (xy 293.443672 -277.849838) (xy 293.447632 -277.800784)
			(xy 293.459409 -277.753) (xy 293.4787 -277.707724) (xy 293.505003 -277.666128) (xy 293.537638 -277.629291)
			(xy 293.575759 -277.598166) (xy 293.61838 -277.573559) (xy 293.664396 -277.556107) (xy 293.712615 -277.546263)
			(xy 293.76179 -277.544282) (xy 293.810645 -277.550214) (xy 293.857916 -277.563906) (xy 293.902378 -277.585004)
			(xy 293.942881 -277.61296) (xy 293.978374 -277.647052) (xy 294.007939 -277.686396) (xy 294.03081 -277.729973)
			(xy 294.046394 -277.776654) (xy 294.054289 -277.825231) (xy 294.054784 -277.849838) (xy 295.343846 -277.849838)
			(xy 295.347806 -277.800784) (xy 295.359583 -277.753) (xy 295.378874 -277.707724) (xy 295.405177 -277.666128)
			(xy 295.437812 -277.629291) (xy 295.475933 -277.598166) (xy 295.518554 -277.573559) (xy 295.56457 -277.556107)
			(xy 295.612789 -277.546263) (xy 295.661964 -277.544282) (xy 295.710819 -277.550214) (xy 295.75809 -277.563906)
			(xy 295.802552 -277.585004) (xy 295.843055 -277.61296) (xy 295.878548 -277.647052) (xy 295.908113 -277.686396)
			(xy 295.930984 -277.729973) (xy 295.946568 -277.776654) (xy 295.954463 -277.825231) (xy 295.954958 -277.849838)
			(xy 297.243766 -277.849838) (xy 297.247726 -277.800784) (xy 297.259503 -277.753) (xy 297.278794 -277.707724)
			(xy 297.305097 -277.666128) (xy 297.337732 -277.629291) (xy 297.375853 -277.598166) (xy 297.418474 -277.573559)
			(xy 297.46449 -277.556107) (xy 297.512709 -277.546263) (xy 297.561884 -277.544282) (xy 297.610739 -277.550214)
			(xy 297.65801 -277.563906) (xy 297.702472 -277.585004) (xy 297.742975 -277.61296) (xy 297.778468 -277.647052)
			(xy 297.808033 -277.686396) (xy 297.830904 -277.729973) (xy 297.846488 -277.776654) (xy 297.854383 -277.825231)
			(xy 297.854878 -277.849838) (xy 299.143686 -277.849838) (xy 299.147646 -277.800784) (xy 299.159423 -277.753)
			(xy 299.178714 -277.707724) (xy 299.205017 -277.666128) (xy 299.237652 -277.629291) (xy 299.275773 -277.598166)
			(xy 299.318394 -277.573559) (xy 299.36441 -277.556107) (xy 299.412629 -277.546263) (xy 299.461804 -277.544282)
			(xy 299.510659 -277.550214) (xy 299.55793 -277.563906) (xy 299.602392 -277.585004) (xy 299.642895 -277.61296)
			(xy 299.678388 -277.647052) (xy 299.707953 -277.686396) (xy 299.730824 -277.729973) (xy 299.746408 -277.776654)
			(xy 299.754303 -277.825231) (xy 299.754798 -277.849838) (xy 301.04386 -277.849838) (xy 301.04782 -277.800784)
			(xy 301.059597 -277.753) (xy 301.078888 -277.707724) (xy 301.105191 -277.666128) (xy 301.137826 -277.629291)
			(xy 301.175947 -277.598166) (xy 301.218568 -277.573559) (xy 301.264584 -277.556107) (xy 301.312803 -277.546263)
			(xy 301.361978 -277.544282) (xy 301.410833 -277.550214) (xy 301.458104 -277.563906) (xy 301.502566 -277.585004)
			(xy 301.543069 -277.61296) (xy 301.578562 -277.647052) (xy 301.608127 -277.686396) (xy 301.630998 -277.729973)
			(xy 301.646582 -277.776654) (xy 301.654477 -277.825231) (xy 301.654972 -277.849838) (xy 302.94378 -277.849838)
			(xy 302.94774 -277.800784) (xy 302.959517 -277.753) (xy 302.978808 -277.707724) (xy 303.005111 -277.666128)
			(xy 303.037746 -277.629291) (xy 303.075867 -277.598166) (xy 303.118488 -277.573559) (xy 303.164504 -277.556107)
			(xy 303.212723 -277.546263) (xy 303.261898 -277.544282) (xy 303.310753 -277.550214) (xy 303.358024 -277.563906)
			(xy 303.402486 -277.585004) (xy 303.442989 -277.61296) (xy 303.478482 -277.647052) (xy 303.508047 -277.686396)
			(xy 303.530918 -277.729973) (xy 303.546502 -277.776654) (xy 303.554397 -277.825231) (xy 303.554892 -277.849838)
			(xy 304.8437 -277.849838) (xy 304.84766 -277.800784) (xy 304.859437 -277.753) (xy 304.878728 -277.707724)
			(xy 304.905031 -277.666128) (xy 304.937666 -277.629291) (xy 304.975787 -277.598166) (xy 305.018408 -277.573559)
			(xy 305.064424 -277.556107) (xy 305.112643 -277.546263) (xy 305.161818 -277.544282) (xy 305.210673 -277.550214)
			(xy 305.257944 -277.563906) (xy 305.302406 -277.585004) (xy 305.342909 -277.61296) (xy 305.378402 -277.647052)
			(xy 305.407967 -277.686396) (xy 305.430838 -277.729973) (xy 305.446422 -277.776654) (xy 305.454317 -277.825231)
			(xy 305.454812 -277.849838) (xy 306.743874 -277.849838) (xy 306.747834 -277.800784) (xy 306.759611 -277.753)
			(xy 306.778902 -277.707724) (xy 306.805205 -277.666128) (xy 306.83784 -277.629291) (xy 306.875961 -277.598166)
			(xy 306.918582 -277.573559) (xy 306.964598 -277.556107) (xy 307.012817 -277.546263) (xy 307.061992 -277.544282)
			(xy 307.110847 -277.550214) (xy 307.158118 -277.563906) (xy 307.20258 -277.585004) (xy 307.243083 -277.61296)
			(xy 307.278576 -277.647052) (xy 307.308141 -277.686396) (xy 307.331012 -277.729973) (xy 307.346596 -277.776654)
			(xy 307.354491 -277.825231) (xy 307.354986 -277.849838) (xy 308.643794 -277.849838) (xy 308.647754 -277.800784)
			(xy 308.659531 -277.753) (xy 308.678822 -277.707724) (xy 308.705125 -277.666128) (xy 308.73776 -277.629291)
			(xy 308.775881 -277.598166) (xy 308.818502 -277.573559) (xy 308.864518 -277.556107) (xy 308.912737 -277.546263)
			(xy 308.961912 -277.544282) (xy 309.010767 -277.550214) (xy 309.058038 -277.563906) (xy 309.1025 -277.585004)
			(xy 309.143003 -277.61296) (xy 309.178496 -277.647052) (xy 309.208061 -277.686396) (xy 309.230932 -277.729973)
			(xy 309.246516 -277.776654) (xy 309.254411 -277.825231) (xy 309.254906 -277.849838) (xy 310.543714 -277.849838)
			(xy 310.547674 -277.800784) (xy 310.559451 -277.753) (xy 310.578742 -277.707724) (xy 310.605045 -277.666128)
			(xy 310.63768 -277.629291) (xy 310.675801 -277.598166) (xy 310.718422 -277.573559) (xy 310.764438 -277.556107)
			(xy 310.812657 -277.546263) (xy 310.861832 -277.544282) (xy 310.910687 -277.550214) (xy 310.957958 -277.563906)
			(xy 311.00242 -277.585004) (xy 311.042923 -277.61296) (xy 311.078416 -277.647052) (xy 311.107981 -277.686396)
			(xy 311.130852 -277.729973) (xy 311.146436 -277.776654) (xy 311.154331 -277.825231) (xy 311.154826 -277.849838)
			(xy 312.443888 -277.849838) (xy 312.447848 -277.800784) (xy 312.459625 -277.753) (xy 312.478916 -277.707724)
			(xy 312.505219 -277.666128) (xy 312.537854 -277.629291) (xy 312.575975 -277.598166) (xy 312.618596 -277.573559)
			(xy 312.664612 -277.556107) (xy 312.712831 -277.546263) (xy 312.762006 -277.544282) (xy 312.810861 -277.550214)
			(xy 312.858132 -277.563906) (xy 312.902594 -277.585004) (xy 312.943097 -277.61296) (xy 312.97859 -277.647052)
			(xy 313.008155 -277.686396) (xy 313.031026 -277.729973) (xy 313.04661 -277.776654) (xy 313.054505 -277.825231)
			(xy 313.055 -277.849838) (xy 392.443982 -277.849838) (xy 392.447942 -277.800784) (xy 392.459719 -277.753)
			(xy 392.47901 -277.707724) (xy 392.505313 -277.666128) (xy 392.537948 -277.629291) (xy 392.576069 -277.598166)
			(xy 392.61869 -277.573559) (xy 392.664706 -277.556107) (xy 392.712925 -277.546263) (xy 392.7621 -277.544282)
			(xy 392.810955 -277.550214) (xy 392.858226 -277.563906) (xy 392.902688 -277.585004) (xy 392.943191 -277.61296)
			(xy 392.978684 -277.647052) (xy 393.008249 -277.686396) (xy 393.03112 -277.729973) (xy 393.046704 -277.776654)
			(xy 393.054599 -277.825231) (xy 393.055094 -277.849838) (xy 394.344156 -277.849838) (xy 394.348116 -277.800784)
			(xy 394.359893 -277.753) (xy 394.379184 -277.707724) (xy 394.405487 -277.666128) (xy 394.438122 -277.629291)
			(xy 394.476243 -277.598166) (xy 394.518864 -277.573559) (xy 394.56488 -277.556107) (xy 394.613099 -277.546263)
			(xy 394.662274 -277.544282) (xy 394.711129 -277.550214) (xy 394.7584 -277.563906) (xy 394.802862 -277.585004)
			(xy 394.843365 -277.61296) (xy 394.878858 -277.647052) (xy 394.908423 -277.686396) (xy 394.931294 -277.729973)
			(xy 394.946878 -277.776654) (xy 394.954773 -277.825231) (xy 394.955268 -277.849838) (xy 396.244076 -277.849838)
			(xy 396.248036 -277.800784) (xy 396.259813 -277.753) (xy 396.279104 -277.707724) (xy 396.305407 -277.666128)
			(xy 396.338042 -277.629291) (xy 396.376163 -277.598166) (xy 396.418784 -277.573559) (xy 396.4648 -277.556107)
			(xy 396.513019 -277.546263) (xy 396.562194 -277.544282) (xy 396.611049 -277.550214) (xy 396.65832 -277.563906)
			(xy 396.702782 -277.585004) (xy 396.743285 -277.61296) (xy 396.778778 -277.647052) (xy 396.808343 -277.686396)
			(xy 396.831214 -277.729973) (xy 396.846798 -277.776654) (xy 396.854693 -277.825231) (xy 396.855188 -277.849838)
			(xy 398.143996 -277.849838) (xy 398.147956 -277.800784) (xy 398.159733 -277.753) (xy 398.179024 -277.707724)
			(xy 398.205327 -277.666128) (xy 398.237962 -277.629291) (xy 398.276083 -277.598166) (xy 398.318704 -277.573559)
			(xy 398.36472 -277.556107) (xy 398.412939 -277.546263) (xy 398.462114 -277.544282) (xy 398.510969 -277.550214)
			(xy 398.55824 -277.563906) (xy 398.602702 -277.585004) (xy 398.643205 -277.61296) (xy 398.678698 -277.647052)
			(xy 398.708263 -277.686396) (xy 398.731134 -277.729973) (xy 398.746718 -277.776654) (xy 398.754613 -277.825231)
			(xy 398.755108 -277.849838) (xy 400.04417 -277.849838) (xy 400.04813 -277.800784) (xy 400.059907 -277.753)
			(xy 400.079198 -277.707724) (xy 400.105501 -277.666128) (xy 400.138136 -277.629291) (xy 400.176257 -277.598166)
			(xy 400.218878 -277.573559) (xy 400.264894 -277.556107) (xy 400.313113 -277.546263) (xy 400.362288 -277.544282)
			(xy 400.411143 -277.550214) (xy 400.458414 -277.563906) (xy 400.502876 -277.585004) (xy 400.543379 -277.61296)
			(xy 400.578872 -277.647052) (xy 400.608437 -277.686396) (xy 400.631308 -277.729973) (xy 400.646892 -277.776654)
			(xy 400.654787 -277.825231) (xy 400.655282 -277.849838) (xy 401.94409 -277.849838) (xy 401.94805 -277.800784)
			(xy 401.959827 -277.753) (xy 401.979118 -277.707724) (xy 402.005421 -277.666128) (xy 402.038056 -277.629291)
			(xy 402.076177 -277.598166) (xy 402.118798 -277.573559) (xy 402.164814 -277.556107) (xy 402.213033 -277.546263)
			(xy 402.262208 -277.544282) (xy 402.311063 -277.550214) (xy 402.358334 -277.563906) (xy 402.402796 -277.585004)
			(xy 402.443299 -277.61296) (xy 402.478792 -277.647052) (xy 402.508357 -277.686396) (xy 402.531228 -277.729973)
			(xy 402.546812 -277.776654) (xy 402.554707 -277.825231) (xy 402.555202 -277.849838) (xy 403.84401 -277.849838)
			(xy 403.84797 -277.800784) (xy 403.859747 -277.753) (xy 403.879038 -277.707724) (xy 403.905341 -277.666128)
			(xy 403.937976 -277.629291) (xy 403.976097 -277.598166) (xy 404.018718 -277.573559) (xy 404.064734 -277.556107)
			(xy 404.112953 -277.546263) (xy 404.162128 -277.544282) (xy 404.210983 -277.550214) (xy 404.258254 -277.563906)
			(xy 404.302716 -277.585004) (xy 404.343219 -277.61296) (xy 404.378712 -277.647052) (xy 404.408277 -277.686396)
			(xy 404.431148 -277.729973) (xy 404.446732 -277.776654) (xy 404.454627 -277.825231) (xy 404.455122 -277.849838)
			(xy 405.744184 -277.849838) (xy 405.748144 -277.800784) (xy 405.759921 -277.753) (xy 405.779212 -277.707724)
			(xy 405.805515 -277.666128) (xy 405.83815 -277.629291) (xy 405.876271 -277.598166) (xy 405.918892 -277.573559)
			(xy 405.964908 -277.556107) (xy 406.013127 -277.546263) (xy 406.062302 -277.544282) (xy 406.111157 -277.550214)
			(xy 406.158428 -277.563906) (xy 406.20289 -277.585004) (xy 406.243393 -277.61296) (xy 406.278886 -277.647052)
			(xy 406.308451 -277.686396) (xy 406.331322 -277.729973) (xy 406.346906 -277.776654) (xy 406.354801 -277.825231)
			(xy 406.355296 -277.849838) (xy 407.64385 -277.849838) (xy 407.64781 -277.800784) (xy 407.659587 -277.753)
			(xy 407.678878 -277.707724) (xy 407.705181 -277.666128) (xy 407.737816 -277.629291) (xy 407.775937 -277.598166)
			(xy 407.818558 -277.573559) (xy 407.864574 -277.556107) (xy 407.912793 -277.546263) (xy 407.961968 -277.544282)
			(xy 408.010823 -277.550214) (xy 408.058094 -277.563906) (xy 408.102556 -277.585004) (xy 408.143059 -277.61296)
			(xy 408.178552 -277.647052) (xy 408.208117 -277.686396) (xy 408.230988 -277.729973) (xy 408.246572 -277.776654)
			(xy 408.254467 -277.825231) (xy 408.254962 -277.849838) (xy 409.54377 -277.849838) (xy 409.54773 -277.800784)
			(xy 409.559507 -277.753) (xy 409.578798 -277.707724) (xy 409.605101 -277.666128) (xy 409.637736 -277.629291)
			(xy 409.675857 -277.598166) (xy 409.718478 -277.573559) (xy 409.764494 -277.556107) (xy 409.812713 -277.546263)
			(xy 409.861888 -277.544282) (xy 409.910743 -277.550214) (xy 409.958014 -277.563906) (xy 410.002476 -277.585004)
			(xy 410.042979 -277.61296) (xy 410.078472 -277.647052) (xy 410.108037 -277.686396) (xy 410.130908 -277.729973)
			(xy 410.146492 -277.776654) (xy 410.154387 -277.825231) (xy 410.154882 -277.849838) (xy 411.443944 -277.849838)
			(xy 411.447904 -277.800784) (xy 411.459681 -277.753) (xy 411.478972 -277.707724) (xy 411.505275 -277.666128)
			(xy 411.53791 -277.629291) (xy 411.576031 -277.598166) (xy 411.618652 -277.573559) (xy 411.664668 -277.556107)
			(xy 411.712887 -277.546263) (xy 411.762062 -277.544282) (xy 411.810917 -277.550214) (xy 411.858188 -277.563906)
			(xy 411.90265 -277.585004) (xy 411.943153 -277.61296) (xy 411.978646 -277.647052) (xy 412.008211 -277.686396)
			(xy 412.031082 -277.729973) (xy 412.046666 -277.776654) (xy 412.054561 -277.825231) (xy 412.055056 -277.849838)
			(xy 413.343864 -277.849838) (xy 413.347824 -277.800784) (xy 413.359601 -277.753) (xy 413.378892 -277.707724)
			(xy 413.405195 -277.666128) (xy 413.43783 -277.629291) (xy 413.475951 -277.598166) (xy 413.518572 -277.573559)
			(xy 413.564588 -277.556107) (xy 413.612807 -277.546263) (xy 413.661982 -277.544282) (xy 413.710837 -277.550214)
			(xy 413.758108 -277.563906) (xy 413.80257 -277.585004) (xy 413.843073 -277.61296) (xy 413.878566 -277.647052)
			(xy 413.908131 -277.686396) (xy 413.931002 -277.729973) (xy 413.946586 -277.776654) (xy 413.954481 -277.825231)
			(xy 413.954976 -277.849838) (xy 415.243784 -277.849838) (xy 415.247744 -277.800784) (xy 415.259521 -277.753)
			(xy 415.278812 -277.707724) (xy 415.305115 -277.666128) (xy 415.33775 -277.629291) (xy 415.375871 -277.598166)
			(xy 415.418492 -277.573559) (xy 415.464508 -277.556107) (xy 415.512727 -277.546263) (xy 415.561902 -277.544282)
			(xy 415.610757 -277.550214) (xy 415.658028 -277.563906) (xy 415.70249 -277.585004) (xy 415.742993 -277.61296)
			(xy 415.778486 -277.647052) (xy 415.808051 -277.686396) (xy 415.830922 -277.729973) (xy 415.846506 -277.776654)
			(xy 415.854401 -277.825231) (xy 415.854896 -277.849838) (xy 417.143958 -277.849838) (xy 417.147918 -277.800784)
			(xy 417.159695 -277.753) (xy 417.178986 -277.707724) (xy 417.205289 -277.666128) (xy 417.237924 -277.629291)
			(xy 417.276045 -277.598166) (xy 417.318666 -277.573559) (xy 417.364682 -277.556107) (xy 417.412901 -277.546263)
			(xy 417.462076 -277.544282) (xy 417.510931 -277.550214) (xy 417.558202 -277.563906) (xy 417.602664 -277.585004)
			(xy 417.643167 -277.61296) (xy 417.67866 -277.647052) (xy 417.708225 -277.686396) (xy 417.731096 -277.729973)
			(xy 417.74668 -277.776654) (xy 417.754575 -277.825231) (xy 417.75507 -277.849838) (xy 419.043878 -277.849838)
			(xy 419.047838 -277.800784) (xy 419.059615 -277.753) (xy 419.078906 -277.707724) (xy 419.105209 -277.666128)
			(xy 419.137844 -277.629291) (xy 419.175965 -277.598166) (xy 419.218586 -277.573559) (xy 419.264602 -277.556107)
			(xy 419.312821 -277.546263) (xy 419.361996 -277.544282) (xy 419.410851 -277.550214) (xy 419.458122 -277.563906)
			(xy 419.502584 -277.585004) (xy 419.543087 -277.61296) (xy 419.57858 -277.647052) (xy 419.608145 -277.686396)
			(xy 419.631016 -277.729973) (xy 419.6466 -277.776654) (xy 419.654495 -277.825231) (xy 419.65499 -277.849838)
			(xy 420.943798 -277.849838) (xy 420.947758 -277.800784) (xy 420.959535 -277.753) (xy 420.978826 -277.707724)
			(xy 421.005129 -277.666128) (xy 421.037764 -277.629291) (xy 421.075885 -277.598166) (xy 421.118506 -277.573559)
			(xy 421.164522 -277.556107) (xy 421.212741 -277.546263) (xy 421.261916 -277.544282) (xy 421.310771 -277.550214)
			(xy 421.358042 -277.563906) (xy 421.402504 -277.585004) (xy 421.443007 -277.61296) (xy 421.4785 -277.647052)
			(xy 421.508065 -277.686396) (xy 421.530936 -277.729973) (xy 421.54652 -277.776654) (xy 421.554415 -277.825231)
			(xy 421.55491 -277.849838) (xy 422.843972 -277.849838) (xy 422.847932 -277.800784) (xy 422.859709 -277.753)
			(xy 422.879 -277.707724) (xy 422.905303 -277.666128) (xy 422.937938 -277.629291) (xy 422.976059 -277.598166)
			(xy 423.01868 -277.573559) (xy 423.064696 -277.556107) (xy 423.112915 -277.546263) (xy 423.16209 -277.544282)
			(xy 423.210945 -277.550214) (xy 423.258216 -277.563906) (xy 423.302678 -277.585004) (xy 423.343181 -277.61296)
			(xy 423.378674 -277.647052) (xy 423.408239 -277.686396) (xy 423.43111 -277.729973) (xy 423.446694 -277.776654)
			(xy 423.454589 -277.825231) (xy 423.455084 -277.849838) (xy 424.743892 -277.849838) (xy 424.747852 -277.800784)
			(xy 424.759629 -277.753) (xy 424.77892 -277.707724) (xy 424.805223 -277.666128) (xy 424.837858 -277.629291)
			(xy 424.875979 -277.598166) (xy 424.9186 -277.573559) (xy 424.964616 -277.556107) (xy 425.012835 -277.546263)
			(xy 425.06201 -277.544282) (xy 425.110865 -277.550214) (xy 425.158136 -277.563906) (xy 425.202598 -277.585004)
			(xy 425.243101 -277.61296) (xy 425.278594 -277.647052) (xy 425.308159 -277.686396) (xy 425.33103 -277.729973)
			(xy 425.346614 -277.776654) (xy 425.354509 -277.825231) (xy 425.355004 -277.849838) (xy 426.643812 -277.849838)
			(xy 426.647772 -277.800784) (xy 426.659549 -277.753) (xy 426.67884 -277.707724) (xy 426.705143 -277.666128)
			(xy 426.737778 -277.629291) (xy 426.775899 -277.598166) (xy 426.81852 -277.573559) (xy 426.864536 -277.556107)
			(xy 426.912755 -277.546263) (xy 426.96193 -277.544282) (xy 427.010785 -277.550214) (xy 427.058056 -277.563906)
			(xy 427.102518 -277.585004) (xy 427.143021 -277.61296) (xy 427.178514 -277.647052) (xy 427.208079 -277.686396)
			(xy 427.23095 -277.729973) (xy 427.246534 -277.776654) (xy 427.254429 -277.825231) (xy 427.254924 -277.849838)
			(xy 428.543986 -277.849838) (xy 428.547946 -277.800784) (xy 428.559723 -277.753) (xy 428.579014 -277.707724)
			(xy 428.605317 -277.666128) (xy 428.637952 -277.629291) (xy 428.676073 -277.598166) (xy 428.718694 -277.573559)
			(xy 428.76471 -277.556107) (xy 428.812929 -277.546263) (xy 428.862104 -277.544282) (xy 428.910959 -277.550214)
			(xy 428.95823 -277.563906) (xy 429.002692 -277.585004) (xy 429.043195 -277.61296) (xy 429.078688 -277.647052)
			(xy 429.108253 -277.686396) (xy 429.131124 -277.729973) (xy 429.146708 -277.776654) (xy 429.154603 -277.825231)
			(xy 429.155098 -277.849838) (xy 429.154603 -277.874445) (xy 429.146708 -277.923022) (xy 429.131124 -277.969703)
			(xy 429.108253 -278.01328) (xy 429.078688 -278.052624) (xy 429.043195 -278.086716) (xy 429.002692 -278.114672)
			(xy 428.95823 -278.13577) (xy 428.910959 -278.149462) (xy 428.862104 -278.155394) (xy 428.812929 -278.153413)
			(xy 428.76471 -278.143569) (xy 428.718694 -278.126117) (xy 428.676073 -278.10151) (xy 428.637952 -278.070385)
			(xy 428.605317 -278.033548) (xy 428.579014 -277.991952) (xy 428.559723 -277.946676) (xy 428.547946 -277.898892)
			(xy 428.543986 -277.849838) (xy 427.254924 -277.849838) (xy 427.254429 -277.874445) (xy 427.246534 -277.923022)
			(xy 427.23095 -277.969703) (xy 427.208079 -278.01328) (xy 427.178514 -278.052624) (xy 427.143021 -278.086716)
			(xy 427.102518 -278.114672) (xy 427.058056 -278.13577) (xy 427.010785 -278.149462) (xy 426.96193 -278.155394)
			(xy 426.912755 -278.153413) (xy 426.864536 -278.143569) (xy 426.81852 -278.126117) (xy 426.775899 -278.10151)
			(xy 426.737778 -278.070385) (xy 426.705143 -278.033548) (xy 426.67884 -277.991952) (xy 426.659549 -277.946676)
			(xy 426.647772 -277.898892) (xy 426.643812 -277.849838) (xy 425.355004 -277.849838) (xy 425.354509 -277.874445)
			(xy 425.346614 -277.923022) (xy 425.33103 -277.969703) (xy 425.308159 -278.01328) (xy 425.278594 -278.052624)
			(xy 425.243101 -278.086716) (xy 425.202598 -278.114672) (xy 425.158136 -278.13577) (xy 425.110865 -278.149462)
			(xy 425.06201 -278.155394) (xy 425.012835 -278.153413) (xy 424.964616 -278.143569) (xy 424.9186 -278.126117)
			(xy 424.875979 -278.10151) (xy 424.837858 -278.070385) (xy 424.805223 -278.033548) (xy 424.77892 -277.991952)
			(xy 424.759629 -277.946676) (xy 424.747852 -277.898892) (xy 424.743892 -277.849838) (xy 423.455084 -277.849838)
			(xy 423.454589 -277.874445) (xy 423.446694 -277.923022) (xy 423.43111 -277.969703) (xy 423.408239 -278.01328)
			(xy 423.378674 -278.052624) (xy 423.343181 -278.086716) (xy 423.302678 -278.114672) (xy 423.258216 -278.13577)
			(xy 423.210945 -278.149462) (xy 423.16209 -278.155394) (xy 423.112915 -278.153413) (xy 423.064696 -278.143569)
			(xy 423.01868 -278.126117) (xy 422.976059 -278.10151) (xy 422.937938 -278.070385) (xy 422.905303 -278.033548)
			(xy 422.879 -277.991952) (xy 422.859709 -277.946676) (xy 422.847932 -277.898892) (xy 422.843972 -277.849838)
			(xy 421.55491 -277.849838) (xy 421.554415 -277.874445) (xy 421.54652 -277.923022) (xy 421.530936 -277.969703)
			(xy 421.508065 -278.01328) (xy 421.4785 -278.052624) (xy 421.443007 -278.086716) (xy 421.402504 -278.114672)
			(xy 421.358042 -278.13577) (xy 421.310771 -278.149462) (xy 421.261916 -278.155394) (xy 421.212741 -278.153413)
			(xy 421.164522 -278.143569) (xy 421.118506 -278.126117) (xy 421.075885 -278.10151) (xy 421.037764 -278.070385)
			(xy 421.005129 -278.033548) (xy 420.978826 -277.991952) (xy 420.959535 -277.946676) (xy 420.947758 -277.898892)
			(xy 420.943798 -277.849838) (xy 419.65499 -277.849838) (xy 419.654495 -277.874445) (xy 419.6466 -277.923022)
			(xy 419.631016 -277.969703) (xy 419.608145 -278.01328) (xy 419.57858 -278.052624) (xy 419.543087 -278.086716)
			(xy 419.502584 -278.114672) (xy 419.458122 -278.13577) (xy 419.410851 -278.149462) (xy 419.361996 -278.155394)
			(xy 419.312821 -278.153413) (xy 419.264602 -278.143569) (xy 419.218586 -278.126117) (xy 419.175965 -278.10151)
			(xy 419.137844 -278.070385) (xy 419.105209 -278.033548) (xy 419.078906 -277.991952) (xy 419.059615 -277.946676)
			(xy 419.047838 -277.898892) (xy 419.043878 -277.849838) (xy 417.75507 -277.849838) (xy 417.754575 -277.874445)
			(xy 417.74668 -277.923022) (xy 417.731096 -277.969703) (xy 417.708225 -278.01328) (xy 417.67866 -278.052624)
			(xy 417.643167 -278.086716) (xy 417.602664 -278.114672) (xy 417.558202 -278.13577) (xy 417.510931 -278.149462)
			(xy 417.462076 -278.155394) (xy 417.412901 -278.153413) (xy 417.364682 -278.143569) (xy 417.318666 -278.126117)
			(xy 417.276045 -278.10151) (xy 417.237924 -278.070385) (xy 417.205289 -278.033548) (xy 417.178986 -277.991952)
			(xy 417.159695 -277.946676) (xy 417.147918 -277.898892) (xy 417.143958 -277.849838) (xy 415.854896 -277.849838)
			(xy 415.854401 -277.874445) (xy 415.846506 -277.923022) (xy 415.830922 -277.969703) (xy 415.808051 -278.01328)
			(xy 415.778486 -278.052624) (xy 415.742993 -278.086716) (xy 415.70249 -278.114672) (xy 415.658028 -278.13577)
			(xy 415.610757 -278.149462) (xy 415.561902 -278.155394) (xy 415.512727 -278.153413) (xy 415.464508 -278.143569)
			(xy 415.418492 -278.126117) (xy 415.375871 -278.10151) (xy 415.33775 -278.070385) (xy 415.305115 -278.033548)
			(xy 415.278812 -277.991952) (xy 415.259521 -277.946676) (xy 415.247744 -277.898892) (xy 415.243784 -277.849838)
			(xy 413.954976 -277.849838) (xy 413.954481 -277.874445) (xy 413.946586 -277.923022) (xy 413.931002 -277.969703)
			(xy 413.908131 -278.01328) (xy 413.878566 -278.052624) (xy 413.843073 -278.086716) (xy 413.80257 -278.114672)
			(xy 413.758108 -278.13577) (xy 413.710837 -278.149462) (xy 413.661982 -278.155394) (xy 413.612807 -278.153413)
			(xy 413.564588 -278.143569) (xy 413.518572 -278.126117) (xy 413.475951 -278.10151) (xy 413.43783 -278.070385)
			(xy 413.405195 -278.033548) (xy 413.378892 -277.991952) (xy 413.359601 -277.946676) (xy 413.347824 -277.898892)
			(xy 413.343864 -277.849838) (xy 412.055056 -277.849838) (xy 412.054561 -277.874445) (xy 412.046666 -277.923022)
			(xy 412.031082 -277.969703) (xy 412.008211 -278.01328) (xy 411.978646 -278.052624) (xy 411.943153 -278.086716)
			(xy 411.90265 -278.114672) (xy 411.858188 -278.13577) (xy 411.810917 -278.149462) (xy 411.762062 -278.155394)
			(xy 411.712887 -278.153413) (xy 411.664668 -278.143569) (xy 411.618652 -278.126117) (xy 411.576031 -278.10151)
			(xy 411.53791 -278.070385) (xy 411.505275 -278.033548) (xy 411.478972 -277.991952) (xy 411.459681 -277.946676)
			(xy 411.447904 -277.898892) (xy 411.443944 -277.849838) (xy 410.154882 -277.849838) (xy 410.154387 -277.874445)
			(xy 410.146492 -277.923022) (xy 410.130908 -277.969703) (xy 410.108037 -278.01328) (xy 410.078472 -278.052624)
			(xy 410.042979 -278.086716) (xy 410.002476 -278.114672) (xy 409.958014 -278.13577) (xy 409.910743 -278.149462)
			(xy 409.861888 -278.155394) (xy 409.812713 -278.153413) (xy 409.764494 -278.143569) (xy 409.718478 -278.126117)
			(xy 409.675857 -278.10151) (xy 409.637736 -278.070385) (xy 409.605101 -278.033548) (xy 409.578798 -277.991952)
			(xy 409.559507 -277.946676) (xy 409.54773 -277.898892) (xy 409.54377 -277.849838) (xy 408.254962 -277.849838)
			(xy 408.254467 -277.874445) (xy 408.246572 -277.923022) (xy 408.230988 -277.969703) (xy 408.208117 -278.01328)
			(xy 408.178552 -278.052624) (xy 408.143059 -278.086716) (xy 408.102556 -278.114672) (xy 408.058094 -278.13577)
			(xy 408.010823 -278.149462) (xy 407.961968 -278.155394) (xy 407.912793 -278.153413) (xy 407.864574 -278.143569)
			(xy 407.818558 -278.126117) (xy 407.775937 -278.10151) (xy 407.737816 -278.070385) (xy 407.705181 -278.033548)
			(xy 407.678878 -277.991952) (xy 407.659587 -277.946676) (xy 407.64781 -277.898892) (xy 407.64385 -277.849838)
			(xy 406.355296 -277.849838) (xy 406.354801 -277.874445) (xy 406.346906 -277.923022) (xy 406.331322 -277.969703)
			(xy 406.308451 -278.01328) (xy 406.278886 -278.052624) (xy 406.243393 -278.086716) (xy 406.20289 -278.114672)
			(xy 406.158428 -278.13577) (xy 406.111157 -278.149462) (xy 406.062302 -278.155394) (xy 406.013127 -278.153413)
			(xy 405.964908 -278.143569) (xy 405.918892 -278.126117) (xy 405.876271 -278.10151) (xy 405.83815 -278.070385)
			(xy 405.805515 -278.033548) (xy 405.779212 -277.991952) (xy 405.759921 -277.946676) (xy 405.748144 -277.898892)
			(xy 405.744184 -277.849838) (xy 404.455122 -277.849838) (xy 404.454627 -277.874445) (xy 404.446732 -277.923022)
			(xy 404.431148 -277.969703) (xy 404.408277 -278.01328) (xy 404.378712 -278.052624) (xy 404.343219 -278.086716)
			(xy 404.302716 -278.114672) (xy 404.258254 -278.13577) (xy 404.210983 -278.149462) (xy 404.162128 -278.155394)
			(xy 404.112953 -278.153413) (xy 404.064734 -278.143569) (xy 404.018718 -278.126117) (xy 403.976097 -278.10151)
			(xy 403.937976 -278.070385) (xy 403.905341 -278.033548) (xy 403.879038 -277.991952) (xy 403.859747 -277.946676)
			(xy 403.84797 -277.898892) (xy 403.84401 -277.849838) (xy 402.555202 -277.849838) (xy 402.554707 -277.874445)
			(xy 402.546812 -277.923022) (xy 402.531228 -277.969703) (xy 402.508357 -278.01328) (xy 402.478792 -278.052624)
			(xy 402.443299 -278.086716) (xy 402.402796 -278.114672) (xy 402.358334 -278.13577) (xy 402.311063 -278.149462)
			(xy 402.262208 -278.155394) (xy 402.213033 -278.153413) (xy 402.164814 -278.143569) (xy 402.118798 -278.126117)
			(xy 402.076177 -278.10151) (xy 402.038056 -278.070385) (xy 402.005421 -278.033548) (xy 401.979118 -277.991952)
			(xy 401.959827 -277.946676) (xy 401.94805 -277.898892) (xy 401.94409 -277.849838) (xy 400.655282 -277.849838)
			(xy 400.654787 -277.874445) (xy 400.646892 -277.923022) (xy 400.631308 -277.969703) (xy 400.608437 -278.01328)
			(xy 400.578872 -278.052624) (xy 400.543379 -278.086716) (xy 400.502876 -278.114672) (xy 400.458414 -278.13577)
			(xy 400.411143 -278.149462) (xy 400.362288 -278.155394) (xy 400.313113 -278.153413) (xy 400.264894 -278.143569)
			(xy 400.218878 -278.126117) (xy 400.176257 -278.10151) (xy 400.138136 -278.070385) (xy 400.105501 -278.033548)
			(xy 400.079198 -277.991952) (xy 400.059907 -277.946676) (xy 400.04813 -277.898892) (xy 400.04417 -277.849838)
			(xy 398.755108 -277.849838) (xy 398.754613 -277.874445) (xy 398.746718 -277.923022) (xy 398.731134 -277.969703)
			(xy 398.708263 -278.01328) (xy 398.678698 -278.052624) (xy 398.643205 -278.086716) (xy 398.602702 -278.114672)
			(xy 398.55824 -278.13577) (xy 398.510969 -278.149462) (xy 398.462114 -278.155394) (xy 398.412939 -278.153413)
			(xy 398.36472 -278.143569) (xy 398.318704 -278.126117) (xy 398.276083 -278.10151) (xy 398.237962 -278.070385)
			(xy 398.205327 -278.033548) (xy 398.179024 -277.991952) (xy 398.159733 -277.946676) (xy 398.147956 -277.898892)
			(xy 398.143996 -277.849838) (xy 396.855188 -277.849838) (xy 396.854693 -277.874445) (xy 396.846798 -277.923022)
			(xy 396.831214 -277.969703) (xy 396.808343 -278.01328) (xy 396.778778 -278.052624) (xy 396.743285 -278.086716)
			(xy 396.702782 -278.114672) (xy 396.65832 -278.13577) (xy 396.611049 -278.149462) (xy 396.562194 -278.155394)
			(xy 396.513019 -278.153413) (xy 396.4648 -278.143569) (xy 396.418784 -278.126117) (xy 396.376163 -278.10151)
			(xy 396.338042 -278.070385) (xy 396.305407 -278.033548) (xy 396.279104 -277.991952) (xy 396.259813 -277.946676)
			(xy 396.248036 -277.898892) (xy 396.244076 -277.849838) (xy 394.955268 -277.849838) (xy 394.954773 -277.874445)
			(xy 394.946878 -277.923022) (xy 394.931294 -277.969703) (xy 394.908423 -278.01328) (xy 394.878858 -278.052624)
			(xy 394.843365 -278.086716) (xy 394.802862 -278.114672) (xy 394.7584 -278.13577) (xy 394.711129 -278.149462)
			(xy 394.662274 -278.155394) (xy 394.613099 -278.153413) (xy 394.56488 -278.143569) (xy 394.518864 -278.126117)
			(xy 394.476243 -278.10151) (xy 394.438122 -278.070385) (xy 394.405487 -278.033548) (xy 394.379184 -277.991952)
			(xy 394.359893 -277.946676) (xy 394.348116 -277.898892) (xy 394.344156 -277.849838) (xy 393.055094 -277.849838)
			(xy 393.054599 -277.874445) (xy 393.046704 -277.923022) (xy 393.03112 -277.969703) (xy 393.008249 -278.01328)
			(xy 392.978684 -278.052624) (xy 392.943191 -278.086716) (xy 392.902688 -278.114672) (xy 392.858226 -278.13577)
			(xy 392.810955 -278.149462) (xy 392.7621 -278.155394) (xy 392.712925 -278.153413) (xy 392.664706 -278.143569)
			(xy 392.61869 -278.126117) (xy 392.576069 -278.10151) (xy 392.537948 -278.070385) (xy 392.505313 -278.033548)
			(xy 392.47901 -277.991952) (xy 392.459719 -277.946676) (xy 392.447942 -277.898892) (xy 392.443982 -277.849838)
			(xy 313.055 -277.849838) (xy 313.054505 -277.874445) (xy 313.04661 -277.923022) (xy 313.031026 -277.969703)
			(xy 313.008155 -278.01328) (xy 312.97859 -278.052624) (xy 312.943097 -278.086716) (xy 312.902594 -278.114672)
			(xy 312.858132 -278.13577) (xy 312.810861 -278.149462) (xy 312.762006 -278.155394) (xy 312.712831 -278.153413)
			(xy 312.664612 -278.143569) (xy 312.618596 -278.126117) (xy 312.575975 -278.10151) (xy 312.537854 -278.070385)
			(xy 312.505219 -278.033548) (xy 312.478916 -277.991952) (xy 312.459625 -277.946676) (xy 312.447848 -277.898892)
			(xy 312.443888 -277.849838) (xy 311.154826 -277.849838) (xy 311.154331 -277.874445) (xy 311.146436 -277.923022)
			(xy 311.130852 -277.969703) (xy 311.107981 -278.01328) (xy 311.078416 -278.052624) (xy 311.042923 -278.086716)
			(xy 311.00242 -278.114672) (xy 310.957958 -278.13577) (xy 310.910687 -278.149462) (xy 310.861832 -278.155394)
			(xy 310.812657 -278.153413) (xy 310.764438 -278.143569) (xy 310.718422 -278.126117) (xy 310.675801 -278.10151)
			(xy 310.63768 -278.070385) (xy 310.605045 -278.033548) (xy 310.578742 -277.991952) (xy 310.559451 -277.946676)
			(xy 310.547674 -277.898892) (xy 310.543714 -277.849838) (xy 309.254906 -277.849838) (xy 309.254411 -277.874445)
			(xy 309.246516 -277.923022) (xy 309.230932 -277.969703) (xy 309.208061 -278.01328) (xy 309.178496 -278.052624)
			(xy 309.143003 -278.086716) (xy 309.1025 -278.114672) (xy 309.058038 -278.13577) (xy 309.010767 -278.149462)
			(xy 308.961912 -278.155394) (xy 308.912737 -278.153413) (xy 308.864518 -278.143569) (xy 308.818502 -278.126117)
			(xy 308.775881 -278.10151) (xy 308.73776 -278.070385) (xy 308.705125 -278.033548) (xy 308.678822 -277.991952)
			(xy 308.659531 -277.946676) (xy 308.647754 -277.898892) (xy 308.643794 -277.849838) (xy 307.354986 -277.849838)
			(xy 307.354491 -277.874445) (xy 307.346596 -277.923022) (xy 307.331012 -277.969703) (xy 307.308141 -278.01328)
			(xy 307.278576 -278.052624) (xy 307.243083 -278.086716) (xy 307.20258 -278.114672) (xy 307.158118 -278.13577)
			(xy 307.110847 -278.149462) (xy 307.061992 -278.155394) (xy 307.012817 -278.153413) (xy 306.964598 -278.143569)
			(xy 306.918582 -278.126117) (xy 306.875961 -278.10151) (xy 306.83784 -278.070385) (xy 306.805205 -278.033548)
			(xy 306.778902 -277.991952) (xy 306.759611 -277.946676) (xy 306.747834 -277.898892) (xy 306.743874 -277.849838)
			(xy 305.454812 -277.849838) (xy 305.454317 -277.874445) (xy 305.446422 -277.923022) (xy 305.430838 -277.969703)
			(xy 305.407967 -278.01328) (xy 305.378402 -278.052624) (xy 305.342909 -278.086716) (xy 305.302406 -278.114672)
			(xy 305.257944 -278.13577) (xy 305.210673 -278.149462) (xy 305.161818 -278.155394) (xy 305.112643 -278.153413)
			(xy 305.064424 -278.143569) (xy 305.018408 -278.126117) (xy 304.975787 -278.10151) (xy 304.937666 -278.070385)
			(xy 304.905031 -278.033548) (xy 304.878728 -277.991952) (xy 304.859437 -277.946676) (xy 304.84766 -277.898892)
			(xy 304.8437 -277.849838) (xy 303.554892 -277.849838) (xy 303.554397 -277.874445) (xy 303.546502 -277.923022)
			(xy 303.530918 -277.969703) (xy 303.508047 -278.01328) (xy 303.478482 -278.052624) (xy 303.442989 -278.086716)
			(xy 303.402486 -278.114672) (xy 303.358024 -278.13577) (xy 303.310753 -278.149462) (xy 303.261898 -278.155394)
			(xy 303.212723 -278.153413) (xy 303.164504 -278.143569) (xy 303.118488 -278.126117) (xy 303.075867 -278.10151)
			(xy 303.037746 -278.070385) (xy 303.005111 -278.033548) (xy 302.978808 -277.991952) (xy 302.959517 -277.946676)
			(xy 302.94774 -277.898892) (xy 302.94378 -277.849838) (xy 301.654972 -277.849838) (xy 301.654477 -277.874445)
			(xy 301.646582 -277.923022) (xy 301.630998 -277.969703) (xy 301.608127 -278.01328) (xy 301.578562 -278.052624)
			(xy 301.543069 -278.086716) (xy 301.502566 -278.114672) (xy 301.458104 -278.13577) (xy 301.410833 -278.149462)
			(xy 301.361978 -278.155394) (xy 301.312803 -278.153413) (xy 301.264584 -278.143569) (xy 301.218568 -278.126117)
			(xy 301.175947 -278.10151) (xy 301.137826 -278.070385) (xy 301.105191 -278.033548) (xy 301.078888 -277.991952)
			(xy 301.059597 -277.946676) (xy 301.04782 -277.898892) (xy 301.04386 -277.849838) (xy 299.754798 -277.849838)
			(xy 299.754303 -277.874445) (xy 299.746408 -277.923022) (xy 299.730824 -277.969703) (xy 299.707953 -278.01328)
			(xy 299.678388 -278.052624) (xy 299.642895 -278.086716) (xy 299.602392 -278.114672) (xy 299.55793 -278.13577)
			(xy 299.510659 -278.149462) (xy 299.461804 -278.155394) (xy 299.412629 -278.153413) (xy 299.36441 -278.143569)
			(xy 299.318394 -278.126117) (xy 299.275773 -278.10151) (xy 299.237652 -278.070385) (xy 299.205017 -278.033548)
			(xy 299.178714 -277.991952) (xy 299.159423 -277.946676) (xy 299.147646 -277.898892) (xy 299.143686 -277.849838)
			(xy 297.854878 -277.849838) (xy 297.854383 -277.874445) (xy 297.846488 -277.923022) (xy 297.830904 -277.969703)
			(xy 297.808033 -278.01328) (xy 297.778468 -278.052624) (xy 297.742975 -278.086716) (xy 297.702472 -278.114672)
			(xy 297.65801 -278.13577) (xy 297.610739 -278.149462) (xy 297.561884 -278.155394) (xy 297.512709 -278.153413)
			(xy 297.46449 -278.143569) (xy 297.418474 -278.126117) (xy 297.375853 -278.10151) (xy 297.337732 -278.070385)
			(xy 297.305097 -278.033548) (xy 297.278794 -277.991952) (xy 297.259503 -277.946676) (xy 297.247726 -277.898892)
			(xy 297.243766 -277.849838) (xy 295.954958 -277.849838) (xy 295.954463 -277.874445) (xy 295.946568 -277.923022)
			(xy 295.930984 -277.969703) (xy 295.908113 -278.01328) (xy 295.878548 -278.052624) (xy 295.843055 -278.086716)
			(xy 295.802552 -278.114672) (xy 295.75809 -278.13577) (xy 295.710819 -278.149462) (xy 295.661964 -278.155394)
			(xy 295.612789 -278.153413) (xy 295.56457 -278.143569) (xy 295.518554 -278.126117) (xy 295.475933 -278.10151)
			(xy 295.437812 -278.070385) (xy 295.405177 -278.033548) (xy 295.378874 -277.991952) (xy 295.359583 -277.946676)
			(xy 295.347806 -277.898892) (xy 295.343846 -277.849838) (xy 294.054784 -277.849838) (xy 294.054289 -277.874445)
			(xy 294.046394 -277.923022) (xy 294.03081 -277.969703) (xy 294.007939 -278.01328) (xy 293.978374 -278.052624)
			(xy 293.942881 -278.086716) (xy 293.902378 -278.114672) (xy 293.857916 -278.13577) (xy 293.810645 -278.149462)
			(xy 293.76179 -278.155394) (xy 293.712615 -278.153413) (xy 293.664396 -278.143569) (xy 293.61838 -278.126117)
			(xy 293.575759 -278.10151) (xy 293.537638 -278.070385) (xy 293.505003 -278.033548) (xy 293.4787 -277.991952)
			(xy 293.459409 -277.946676) (xy 293.447632 -277.898892) (xy 293.443672 -277.849838) (xy 292.154864 -277.849838)
			(xy 292.154369 -277.874445) (xy 292.146474 -277.923022) (xy 292.13089 -277.969703) (xy 292.108019 -278.01328)
			(xy 292.078454 -278.052624) (xy 292.042961 -278.086716) (xy 292.002458 -278.114672) (xy 291.957996 -278.13577)
			(xy 291.910725 -278.149462) (xy 291.86187 -278.155394) (xy 291.812695 -278.153413) (xy 291.764476 -278.143569)
			(xy 291.71846 -278.126117) (xy 291.675839 -278.10151) (xy 291.637718 -278.070385) (xy 291.605083 -278.033548)
			(xy 291.57878 -277.991952) (xy 291.559489 -277.946676) (xy 291.547712 -277.898892) (xy 291.543752 -277.849838)
			(xy 290.255198 -277.849838) (xy 290.254703 -277.874445) (xy 290.246808 -277.923022) (xy 290.231224 -277.969703)
			(xy 290.208353 -278.01328) (xy 290.178788 -278.052624) (xy 290.143295 -278.086716) (xy 290.102792 -278.114672)
			(xy 290.05833 -278.13577) (xy 290.011059 -278.149462) (xy 289.962204 -278.155394) (xy 289.913029 -278.153413)
			(xy 289.86481 -278.143569) (xy 289.818794 -278.126117) (xy 289.776173 -278.10151) (xy 289.738052 -278.070385)
			(xy 289.705417 -278.033548) (xy 289.679114 -277.991952) (xy 289.659823 -277.946676) (xy 289.648046 -277.898892)
			(xy 289.644086 -277.849838) (xy 288.355024 -277.849838) (xy 288.354529 -277.874445) (xy 288.346634 -277.923022)
			(xy 288.33105 -277.969703) (xy 288.308179 -278.01328) (xy 288.278614 -278.052624) (xy 288.243121 -278.086716)
			(xy 288.202618 -278.114672) (xy 288.158156 -278.13577) (xy 288.110885 -278.149462) (xy 288.06203 -278.155394)
			(xy 288.012855 -278.153413) (xy 287.964636 -278.143569) (xy 287.91862 -278.126117) (xy 287.875999 -278.10151)
			(xy 287.837878 -278.070385) (xy 287.805243 -278.033548) (xy 287.77894 -277.991952) (xy 287.759649 -277.946676)
			(xy 287.747872 -277.898892) (xy 287.743912 -277.849838) (xy 286.455104 -277.849838) (xy 286.454609 -277.874445)
			(xy 286.446714 -277.923022) (xy 286.43113 -277.969703) (xy 286.408259 -278.01328) (xy 286.378694 -278.052624)
			(xy 286.343201 -278.086716) (xy 286.302698 -278.114672) (xy 286.258236 -278.13577) (xy 286.210965 -278.149462)
			(xy 286.16211 -278.155394) (xy 286.112935 -278.153413) (xy 286.064716 -278.143569) (xy 286.0187 -278.126117)
			(xy 285.976079 -278.10151) (xy 285.937958 -278.070385) (xy 285.905323 -278.033548) (xy 285.87902 -277.991952)
			(xy 285.859729 -277.946676) (xy 285.847952 -277.898892) (xy 285.843992 -277.849838) (xy 284.555184 -277.849838)
			(xy 284.554689 -277.874445) (xy 284.546794 -277.923022) (xy 284.53121 -277.969703) (xy 284.508339 -278.01328)
			(xy 284.478774 -278.052624) (xy 284.443281 -278.086716) (xy 284.402778 -278.114672) (xy 284.358316 -278.13577)
			(xy 284.311045 -278.149462) (xy 284.26219 -278.155394) (xy 284.213015 -278.153413) (xy 284.164796 -278.143569)
			(xy 284.11878 -278.126117) (xy 284.076159 -278.10151) (xy 284.038038 -278.070385) (xy 284.005403 -278.033548)
			(xy 283.9791 -277.991952) (xy 283.959809 -277.946676) (xy 283.948032 -277.898892) (xy 283.944072 -277.849838)
			(xy 282.65501 -277.849838) (xy 282.654515 -277.874445) (xy 282.64662 -277.923022) (xy 282.631036 -277.969703)
			(xy 282.608165 -278.01328) (xy 282.5786 -278.052624) (xy 282.543107 -278.086716) (xy 282.502604 -278.114672)
			(xy 282.458142 -278.13577) (xy 282.410871 -278.149462) (xy 282.362016 -278.155394) (xy 282.312841 -278.153413)
			(xy 282.264622 -278.143569) (xy 282.218606 -278.126117) (xy 282.175985 -278.10151) (xy 282.137864 -278.070385)
			(xy 282.105229 -278.033548) (xy 282.078926 -277.991952) (xy 282.059635 -277.946676) (xy 282.047858 -277.898892)
			(xy 282.043898 -277.849838) (xy 280.75509 -277.849838) (xy 280.754595 -277.874445) (xy 280.7467 -277.923022)
			(xy 280.731116 -277.969703) (xy 280.708245 -278.01328) (xy 280.67868 -278.052624) (xy 280.643187 -278.086716)
			(xy 280.602684 -278.114672) (xy 280.558222 -278.13577) (xy 280.510951 -278.149462) (xy 280.462096 -278.155394)
			(xy 280.412921 -278.153413) (xy 280.364702 -278.143569) (xy 280.318686 -278.126117) (xy 280.276065 -278.10151)
			(xy 280.237944 -278.070385) (xy 280.205309 -278.033548) (xy 280.179006 -277.991952) (xy 280.159715 -277.946676)
			(xy 280.147938 -277.898892) (xy 280.143978 -277.849838) (xy 278.85517 -277.849838) (xy 278.854675 -277.874445)
			(xy 278.84678 -277.923022) (xy 278.831196 -277.969703) (xy 278.808325 -278.01328) (xy 278.77876 -278.052624)
			(xy 278.743267 -278.086716) (xy 278.702764 -278.114672) (xy 278.658302 -278.13577) (xy 278.611031 -278.149462)
			(xy 278.562176 -278.155394) (xy 278.513001 -278.153413) (xy 278.464782 -278.143569) (xy 278.418766 -278.126117)
			(xy 278.376145 -278.10151) (xy 278.338024 -278.070385) (xy 278.305389 -278.033548) (xy 278.279086 -277.991952)
			(xy 278.259795 -277.946676) (xy 278.248018 -277.898892) (xy 278.244058 -277.849838) (xy 276.954996 -277.849838)
			(xy 276.954501 -277.874445) (xy 276.946606 -277.923022) (xy 276.931022 -277.969703) (xy 276.908151 -278.01328)
			(xy 276.878586 -278.052624) (xy 276.843093 -278.086716) (xy 276.80259 -278.114672) (xy 276.758128 -278.13577)
			(xy 276.710857 -278.149462) (xy 276.662002 -278.155394) (xy 276.612827 -278.153413) (xy 276.564608 -278.143569)
			(xy 276.518592 -278.126117) (xy 276.475971 -278.10151) (xy 276.43785 -278.070385) (xy 276.405215 -278.033548)
			(xy 276.378912 -277.991952) (xy 276.359621 -277.946676) (xy 276.347844 -277.898892) (xy 276.343884 -277.849838)
			(xy 196.955156 -277.849838) (xy 196.954661 -277.874445) (xy 196.946766 -277.923022) (xy 196.931182 -277.969703)
			(xy 196.908311 -278.01328) (xy 196.878746 -278.052624) (xy 196.843253 -278.086716) (xy 196.80275 -278.114672)
			(xy 196.758288 -278.13577) (xy 196.711017 -278.149462) (xy 196.662162 -278.155394) (xy 196.612987 -278.153413)
			(xy 196.564768 -278.143569) (xy 196.518752 -278.126117) (xy 196.476131 -278.10151) (xy 196.43801 -278.070385)
			(xy 196.405375 -278.033548) (xy 196.379072 -277.991952) (xy 196.359781 -277.946676) (xy 196.348004 -277.898892)
			(xy 196.344044 -277.849838) (xy 195.054982 -277.849838) (xy 195.054487 -277.874445) (xy 195.046592 -277.923022)
			(xy 195.031008 -277.969703) (xy 195.008137 -278.01328) (xy 194.978572 -278.052624) (xy 194.943079 -278.086716)
			(xy 194.902576 -278.114672) (xy 194.858114 -278.13577) (xy 194.810843 -278.149462) (xy 194.761988 -278.155394)
			(xy 194.712813 -278.153413) (xy 194.664594 -278.143569) (xy 194.618578 -278.126117) (xy 194.575957 -278.10151)
			(xy 194.537836 -278.070385) (xy 194.505201 -278.033548) (xy 194.478898 -277.991952) (xy 194.459607 -277.946676)
			(xy 194.44783 -277.898892) (xy 194.44387 -277.849838) (xy 193.155062 -277.849838) (xy 193.154567 -277.874445)
			(xy 193.146672 -277.923022) (xy 193.131088 -277.969703) (xy 193.108217 -278.01328) (xy 193.078652 -278.052624)
			(xy 193.043159 -278.086716) (xy 193.002656 -278.114672) (xy 192.958194 -278.13577) (xy 192.910923 -278.149462)
			(xy 192.862068 -278.155394) (xy 192.812893 -278.153413) (xy 192.764674 -278.143569) (xy 192.718658 -278.126117)
			(xy 192.676037 -278.10151) (xy 192.637916 -278.070385) (xy 192.605281 -278.033548) (xy 192.578978 -277.991952)
			(xy 192.559687 -277.946676) (xy 192.54791 -277.898892) (xy 192.54395 -277.849838) (xy 191.255142 -277.849838)
			(xy 191.254647 -277.874445) (xy 191.246752 -277.923022) (xy 191.231168 -277.969703) (xy 191.208297 -278.01328)
			(xy 191.178732 -278.052624) (xy 191.143239 -278.086716) (xy 191.102736 -278.114672) (xy 191.058274 -278.13577)
			(xy 191.011003 -278.149462) (xy 190.962148 -278.155394) (xy 190.912973 -278.153413) (xy 190.864754 -278.143569)
			(xy 190.818738 -278.126117) (xy 190.776117 -278.10151) (xy 190.737996 -278.070385) (xy 190.705361 -278.033548)
			(xy 190.679058 -277.991952) (xy 190.659767 -277.946676) (xy 190.64799 -277.898892) (xy 190.64403 -277.849838)
			(xy 189.354968 -277.849838) (xy 189.354473 -277.874445) (xy 189.346578 -277.923022) (xy 189.330994 -277.969703)
			(xy 189.308123 -278.01328) (xy 189.278558 -278.052624) (xy 189.243065 -278.086716) (xy 189.202562 -278.114672)
			(xy 189.1581 -278.13577) (xy 189.110829 -278.149462) (xy 189.061974 -278.155394) (xy 189.012799 -278.153413)
			(xy 188.96458 -278.143569) (xy 188.918564 -278.126117) (xy 188.875943 -278.10151) (xy 188.837822 -278.070385)
			(xy 188.805187 -278.033548) (xy 188.778884 -277.991952) (xy 188.759593 -277.946676) (xy 188.747816 -277.898892)
			(xy 188.743856 -277.849838) (xy 187.455048 -277.849838) (xy 187.454553 -277.874445) (xy 187.446658 -277.923022)
			(xy 187.431074 -277.969703) (xy 187.408203 -278.01328) (xy 187.378638 -278.052624) (xy 187.343145 -278.086716)
			(xy 187.302642 -278.114672) (xy 187.25818 -278.13577) (xy 187.210909 -278.149462) (xy 187.162054 -278.155394)
			(xy 187.112879 -278.153413) (xy 187.06466 -278.143569) (xy 187.018644 -278.126117) (xy 186.976023 -278.10151)
			(xy 186.937902 -278.070385) (xy 186.905267 -278.033548) (xy 186.878964 -277.991952) (xy 186.859673 -277.946676)
			(xy 186.847896 -277.898892) (xy 186.843936 -277.849838) (xy 185.555128 -277.849838) (xy 185.554633 -277.874445)
			(xy 185.546738 -277.923022) (xy 185.531154 -277.969703) (xy 185.508283 -278.01328) (xy 185.478718 -278.052624)
			(xy 185.443225 -278.086716) (xy 185.402722 -278.114672) (xy 185.35826 -278.13577) (xy 185.310989 -278.149462)
			(xy 185.262134 -278.155394) (xy 185.212959 -278.153413) (xy 185.16474 -278.143569) (xy 185.118724 -278.126117)
			(xy 185.076103 -278.10151) (xy 185.037982 -278.070385) (xy 185.005347 -278.033548) (xy 184.979044 -277.991952)
			(xy 184.959753 -277.946676) (xy 184.947976 -277.898892) (xy 184.944016 -277.849838) (xy 183.654954 -277.849838)
			(xy 183.654459 -277.874445) (xy 183.646564 -277.923022) (xy 183.63098 -277.969703) (xy 183.608109 -278.01328)
			(xy 183.578544 -278.052624) (xy 183.543051 -278.086716) (xy 183.502548 -278.114672) (xy 183.458086 -278.13577)
			(xy 183.410815 -278.149462) (xy 183.36196 -278.155394) (xy 183.312785 -278.153413) (xy 183.264566 -278.143569)
			(xy 183.21855 -278.126117) (xy 183.175929 -278.10151) (xy 183.137808 -278.070385) (xy 183.105173 -278.033548)
			(xy 183.07887 -277.991952) (xy 183.059579 -277.946676) (xy 183.047802 -277.898892) (xy 183.043842 -277.849838)
			(xy 181.755034 -277.849838) (xy 181.754539 -277.874445) (xy 181.746644 -277.923022) (xy 181.73106 -277.969703)
			(xy 181.708189 -278.01328) (xy 181.678624 -278.052624) (xy 181.643131 -278.086716) (xy 181.602628 -278.114672)
			(xy 181.558166 -278.13577) (xy 181.510895 -278.149462) (xy 181.46204 -278.155394) (xy 181.412865 -278.153413)
			(xy 181.364646 -278.143569) (xy 181.31863 -278.126117) (xy 181.276009 -278.10151) (xy 181.237888 -278.070385)
			(xy 181.205253 -278.033548) (xy 181.17895 -277.991952) (xy 181.159659 -277.946676) (xy 181.147882 -277.898892)
			(xy 181.143922 -277.849838) (xy 179.855114 -277.849838) (xy 179.854619 -277.874445) (xy 179.846724 -277.923022)
			(xy 179.83114 -277.969703) (xy 179.808269 -278.01328) (xy 179.778704 -278.052624) (xy 179.743211 -278.086716)
			(xy 179.702708 -278.114672) (xy 179.658246 -278.13577) (xy 179.610975 -278.149462) (xy 179.56212 -278.155394)
			(xy 179.512945 -278.153413) (xy 179.464726 -278.143569) (xy 179.41871 -278.126117) (xy 179.376089 -278.10151)
			(xy 179.337968 -278.070385) (xy 179.305333 -278.033548) (xy 179.27903 -277.991952) (xy 179.259739 -277.946676)
			(xy 179.247962 -277.898892) (xy 179.244002 -277.849838) (xy 177.95494 -277.849838) (xy 177.954445 -277.874445)
			(xy 177.94655 -277.923022) (xy 177.930966 -277.969703) (xy 177.908095 -278.01328) (xy 177.87853 -278.052624)
			(xy 177.843037 -278.086716) (xy 177.802534 -278.114672) (xy 177.758072 -278.13577) (xy 177.710801 -278.149462)
			(xy 177.661946 -278.155394) (xy 177.612771 -278.153413) (xy 177.564552 -278.143569) (xy 177.518536 -278.126117)
			(xy 177.475915 -278.10151) (xy 177.437794 -278.070385) (xy 177.405159 -278.033548) (xy 177.378856 -277.991952)
			(xy 177.359565 -277.946676) (xy 177.347788 -277.898892) (xy 177.343828 -277.849838) (xy 176.05502 -277.849838)
			(xy 176.054525 -277.874445) (xy 176.04663 -277.923022) (xy 176.031046 -277.969703) (xy 176.008175 -278.01328)
			(xy 175.97861 -278.052624) (xy 175.943117 -278.086716) (xy 175.902614 -278.114672) (xy 175.858152 -278.13577)
			(xy 175.810881 -278.149462) (xy 175.762026 -278.155394) (xy 175.712851 -278.153413) (xy 175.664632 -278.143569)
			(xy 175.618616 -278.126117) (xy 175.575995 -278.10151) (xy 175.537874 -278.070385) (xy 175.505239 -278.033548)
			(xy 175.478936 -277.991952) (xy 175.459645 -277.946676) (xy 175.447868 -277.898892) (xy 175.443908 -277.849838)
			(xy 174.155354 -277.849838) (xy 174.154859 -277.874445) (xy 174.146964 -277.923022) (xy 174.13138 -277.969703)
			(xy 174.108509 -278.01328) (xy 174.078944 -278.052624) (xy 174.043451 -278.086716) (xy 174.002948 -278.114672)
			(xy 173.958486 -278.13577) (xy 173.911215 -278.149462) (xy 173.86236 -278.155394) (xy 173.813185 -278.153413)
			(xy 173.764966 -278.143569) (xy 173.71895 -278.126117) (xy 173.676329 -278.10151) (xy 173.638208 -278.070385)
			(xy 173.605573 -278.033548) (xy 173.57927 -277.991952) (xy 173.559979 -277.946676) (xy 173.548202 -277.898892)
			(xy 173.544242 -277.849838) (xy 172.25518 -277.849838) (xy 172.254685 -277.874445) (xy 172.24679 -277.923022)
			(xy 172.231206 -277.969703) (xy 172.208335 -278.01328) (xy 172.17877 -278.052624) (xy 172.143277 -278.086716)
			(xy 172.102774 -278.114672) (xy 172.058312 -278.13577) (xy 172.011041 -278.149462) (xy 171.962186 -278.155394)
			(xy 171.913011 -278.153413) (xy 171.864792 -278.143569) (xy 171.818776 -278.126117) (xy 171.776155 -278.10151)
			(xy 171.738034 -278.070385) (xy 171.705399 -278.033548) (xy 171.679096 -277.991952) (xy 171.659805 -277.946676)
			(xy 171.648028 -277.898892) (xy 171.644068 -277.849838) (xy 170.35526 -277.849838) (xy 170.354765 -277.874445)
			(xy 170.34687 -277.923022) (xy 170.331286 -277.969703) (xy 170.308415 -278.01328) (xy 170.27885 -278.052624)
			(xy 170.243357 -278.086716) (xy 170.202854 -278.114672) (xy 170.158392 -278.13577) (xy 170.111121 -278.149462)
			(xy 170.062266 -278.155394) (xy 170.013091 -278.153413) (xy 169.964872 -278.143569) (xy 169.918856 -278.126117)
			(xy 169.876235 -278.10151) (xy 169.838114 -278.070385) (xy 169.805479 -278.033548) (xy 169.779176 -277.991952)
			(xy 169.759885 -277.946676) (xy 169.748108 -277.898892) (xy 169.744148 -277.849838) (xy 168.45534 -277.849838)
			(xy 168.454845 -277.874445) (xy 168.44695 -277.923022) (xy 168.431366 -277.969703) (xy 168.408495 -278.01328)
			(xy 168.37893 -278.052624) (xy 168.343437 -278.086716) (xy 168.302934 -278.114672) (xy 168.258472 -278.13577)
			(xy 168.211201 -278.149462) (xy 168.162346 -278.155394) (xy 168.113171 -278.153413) (xy 168.064952 -278.143569)
			(xy 168.018936 -278.126117) (xy 167.976315 -278.10151) (xy 167.938194 -278.070385) (xy 167.905559 -278.033548)
			(xy 167.879256 -277.991952) (xy 167.859965 -277.946676) (xy 167.848188 -277.898892) (xy 167.844228 -277.849838)
			(xy 166.555166 -277.849838) (xy 166.554671 -277.874445) (xy 166.546776 -277.923022) (xy 166.531192 -277.969703)
			(xy 166.508321 -278.01328) (xy 166.478756 -278.052624) (xy 166.443263 -278.086716) (xy 166.40276 -278.114672)
			(xy 166.358298 -278.13577) (xy 166.311027 -278.149462) (xy 166.262172 -278.155394) (xy 166.212997 -278.153413)
			(xy 166.164778 -278.143569) (xy 166.118762 -278.126117) (xy 166.076141 -278.10151) (xy 166.03802 -278.070385)
			(xy 166.005385 -278.033548) (xy 165.979082 -277.991952) (xy 165.959791 -277.946676) (xy 165.948014 -277.898892)
			(xy 165.944054 -277.849838) (xy 164.655246 -277.849838) (xy 164.654751 -277.874445) (xy 164.646856 -277.923022)
			(xy 164.631272 -277.969703) (xy 164.608401 -278.01328) (xy 164.578836 -278.052624) (xy 164.543343 -278.086716)
			(xy 164.50284 -278.114672) (xy 164.458378 -278.13577) (xy 164.411107 -278.149462) (xy 164.362252 -278.155394)
			(xy 164.313077 -278.153413) (xy 164.264858 -278.143569) (xy 164.218842 -278.126117) (xy 164.176221 -278.10151)
			(xy 164.1381 -278.070385) (xy 164.105465 -278.033548) (xy 164.079162 -277.991952) (xy 164.059871 -277.946676)
			(xy 164.048094 -277.898892) (xy 164.044134 -277.849838) (xy 162.755326 -277.849838) (xy 162.754831 -277.874445)
			(xy 162.746936 -277.923022) (xy 162.731352 -277.969703) (xy 162.708481 -278.01328) (xy 162.678916 -278.052624)
			(xy 162.643423 -278.086716) (xy 162.60292 -278.114672) (xy 162.558458 -278.13577) (xy 162.511187 -278.149462)
			(xy 162.462332 -278.155394) (xy 162.413157 -278.153413) (xy 162.364938 -278.143569) (xy 162.318922 -278.126117)
			(xy 162.276301 -278.10151) (xy 162.23818 -278.070385) (xy 162.205545 -278.033548) (xy 162.179242 -277.991952)
			(xy 162.159951 -277.946676) (xy 162.148174 -277.898892) (xy 162.144214 -277.849838) (xy 160.855152 -277.849838)
			(xy 160.854657 -277.874445) (xy 160.846762 -277.923022) (xy 160.831178 -277.969703) (xy 160.808307 -278.01328)
			(xy 160.778742 -278.052624) (xy 160.743249 -278.086716) (xy 160.702746 -278.114672) (xy 160.658284 -278.13577)
			(xy 160.611013 -278.149462) (xy 160.562158 -278.155394) (xy 160.512983 -278.153413) (xy 160.464764 -278.143569)
			(xy 160.418748 -278.126117) (xy 160.376127 -278.10151) (xy 160.338006 -278.070385) (xy 160.305371 -278.033548)
			(xy 160.279068 -277.991952) (xy 160.259777 -277.946676) (xy 160.248 -277.898892) (xy 160.24404 -277.849838)
			(xy 80.855058 -277.849838) (xy 80.854563 -277.874445) (xy 80.846668 -277.923022) (xy 80.831084 -277.969703)
			(xy 80.808213 -278.01328) (xy 80.778648 -278.052624) (xy 80.743155 -278.086716) (xy 80.702652 -278.114672)
			(xy 80.65819 -278.13577) (xy 80.610919 -278.149462) (xy 80.562064 -278.155394) (xy 80.512889 -278.153413)
			(xy 80.46467 -278.143569) (xy 80.418654 -278.126117) (xy 80.376033 -278.10151) (xy 80.337912 -278.070385)
			(xy 80.305277 -278.033548) (xy 80.278974 -277.991952) (xy 80.259683 -277.946676) (xy 80.247906 -277.898892)
			(xy 80.243946 -277.849838) (xy 78.954884 -277.849838) (xy 78.954389 -277.874445) (xy 78.946494 -277.923022)
			(xy 78.93091 -277.969703) (xy 78.908039 -278.01328) (xy 78.878474 -278.052624) (xy 78.842981 -278.086716)
			(xy 78.802478 -278.114672) (xy 78.758016 -278.13577) (xy 78.710745 -278.149462) (xy 78.66189 -278.155394)
			(xy 78.612715 -278.153413) (xy 78.564496 -278.143569) (xy 78.51848 -278.126117) (xy 78.475859 -278.10151)
			(xy 78.437738 -278.070385) (xy 78.405103 -278.033548) (xy 78.3788 -277.991952) (xy 78.359509 -277.946676)
			(xy 78.347732 -277.898892) (xy 78.343772 -277.849838) (xy 77.054964 -277.849838) (xy 77.054469 -277.874445)
			(xy 77.046574 -277.923022) (xy 77.03099 -277.969703) (xy 77.008119 -278.01328) (xy 76.978554 -278.052624)
			(xy 76.943061 -278.086716) (xy 76.902558 -278.114672) (xy 76.858096 -278.13577) (xy 76.810825 -278.149462)
			(xy 76.76197 -278.155394) (xy 76.712795 -278.153413) (xy 76.664576 -278.143569) (xy 76.61856 -278.126117)
			(xy 76.575939 -278.10151) (xy 76.537818 -278.070385) (xy 76.505183 -278.033548) (xy 76.47888 -277.991952)
			(xy 76.459589 -277.946676) (xy 76.447812 -277.898892) (xy 76.443852 -277.849838) (xy 75.155044 -277.849838)
			(xy 75.154549 -277.874445) (xy 75.146654 -277.923022) (xy 75.13107 -277.969703) (xy 75.108199 -278.01328)
			(xy 75.078634 -278.052624) (xy 75.043141 -278.086716) (xy 75.002638 -278.114672) (xy 74.958176 -278.13577)
			(xy 74.910905 -278.149462) (xy 74.86205 -278.155394) (xy 74.812875 -278.153413) (xy 74.764656 -278.143569)
			(xy 74.71864 -278.126117) (xy 74.676019 -278.10151) (xy 74.637898 -278.070385) (xy 74.605263 -278.033548)
			(xy 74.57896 -277.991952) (xy 74.559669 -277.946676) (xy 74.547892 -277.898892) (xy 74.543932 -277.849838)
			(xy 73.25487 -277.849838) (xy 73.254375 -277.874445) (xy 73.24648 -277.923022) (xy 73.230896 -277.969703)
			(xy 73.208025 -278.01328) (xy 73.17846 -278.052624) (xy 73.142967 -278.086716) (xy 73.102464 -278.114672)
			(xy 73.058002 -278.13577) (xy 73.010731 -278.149462) (xy 72.961876 -278.155394) (xy 72.912701 -278.153413)
			(xy 72.864482 -278.143569) (xy 72.818466 -278.126117) (xy 72.775845 -278.10151) (xy 72.737724 -278.070385)
			(xy 72.705089 -278.033548) (xy 72.678786 -277.991952) (xy 72.659495 -277.946676) (xy 72.647718 -277.898892)
			(xy 72.643758 -277.849838) (xy 71.35495 -277.849838) (xy 71.354455 -277.874445) (xy 71.34656 -277.923022)
			(xy 71.330976 -277.969703) (xy 71.308105 -278.01328) (xy 71.27854 -278.052624) (xy 71.243047 -278.086716)
			(xy 71.202544 -278.114672) (xy 71.158082 -278.13577) (xy 71.110811 -278.149462) (xy 71.061956 -278.155394)
			(xy 71.012781 -278.153413) (xy 70.964562 -278.143569) (xy 70.918546 -278.126117) (xy 70.875925 -278.10151)
			(xy 70.837804 -278.070385) (xy 70.805169 -278.033548) (xy 70.778866 -277.991952) (xy 70.759575 -277.946676)
			(xy 70.747798 -277.898892) (xy 70.743838 -277.849838) (xy 69.45503 -277.849838) (xy 69.454535 -277.874445)
			(xy 69.44664 -277.923022) (xy 69.431056 -277.969703) (xy 69.408185 -278.01328) (xy 69.37862 -278.052624)
			(xy 69.343127 -278.086716) (xy 69.302624 -278.114672) (xy 69.258162 -278.13577) (xy 69.210891 -278.149462)
			(xy 69.162036 -278.155394) (xy 69.112861 -278.153413) (xy 69.064642 -278.143569) (xy 69.018626 -278.126117)
			(xy 68.976005 -278.10151) (xy 68.937884 -278.070385) (xy 68.905249 -278.033548) (xy 68.878946 -277.991952)
			(xy 68.859655 -277.946676) (xy 68.847878 -277.898892) (xy 68.843918 -277.849838) (xy 67.554856 -277.849838)
			(xy 67.554361 -277.874445) (xy 67.546466 -277.923022) (xy 67.530882 -277.969703) (xy 67.508011 -278.01328)
			(xy 67.478446 -278.052624) (xy 67.442953 -278.086716) (xy 67.40245 -278.114672) (xy 67.357988 -278.13577)
			(xy 67.310717 -278.149462) (xy 67.261862 -278.155394) (xy 67.212687 -278.153413) (xy 67.164468 -278.143569)
			(xy 67.118452 -278.126117) (xy 67.075831 -278.10151) (xy 67.03771 -278.070385) (xy 67.005075 -278.033548)
			(xy 66.978772 -277.991952) (xy 66.959481 -277.946676) (xy 66.947704 -277.898892) (xy 66.943744 -277.849838)
			(xy 65.654936 -277.849838) (xy 65.654441 -277.874445) (xy 65.646546 -277.923022) (xy 65.630962 -277.969703)
			(xy 65.608091 -278.01328) (xy 65.578526 -278.052624) (xy 65.543033 -278.086716) (xy 65.50253 -278.114672)
			(xy 65.458068 -278.13577) (xy 65.410797 -278.149462) (xy 65.361942 -278.155394) (xy 65.312767 -278.153413)
			(xy 65.264548 -278.143569) (xy 65.218532 -278.126117) (xy 65.175911 -278.10151) (xy 65.13779 -278.070385)
			(xy 65.105155 -278.033548) (xy 65.078852 -277.991952) (xy 65.059561 -277.946676) (xy 65.047784 -277.898892)
			(xy 65.043824 -277.849838) (xy 63.755016 -277.849838) (xy 63.754521 -277.874445) (xy 63.746626 -277.923022)
			(xy 63.731042 -277.969703) (xy 63.708171 -278.01328) (xy 63.678606 -278.052624) (xy 63.643113 -278.086716)
			(xy 63.60261 -278.114672) (xy 63.558148 -278.13577) (xy 63.510877 -278.149462) (xy 63.462022 -278.155394)
			(xy 63.412847 -278.153413) (xy 63.364628 -278.143569) (xy 63.318612 -278.126117) (xy 63.275991 -278.10151)
			(xy 63.23787 -278.070385) (xy 63.205235 -278.033548) (xy 63.178932 -277.991952) (xy 63.159641 -277.946676)
			(xy 63.147864 -277.898892) (xy 63.143904 -277.849838) (xy 61.854842 -277.849838) (xy 61.854347 -277.874445)
			(xy 61.846452 -277.923022) (xy 61.830868 -277.969703) (xy 61.807997 -278.01328) (xy 61.778432 -278.052624)
			(xy 61.742939 -278.086716) (xy 61.702436 -278.114672) (xy 61.657974 -278.13577) (xy 61.610703 -278.149462)
			(xy 61.561848 -278.155394) (xy 61.512673 -278.153413) (xy 61.464454 -278.143569) (xy 61.418438 -278.126117)
			(xy 61.375817 -278.10151) (xy 61.337696 -278.070385) (xy 61.305061 -278.033548) (xy 61.278758 -277.991952)
			(xy 61.259467 -277.946676) (xy 61.24769 -277.898892) (xy 61.24373 -277.849838) (xy 59.954922 -277.849838)
			(xy 59.954427 -277.874445) (xy 59.946532 -277.923022) (xy 59.930948 -277.969703) (xy 59.908077 -278.01328)
			(xy 59.878512 -278.052624) (xy 59.843019 -278.086716) (xy 59.802516 -278.114672) (xy 59.758054 -278.13577)
			(xy 59.710783 -278.149462) (xy 59.661928 -278.155394) (xy 59.612753 -278.153413) (xy 59.564534 -278.143569)
			(xy 59.518518 -278.126117) (xy 59.475897 -278.10151) (xy 59.437776 -278.070385) (xy 59.405141 -278.033548)
			(xy 59.378838 -277.991952) (xy 59.359547 -277.946676) (xy 59.34777 -277.898892) (xy 59.34381 -277.849838)
			(xy 58.055256 -277.849838) (xy 58.054761 -277.874445) (xy 58.046866 -277.923022) (xy 58.031282 -277.969703)
			(xy 58.008411 -278.01328) (xy 57.978846 -278.052624) (xy 57.943353 -278.086716) (xy 57.90285 -278.114672)
			(xy 57.858388 -278.13577) (xy 57.811117 -278.149462) (xy 57.762262 -278.155394) (xy 57.713087 -278.153413)
			(xy 57.664868 -278.143569) (xy 57.618852 -278.126117) (xy 57.576231 -278.10151) (xy 57.53811 -278.070385)
			(xy 57.505475 -278.033548) (xy 57.479172 -277.991952) (xy 57.459881 -277.946676) (xy 57.448104 -277.898892)
			(xy 57.444144 -277.849838) (xy 56.155082 -277.849838) (xy 56.154587 -277.874445) (xy 56.146692 -277.923022)
			(xy 56.131108 -277.969703) (xy 56.108237 -278.01328) (xy 56.078672 -278.052624) (xy 56.043179 -278.086716)
			(xy 56.002676 -278.114672) (xy 55.958214 -278.13577) (xy 55.910943 -278.149462) (xy 55.862088 -278.155394)
			(xy 55.812913 -278.153413) (xy 55.764694 -278.143569) (xy 55.718678 -278.126117) (xy 55.676057 -278.10151)
			(xy 55.637936 -278.070385) (xy 55.605301 -278.033548) (xy 55.578998 -277.991952) (xy 55.559707 -277.946676)
			(xy 55.54793 -277.898892) (xy 55.54397 -277.849838) (xy 54.255162 -277.849838) (xy 54.254667 -277.874445)
			(xy 54.246772 -277.923022) (xy 54.231188 -277.969703) (xy 54.208317 -278.01328) (xy 54.178752 -278.052624)
			(xy 54.143259 -278.086716) (xy 54.102756 -278.114672) (xy 54.058294 -278.13577) (xy 54.011023 -278.149462)
			(xy 53.962168 -278.155394) (xy 53.912993 -278.153413) (xy 53.864774 -278.143569) (xy 53.818758 -278.126117)
			(xy 53.776137 -278.10151) (xy 53.738016 -278.070385) (xy 53.705381 -278.033548) (xy 53.679078 -277.991952)
			(xy 53.659787 -277.946676) (xy 53.64801 -277.898892) (xy 53.64405 -277.849838) (xy 52.355242 -277.849838)
			(xy 52.354747 -277.874445) (xy 52.346852 -277.923022) (xy 52.331268 -277.969703) (xy 52.308397 -278.01328)
			(xy 52.278832 -278.052624) (xy 52.243339 -278.086716) (xy 52.202836 -278.114672) (xy 52.158374 -278.13577)
			(xy 52.111103 -278.149462) (xy 52.062248 -278.155394) (xy 52.013073 -278.153413) (xy 51.964854 -278.143569)
			(xy 51.918838 -278.126117) (xy 51.876217 -278.10151) (xy 51.838096 -278.070385) (xy 51.805461 -278.033548)
			(xy 51.779158 -277.991952) (xy 51.759867 -277.946676) (xy 51.74809 -277.898892) (xy 51.74413 -277.849838)
			(xy 50.455068 -277.849838) (xy 50.454573 -277.874445) (xy 50.446678 -277.923022) (xy 50.431094 -277.969703)
			(xy 50.408223 -278.01328) (xy 50.378658 -278.052624) (xy 50.343165 -278.086716) (xy 50.302662 -278.114672)
			(xy 50.2582 -278.13577) (xy 50.210929 -278.149462) (xy 50.162074 -278.155394) (xy 50.112899 -278.153413)
			(xy 50.06468 -278.143569) (xy 50.018664 -278.126117) (xy 49.976043 -278.10151) (xy 49.937922 -278.070385)
			(xy 49.905287 -278.033548) (xy 49.878984 -277.991952) (xy 49.859693 -277.946676) (xy 49.847916 -277.898892)
			(xy 49.843956 -277.849838) (xy 48.555148 -277.849838) (xy 48.554653 -277.874445) (xy 48.546758 -277.923022)
			(xy 48.531174 -277.969703) (xy 48.508303 -278.01328) (xy 48.478738 -278.052624) (xy 48.443245 -278.086716)
			(xy 48.402742 -278.114672) (xy 48.35828 -278.13577) (xy 48.311009 -278.149462) (xy 48.262154 -278.155394)
			(xy 48.212979 -278.153413) (xy 48.16476 -278.143569) (xy 48.118744 -278.126117) (xy 48.076123 -278.10151)
			(xy 48.038002 -278.070385) (xy 48.005367 -278.033548) (xy 47.979064 -277.991952) (xy 47.959773 -277.946676)
			(xy 47.947996 -277.898892) (xy 47.944036 -277.849838) (xy 46.655228 -277.849838) (xy 46.654733 -277.874445)
			(xy 46.646838 -277.923022) (xy 46.631254 -277.969703) (xy 46.608383 -278.01328) (xy 46.578818 -278.052624)
			(xy 46.543325 -278.086716) (xy 46.502822 -278.114672) (xy 46.45836 -278.13577) (xy 46.411089 -278.149462)
			(xy 46.362234 -278.155394) (xy 46.313059 -278.153413) (xy 46.26484 -278.143569) (xy 46.218824 -278.126117)
			(xy 46.176203 -278.10151) (xy 46.138082 -278.070385) (xy 46.105447 -278.033548) (xy 46.079144 -277.991952)
			(xy 46.059853 -277.946676) (xy 46.048076 -277.898892) (xy 46.044116 -277.849838) (xy 44.755054 -277.849838)
			(xy 44.754559 -277.874445) (xy 44.746664 -277.923022) (xy 44.73108 -277.969703) (xy 44.708209 -278.01328)
			(xy 44.678644 -278.052624) (xy 44.643151 -278.086716) (xy 44.602648 -278.114672) (xy 44.558186 -278.13577)
			(xy 44.510915 -278.149462) (xy 44.46206 -278.155394) (xy 44.412885 -278.153413) (xy 44.364666 -278.143569)
			(xy 44.31865 -278.126117) (xy 44.276029 -278.10151) (xy 44.237908 -278.070385) (xy 44.205273 -278.033548)
			(xy 44.17897 -277.991952) (xy 44.159679 -277.946676) (xy 44.147902 -277.898892) (xy 44.143942 -277.849838)
			(xy 0.508 -277.849838) (xy 0.508 -278.799798) (xy 44.143942 -278.799798) (xy 44.147902 -278.750744)
			(xy 44.159679 -278.70296) (xy 44.17897 -278.657684) (xy 44.205273 -278.616088) (xy 44.237908 -278.579251)
			(xy 44.276029 -278.548126) (xy 44.31865 -278.523519) (xy 44.364666 -278.506067) (xy 44.412885 -278.496223)
			(xy 44.46206 -278.494242) (xy 44.510915 -278.500174) (xy 44.558186 -278.513866) (xy 44.602648 -278.534964)
			(xy 44.643151 -278.56292) (xy 44.678644 -278.597012) (xy 44.708209 -278.636356) (xy 44.73108 -278.679933)
			(xy 44.746664 -278.726614) (xy 44.754559 -278.775191) (xy 44.755054 -278.799798) (xy 46.044116 -278.799798)
			(xy 46.048076 -278.750744) (xy 46.059853 -278.70296) (xy 46.079144 -278.657684) (xy 46.105447 -278.616088)
			(xy 46.138082 -278.579251) (xy 46.176203 -278.548126) (xy 46.218824 -278.523519) (xy 46.26484 -278.506067)
			(xy 46.313059 -278.496223) (xy 46.362234 -278.494242) (xy 46.411089 -278.500174) (xy 46.45836 -278.513866)
			(xy 46.502822 -278.534964) (xy 46.543325 -278.56292) (xy 46.578818 -278.597012) (xy 46.608383 -278.636356)
			(xy 46.631254 -278.679933) (xy 46.646838 -278.726614) (xy 46.654733 -278.775191) (xy 46.655228 -278.799798)
			(xy 47.944036 -278.799798) (xy 47.947996 -278.750744) (xy 47.959773 -278.70296) (xy 47.979064 -278.657684)
			(xy 48.005367 -278.616088) (xy 48.038002 -278.579251) (xy 48.076123 -278.548126) (xy 48.118744 -278.523519)
			(xy 48.16476 -278.506067) (xy 48.212979 -278.496223) (xy 48.262154 -278.494242) (xy 48.311009 -278.500174)
			(xy 48.35828 -278.513866) (xy 48.402742 -278.534964) (xy 48.443245 -278.56292) (xy 48.478738 -278.597012)
			(xy 48.508303 -278.636356) (xy 48.531174 -278.679933) (xy 48.546758 -278.726614) (xy 48.554653 -278.775191)
			(xy 48.555148 -278.799798) (xy 49.843956 -278.799798) (xy 49.847916 -278.750744) (xy 49.859693 -278.70296)
			(xy 49.878984 -278.657684) (xy 49.905287 -278.616088) (xy 49.937922 -278.579251) (xy 49.976043 -278.548126)
			(xy 50.018664 -278.523519) (xy 50.06468 -278.506067) (xy 50.112899 -278.496223) (xy 50.162074 -278.494242)
			(xy 50.210929 -278.500174) (xy 50.2582 -278.513866) (xy 50.302662 -278.534964) (xy 50.343165 -278.56292)
			(xy 50.378658 -278.597012) (xy 50.408223 -278.636356) (xy 50.431094 -278.679933) (xy 50.446678 -278.726614)
			(xy 50.454573 -278.775191) (xy 50.455068 -278.799798) (xy 51.74413 -278.799798) (xy 51.74809 -278.750744)
			(xy 51.759867 -278.70296) (xy 51.779158 -278.657684) (xy 51.805461 -278.616088) (xy 51.838096 -278.579251)
			(xy 51.876217 -278.548126) (xy 51.918838 -278.523519) (xy 51.964854 -278.506067) (xy 52.013073 -278.496223)
			(xy 52.062248 -278.494242) (xy 52.111103 -278.500174) (xy 52.158374 -278.513866) (xy 52.202836 -278.534964)
			(xy 52.243339 -278.56292) (xy 52.278832 -278.597012) (xy 52.308397 -278.636356) (xy 52.331268 -278.679933)
			(xy 52.346852 -278.726614) (xy 52.354747 -278.775191) (xy 52.355242 -278.799798) (xy 53.64405 -278.799798)
			(xy 53.64801 -278.750744) (xy 53.659787 -278.70296) (xy 53.679078 -278.657684) (xy 53.705381 -278.616088)
			(xy 53.738016 -278.579251) (xy 53.776137 -278.548126) (xy 53.818758 -278.523519) (xy 53.864774 -278.506067)
			(xy 53.912993 -278.496223) (xy 53.962168 -278.494242) (xy 54.011023 -278.500174) (xy 54.058294 -278.513866)
			(xy 54.102756 -278.534964) (xy 54.143259 -278.56292) (xy 54.178752 -278.597012) (xy 54.208317 -278.636356)
			(xy 54.231188 -278.679933) (xy 54.246772 -278.726614) (xy 54.254667 -278.775191) (xy 54.255162 -278.799798)
			(xy 55.54397 -278.799798) (xy 55.54793 -278.750744) (xy 55.559707 -278.70296) (xy 55.578998 -278.657684)
			(xy 55.605301 -278.616088) (xy 55.637936 -278.579251) (xy 55.676057 -278.548126) (xy 55.718678 -278.523519)
			(xy 55.764694 -278.506067) (xy 55.812913 -278.496223) (xy 55.862088 -278.494242) (xy 55.910943 -278.500174)
			(xy 55.958214 -278.513866) (xy 56.002676 -278.534964) (xy 56.043179 -278.56292) (xy 56.078672 -278.597012)
			(xy 56.108237 -278.636356) (xy 56.131108 -278.679933) (xy 56.146692 -278.726614) (xy 56.154587 -278.775191)
			(xy 56.155082 -278.799798) (xy 57.444144 -278.799798) (xy 57.448104 -278.750744) (xy 57.459881 -278.70296)
			(xy 57.479172 -278.657684) (xy 57.505475 -278.616088) (xy 57.53811 -278.579251) (xy 57.576231 -278.548126)
			(xy 57.618852 -278.523519) (xy 57.664868 -278.506067) (xy 57.713087 -278.496223) (xy 57.762262 -278.494242)
			(xy 57.811117 -278.500174) (xy 57.858388 -278.513866) (xy 57.90285 -278.534964) (xy 57.943353 -278.56292)
			(xy 57.978846 -278.597012) (xy 58.008411 -278.636356) (xy 58.031282 -278.679933) (xy 58.046866 -278.726614)
			(xy 58.054761 -278.775191) (xy 58.055256 -278.799798) (xy 59.34381 -278.799798) (xy 59.34777 -278.750744)
			(xy 59.359547 -278.70296) (xy 59.378838 -278.657684) (xy 59.405141 -278.616088) (xy 59.437776 -278.579251)
			(xy 59.475897 -278.548126) (xy 59.518518 -278.523519) (xy 59.564534 -278.506067) (xy 59.612753 -278.496223)
			(xy 59.661928 -278.494242) (xy 59.710783 -278.500174) (xy 59.758054 -278.513866) (xy 59.802516 -278.534964)
			(xy 59.843019 -278.56292) (xy 59.878512 -278.597012) (xy 59.908077 -278.636356) (xy 59.930948 -278.679933)
			(xy 59.946532 -278.726614) (xy 59.954427 -278.775191) (xy 59.954922 -278.799798) (xy 61.24373 -278.799798)
			(xy 61.24769 -278.750744) (xy 61.259467 -278.70296) (xy 61.278758 -278.657684) (xy 61.305061 -278.616088)
			(xy 61.337696 -278.579251) (xy 61.375817 -278.548126) (xy 61.418438 -278.523519) (xy 61.464454 -278.506067)
			(xy 61.512673 -278.496223) (xy 61.561848 -278.494242) (xy 61.610703 -278.500174) (xy 61.657974 -278.513866)
			(xy 61.702436 -278.534964) (xy 61.742939 -278.56292) (xy 61.778432 -278.597012) (xy 61.807997 -278.636356)
			(xy 61.830868 -278.679933) (xy 61.846452 -278.726614) (xy 61.854347 -278.775191) (xy 61.854842 -278.799798)
			(xy 63.143904 -278.799798) (xy 63.147864 -278.750744) (xy 63.159641 -278.70296) (xy 63.178932 -278.657684)
			(xy 63.205235 -278.616088) (xy 63.23787 -278.579251) (xy 63.275991 -278.548126) (xy 63.318612 -278.523519)
			(xy 63.364628 -278.506067) (xy 63.412847 -278.496223) (xy 63.462022 -278.494242) (xy 63.510877 -278.500174)
			(xy 63.558148 -278.513866) (xy 63.60261 -278.534964) (xy 63.643113 -278.56292) (xy 63.678606 -278.597012)
			(xy 63.708171 -278.636356) (xy 63.731042 -278.679933) (xy 63.746626 -278.726614) (xy 63.754521 -278.775191)
			(xy 63.755016 -278.799798) (xy 65.043824 -278.799798) (xy 65.047784 -278.750744) (xy 65.059561 -278.70296)
			(xy 65.078852 -278.657684) (xy 65.105155 -278.616088) (xy 65.13779 -278.579251) (xy 65.175911 -278.548126)
			(xy 65.218532 -278.523519) (xy 65.264548 -278.506067) (xy 65.312767 -278.496223) (xy 65.361942 -278.494242)
			(xy 65.410797 -278.500174) (xy 65.458068 -278.513866) (xy 65.50253 -278.534964) (xy 65.543033 -278.56292)
			(xy 65.578526 -278.597012) (xy 65.608091 -278.636356) (xy 65.630962 -278.679933) (xy 65.646546 -278.726614)
			(xy 65.654441 -278.775191) (xy 65.654936 -278.799798) (xy 66.943744 -278.799798) (xy 66.947704 -278.750744)
			(xy 66.959481 -278.70296) (xy 66.978772 -278.657684) (xy 67.005075 -278.616088) (xy 67.03771 -278.579251)
			(xy 67.075831 -278.548126) (xy 67.118452 -278.523519) (xy 67.164468 -278.506067) (xy 67.212687 -278.496223)
			(xy 67.261862 -278.494242) (xy 67.310717 -278.500174) (xy 67.357988 -278.513866) (xy 67.40245 -278.534964)
			(xy 67.442953 -278.56292) (xy 67.478446 -278.597012) (xy 67.508011 -278.636356) (xy 67.530882 -278.679933)
			(xy 67.546466 -278.726614) (xy 67.554361 -278.775191) (xy 67.554856 -278.799798) (xy 68.843918 -278.799798)
			(xy 68.847878 -278.750744) (xy 68.859655 -278.70296) (xy 68.878946 -278.657684) (xy 68.905249 -278.616088)
			(xy 68.937884 -278.579251) (xy 68.976005 -278.548126) (xy 69.018626 -278.523519) (xy 69.064642 -278.506067)
			(xy 69.112861 -278.496223) (xy 69.162036 -278.494242) (xy 69.210891 -278.500174) (xy 69.258162 -278.513866)
			(xy 69.302624 -278.534964) (xy 69.343127 -278.56292) (xy 69.37862 -278.597012) (xy 69.408185 -278.636356)
			(xy 69.431056 -278.679933) (xy 69.44664 -278.726614) (xy 69.454535 -278.775191) (xy 69.45503 -278.799798)
			(xy 70.743838 -278.799798) (xy 70.747798 -278.750744) (xy 70.759575 -278.70296) (xy 70.778866 -278.657684)
			(xy 70.805169 -278.616088) (xy 70.837804 -278.579251) (xy 70.875925 -278.548126) (xy 70.918546 -278.523519)
			(xy 70.964562 -278.506067) (xy 71.012781 -278.496223) (xy 71.061956 -278.494242) (xy 71.110811 -278.500174)
			(xy 71.158082 -278.513866) (xy 71.202544 -278.534964) (xy 71.243047 -278.56292) (xy 71.27854 -278.597012)
			(xy 71.308105 -278.636356) (xy 71.330976 -278.679933) (xy 71.34656 -278.726614) (xy 71.354455 -278.775191)
			(xy 71.35495 -278.799798) (xy 72.643758 -278.799798) (xy 72.647718 -278.750744) (xy 72.659495 -278.70296)
			(xy 72.678786 -278.657684) (xy 72.705089 -278.616088) (xy 72.737724 -278.579251) (xy 72.775845 -278.548126)
			(xy 72.818466 -278.523519) (xy 72.864482 -278.506067) (xy 72.912701 -278.496223) (xy 72.961876 -278.494242)
			(xy 73.010731 -278.500174) (xy 73.058002 -278.513866) (xy 73.102464 -278.534964) (xy 73.142967 -278.56292)
			(xy 73.17846 -278.597012) (xy 73.208025 -278.636356) (xy 73.230896 -278.679933) (xy 73.24648 -278.726614)
			(xy 73.254375 -278.775191) (xy 73.25487 -278.799798) (xy 74.543932 -278.799798) (xy 74.547892 -278.750744)
			(xy 74.559669 -278.70296) (xy 74.57896 -278.657684) (xy 74.605263 -278.616088) (xy 74.637898 -278.579251)
			(xy 74.676019 -278.548126) (xy 74.71864 -278.523519) (xy 74.764656 -278.506067) (xy 74.812875 -278.496223)
			(xy 74.86205 -278.494242) (xy 74.910905 -278.500174) (xy 74.958176 -278.513866) (xy 75.002638 -278.534964)
			(xy 75.043141 -278.56292) (xy 75.078634 -278.597012) (xy 75.108199 -278.636356) (xy 75.13107 -278.679933)
			(xy 75.146654 -278.726614) (xy 75.154549 -278.775191) (xy 75.155044 -278.799798) (xy 76.443852 -278.799798)
			(xy 76.447812 -278.750744) (xy 76.459589 -278.70296) (xy 76.47888 -278.657684) (xy 76.505183 -278.616088)
			(xy 76.537818 -278.579251) (xy 76.575939 -278.548126) (xy 76.61856 -278.523519) (xy 76.664576 -278.506067)
			(xy 76.712795 -278.496223) (xy 76.76197 -278.494242) (xy 76.810825 -278.500174) (xy 76.858096 -278.513866)
			(xy 76.902558 -278.534964) (xy 76.943061 -278.56292) (xy 76.978554 -278.597012) (xy 77.008119 -278.636356)
			(xy 77.03099 -278.679933) (xy 77.046574 -278.726614) (xy 77.054469 -278.775191) (xy 77.054964 -278.799798)
			(xy 78.343772 -278.799798) (xy 78.347732 -278.750744) (xy 78.359509 -278.70296) (xy 78.3788 -278.657684)
			(xy 78.405103 -278.616088) (xy 78.437738 -278.579251) (xy 78.475859 -278.548126) (xy 78.51848 -278.523519)
			(xy 78.564496 -278.506067) (xy 78.612715 -278.496223) (xy 78.66189 -278.494242) (xy 78.710745 -278.500174)
			(xy 78.758016 -278.513866) (xy 78.802478 -278.534964) (xy 78.842981 -278.56292) (xy 78.878474 -278.597012)
			(xy 78.908039 -278.636356) (xy 78.93091 -278.679933) (xy 78.946494 -278.726614) (xy 78.954389 -278.775191)
			(xy 78.954884 -278.799798) (xy 80.243946 -278.799798) (xy 80.247906 -278.750744) (xy 80.259683 -278.70296)
			(xy 80.278974 -278.657684) (xy 80.305277 -278.616088) (xy 80.337912 -278.579251) (xy 80.376033 -278.548126)
			(xy 80.418654 -278.523519) (xy 80.46467 -278.506067) (xy 80.512889 -278.496223) (xy 80.562064 -278.494242)
			(xy 80.610919 -278.500174) (xy 80.65819 -278.513866) (xy 80.702652 -278.534964) (xy 80.743155 -278.56292)
			(xy 80.778648 -278.597012) (xy 80.808213 -278.636356) (xy 80.831084 -278.679933) (xy 80.846668 -278.726614)
			(xy 80.854563 -278.775191) (xy 80.855058 -278.799798) (xy 160.24404 -278.799798) (xy 160.248 -278.750744)
			(xy 160.259777 -278.70296) (xy 160.279068 -278.657684) (xy 160.305371 -278.616088) (xy 160.338006 -278.579251)
			(xy 160.376127 -278.548126) (xy 160.418748 -278.523519) (xy 160.464764 -278.506067) (xy 160.512983 -278.496223)
			(xy 160.562158 -278.494242) (xy 160.611013 -278.500174) (xy 160.658284 -278.513866) (xy 160.702746 -278.534964)
			(xy 160.743249 -278.56292) (xy 160.778742 -278.597012) (xy 160.808307 -278.636356) (xy 160.831178 -278.679933)
			(xy 160.846762 -278.726614) (xy 160.854657 -278.775191) (xy 160.855152 -278.799798) (xy 162.144214 -278.799798)
			(xy 162.148174 -278.750744) (xy 162.159951 -278.70296) (xy 162.179242 -278.657684) (xy 162.205545 -278.616088)
			(xy 162.23818 -278.579251) (xy 162.276301 -278.548126) (xy 162.318922 -278.523519) (xy 162.364938 -278.506067)
			(xy 162.413157 -278.496223) (xy 162.462332 -278.494242) (xy 162.511187 -278.500174) (xy 162.558458 -278.513866)
			(xy 162.60292 -278.534964) (xy 162.643423 -278.56292) (xy 162.678916 -278.597012) (xy 162.708481 -278.636356)
			(xy 162.731352 -278.679933) (xy 162.746936 -278.726614) (xy 162.754831 -278.775191) (xy 162.755326 -278.799798)
			(xy 164.044134 -278.799798) (xy 164.048094 -278.750744) (xy 164.059871 -278.70296) (xy 164.079162 -278.657684)
			(xy 164.105465 -278.616088) (xy 164.1381 -278.579251) (xy 164.176221 -278.548126) (xy 164.218842 -278.523519)
			(xy 164.264858 -278.506067) (xy 164.313077 -278.496223) (xy 164.362252 -278.494242) (xy 164.411107 -278.500174)
			(xy 164.458378 -278.513866) (xy 164.50284 -278.534964) (xy 164.543343 -278.56292) (xy 164.578836 -278.597012)
			(xy 164.608401 -278.636356) (xy 164.631272 -278.679933) (xy 164.646856 -278.726614) (xy 164.654751 -278.775191)
			(xy 164.655246 -278.799798) (xy 165.944054 -278.799798) (xy 165.948014 -278.750744) (xy 165.959791 -278.70296)
			(xy 165.979082 -278.657684) (xy 166.005385 -278.616088) (xy 166.03802 -278.579251) (xy 166.076141 -278.548126)
			(xy 166.118762 -278.523519) (xy 166.164778 -278.506067) (xy 166.212997 -278.496223) (xy 166.262172 -278.494242)
			(xy 166.311027 -278.500174) (xy 166.358298 -278.513866) (xy 166.40276 -278.534964) (xy 166.443263 -278.56292)
			(xy 166.478756 -278.597012) (xy 166.508321 -278.636356) (xy 166.531192 -278.679933) (xy 166.546776 -278.726614)
			(xy 166.554671 -278.775191) (xy 166.555166 -278.799798) (xy 167.844228 -278.799798) (xy 167.848188 -278.750744)
			(xy 167.859965 -278.70296) (xy 167.879256 -278.657684) (xy 167.905559 -278.616088) (xy 167.938194 -278.579251)
			(xy 167.976315 -278.548126) (xy 168.018936 -278.523519) (xy 168.064952 -278.506067) (xy 168.113171 -278.496223)
			(xy 168.162346 -278.494242) (xy 168.211201 -278.500174) (xy 168.258472 -278.513866) (xy 168.302934 -278.534964)
			(xy 168.343437 -278.56292) (xy 168.37893 -278.597012) (xy 168.408495 -278.636356) (xy 168.431366 -278.679933)
			(xy 168.44695 -278.726614) (xy 168.454845 -278.775191) (xy 168.45534 -278.799798) (xy 169.744148 -278.799798)
			(xy 169.748108 -278.750744) (xy 169.759885 -278.70296) (xy 169.779176 -278.657684) (xy 169.805479 -278.616088)
			(xy 169.838114 -278.579251) (xy 169.876235 -278.548126) (xy 169.918856 -278.523519) (xy 169.964872 -278.506067)
			(xy 170.013091 -278.496223) (xy 170.062266 -278.494242) (xy 170.111121 -278.500174) (xy 170.158392 -278.513866)
			(xy 170.202854 -278.534964) (xy 170.243357 -278.56292) (xy 170.27885 -278.597012) (xy 170.308415 -278.636356)
			(xy 170.331286 -278.679933) (xy 170.34687 -278.726614) (xy 170.354765 -278.775191) (xy 170.35526 -278.799798)
			(xy 171.644068 -278.799798) (xy 171.648028 -278.750744) (xy 171.659805 -278.70296) (xy 171.679096 -278.657684)
			(xy 171.705399 -278.616088) (xy 171.738034 -278.579251) (xy 171.776155 -278.548126) (xy 171.818776 -278.523519)
			(xy 171.864792 -278.506067) (xy 171.913011 -278.496223) (xy 171.962186 -278.494242) (xy 172.011041 -278.500174)
			(xy 172.058312 -278.513866) (xy 172.102774 -278.534964) (xy 172.143277 -278.56292) (xy 172.17877 -278.597012)
			(xy 172.208335 -278.636356) (xy 172.231206 -278.679933) (xy 172.24679 -278.726614) (xy 172.254685 -278.775191)
			(xy 172.25518 -278.799798) (xy 173.544242 -278.799798) (xy 173.548202 -278.750744) (xy 173.559979 -278.70296)
			(xy 173.57927 -278.657684) (xy 173.605573 -278.616088) (xy 173.638208 -278.579251) (xy 173.676329 -278.548126)
			(xy 173.71895 -278.523519) (xy 173.764966 -278.506067) (xy 173.813185 -278.496223) (xy 173.86236 -278.494242)
			(xy 173.911215 -278.500174) (xy 173.958486 -278.513866) (xy 174.002948 -278.534964) (xy 174.043451 -278.56292)
			(xy 174.078944 -278.597012) (xy 174.108509 -278.636356) (xy 174.13138 -278.679933) (xy 174.146964 -278.726614)
			(xy 174.154859 -278.775191) (xy 174.155354 -278.799798) (xy 175.443908 -278.799798) (xy 175.447868 -278.750744)
			(xy 175.459645 -278.70296) (xy 175.478936 -278.657684) (xy 175.505239 -278.616088) (xy 175.537874 -278.579251)
			(xy 175.575995 -278.548126) (xy 175.618616 -278.523519) (xy 175.664632 -278.506067) (xy 175.712851 -278.496223)
			(xy 175.762026 -278.494242) (xy 175.810881 -278.500174) (xy 175.858152 -278.513866) (xy 175.902614 -278.534964)
			(xy 175.943117 -278.56292) (xy 175.97861 -278.597012) (xy 176.008175 -278.636356) (xy 176.031046 -278.679933)
			(xy 176.04663 -278.726614) (xy 176.054525 -278.775191) (xy 176.05502 -278.799798) (xy 177.343828 -278.799798)
			(xy 177.347788 -278.750744) (xy 177.359565 -278.70296) (xy 177.378856 -278.657684) (xy 177.405159 -278.616088)
			(xy 177.437794 -278.579251) (xy 177.475915 -278.548126) (xy 177.518536 -278.523519) (xy 177.564552 -278.506067)
			(xy 177.612771 -278.496223) (xy 177.661946 -278.494242) (xy 177.710801 -278.500174) (xy 177.758072 -278.513866)
			(xy 177.802534 -278.534964) (xy 177.843037 -278.56292) (xy 177.87853 -278.597012) (xy 177.908095 -278.636356)
			(xy 177.930966 -278.679933) (xy 177.94655 -278.726614) (xy 177.954445 -278.775191) (xy 177.95494 -278.799798)
			(xy 179.244002 -278.799798) (xy 179.247962 -278.750744) (xy 179.259739 -278.70296) (xy 179.27903 -278.657684)
			(xy 179.305333 -278.616088) (xy 179.337968 -278.579251) (xy 179.376089 -278.548126) (xy 179.41871 -278.523519)
			(xy 179.464726 -278.506067) (xy 179.512945 -278.496223) (xy 179.56212 -278.494242) (xy 179.610975 -278.500174)
			(xy 179.658246 -278.513866) (xy 179.702708 -278.534964) (xy 179.743211 -278.56292) (xy 179.778704 -278.597012)
			(xy 179.808269 -278.636356) (xy 179.83114 -278.679933) (xy 179.846724 -278.726614) (xy 179.854619 -278.775191)
			(xy 179.855114 -278.799798) (xy 181.143922 -278.799798) (xy 181.147882 -278.750744) (xy 181.159659 -278.70296)
			(xy 181.17895 -278.657684) (xy 181.205253 -278.616088) (xy 181.237888 -278.579251) (xy 181.276009 -278.548126)
			(xy 181.31863 -278.523519) (xy 181.364646 -278.506067) (xy 181.412865 -278.496223) (xy 181.46204 -278.494242)
			(xy 181.510895 -278.500174) (xy 181.558166 -278.513866) (xy 181.602628 -278.534964) (xy 181.643131 -278.56292)
			(xy 181.678624 -278.597012) (xy 181.708189 -278.636356) (xy 181.73106 -278.679933) (xy 181.746644 -278.726614)
			(xy 181.754539 -278.775191) (xy 181.755034 -278.799798) (xy 183.043842 -278.799798) (xy 183.047802 -278.750744)
			(xy 183.059579 -278.70296) (xy 183.07887 -278.657684) (xy 183.105173 -278.616088) (xy 183.137808 -278.579251)
			(xy 183.175929 -278.548126) (xy 183.21855 -278.523519) (xy 183.264566 -278.506067) (xy 183.312785 -278.496223)
			(xy 183.36196 -278.494242) (xy 183.410815 -278.500174) (xy 183.458086 -278.513866) (xy 183.502548 -278.534964)
			(xy 183.543051 -278.56292) (xy 183.578544 -278.597012) (xy 183.608109 -278.636356) (xy 183.63098 -278.679933)
			(xy 183.646564 -278.726614) (xy 183.654459 -278.775191) (xy 183.654954 -278.799798) (xy 184.944016 -278.799798)
			(xy 184.947976 -278.750744) (xy 184.959753 -278.70296) (xy 184.979044 -278.657684) (xy 185.005347 -278.616088)
			(xy 185.037982 -278.579251) (xy 185.076103 -278.548126) (xy 185.118724 -278.523519) (xy 185.16474 -278.506067)
			(xy 185.212959 -278.496223) (xy 185.262134 -278.494242) (xy 185.310989 -278.500174) (xy 185.35826 -278.513866)
			(xy 185.402722 -278.534964) (xy 185.443225 -278.56292) (xy 185.478718 -278.597012) (xy 185.508283 -278.636356)
			(xy 185.531154 -278.679933) (xy 185.546738 -278.726614) (xy 185.554633 -278.775191) (xy 185.555128 -278.799798)
			(xy 186.843936 -278.799798) (xy 186.847896 -278.750744) (xy 186.859673 -278.70296) (xy 186.878964 -278.657684)
			(xy 186.905267 -278.616088) (xy 186.937902 -278.579251) (xy 186.976023 -278.548126) (xy 187.018644 -278.523519)
			(xy 187.06466 -278.506067) (xy 187.112879 -278.496223) (xy 187.162054 -278.494242) (xy 187.210909 -278.500174)
			(xy 187.25818 -278.513866) (xy 187.302642 -278.534964) (xy 187.343145 -278.56292) (xy 187.378638 -278.597012)
			(xy 187.408203 -278.636356) (xy 187.431074 -278.679933) (xy 187.446658 -278.726614) (xy 187.454553 -278.775191)
			(xy 187.455048 -278.799798) (xy 188.743856 -278.799798) (xy 188.747816 -278.750744) (xy 188.759593 -278.70296)
			(xy 188.778884 -278.657684) (xy 188.805187 -278.616088) (xy 188.837822 -278.579251) (xy 188.875943 -278.548126)
			(xy 188.918564 -278.523519) (xy 188.96458 -278.506067) (xy 189.012799 -278.496223) (xy 189.061974 -278.494242)
			(xy 189.110829 -278.500174) (xy 189.1581 -278.513866) (xy 189.202562 -278.534964) (xy 189.243065 -278.56292)
			(xy 189.278558 -278.597012) (xy 189.308123 -278.636356) (xy 189.330994 -278.679933) (xy 189.346578 -278.726614)
			(xy 189.354473 -278.775191) (xy 189.354968 -278.799798) (xy 190.64403 -278.799798) (xy 190.64799 -278.750744)
			(xy 190.659767 -278.70296) (xy 190.679058 -278.657684) (xy 190.705361 -278.616088) (xy 190.737996 -278.579251)
			(xy 190.776117 -278.548126) (xy 190.818738 -278.523519) (xy 190.864754 -278.506067) (xy 190.912973 -278.496223)
			(xy 190.962148 -278.494242) (xy 191.011003 -278.500174) (xy 191.058274 -278.513866) (xy 191.102736 -278.534964)
			(xy 191.143239 -278.56292) (xy 191.178732 -278.597012) (xy 191.208297 -278.636356) (xy 191.231168 -278.679933)
			(xy 191.246752 -278.726614) (xy 191.254647 -278.775191) (xy 191.255142 -278.799798) (xy 192.54395 -278.799798)
			(xy 192.54791 -278.750744) (xy 192.559687 -278.70296) (xy 192.578978 -278.657684) (xy 192.605281 -278.616088)
			(xy 192.637916 -278.579251) (xy 192.676037 -278.548126) (xy 192.718658 -278.523519) (xy 192.764674 -278.506067)
			(xy 192.812893 -278.496223) (xy 192.862068 -278.494242) (xy 192.910923 -278.500174) (xy 192.958194 -278.513866)
			(xy 193.002656 -278.534964) (xy 193.043159 -278.56292) (xy 193.078652 -278.597012) (xy 193.108217 -278.636356)
			(xy 193.131088 -278.679933) (xy 193.146672 -278.726614) (xy 193.154567 -278.775191) (xy 193.155062 -278.799798)
			(xy 194.44387 -278.799798) (xy 194.44783 -278.750744) (xy 194.459607 -278.70296) (xy 194.478898 -278.657684)
			(xy 194.505201 -278.616088) (xy 194.537836 -278.579251) (xy 194.575957 -278.548126) (xy 194.618578 -278.523519)
			(xy 194.664594 -278.506067) (xy 194.712813 -278.496223) (xy 194.761988 -278.494242) (xy 194.810843 -278.500174)
			(xy 194.858114 -278.513866) (xy 194.902576 -278.534964) (xy 194.943079 -278.56292) (xy 194.978572 -278.597012)
			(xy 195.008137 -278.636356) (xy 195.031008 -278.679933) (xy 195.046592 -278.726614) (xy 195.054487 -278.775191)
			(xy 195.054982 -278.799798) (xy 196.344044 -278.799798) (xy 196.348004 -278.750744) (xy 196.359781 -278.70296)
			(xy 196.379072 -278.657684) (xy 196.405375 -278.616088) (xy 196.43801 -278.579251) (xy 196.476131 -278.548126)
			(xy 196.518752 -278.523519) (xy 196.564768 -278.506067) (xy 196.612987 -278.496223) (xy 196.662162 -278.494242)
			(xy 196.711017 -278.500174) (xy 196.758288 -278.513866) (xy 196.80275 -278.534964) (xy 196.843253 -278.56292)
			(xy 196.878746 -278.597012) (xy 196.908311 -278.636356) (xy 196.931182 -278.679933) (xy 196.946766 -278.726614)
			(xy 196.954661 -278.775191) (xy 196.955156 -278.799798) (xy 276.343884 -278.799798) (xy 276.347844 -278.750744)
			(xy 276.359621 -278.70296) (xy 276.378912 -278.657684) (xy 276.405215 -278.616088) (xy 276.43785 -278.579251)
			(xy 276.475971 -278.548126) (xy 276.518592 -278.523519) (xy 276.564608 -278.506067) (xy 276.612827 -278.496223)
			(xy 276.662002 -278.494242) (xy 276.710857 -278.500174) (xy 276.758128 -278.513866) (xy 276.80259 -278.534964)
			(xy 276.843093 -278.56292) (xy 276.878586 -278.597012) (xy 276.908151 -278.636356) (xy 276.931022 -278.679933)
			(xy 276.946606 -278.726614) (xy 276.954501 -278.775191) (xy 276.954996 -278.799798) (xy 278.244058 -278.799798)
			(xy 278.248018 -278.750744) (xy 278.259795 -278.70296) (xy 278.279086 -278.657684) (xy 278.305389 -278.616088)
			(xy 278.338024 -278.579251) (xy 278.376145 -278.548126) (xy 278.418766 -278.523519) (xy 278.464782 -278.506067)
			(xy 278.513001 -278.496223) (xy 278.562176 -278.494242) (xy 278.611031 -278.500174) (xy 278.658302 -278.513866)
			(xy 278.702764 -278.534964) (xy 278.743267 -278.56292) (xy 278.77876 -278.597012) (xy 278.808325 -278.636356)
			(xy 278.831196 -278.679933) (xy 278.84678 -278.726614) (xy 278.854675 -278.775191) (xy 278.85517 -278.799798)
			(xy 280.143978 -278.799798) (xy 280.147938 -278.750744) (xy 280.159715 -278.70296) (xy 280.179006 -278.657684)
			(xy 280.205309 -278.616088) (xy 280.237944 -278.579251) (xy 280.276065 -278.548126) (xy 280.318686 -278.523519)
			(xy 280.364702 -278.506067) (xy 280.412921 -278.496223) (xy 280.462096 -278.494242) (xy 280.510951 -278.500174)
			(xy 280.558222 -278.513866) (xy 280.602684 -278.534964) (xy 280.643187 -278.56292) (xy 280.67868 -278.597012)
			(xy 280.708245 -278.636356) (xy 280.731116 -278.679933) (xy 280.7467 -278.726614) (xy 280.754595 -278.775191)
			(xy 280.75509 -278.799798) (xy 282.043898 -278.799798) (xy 282.047858 -278.750744) (xy 282.059635 -278.70296)
			(xy 282.078926 -278.657684) (xy 282.105229 -278.616088) (xy 282.137864 -278.579251) (xy 282.175985 -278.548126)
			(xy 282.218606 -278.523519) (xy 282.264622 -278.506067) (xy 282.312841 -278.496223) (xy 282.362016 -278.494242)
			(xy 282.410871 -278.500174) (xy 282.458142 -278.513866) (xy 282.502604 -278.534964) (xy 282.543107 -278.56292)
			(xy 282.5786 -278.597012) (xy 282.608165 -278.636356) (xy 282.631036 -278.679933) (xy 282.64662 -278.726614)
			(xy 282.654515 -278.775191) (xy 282.65501 -278.799798) (xy 283.944072 -278.799798) (xy 283.948032 -278.750744)
			(xy 283.959809 -278.70296) (xy 283.9791 -278.657684) (xy 284.005403 -278.616088) (xy 284.038038 -278.579251)
			(xy 284.076159 -278.548126) (xy 284.11878 -278.523519) (xy 284.164796 -278.506067) (xy 284.213015 -278.496223)
			(xy 284.26219 -278.494242) (xy 284.311045 -278.500174) (xy 284.358316 -278.513866) (xy 284.402778 -278.534964)
			(xy 284.443281 -278.56292) (xy 284.478774 -278.597012) (xy 284.508339 -278.636356) (xy 284.53121 -278.679933)
			(xy 284.546794 -278.726614) (xy 284.554689 -278.775191) (xy 284.555184 -278.799798) (xy 285.843992 -278.799798)
			(xy 285.847952 -278.750744) (xy 285.859729 -278.70296) (xy 285.87902 -278.657684) (xy 285.905323 -278.616088)
			(xy 285.937958 -278.579251) (xy 285.976079 -278.548126) (xy 286.0187 -278.523519) (xy 286.064716 -278.506067)
			(xy 286.112935 -278.496223) (xy 286.16211 -278.494242) (xy 286.210965 -278.500174) (xy 286.258236 -278.513866)
			(xy 286.302698 -278.534964) (xy 286.343201 -278.56292) (xy 286.378694 -278.597012) (xy 286.408259 -278.636356)
			(xy 286.43113 -278.679933) (xy 286.446714 -278.726614) (xy 286.454609 -278.775191) (xy 286.455104 -278.799798)
			(xy 287.743912 -278.799798) (xy 287.747872 -278.750744) (xy 287.759649 -278.70296) (xy 287.77894 -278.657684)
			(xy 287.805243 -278.616088) (xy 287.837878 -278.579251) (xy 287.875999 -278.548126) (xy 287.91862 -278.523519)
			(xy 287.964636 -278.506067) (xy 288.012855 -278.496223) (xy 288.06203 -278.494242) (xy 288.110885 -278.500174)
			(xy 288.158156 -278.513866) (xy 288.202618 -278.534964) (xy 288.243121 -278.56292) (xy 288.278614 -278.597012)
			(xy 288.308179 -278.636356) (xy 288.33105 -278.679933) (xy 288.346634 -278.726614) (xy 288.354529 -278.775191)
			(xy 288.355024 -278.799798) (xy 289.644086 -278.799798) (xy 289.648046 -278.750744) (xy 289.659823 -278.70296)
			(xy 289.679114 -278.657684) (xy 289.705417 -278.616088) (xy 289.738052 -278.579251) (xy 289.776173 -278.548126)
			(xy 289.818794 -278.523519) (xy 289.86481 -278.506067) (xy 289.913029 -278.496223) (xy 289.962204 -278.494242)
			(xy 290.011059 -278.500174) (xy 290.05833 -278.513866) (xy 290.102792 -278.534964) (xy 290.143295 -278.56292)
			(xy 290.178788 -278.597012) (xy 290.208353 -278.636356) (xy 290.231224 -278.679933) (xy 290.246808 -278.726614)
			(xy 290.254703 -278.775191) (xy 290.255198 -278.799798) (xy 291.543752 -278.799798) (xy 291.547712 -278.750744)
			(xy 291.559489 -278.70296) (xy 291.57878 -278.657684) (xy 291.605083 -278.616088) (xy 291.637718 -278.579251)
			(xy 291.675839 -278.548126) (xy 291.71846 -278.523519) (xy 291.764476 -278.506067) (xy 291.812695 -278.496223)
			(xy 291.86187 -278.494242) (xy 291.910725 -278.500174) (xy 291.957996 -278.513866) (xy 292.002458 -278.534964)
			(xy 292.042961 -278.56292) (xy 292.078454 -278.597012) (xy 292.108019 -278.636356) (xy 292.13089 -278.679933)
			(xy 292.146474 -278.726614) (xy 292.154369 -278.775191) (xy 292.154864 -278.799798) (xy 293.443672 -278.799798)
			(xy 293.447632 -278.750744) (xy 293.459409 -278.70296) (xy 293.4787 -278.657684) (xy 293.505003 -278.616088)
			(xy 293.537638 -278.579251) (xy 293.575759 -278.548126) (xy 293.61838 -278.523519) (xy 293.664396 -278.506067)
			(xy 293.712615 -278.496223) (xy 293.76179 -278.494242) (xy 293.810645 -278.500174) (xy 293.857916 -278.513866)
			(xy 293.902378 -278.534964) (xy 293.942881 -278.56292) (xy 293.978374 -278.597012) (xy 294.007939 -278.636356)
			(xy 294.03081 -278.679933) (xy 294.046394 -278.726614) (xy 294.054289 -278.775191) (xy 294.054784 -278.799798)
			(xy 295.343846 -278.799798) (xy 295.347806 -278.750744) (xy 295.359583 -278.70296) (xy 295.378874 -278.657684)
			(xy 295.405177 -278.616088) (xy 295.437812 -278.579251) (xy 295.475933 -278.548126) (xy 295.518554 -278.523519)
			(xy 295.56457 -278.506067) (xy 295.612789 -278.496223) (xy 295.661964 -278.494242) (xy 295.710819 -278.500174)
			(xy 295.75809 -278.513866) (xy 295.802552 -278.534964) (xy 295.843055 -278.56292) (xy 295.878548 -278.597012)
			(xy 295.908113 -278.636356) (xy 295.930984 -278.679933) (xy 295.946568 -278.726614) (xy 295.954463 -278.775191)
			(xy 295.954958 -278.799798) (xy 297.243766 -278.799798) (xy 297.247726 -278.750744) (xy 297.259503 -278.70296)
			(xy 297.278794 -278.657684) (xy 297.305097 -278.616088) (xy 297.337732 -278.579251) (xy 297.375853 -278.548126)
			(xy 297.418474 -278.523519) (xy 297.46449 -278.506067) (xy 297.512709 -278.496223) (xy 297.561884 -278.494242)
			(xy 297.610739 -278.500174) (xy 297.65801 -278.513866) (xy 297.702472 -278.534964) (xy 297.742975 -278.56292)
			(xy 297.778468 -278.597012) (xy 297.808033 -278.636356) (xy 297.830904 -278.679933) (xy 297.846488 -278.726614)
			(xy 297.854383 -278.775191) (xy 297.854878 -278.799798) (xy 299.143686 -278.799798) (xy 299.147646 -278.750744)
			(xy 299.159423 -278.70296) (xy 299.178714 -278.657684) (xy 299.205017 -278.616088) (xy 299.237652 -278.579251)
			(xy 299.275773 -278.548126) (xy 299.318394 -278.523519) (xy 299.36441 -278.506067) (xy 299.412629 -278.496223)
			(xy 299.461804 -278.494242) (xy 299.510659 -278.500174) (xy 299.55793 -278.513866) (xy 299.602392 -278.534964)
			(xy 299.642895 -278.56292) (xy 299.678388 -278.597012) (xy 299.707953 -278.636356) (xy 299.730824 -278.679933)
			(xy 299.746408 -278.726614) (xy 299.754303 -278.775191) (xy 299.754798 -278.799798) (xy 301.04386 -278.799798)
			(xy 301.04782 -278.750744) (xy 301.059597 -278.70296) (xy 301.078888 -278.657684) (xy 301.105191 -278.616088)
			(xy 301.137826 -278.579251) (xy 301.175947 -278.548126) (xy 301.218568 -278.523519) (xy 301.264584 -278.506067)
			(xy 301.312803 -278.496223) (xy 301.361978 -278.494242) (xy 301.410833 -278.500174) (xy 301.458104 -278.513866)
			(xy 301.502566 -278.534964) (xy 301.543069 -278.56292) (xy 301.578562 -278.597012) (xy 301.608127 -278.636356)
			(xy 301.630998 -278.679933) (xy 301.646582 -278.726614) (xy 301.654477 -278.775191) (xy 301.654972 -278.799798)
			(xy 302.94378 -278.799798) (xy 302.94774 -278.750744) (xy 302.959517 -278.70296) (xy 302.978808 -278.657684)
			(xy 303.005111 -278.616088) (xy 303.037746 -278.579251) (xy 303.075867 -278.548126) (xy 303.118488 -278.523519)
			(xy 303.164504 -278.506067) (xy 303.212723 -278.496223) (xy 303.261898 -278.494242) (xy 303.310753 -278.500174)
			(xy 303.358024 -278.513866) (xy 303.402486 -278.534964) (xy 303.442989 -278.56292) (xy 303.478482 -278.597012)
			(xy 303.508047 -278.636356) (xy 303.530918 -278.679933) (xy 303.546502 -278.726614) (xy 303.554397 -278.775191)
			(xy 303.554892 -278.799798) (xy 304.8437 -278.799798) (xy 304.84766 -278.750744) (xy 304.859437 -278.70296)
			(xy 304.878728 -278.657684) (xy 304.905031 -278.616088) (xy 304.937666 -278.579251) (xy 304.975787 -278.548126)
			(xy 305.018408 -278.523519) (xy 305.064424 -278.506067) (xy 305.112643 -278.496223) (xy 305.161818 -278.494242)
			(xy 305.210673 -278.500174) (xy 305.257944 -278.513866) (xy 305.302406 -278.534964) (xy 305.342909 -278.56292)
			(xy 305.378402 -278.597012) (xy 305.407967 -278.636356) (xy 305.430838 -278.679933) (xy 305.446422 -278.726614)
			(xy 305.454317 -278.775191) (xy 305.454812 -278.799798) (xy 306.743874 -278.799798) (xy 306.747834 -278.750744)
			(xy 306.759611 -278.70296) (xy 306.778902 -278.657684) (xy 306.805205 -278.616088) (xy 306.83784 -278.579251)
			(xy 306.875961 -278.548126) (xy 306.918582 -278.523519) (xy 306.964598 -278.506067) (xy 307.012817 -278.496223)
			(xy 307.061992 -278.494242) (xy 307.110847 -278.500174) (xy 307.158118 -278.513866) (xy 307.20258 -278.534964)
			(xy 307.243083 -278.56292) (xy 307.278576 -278.597012) (xy 307.308141 -278.636356) (xy 307.331012 -278.679933)
			(xy 307.346596 -278.726614) (xy 307.354491 -278.775191) (xy 307.354986 -278.799798) (xy 308.643794 -278.799798)
			(xy 308.647754 -278.750744) (xy 308.659531 -278.70296) (xy 308.678822 -278.657684) (xy 308.705125 -278.616088)
			(xy 308.73776 -278.579251) (xy 308.775881 -278.548126) (xy 308.818502 -278.523519) (xy 308.864518 -278.506067)
			(xy 308.912737 -278.496223) (xy 308.961912 -278.494242) (xy 309.010767 -278.500174) (xy 309.058038 -278.513866)
			(xy 309.1025 -278.534964) (xy 309.143003 -278.56292) (xy 309.178496 -278.597012) (xy 309.208061 -278.636356)
			(xy 309.230932 -278.679933) (xy 309.246516 -278.726614) (xy 309.254411 -278.775191) (xy 309.254906 -278.799798)
			(xy 310.543714 -278.799798) (xy 310.547674 -278.750744) (xy 310.559451 -278.70296) (xy 310.578742 -278.657684)
			(xy 310.605045 -278.616088) (xy 310.63768 -278.579251) (xy 310.675801 -278.548126) (xy 310.718422 -278.523519)
			(xy 310.764438 -278.506067) (xy 310.812657 -278.496223) (xy 310.861832 -278.494242) (xy 310.910687 -278.500174)
			(xy 310.957958 -278.513866) (xy 311.00242 -278.534964) (xy 311.042923 -278.56292) (xy 311.078416 -278.597012)
			(xy 311.107981 -278.636356) (xy 311.130852 -278.679933) (xy 311.146436 -278.726614) (xy 311.154331 -278.775191)
			(xy 311.154826 -278.799798) (xy 312.443888 -278.799798) (xy 312.447848 -278.750744) (xy 312.459625 -278.70296)
			(xy 312.478916 -278.657684) (xy 312.505219 -278.616088) (xy 312.537854 -278.579251) (xy 312.575975 -278.548126)
			(xy 312.618596 -278.523519) (xy 312.664612 -278.506067) (xy 312.712831 -278.496223) (xy 312.762006 -278.494242)
			(xy 312.810861 -278.500174) (xy 312.858132 -278.513866) (xy 312.902594 -278.534964) (xy 312.943097 -278.56292)
			(xy 312.97859 -278.597012) (xy 313.008155 -278.636356) (xy 313.031026 -278.679933) (xy 313.04661 -278.726614)
			(xy 313.054505 -278.775191) (xy 313.055 -278.799798) (xy 392.443982 -278.799798) (xy 392.447942 -278.750744)
			(xy 392.459719 -278.70296) (xy 392.47901 -278.657684) (xy 392.505313 -278.616088) (xy 392.537948 -278.579251)
			(xy 392.576069 -278.548126) (xy 392.61869 -278.523519) (xy 392.664706 -278.506067) (xy 392.712925 -278.496223)
			(xy 392.7621 -278.494242) (xy 392.810955 -278.500174) (xy 392.858226 -278.513866) (xy 392.902688 -278.534964)
			(xy 392.943191 -278.56292) (xy 392.978684 -278.597012) (xy 393.008249 -278.636356) (xy 393.03112 -278.679933)
			(xy 393.046704 -278.726614) (xy 393.054599 -278.775191) (xy 393.055094 -278.799798) (xy 394.344156 -278.799798)
			(xy 394.348116 -278.750744) (xy 394.359893 -278.70296) (xy 394.379184 -278.657684) (xy 394.405487 -278.616088)
			(xy 394.438122 -278.579251) (xy 394.476243 -278.548126) (xy 394.518864 -278.523519) (xy 394.56488 -278.506067)
			(xy 394.613099 -278.496223) (xy 394.662274 -278.494242) (xy 394.711129 -278.500174) (xy 394.7584 -278.513866)
			(xy 394.802862 -278.534964) (xy 394.843365 -278.56292) (xy 394.878858 -278.597012) (xy 394.908423 -278.636356)
			(xy 394.931294 -278.679933) (xy 394.946878 -278.726614) (xy 394.954773 -278.775191) (xy 394.955268 -278.799798)
			(xy 396.244076 -278.799798) (xy 396.248036 -278.750744) (xy 396.259813 -278.70296) (xy 396.279104 -278.657684)
			(xy 396.305407 -278.616088) (xy 396.338042 -278.579251) (xy 396.376163 -278.548126) (xy 396.418784 -278.523519)
			(xy 396.4648 -278.506067) (xy 396.513019 -278.496223) (xy 396.562194 -278.494242) (xy 396.611049 -278.500174)
			(xy 396.65832 -278.513866) (xy 396.702782 -278.534964) (xy 396.743285 -278.56292) (xy 396.778778 -278.597012)
			(xy 396.808343 -278.636356) (xy 396.831214 -278.679933) (xy 396.846798 -278.726614) (xy 396.854693 -278.775191)
			(xy 396.855188 -278.799798) (xy 398.143996 -278.799798) (xy 398.147956 -278.750744) (xy 398.159733 -278.70296)
			(xy 398.179024 -278.657684) (xy 398.205327 -278.616088) (xy 398.237962 -278.579251) (xy 398.276083 -278.548126)
			(xy 398.318704 -278.523519) (xy 398.36472 -278.506067) (xy 398.412939 -278.496223) (xy 398.462114 -278.494242)
			(xy 398.510969 -278.500174) (xy 398.55824 -278.513866) (xy 398.602702 -278.534964) (xy 398.643205 -278.56292)
			(xy 398.678698 -278.597012) (xy 398.708263 -278.636356) (xy 398.731134 -278.679933) (xy 398.746718 -278.726614)
			(xy 398.754613 -278.775191) (xy 398.755108 -278.799798) (xy 400.04417 -278.799798) (xy 400.04813 -278.750744)
			(xy 400.059907 -278.70296) (xy 400.079198 -278.657684) (xy 400.105501 -278.616088) (xy 400.138136 -278.579251)
			(xy 400.176257 -278.548126) (xy 400.218878 -278.523519) (xy 400.264894 -278.506067) (xy 400.313113 -278.496223)
			(xy 400.362288 -278.494242) (xy 400.411143 -278.500174) (xy 400.458414 -278.513866) (xy 400.502876 -278.534964)
			(xy 400.543379 -278.56292) (xy 400.578872 -278.597012) (xy 400.608437 -278.636356) (xy 400.631308 -278.679933)
			(xy 400.646892 -278.726614) (xy 400.654787 -278.775191) (xy 400.655282 -278.799798) (xy 401.94409 -278.799798)
			(xy 401.94805 -278.750744) (xy 401.959827 -278.70296) (xy 401.979118 -278.657684) (xy 402.005421 -278.616088)
			(xy 402.038056 -278.579251) (xy 402.076177 -278.548126) (xy 402.118798 -278.523519) (xy 402.164814 -278.506067)
			(xy 402.213033 -278.496223) (xy 402.262208 -278.494242) (xy 402.311063 -278.500174) (xy 402.358334 -278.513866)
			(xy 402.402796 -278.534964) (xy 402.443299 -278.56292) (xy 402.478792 -278.597012) (xy 402.508357 -278.636356)
			(xy 402.531228 -278.679933) (xy 402.546812 -278.726614) (xy 402.554707 -278.775191) (xy 402.555202 -278.799798)
			(xy 403.84401 -278.799798) (xy 403.84797 -278.750744) (xy 403.859747 -278.70296) (xy 403.879038 -278.657684)
			(xy 403.905341 -278.616088) (xy 403.937976 -278.579251) (xy 403.976097 -278.548126) (xy 404.018718 -278.523519)
			(xy 404.064734 -278.506067) (xy 404.112953 -278.496223) (xy 404.162128 -278.494242) (xy 404.210983 -278.500174)
			(xy 404.258254 -278.513866) (xy 404.302716 -278.534964) (xy 404.343219 -278.56292) (xy 404.378712 -278.597012)
			(xy 404.408277 -278.636356) (xy 404.431148 -278.679933) (xy 404.446732 -278.726614) (xy 404.454627 -278.775191)
			(xy 404.455122 -278.799798) (xy 405.744184 -278.799798) (xy 405.748144 -278.750744) (xy 405.759921 -278.70296)
			(xy 405.779212 -278.657684) (xy 405.805515 -278.616088) (xy 405.83815 -278.579251) (xy 405.876271 -278.548126)
			(xy 405.918892 -278.523519) (xy 405.964908 -278.506067) (xy 406.013127 -278.496223) (xy 406.062302 -278.494242)
			(xy 406.111157 -278.500174) (xy 406.158428 -278.513866) (xy 406.20289 -278.534964) (xy 406.243393 -278.56292)
			(xy 406.278886 -278.597012) (xy 406.308451 -278.636356) (xy 406.331322 -278.679933) (xy 406.346906 -278.726614)
			(xy 406.354801 -278.775191) (xy 406.355296 -278.799798) (xy 407.64385 -278.799798) (xy 407.64781 -278.750744)
			(xy 407.659587 -278.70296) (xy 407.678878 -278.657684) (xy 407.705181 -278.616088) (xy 407.737816 -278.579251)
			(xy 407.775937 -278.548126) (xy 407.818558 -278.523519) (xy 407.864574 -278.506067) (xy 407.912793 -278.496223)
			(xy 407.961968 -278.494242) (xy 408.010823 -278.500174) (xy 408.058094 -278.513866) (xy 408.102556 -278.534964)
			(xy 408.143059 -278.56292) (xy 408.178552 -278.597012) (xy 408.208117 -278.636356) (xy 408.230988 -278.679933)
			(xy 408.246572 -278.726614) (xy 408.254467 -278.775191) (xy 408.254962 -278.799798) (xy 409.54377 -278.799798)
			(xy 409.54773 -278.750744) (xy 409.559507 -278.70296) (xy 409.578798 -278.657684) (xy 409.605101 -278.616088)
			(xy 409.637736 -278.579251) (xy 409.675857 -278.548126) (xy 409.718478 -278.523519) (xy 409.764494 -278.506067)
			(xy 409.812713 -278.496223) (xy 409.861888 -278.494242) (xy 409.910743 -278.500174) (xy 409.958014 -278.513866)
			(xy 410.002476 -278.534964) (xy 410.042979 -278.56292) (xy 410.078472 -278.597012) (xy 410.108037 -278.636356)
			(xy 410.130908 -278.679933) (xy 410.146492 -278.726614) (xy 410.154387 -278.775191) (xy 410.154882 -278.799798)
			(xy 411.443944 -278.799798) (xy 411.447904 -278.750744) (xy 411.459681 -278.70296) (xy 411.478972 -278.657684)
			(xy 411.505275 -278.616088) (xy 411.53791 -278.579251) (xy 411.576031 -278.548126) (xy 411.618652 -278.523519)
			(xy 411.664668 -278.506067) (xy 411.712887 -278.496223) (xy 411.762062 -278.494242) (xy 411.810917 -278.500174)
			(xy 411.858188 -278.513866) (xy 411.90265 -278.534964) (xy 411.943153 -278.56292) (xy 411.978646 -278.597012)
			(xy 412.008211 -278.636356) (xy 412.031082 -278.679933) (xy 412.046666 -278.726614) (xy 412.054561 -278.775191)
			(xy 412.055056 -278.799798) (xy 413.343864 -278.799798) (xy 413.347824 -278.750744) (xy 413.359601 -278.70296)
			(xy 413.378892 -278.657684) (xy 413.405195 -278.616088) (xy 413.43783 -278.579251) (xy 413.475951 -278.548126)
			(xy 413.518572 -278.523519) (xy 413.564588 -278.506067) (xy 413.612807 -278.496223) (xy 413.661982 -278.494242)
			(xy 413.710837 -278.500174) (xy 413.758108 -278.513866) (xy 413.80257 -278.534964) (xy 413.843073 -278.56292)
			(xy 413.878566 -278.597012) (xy 413.908131 -278.636356) (xy 413.931002 -278.679933) (xy 413.946586 -278.726614)
			(xy 413.954481 -278.775191) (xy 413.954976 -278.799798) (xy 415.243784 -278.799798) (xy 415.247744 -278.750744)
			(xy 415.259521 -278.70296) (xy 415.278812 -278.657684) (xy 415.305115 -278.616088) (xy 415.33775 -278.579251)
			(xy 415.375871 -278.548126) (xy 415.418492 -278.523519) (xy 415.464508 -278.506067) (xy 415.512727 -278.496223)
			(xy 415.561902 -278.494242) (xy 415.610757 -278.500174) (xy 415.658028 -278.513866) (xy 415.70249 -278.534964)
			(xy 415.742993 -278.56292) (xy 415.778486 -278.597012) (xy 415.808051 -278.636356) (xy 415.830922 -278.679933)
			(xy 415.846506 -278.726614) (xy 415.854401 -278.775191) (xy 415.854896 -278.799798) (xy 417.143958 -278.799798)
			(xy 417.147918 -278.750744) (xy 417.159695 -278.70296) (xy 417.178986 -278.657684) (xy 417.205289 -278.616088)
			(xy 417.237924 -278.579251) (xy 417.276045 -278.548126) (xy 417.318666 -278.523519) (xy 417.364682 -278.506067)
			(xy 417.412901 -278.496223) (xy 417.462076 -278.494242) (xy 417.510931 -278.500174) (xy 417.558202 -278.513866)
			(xy 417.602664 -278.534964) (xy 417.643167 -278.56292) (xy 417.67866 -278.597012) (xy 417.708225 -278.636356)
			(xy 417.731096 -278.679933) (xy 417.74668 -278.726614) (xy 417.754575 -278.775191) (xy 417.75507 -278.799798)
			(xy 419.043878 -278.799798) (xy 419.047838 -278.750744) (xy 419.059615 -278.70296) (xy 419.078906 -278.657684)
			(xy 419.105209 -278.616088) (xy 419.137844 -278.579251) (xy 419.175965 -278.548126) (xy 419.218586 -278.523519)
			(xy 419.264602 -278.506067) (xy 419.312821 -278.496223) (xy 419.361996 -278.494242) (xy 419.410851 -278.500174)
			(xy 419.458122 -278.513866) (xy 419.502584 -278.534964) (xy 419.543087 -278.56292) (xy 419.57858 -278.597012)
			(xy 419.608145 -278.636356) (xy 419.631016 -278.679933) (xy 419.6466 -278.726614) (xy 419.654495 -278.775191)
			(xy 419.65499 -278.799798) (xy 420.943798 -278.799798) (xy 420.947758 -278.750744) (xy 420.959535 -278.70296)
			(xy 420.978826 -278.657684) (xy 421.005129 -278.616088) (xy 421.037764 -278.579251) (xy 421.075885 -278.548126)
			(xy 421.118506 -278.523519) (xy 421.164522 -278.506067) (xy 421.212741 -278.496223) (xy 421.261916 -278.494242)
			(xy 421.310771 -278.500174) (xy 421.358042 -278.513866) (xy 421.402504 -278.534964) (xy 421.443007 -278.56292)
			(xy 421.4785 -278.597012) (xy 421.508065 -278.636356) (xy 421.530936 -278.679933) (xy 421.54652 -278.726614)
			(xy 421.554415 -278.775191) (xy 421.55491 -278.799798) (xy 422.843972 -278.799798) (xy 422.847932 -278.750744)
			(xy 422.859709 -278.70296) (xy 422.879 -278.657684) (xy 422.905303 -278.616088) (xy 422.937938 -278.579251)
			(xy 422.976059 -278.548126) (xy 423.01868 -278.523519) (xy 423.064696 -278.506067) (xy 423.112915 -278.496223)
			(xy 423.16209 -278.494242) (xy 423.210945 -278.500174) (xy 423.258216 -278.513866) (xy 423.302678 -278.534964)
			(xy 423.343181 -278.56292) (xy 423.378674 -278.597012) (xy 423.408239 -278.636356) (xy 423.43111 -278.679933)
			(xy 423.446694 -278.726614) (xy 423.454589 -278.775191) (xy 423.455084 -278.799798) (xy 424.743892 -278.799798)
			(xy 424.747852 -278.750744) (xy 424.759629 -278.70296) (xy 424.77892 -278.657684) (xy 424.805223 -278.616088)
			(xy 424.837858 -278.579251) (xy 424.875979 -278.548126) (xy 424.9186 -278.523519) (xy 424.964616 -278.506067)
			(xy 425.012835 -278.496223) (xy 425.06201 -278.494242) (xy 425.110865 -278.500174) (xy 425.158136 -278.513866)
			(xy 425.202598 -278.534964) (xy 425.243101 -278.56292) (xy 425.278594 -278.597012) (xy 425.308159 -278.636356)
			(xy 425.33103 -278.679933) (xy 425.346614 -278.726614) (xy 425.354509 -278.775191) (xy 425.355004 -278.799798)
			(xy 426.643812 -278.799798) (xy 426.647772 -278.750744) (xy 426.659549 -278.70296) (xy 426.67884 -278.657684)
			(xy 426.705143 -278.616088) (xy 426.737778 -278.579251) (xy 426.775899 -278.548126) (xy 426.81852 -278.523519)
			(xy 426.864536 -278.506067) (xy 426.912755 -278.496223) (xy 426.96193 -278.494242) (xy 427.010785 -278.500174)
			(xy 427.058056 -278.513866) (xy 427.102518 -278.534964) (xy 427.143021 -278.56292) (xy 427.178514 -278.597012)
			(xy 427.208079 -278.636356) (xy 427.23095 -278.679933) (xy 427.246534 -278.726614) (xy 427.254429 -278.775191)
			(xy 427.254924 -278.799798) (xy 428.543986 -278.799798) (xy 428.547946 -278.750744) (xy 428.559723 -278.70296)
			(xy 428.579014 -278.657684) (xy 428.605317 -278.616088) (xy 428.637952 -278.579251) (xy 428.676073 -278.548126)
			(xy 428.718694 -278.523519) (xy 428.76471 -278.506067) (xy 428.812929 -278.496223) (xy 428.862104 -278.494242)
			(xy 428.910959 -278.500174) (xy 428.95823 -278.513866) (xy 429.002692 -278.534964) (xy 429.043195 -278.56292)
			(xy 429.078688 -278.597012) (xy 429.108253 -278.636356) (xy 429.131124 -278.679933) (xy 429.146708 -278.726614)
			(xy 429.154603 -278.775191) (xy 429.155098 -278.799798) (xy 429.154603 -278.824405) (xy 429.146708 -278.872982)
			(xy 429.131124 -278.919663) (xy 429.108253 -278.96324) (xy 429.078688 -279.002584) (xy 429.043195 -279.036676)
			(xy 429.002692 -279.064632) (xy 428.95823 -279.08573) (xy 428.910959 -279.099422) (xy 428.862104 -279.105354)
			(xy 428.812929 -279.103373) (xy 428.76471 -279.093529) (xy 428.718694 -279.076077) (xy 428.676073 -279.05147)
			(xy 428.637952 -279.020345) (xy 428.605317 -278.983508) (xy 428.579014 -278.941912) (xy 428.559723 -278.896636)
			(xy 428.547946 -278.848852) (xy 428.543986 -278.799798) (xy 427.254924 -278.799798) (xy 427.254429 -278.824405)
			(xy 427.246534 -278.872982) (xy 427.23095 -278.919663) (xy 427.208079 -278.96324) (xy 427.178514 -279.002584)
			(xy 427.143021 -279.036676) (xy 427.102518 -279.064632) (xy 427.058056 -279.08573) (xy 427.010785 -279.099422)
			(xy 426.96193 -279.105354) (xy 426.912755 -279.103373) (xy 426.864536 -279.093529) (xy 426.81852 -279.076077)
			(xy 426.775899 -279.05147) (xy 426.737778 -279.020345) (xy 426.705143 -278.983508) (xy 426.67884 -278.941912)
			(xy 426.659549 -278.896636) (xy 426.647772 -278.848852) (xy 426.643812 -278.799798) (xy 425.355004 -278.799798)
			(xy 425.354509 -278.824405) (xy 425.346614 -278.872982) (xy 425.33103 -278.919663) (xy 425.308159 -278.96324)
			(xy 425.278594 -279.002584) (xy 425.243101 -279.036676) (xy 425.202598 -279.064632) (xy 425.158136 -279.08573)
			(xy 425.110865 -279.099422) (xy 425.06201 -279.105354) (xy 425.012835 -279.103373) (xy 424.964616 -279.093529)
			(xy 424.9186 -279.076077) (xy 424.875979 -279.05147) (xy 424.837858 -279.020345) (xy 424.805223 -278.983508)
			(xy 424.77892 -278.941912) (xy 424.759629 -278.896636) (xy 424.747852 -278.848852) (xy 424.743892 -278.799798)
			(xy 423.455084 -278.799798) (xy 423.454589 -278.824405) (xy 423.446694 -278.872982) (xy 423.43111 -278.919663)
			(xy 423.408239 -278.96324) (xy 423.378674 -279.002584) (xy 423.343181 -279.036676) (xy 423.302678 -279.064632)
			(xy 423.258216 -279.08573) (xy 423.210945 -279.099422) (xy 423.16209 -279.105354) (xy 423.112915 -279.103373)
			(xy 423.064696 -279.093529) (xy 423.01868 -279.076077) (xy 422.976059 -279.05147) (xy 422.937938 -279.020345)
			(xy 422.905303 -278.983508) (xy 422.879 -278.941912) (xy 422.859709 -278.896636) (xy 422.847932 -278.848852)
			(xy 422.843972 -278.799798) (xy 421.55491 -278.799798) (xy 421.554415 -278.824405) (xy 421.54652 -278.872982)
			(xy 421.530936 -278.919663) (xy 421.508065 -278.96324) (xy 421.4785 -279.002584) (xy 421.443007 -279.036676)
			(xy 421.402504 -279.064632) (xy 421.358042 -279.08573) (xy 421.310771 -279.099422) (xy 421.261916 -279.105354)
			(xy 421.212741 -279.103373) (xy 421.164522 -279.093529) (xy 421.118506 -279.076077) (xy 421.075885 -279.05147)
			(xy 421.037764 -279.020345) (xy 421.005129 -278.983508) (xy 420.978826 -278.941912) (xy 420.959535 -278.896636)
			(xy 420.947758 -278.848852) (xy 420.943798 -278.799798) (xy 419.65499 -278.799798) (xy 419.654495 -278.824405)
			(xy 419.6466 -278.872982) (xy 419.631016 -278.919663) (xy 419.608145 -278.96324) (xy 419.57858 -279.002584)
			(xy 419.543087 -279.036676) (xy 419.502584 -279.064632) (xy 419.458122 -279.08573) (xy 419.410851 -279.099422)
			(xy 419.361996 -279.105354) (xy 419.312821 -279.103373) (xy 419.264602 -279.093529) (xy 419.218586 -279.076077)
			(xy 419.175965 -279.05147) (xy 419.137844 -279.020345) (xy 419.105209 -278.983508) (xy 419.078906 -278.941912)
			(xy 419.059615 -278.896636) (xy 419.047838 -278.848852) (xy 419.043878 -278.799798) (xy 417.75507 -278.799798)
			(xy 417.754575 -278.824405) (xy 417.74668 -278.872982) (xy 417.731096 -278.919663) (xy 417.708225 -278.96324)
			(xy 417.67866 -279.002584) (xy 417.643167 -279.036676) (xy 417.602664 -279.064632) (xy 417.558202 -279.08573)
			(xy 417.510931 -279.099422) (xy 417.462076 -279.105354) (xy 417.412901 -279.103373) (xy 417.364682 -279.093529)
			(xy 417.318666 -279.076077) (xy 417.276045 -279.05147) (xy 417.237924 -279.020345) (xy 417.205289 -278.983508)
			(xy 417.178986 -278.941912) (xy 417.159695 -278.896636) (xy 417.147918 -278.848852) (xy 417.143958 -278.799798)
			(xy 415.854896 -278.799798) (xy 415.854401 -278.824405) (xy 415.846506 -278.872982) (xy 415.830922 -278.919663)
			(xy 415.808051 -278.96324) (xy 415.778486 -279.002584) (xy 415.742993 -279.036676) (xy 415.70249 -279.064632)
			(xy 415.658028 -279.08573) (xy 415.610757 -279.099422) (xy 415.561902 -279.105354) (xy 415.512727 -279.103373)
			(xy 415.464508 -279.093529) (xy 415.418492 -279.076077) (xy 415.375871 -279.05147) (xy 415.33775 -279.020345)
			(xy 415.305115 -278.983508) (xy 415.278812 -278.941912) (xy 415.259521 -278.896636) (xy 415.247744 -278.848852)
			(xy 415.243784 -278.799798) (xy 413.954976 -278.799798) (xy 413.954481 -278.824405) (xy 413.946586 -278.872982)
			(xy 413.931002 -278.919663) (xy 413.908131 -278.96324) (xy 413.878566 -279.002584) (xy 413.843073 -279.036676)
			(xy 413.80257 -279.064632) (xy 413.758108 -279.08573) (xy 413.710837 -279.099422) (xy 413.661982 -279.105354)
			(xy 413.612807 -279.103373) (xy 413.564588 -279.093529) (xy 413.518572 -279.076077) (xy 413.475951 -279.05147)
			(xy 413.43783 -279.020345) (xy 413.405195 -278.983508) (xy 413.378892 -278.941912) (xy 413.359601 -278.896636)
			(xy 413.347824 -278.848852) (xy 413.343864 -278.799798) (xy 412.055056 -278.799798) (xy 412.054561 -278.824405)
			(xy 412.046666 -278.872982) (xy 412.031082 -278.919663) (xy 412.008211 -278.96324) (xy 411.978646 -279.002584)
			(xy 411.943153 -279.036676) (xy 411.90265 -279.064632) (xy 411.858188 -279.08573) (xy 411.810917 -279.099422)
			(xy 411.762062 -279.105354) (xy 411.712887 -279.103373) (xy 411.664668 -279.093529) (xy 411.618652 -279.076077)
			(xy 411.576031 -279.05147) (xy 411.53791 -279.020345) (xy 411.505275 -278.983508) (xy 411.478972 -278.941912)
			(xy 411.459681 -278.896636) (xy 411.447904 -278.848852) (xy 411.443944 -278.799798) (xy 410.154882 -278.799798)
			(xy 410.154387 -278.824405) (xy 410.146492 -278.872982) (xy 410.130908 -278.919663) (xy 410.108037 -278.96324)
			(xy 410.078472 -279.002584) (xy 410.042979 -279.036676) (xy 410.002476 -279.064632) (xy 409.958014 -279.08573)
			(xy 409.910743 -279.099422) (xy 409.861888 -279.105354) (xy 409.812713 -279.103373) (xy 409.764494 -279.093529)
			(xy 409.718478 -279.076077) (xy 409.675857 -279.05147) (xy 409.637736 -279.020345) (xy 409.605101 -278.983508)
			(xy 409.578798 -278.941912) (xy 409.559507 -278.896636) (xy 409.54773 -278.848852) (xy 409.54377 -278.799798)
			(xy 408.254962 -278.799798) (xy 408.254467 -278.824405) (xy 408.246572 -278.872982) (xy 408.230988 -278.919663)
			(xy 408.208117 -278.96324) (xy 408.178552 -279.002584) (xy 408.143059 -279.036676) (xy 408.102556 -279.064632)
			(xy 408.058094 -279.08573) (xy 408.010823 -279.099422) (xy 407.961968 -279.105354) (xy 407.912793 -279.103373)
			(xy 407.864574 -279.093529) (xy 407.818558 -279.076077) (xy 407.775937 -279.05147) (xy 407.737816 -279.020345)
			(xy 407.705181 -278.983508) (xy 407.678878 -278.941912) (xy 407.659587 -278.896636) (xy 407.64781 -278.848852)
			(xy 407.64385 -278.799798) (xy 406.355296 -278.799798) (xy 406.354801 -278.824405) (xy 406.346906 -278.872982)
			(xy 406.331322 -278.919663) (xy 406.308451 -278.96324) (xy 406.278886 -279.002584) (xy 406.243393 -279.036676)
			(xy 406.20289 -279.064632) (xy 406.158428 -279.08573) (xy 406.111157 -279.099422) (xy 406.062302 -279.105354)
			(xy 406.013127 -279.103373) (xy 405.964908 -279.093529) (xy 405.918892 -279.076077) (xy 405.876271 -279.05147)
			(xy 405.83815 -279.020345) (xy 405.805515 -278.983508) (xy 405.779212 -278.941912) (xy 405.759921 -278.896636)
			(xy 405.748144 -278.848852) (xy 405.744184 -278.799798) (xy 404.455122 -278.799798) (xy 404.454627 -278.824405)
			(xy 404.446732 -278.872982) (xy 404.431148 -278.919663) (xy 404.408277 -278.96324) (xy 404.378712 -279.002584)
			(xy 404.343219 -279.036676) (xy 404.302716 -279.064632) (xy 404.258254 -279.08573) (xy 404.210983 -279.099422)
			(xy 404.162128 -279.105354) (xy 404.112953 -279.103373) (xy 404.064734 -279.093529) (xy 404.018718 -279.076077)
			(xy 403.976097 -279.05147) (xy 403.937976 -279.020345) (xy 403.905341 -278.983508) (xy 403.879038 -278.941912)
			(xy 403.859747 -278.896636) (xy 403.84797 -278.848852) (xy 403.84401 -278.799798) (xy 402.555202 -278.799798)
			(xy 402.554707 -278.824405) (xy 402.546812 -278.872982) (xy 402.531228 -278.919663) (xy 402.508357 -278.96324)
			(xy 402.478792 -279.002584) (xy 402.443299 -279.036676) (xy 402.402796 -279.064632) (xy 402.358334 -279.08573)
			(xy 402.311063 -279.099422) (xy 402.262208 -279.105354) (xy 402.213033 -279.103373) (xy 402.164814 -279.093529)
			(xy 402.118798 -279.076077) (xy 402.076177 -279.05147) (xy 402.038056 -279.020345) (xy 402.005421 -278.983508)
			(xy 401.979118 -278.941912) (xy 401.959827 -278.896636) (xy 401.94805 -278.848852) (xy 401.94409 -278.799798)
			(xy 400.655282 -278.799798) (xy 400.654787 -278.824405) (xy 400.646892 -278.872982) (xy 400.631308 -278.919663)
			(xy 400.608437 -278.96324) (xy 400.578872 -279.002584) (xy 400.543379 -279.036676) (xy 400.502876 -279.064632)
			(xy 400.458414 -279.08573) (xy 400.411143 -279.099422) (xy 400.362288 -279.105354) (xy 400.313113 -279.103373)
			(xy 400.264894 -279.093529) (xy 400.218878 -279.076077) (xy 400.176257 -279.05147) (xy 400.138136 -279.020345)
			(xy 400.105501 -278.983508) (xy 400.079198 -278.941912) (xy 400.059907 -278.896636) (xy 400.04813 -278.848852)
			(xy 400.04417 -278.799798) (xy 398.755108 -278.799798) (xy 398.754613 -278.824405) (xy 398.746718 -278.872982)
			(xy 398.731134 -278.919663) (xy 398.708263 -278.96324) (xy 398.678698 -279.002584) (xy 398.643205 -279.036676)
			(xy 398.602702 -279.064632) (xy 398.55824 -279.08573) (xy 398.510969 -279.099422) (xy 398.462114 -279.105354)
			(xy 398.412939 -279.103373) (xy 398.36472 -279.093529) (xy 398.318704 -279.076077) (xy 398.276083 -279.05147)
			(xy 398.237962 -279.020345) (xy 398.205327 -278.983508) (xy 398.179024 -278.941912) (xy 398.159733 -278.896636)
			(xy 398.147956 -278.848852) (xy 398.143996 -278.799798) (xy 396.855188 -278.799798) (xy 396.854693 -278.824405)
			(xy 396.846798 -278.872982) (xy 396.831214 -278.919663) (xy 396.808343 -278.96324) (xy 396.778778 -279.002584)
			(xy 396.743285 -279.036676) (xy 396.702782 -279.064632) (xy 396.65832 -279.08573) (xy 396.611049 -279.099422)
			(xy 396.562194 -279.105354) (xy 396.513019 -279.103373) (xy 396.4648 -279.093529) (xy 396.418784 -279.076077)
			(xy 396.376163 -279.05147) (xy 396.338042 -279.020345) (xy 396.305407 -278.983508) (xy 396.279104 -278.941912)
			(xy 396.259813 -278.896636) (xy 396.248036 -278.848852) (xy 396.244076 -278.799798) (xy 394.955268 -278.799798)
			(xy 394.954773 -278.824405) (xy 394.946878 -278.872982) (xy 394.931294 -278.919663) (xy 394.908423 -278.96324)
			(xy 394.878858 -279.002584) (xy 394.843365 -279.036676) (xy 394.802862 -279.064632) (xy 394.7584 -279.08573)
			(xy 394.711129 -279.099422) (xy 394.662274 -279.105354) (xy 394.613099 -279.103373) (xy 394.56488 -279.093529)
			(xy 394.518864 -279.076077) (xy 394.476243 -279.05147) (xy 394.438122 -279.020345) (xy 394.405487 -278.983508)
			(xy 394.379184 -278.941912) (xy 394.359893 -278.896636) (xy 394.348116 -278.848852) (xy 394.344156 -278.799798)
			(xy 393.055094 -278.799798) (xy 393.054599 -278.824405) (xy 393.046704 -278.872982) (xy 393.03112 -278.919663)
			(xy 393.008249 -278.96324) (xy 392.978684 -279.002584) (xy 392.943191 -279.036676) (xy 392.902688 -279.064632)
			(xy 392.858226 -279.08573) (xy 392.810955 -279.099422) (xy 392.7621 -279.105354) (xy 392.712925 -279.103373)
			(xy 392.664706 -279.093529) (xy 392.61869 -279.076077) (xy 392.576069 -279.05147) (xy 392.537948 -279.020345)
			(xy 392.505313 -278.983508) (xy 392.47901 -278.941912) (xy 392.459719 -278.896636) (xy 392.447942 -278.848852)
			(xy 392.443982 -278.799798) (xy 313.055 -278.799798) (xy 313.054505 -278.824405) (xy 313.04661 -278.872982)
			(xy 313.031026 -278.919663) (xy 313.008155 -278.96324) (xy 312.97859 -279.002584) (xy 312.943097 -279.036676)
			(xy 312.902594 -279.064632) (xy 312.858132 -279.08573) (xy 312.810861 -279.099422) (xy 312.762006 -279.105354)
			(xy 312.712831 -279.103373) (xy 312.664612 -279.093529) (xy 312.618596 -279.076077) (xy 312.575975 -279.05147)
			(xy 312.537854 -279.020345) (xy 312.505219 -278.983508) (xy 312.478916 -278.941912) (xy 312.459625 -278.896636)
			(xy 312.447848 -278.848852) (xy 312.443888 -278.799798) (xy 311.154826 -278.799798) (xy 311.154331 -278.824405)
			(xy 311.146436 -278.872982) (xy 311.130852 -278.919663) (xy 311.107981 -278.96324) (xy 311.078416 -279.002584)
			(xy 311.042923 -279.036676) (xy 311.00242 -279.064632) (xy 310.957958 -279.08573) (xy 310.910687 -279.099422)
			(xy 310.861832 -279.105354) (xy 310.812657 -279.103373) (xy 310.764438 -279.093529) (xy 310.718422 -279.076077)
			(xy 310.675801 -279.05147) (xy 310.63768 -279.020345) (xy 310.605045 -278.983508) (xy 310.578742 -278.941912)
			(xy 310.559451 -278.896636) (xy 310.547674 -278.848852) (xy 310.543714 -278.799798) (xy 309.254906 -278.799798)
			(xy 309.254411 -278.824405) (xy 309.246516 -278.872982) (xy 309.230932 -278.919663) (xy 309.208061 -278.96324)
			(xy 309.178496 -279.002584) (xy 309.143003 -279.036676) (xy 309.1025 -279.064632) (xy 309.058038 -279.08573)
			(xy 309.010767 -279.099422) (xy 308.961912 -279.105354) (xy 308.912737 -279.103373) (xy 308.864518 -279.093529)
			(xy 308.818502 -279.076077) (xy 308.775881 -279.05147) (xy 308.73776 -279.020345) (xy 308.705125 -278.983508)
			(xy 308.678822 -278.941912) (xy 308.659531 -278.896636) (xy 308.647754 -278.848852) (xy 308.643794 -278.799798)
			(xy 307.354986 -278.799798) (xy 307.354491 -278.824405) (xy 307.346596 -278.872982) (xy 307.331012 -278.919663)
			(xy 307.308141 -278.96324) (xy 307.278576 -279.002584) (xy 307.243083 -279.036676) (xy 307.20258 -279.064632)
			(xy 307.158118 -279.08573) (xy 307.110847 -279.099422) (xy 307.061992 -279.105354) (xy 307.012817 -279.103373)
			(xy 306.964598 -279.093529) (xy 306.918582 -279.076077) (xy 306.875961 -279.05147) (xy 306.83784 -279.020345)
			(xy 306.805205 -278.983508) (xy 306.778902 -278.941912) (xy 306.759611 -278.896636) (xy 306.747834 -278.848852)
			(xy 306.743874 -278.799798) (xy 305.454812 -278.799798) (xy 305.454317 -278.824405) (xy 305.446422 -278.872982)
			(xy 305.430838 -278.919663) (xy 305.407967 -278.96324) (xy 305.378402 -279.002584) (xy 305.342909 -279.036676)
			(xy 305.302406 -279.064632) (xy 305.257944 -279.08573) (xy 305.210673 -279.099422) (xy 305.161818 -279.105354)
			(xy 305.112643 -279.103373) (xy 305.064424 -279.093529) (xy 305.018408 -279.076077) (xy 304.975787 -279.05147)
			(xy 304.937666 -279.020345) (xy 304.905031 -278.983508) (xy 304.878728 -278.941912) (xy 304.859437 -278.896636)
			(xy 304.84766 -278.848852) (xy 304.8437 -278.799798) (xy 303.554892 -278.799798) (xy 303.554397 -278.824405)
			(xy 303.546502 -278.872982) (xy 303.530918 -278.919663) (xy 303.508047 -278.96324) (xy 303.478482 -279.002584)
			(xy 303.442989 -279.036676) (xy 303.402486 -279.064632) (xy 303.358024 -279.08573) (xy 303.310753 -279.099422)
			(xy 303.261898 -279.105354) (xy 303.212723 -279.103373) (xy 303.164504 -279.093529) (xy 303.118488 -279.076077)
			(xy 303.075867 -279.05147) (xy 303.037746 -279.020345) (xy 303.005111 -278.983508) (xy 302.978808 -278.941912)
			(xy 302.959517 -278.896636) (xy 302.94774 -278.848852) (xy 302.94378 -278.799798) (xy 301.654972 -278.799798)
			(xy 301.654477 -278.824405) (xy 301.646582 -278.872982) (xy 301.630998 -278.919663) (xy 301.608127 -278.96324)
			(xy 301.578562 -279.002584) (xy 301.543069 -279.036676) (xy 301.502566 -279.064632) (xy 301.458104 -279.08573)
			(xy 301.410833 -279.099422) (xy 301.361978 -279.105354) (xy 301.312803 -279.103373) (xy 301.264584 -279.093529)
			(xy 301.218568 -279.076077) (xy 301.175947 -279.05147) (xy 301.137826 -279.020345) (xy 301.105191 -278.983508)
			(xy 301.078888 -278.941912) (xy 301.059597 -278.896636) (xy 301.04782 -278.848852) (xy 301.04386 -278.799798)
			(xy 299.754798 -278.799798) (xy 299.754303 -278.824405) (xy 299.746408 -278.872982) (xy 299.730824 -278.919663)
			(xy 299.707953 -278.96324) (xy 299.678388 -279.002584) (xy 299.642895 -279.036676) (xy 299.602392 -279.064632)
			(xy 299.55793 -279.08573) (xy 299.510659 -279.099422) (xy 299.461804 -279.105354) (xy 299.412629 -279.103373)
			(xy 299.36441 -279.093529) (xy 299.318394 -279.076077) (xy 299.275773 -279.05147) (xy 299.237652 -279.020345)
			(xy 299.205017 -278.983508) (xy 299.178714 -278.941912) (xy 299.159423 -278.896636) (xy 299.147646 -278.848852)
			(xy 299.143686 -278.799798) (xy 297.854878 -278.799798) (xy 297.854383 -278.824405) (xy 297.846488 -278.872982)
			(xy 297.830904 -278.919663) (xy 297.808033 -278.96324) (xy 297.778468 -279.002584) (xy 297.742975 -279.036676)
			(xy 297.702472 -279.064632) (xy 297.65801 -279.08573) (xy 297.610739 -279.099422) (xy 297.561884 -279.105354)
			(xy 297.512709 -279.103373) (xy 297.46449 -279.093529) (xy 297.418474 -279.076077) (xy 297.375853 -279.05147)
			(xy 297.337732 -279.020345) (xy 297.305097 -278.983508) (xy 297.278794 -278.941912) (xy 297.259503 -278.896636)
			(xy 297.247726 -278.848852) (xy 297.243766 -278.799798) (xy 295.954958 -278.799798) (xy 295.954463 -278.824405)
			(xy 295.946568 -278.872982) (xy 295.930984 -278.919663) (xy 295.908113 -278.96324) (xy 295.878548 -279.002584)
			(xy 295.843055 -279.036676) (xy 295.802552 -279.064632) (xy 295.75809 -279.08573) (xy 295.710819 -279.099422)
			(xy 295.661964 -279.105354) (xy 295.612789 -279.103373) (xy 295.56457 -279.093529) (xy 295.518554 -279.076077)
			(xy 295.475933 -279.05147) (xy 295.437812 -279.020345) (xy 295.405177 -278.983508) (xy 295.378874 -278.941912)
			(xy 295.359583 -278.896636) (xy 295.347806 -278.848852) (xy 295.343846 -278.799798) (xy 294.054784 -278.799798)
			(xy 294.054289 -278.824405) (xy 294.046394 -278.872982) (xy 294.03081 -278.919663) (xy 294.007939 -278.96324)
			(xy 293.978374 -279.002584) (xy 293.942881 -279.036676) (xy 293.902378 -279.064632) (xy 293.857916 -279.08573)
			(xy 293.810645 -279.099422) (xy 293.76179 -279.105354) (xy 293.712615 -279.103373) (xy 293.664396 -279.093529)
			(xy 293.61838 -279.076077) (xy 293.575759 -279.05147) (xy 293.537638 -279.020345) (xy 293.505003 -278.983508)
			(xy 293.4787 -278.941912) (xy 293.459409 -278.896636) (xy 293.447632 -278.848852) (xy 293.443672 -278.799798)
			(xy 292.154864 -278.799798) (xy 292.154369 -278.824405) (xy 292.146474 -278.872982) (xy 292.13089 -278.919663)
			(xy 292.108019 -278.96324) (xy 292.078454 -279.002584) (xy 292.042961 -279.036676) (xy 292.002458 -279.064632)
			(xy 291.957996 -279.08573) (xy 291.910725 -279.099422) (xy 291.86187 -279.105354) (xy 291.812695 -279.103373)
			(xy 291.764476 -279.093529) (xy 291.71846 -279.076077) (xy 291.675839 -279.05147) (xy 291.637718 -279.020345)
			(xy 291.605083 -278.983508) (xy 291.57878 -278.941912) (xy 291.559489 -278.896636) (xy 291.547712 -278.848852)
			(xy 291.543752 -278.799798) (xy 290.255198 -278.799798) (xy 290.254703 -278.824405) (xy 290.246808 -278.872982)
			(xy 290.231224 -278.919663) (xy 290.208353 -278.96324) (xy 290.178788 -279.002584) (xy 290.143295 -279.036676)
			(xy 290.102792 -279.064632) (xy 290.05833 -279.08573) (xy 290.011059 -279.099422) (xy 289.962204 -279.105354)
			(xy 289.913029 -279.103373) (xy 289.86481 -279.093529) (xy 289.818794 -279.076077) (xy 289.776173 -279.05147)
			(xy 289.738052 -279.020345) (xy 289.705417 -278.983508) (xy 289.679114 -278.941912) (xy 289.659823 -278.896636)
			(xy 289.648046 -278.848852) (xy 289.644086 -278.799798) (xy 288.355024 -278.799798) (xy 288.354529 -278.824405)
			(xy 288.346634 -278.872982) (xy 288.33105 -278.919663) (xy 288.308179 -278.96324) (xy 288.278614 -279.002584)
			(xy 288.243121 -279.036676) (xy 288.202618 -279.064632) (xy 288.158156 -279.08573) (xy 288.110885 -279.099422)
			(xy 288.06203 -279.105354) (xy 288.012855 -279.103373) (xy 287.964636 -279.093529) (xy 287.91862 -279.076077)
			(xy 287.875999 -279.05147) (xy 287.837878 -279.020345) (xy 287.805243 -278.983508) (xy 287.77894 -278.941912)
			(xy 287.759649 -278.896636) (xy 287.747872 -278.848852) (xy 287.743912 -278.799798) (xy 286.455104 -278.799798)
			(xy 286.454609 -278.824405) (xy 286.446714 -278.872982) (xy 286.43113 -278.919663) (xy 286.408259 -278.96324)
			(xy 286.378694 -279.002584) (xy 286.343201 -279.036676) (xy 286.302698 -279.064632) (xy 286.258236 -279.08573)
			(xy 286.210965 -279.099422) (xy 286.16211 -279.105354) (xy 286.112935 -279.103373) (xy 286.064716 -279.093529)
			(xy 286.0187 -279.076077) (xy 285.976079 -279.05147) (xy 285.937958 -279.020345) (xy 285.905323 -278.983508)
			(xy 285.87902 -278.941912) (xy 285.859729 -278.896636) (xy 285.847952 -278.848852) (xy 285.843992 -278.799798)
			(xy 284.555184 -278.799798) (xy 284.554689 -278.824405) (xy 284.546794 -278.872982) (xy 284.53121 -278.919663)
			(xy 284.508339 -278.96324) (xy 284.478774 -279.002584) (xy 284.443281 -279.036676) (xy 284.402778 -279.064632)
			(xy 284.358316 -279.08573) (xy 284.311045 -279.099422) (xy 284.26219 -279.105354) (xy 284.213015 -279.103373)
			(xy 284.164796 -279.093529) (xy 284.11878 -279.076077) (xy 284.076159 -279.05147) (xy 284.038038 -279.020345)
			(xy 284.005403 -278.983508) (xy 283.9791 -278.941912) (xy 283.959809 -278.896636) (xy 283.948032 -278.848852)
			(xy 283.944072 -278.799798) (xy 282.65501 -278.799798) (xy 282.654515 -278.824405) (xy 282.64662 -278.872982)
			(xy 282.631036 -278.919663) (xy 282.608165 -278.96324) (xy 282.5786 -279.002584) (xy 282.543107 -279.036676)
			(xy 282.502604 -279.064632) (xy 282.458142 -279.08573) (xy 282.410871 -279.099422) (xy 282.362016 -279.105354)
			(xy 282.312841 -279.103373) (xy 282.264622 -279.093529) (xy 282.218606 -279.076077) (xy 282.175985 -279.05147)
			(xy 282.137864 -279.020345) (xy 282.105229 -278.983508) (xy 282.078926 -278.941912) (xy 282.059635 -278.896636)
			(xy 282.047858 -278.848852) (xy 282.043898 -278.799798) (xy 280.75509 -278.799798) (xy 280.754595 -278.824405)
			(xy 280.7467 -278.872982) (xy 280.731116 -278.919663) (xy 280.708245 -278.96324) (xy 280.67868 -279.002584)
			(xy 280.643187 -279.036676) (xy 280.602684 -279.064632) (xy 280.558222 -279.08573) (xy 280.510951 -279.099422)
			(xy 280.462096 -279.105354) (xy 280.412921 -279.103373) (xy 280.364702 -279.093529) (xy 280.318686 -279.076077)
			(xy 280.276065 -279.05147) (xy 280.237944 -279.020345) (xy 280.205309 -278.983508) (xy 280.179006 -278.941912)
			(xy 280.159715 -278.896636) (xy 280.147938 -278.848852) (xy 280.143978 -278.799798) (xy 278.85517 -278.799798)
			(xy 278.854675 -278.824405) (xy 278.84678 -278.872982) (xy 278.831196 -278.919663) (xy 278.808325 -278.96324)
			(xy 278.77876 -279.002584) (xy 278.743267 -279.036676) (xy 278.702764 -279.064632) (xy 278.658302 -279.08573)
			(xy 278.611031 -279.099422) (xy 278.562176 -279.105354) (xy 278.513001 -279.103373) (xy 278.464782 -279.093529)
			(xy 278.418766 -279.076077) (xy 278.376145 -279.05147) (xy 278.338024 -279.020345) (xy 278.305389 -278.983508)
			(xy 278.279086 -278.941912) (xy 278.259795 -278.896636) (xy 278.248018 -278.848852) (xy 278.244058 -278.799798)
			(xy 276.954996 -278.799798) (xy 276.954501 -278.824405) (xy 276.946606 -278.872982) (xy 276.931022 -278.919663)
			(xy 276.908151 -278.96324) (xy 276.878586 -279.002584) (xy 276.843093 -279.036676) (xy 276.80259 -279.064632)
			(xy 276.758128 -279.08573) (xy 276.710857 -279.099422) (xy 276.662002 -279.105354) (xy 276.612827 -279.103373)
			(xy 276.564608 -279.093529) (xy 276.518592 -279.076077) (xy 276.475971 -279.05147) (xy 276.43785 -279.020345)
			(xy 276.405215 -278.983508) (xy 276.378912 -278.941912) (xy 276.359621 -278.896636) (xy 276.347844 -278.848852)
			(xy 276.343884 -278.799798) (xy 196.955156 -278.799798) (xy 196.954661 -278.824405) (xy 196.946766 -278.872982)
			(xy 196.931182 -278.919663) (xy 196.908311 -278.96324) (xy 196.878746 -279.002584) (xy 196.843253 -279.036676)
			(xy 196.80275 -279.064632) (xy 196.758288 -279.08573) (xy 196.711017 -279.099422) (xy 196.662162 -279.105354)
			(xy 196.612987 -279.103373) (xy 196.564768 -279.093529) (xy 196.518752 -279.076077) (xy 196.476131 -279.05147)
			(xy 196.43801 -279.020345) (xy 196.405375 -278.983508) (xy 196.379072 -278.941912) (xy 196.359781 -278.896636)
			(xy 196.348004 -278.848852) (xy 196.344044 -278.799798) (xy 195.054982 -278.799798) (xy 195.054487 -278.824405)
			(xy 195.046592 -278.872982) (xy 195.031008 -278.919663) (xy 195.008137 -278.96324) (xy 194.978572 -279.002584)
			(xy 194.943079 -279.036676) (xy 194.902576 -279.064632) (xy 194.858114 -279.08573) (xy 194.810843 -279.099422)
			(xy 194.761988 -279.105354) (xy 194.712813 -279.103373) (xy 194.664594 -279.093529) (xy 194.618578 -279.076077)
			(xy 194.575957 -279.05147) (xy 194.537836 -279.020345) (xy 194.505201 -278.983508) (xy 194.478898 -278.941912)
			(xy 194.459607 -278.896636) (xy 194.44783 -278.848852) (xy 194.44387 -278.799798) (xy 193.155062 -278.799798)
			(xy 193.154567 -278.824405) (xy 193.146672 -278.872982) (xy 193.131088 -278.919663) (xy 193.108217 -278.96324)
			(xy 193.078652 -279.002584) (xy 193.043159 -279.036676) (xy 193.002656 -279.064632) (xy 192.958194 -279.08573)
			(xy 192.910923 -279.099422) (xy 192.862068 -279.105354) (xy 192.812893 -279.103373) (xy 192.764674 -279.093529)
			(xy 192.718658 -279.076077) (xy 192.676037 -279.05147) (xy 192.637916 -279.020345) (xy 192.605281 -278.983508)
			(xy 192.578978 -278.941912) (xy 192.559687 -278.896636) (xy 192.54791 -278.848852) (xy 192.54395 -278.799798)
			(xy 191.255142 -278.799798) (xy 191.254647 -278.824405) (xy 191.246752 -278.872982) (xy 191.231168 -278.919663)
			(xy 191.208297 -278.96324) (xy 191.178732 -279.002584) (xy 191.143239 -279.036676) (xy 191.102736 -279.064632)
			(xy 191.058274 -279.08573) (xy 191.011003 -279.099422) (xy 190.962148 -279.105354) (xy 190.912973 -279.103373)
			(xy 190.864754 -279.093529) (xy 190.818738 -279.076077) (xy 190.776117 -279.05147) (xy 190.737996 -279.020345)
			(xy 190.705361 -278.983508) (xy 190.679058 -278.941912) (xy 190.659767 -278.896636) (xy 190.64799 -278.848852)
			(xy 190.64403 -278.799798) (xy 189.354968 -278.799798) (xy 189.354473 -278.824405) (xy 189.346578 -278.872982)
			(xy 189.330994 -278.919663) (xy 189.308123 -278.96324) (xy 189.278558 -279.002584) (xy 189.243065 -279.036676)
			(xy 189.202562 -279.064632) (xy 189.1581 -279.08573) (xy 189.110829 -279.099422) (xy 189.061974 -279.105354)
			(xy 189.012799 -279.103373) (xy 188.96458 -279.093529) (xy 188.918564 -279.076077) (xy 188.875943 -279.05147)
			(xy 188.837822 -279.020345) (xy 188.805187 -278.983508) (xy 188.778884 -278.941912) (xy 188.759593 -278.896636)
			(xy 188.747816 -278.848852) (xy 188.743856 -278.799798) (xy 187.455048 -278.799798) (xy 187.454553 -278.824405)
			(xy 187.446658 -278.872982) (xy 187.431074 -278.919663) (xy 187.408203 -278.96324) (xy 187.378638 -279.002584)
			(xy 187.343145 -279.036676) (xy 187.302642 -279.064632) (xy 187.25818 -279.08573) (xy 187.210909 -279.099422)
			(xy 187.162054 -279.105354) (xy 187.112879 -279.103373) (xy 187.06466 -279.093529) (xy 187.018644 -279.076077)
			(xy 186.976023 -279.05147) (xy 186.937902 -279.020345) (xy 186.905267 -278.983508) (xy 186.878964 -278.941912)
			(xy 186.859673 -278.896636) (xy 186.847896 -278.848852) (xy 186.843936 -278.799798) (xy 185.555128 -278.799798)
			(xy 185.554633 -278.824405) (xy 185.546738 -278.872982) (xy 185.531154 -278.919663) (xy 185.508283 -278.96324)
			(xy 185.478718 -279.002584) (xy 185.443225 -279.036676) (xy 185.402722 -279.064632) (xy 185.35826 -279.08573)
			(xy 185.310989 -279.099422) (xy 185.262134 -279.105354) (xy 185.212959 -279.103373) (xy 185.16474 -279.093529)
			(xy 185.118724 -279.076077) (xy 185.076103 -279.05147) (xy 185.037982 -279.020345) (xy 185.005347 -278.983508)
			(xy 184.979044 -278.941912) (xy 184.959753 -278.896636) (xy 184.947976 -278.848852) (xy 184.944016 -278.799798)
			(xy 183.654954 -278.799798) (xy 183.654459 -278.824405) (xy 183.646564 -278.872982) (xy 183.63098 -278.919663)
			(xy 183.608109 -278.96324) (xy 183.578544 -279.002584) (xy 183.543051 -279.036676) (xy 183.502548 -279.064632)
			(xy 183.458086 -279.08573) (xy 183.410815 -279.099422) (xy 183.36196 -279.105354) (xy 183.312785 -279.103373)
			(xy 183.264566 -279.093529) (xy 183.21855 -279.076077) (xy 183.175929 -279.05147) (xy 183.137808 -279.020345)
			(xy 183.105173 -278.983508) (xy 183.07887 -278.941912) (xy 183.059579 -278.896636) (xy 183.047802 -278.848852)
			(xy 183.043842 -278.799798) (xy 181.755034 -278.799798) (xy 181.754539 -278.824405) (xy 181.746644 -278.872982)
			(xy 181.73106 -278.919663) (xy 181.708189 -278.96324) (xy 181.678624 -279.002584) (xy 181.643131 -279.036676)
			(xy 181.602628 -279.064632) (xy 181.558166 -279.08573) (xy 181.510895 -279.099422) (xy 181.46204 -279.105354)
			(xy 181.412865 -279.103373) (xy 181.364646 -279.093529) (xy 181.31863 -279.076077) (xy 181.276009 -279.05147)
			(xy 181.237888 -279.020345) (xy 181.205253 -278.983508) (xy 181.17895 -278.941912) (xy 181.159659 -278.896636)
			(xy 181.147882 -278.848852) (xy 181.143922 -278.799798) (xy 179.855114 -278.799798) (xy 179.854619 -278.824405)
			(xy 179.846724 -278.872982) (xy 179.83114 -278.919663) (xy 179.808269 -278.96324) (xy 179.778704 -279.002584)
			(xy 179.743211 -279.036676) (xy 179.702708 -279.064632) (xy 179.658246 -279.08573) (xy 179.610975 -279.099422)
			(xy 179.56212 -279.105354) (xy 179.512945 -279.103373) (xy 179.464726 -279.093529) (xy 179.41871 -279.076077)
			(xy 179.376089 -279.05147) (xy 179.337968 -279.020345) (xy 179.305333 -278.983508) (xy 179.27903 -278.941912)
			(xy 179.259739 -278.896636) (xy 179.247962 -278.848852) (xy 179.244002 -278.799798) (xy 177.95494 -278.799798)
			(xy 177.954445 -278.824405) (xy 177.94655 -278.872982) (xy 177.930966 -278.919663) (xy 177.908095 -278.96324)
			(xy 177.87853 -279.002584) (xy 177.843037 -279.036676) (xy 177.802534 -279.064632) (xy 177.758072 -279.08573)
			(xy 177.710801 -279.099422) (xy 177.661946 -279.105354) (xy 177.612771 -279.103373) (xy 177.564552 -279.093529)
			(xy 177.518536 -279.076077) (xy 177.475915 -279.05147) (xy 177.437794 -279.020345) (xy 177.405159 -278.983508)
			(xy 177.378856 -278.941912) (xy 177.359565 -278.896636) (xy 177.347788 -278.848852) (xy 177.343828 -278.799798)
			(xy 176.05502 -278.799798) (xy 176.054525 -278.824405) (xy 176.04663 -278.872982) (xy 176.031046 -278.919663)
			(xy 176.008175 -278.96324) (xy 175.97861 -279.002584) (xy 175.943117 -279.036676) (xy 175.902614 -279.064632)
			(xy 175.858152 -279.08573) (xy 175.810881 -279.099422) (xy 175.762026 -279.105354) (xy 175.712851 -279.103373)
			(xy 175.664632 -279.093529) (xy 175.618616 -279.076077) (xy 175.575995 -279.05147) (xy 175.537874 -279.020345)
			(xy 175.505239 -278.983508) (xy 175.478936 -278.941912) (xy 175.459645 -278.896636) (xy 175.447868 -278.848852)
			(xy 175.443908 -278.799798) (xy 174.155354 -278.799798) (xy 174.154859 -278.824405) (xy 174.146964 -278.872982)
			(xy 174.13138 -278.919663) (xy 174.108509 -278.96324) (xy 174.078944 -279.002584) (xy 174.043451 -279.036676)
			(xy 174.002948 -279.064632) (xy 173.958486 -279.08573) (xy 173.911215 -279.099422) (xy 173.86236 -279.105354)
			(xy 173.813185 -279.103373) (xy 173.764966 -279.093529) (xy 173.71895 -279.076077) (xy 173.676329 -279.05147)
			(xy 173.638208 -279.020345) (xy 173.605573 -278.983508) (xy 173.57927 -278.941912) (xy 173.559979 -278.896636)
			(xy 173.548202 -278.848852) (xy 173.544242 -278.799798) (xy 172.25518 -278.799798) (xy 172.254685 -278.824405)
			(xy 172.24679 -278.872982) (xy 172.231206 -278.919663) (xy 172.208335 -278.96324) (xy 172.17877 -279.002584)
			(xy 172.143277 -279.036676) (xy 172.102774 -279.064632) (xy 172.058312 -279.08573) (xy 172.011041 -279.099422)
			(xy 171.962186 -279.105354) (xy 171.913011 -279.103373) (xy 171.864792 -279.093529) (xy 171.818776 -279.076077)
			(xy 171.776155 -279.05147) (xy 171.738034 -279.020345) (xy 171.705399 -278.983508) (xy 171.679096 -278.941912)
			(xy 171.659805 -278.896636) (xy 171.648028 -278.848852) (xy 171.644068 -278.799798) (xy 170.35526 -278.799798)
			(xy 170.354765 -278.824405) (xy 170.34687 -278.872982) (xy 170.331286 -278.919663) (xy 170.308415 -278.96324)
			(xy 170.27885 -279.002584) (xy 170.243357 -279.036676) (xy 170.202854 -279.064632) (xy 170.158392 -279.08573)
			(xy 170.111121 -279.099422) (xy 170.062266 -279.105354) (xy 170.013091 -279.103373) (xy 169.964872 -279.093529)
			(xy 169.918856 -279.076077) (xy 169.876235 -279.05147) (xy 169.838114 -279.020345) (xy 169.805479 -278.983508)
			(xy 169.779176 -278.941912) (xy 169.759885 -278.896636) (xy 169.748108 -278.848852) (xy 169.744148 -278.799798)
			(xy 168.45534 -278.799798) (xy 168.454845 -278.824405) (xy 168.44695 -278.872982) (xy 168.431366 -278.919663)
			(xy 168.408495 -278.96324) (xy 168.37893 -279.002584) (xy 168.343437 -279.036676) (xy 168.302934 -279.064632)
			(xy 168.258472 -279.08573) (xy 168.211201 -279.099422) (xy 168.162346 -279.105354) (xy 168.113171 -279.103373)
			(xy 168.064952 -279.093529) (xy 168.018936 -279.076077) (xy 167.976315 -279.05147) (xy 167.938194 -279.020345)
			(xy 167.905559 -278.983508) (xy 167.879256 -278.941912) (xy 167.859965 -278.896636) (xy 167.848188 -278.848852)
			(xy 167.844228 -278.799798) (xy 166.555166 -278.799798) (xy 166.554671 -278.824405) (xy 166.546776 -278.872982)
			(xy 166.531192 -278.919663) (xy 166.508321 -278.96324) (xy 166.478756 -279.002584) (xy 166.443263 -279.036676)
			(xy 166.40276 -279.064632) (xy 166.358298 -279.08573) (xy 166.311027 -279.099422) (xy 166.262172 -279.105354)
			(xy 166.212997 -279.103373) (xy 166.164778 -279.093529) (xy 166.118762 -279.076077) (xy 166.076141 -279.05147)
			(xy 166.03802 -279.020345) (xy 166.005385 -278.983508) (xy 165.979082 -278.941912) (xy 165.959791 -278.896636)
			(xy 165.948014 -278.848852) (xy 165.944054 -278.799798) (xy 164.655246 -278.799798) (xy 164.654751 -278.824405)
			(xy 164.646856 -278.872982) (xy 164.631272 -278.919663) (xy 164.608401 -278.96324) (xy 164.578836 -279.002584)
			(xy 164.543343 -279.036676) (xy 164.50284 -279.064632) (xy 164.458378 -279.08573) (xy 164.411107 -279.099422)
			(xy 164.362252 -279.105354) (xy 164.313077 -279.103373) (xy 164.264858 -279.093529) (xy 164.218842 -279.076077)
			(xy 164.176221 -279.05147) (xy 164.1381 -279.020345) (xy 164.105465 -278.983508) (xy 164.079162 -278.941912)
			(xy 164.059871 -278.896636) (xy 164.048094 -278.848852) (xy 164.044134 -278.799798) (xy 162.755326 -278.799798)
			(xy 162.754831 -278.824405) (xy 162.746936 -278.872982) (xy 162.731352 -278.919663) (xy 162.708481 -278.96324)
			(xy 162.678916 -279.002584) (xy 162.643423 -279.036676) (xy 162.60292 -279.064632) (xy 162.558458 -279.08573)
			(xy 162.511187 -279.099422) (xy 162.462332 -279.105354) (xy 162.413157 -279.103373) (xy 162.364938 -279.093529)
			(xy 162.318922 -279.076077) (xy 162.276301 -279.05147) (xy 162.23818 -279.020345) (xy 162.205545 -278.983508)
			(xy 162.179242 -278.941912) (xy 162.159951 -278.896636) (xy 162.148174 -278.848852) (xy 162.144214 -278.799798)
			(xy 160.855152 -278.799798) (xy 160.854657 -278.824405) (xy 160.846762 -278.872982) (xy 160.831178 -278.919663)
			(xy 160.808307 -278.96324) (xy 160.778742 -279.002584) (xy 160.743249 -279.036676) (xy 160.702746 -279.064632)
			(xy 160.658284 -279.08573) (xy 160.611013 -279.099422) (xy 160.562158 -279.105354) (xy 160.512983 -279.103373)
			(xy 160.464764 -279.093529) (xy 160.418748 -279.076077) (xy 160.376127 -279.05147) (xy 160.338006 -279.020345)
			(xy 160.305371 -278.983508) (xy 160.279068 -278.941912) (xy 160.259777 -278.896636) (xy 160.248 -278.848852)
			(xy 160.24404 -278.799798) (xy 80.855058 -278.799798) (xy 80.854563 -278.824405) (xy 80.846668 -278.872982)
			(xy 80.831084 -278.919663) (xy 80.808213 -278.96324) (xy 80.778648 -279.002584) (xy 80.743155 -279.036676)
			(xy 80.702652 -279.064632) (xy 80.65819 -279.08573) (xy 80.610919 -279.099422) (xy 80.562064 -279.105354)
			(xy 80.512889 -279.103373) (xy 80.46467 -279.093529) (xy 80.418654 -279.076077) (xy 80.376033 -279.05147)
			(xy 80.337912 -279.020345) (xy 80.305277 -278.983508) (xy 80.278974 -278.941912) (xy 80.259683 -278.896636)
			(xy 80.247906 -278.848852) (xy 80.243946 -278.799798) (xy 78.954884 -278.799798) (xy 78.954389 -278.824405)
			(xy 78.946494 -278.872982) (xy 78.93091 -278.919663) (xy 78.908039 -278.96324) (xy 78.878474 -279.002584)
			(xy 78.842981 -279.036676) (xy 78.802478 -279.064632) (xy 78.758016 -279.08573) (xy 78.710745 -279.099422)
			(xy 78.66189 -279.105354) (xy 78.612715 -279.103373) (xy 78.564496 -279.093529) (xy 78.51848 -279.076077)
			(xy 78.475859 -279.05147) (xy 78.437738 -279.020345) (xy 78.405103 -278.983508) (xy 78.3788 -278.941912)
			(xy 78.359509 -278.896636) (xy 78.347732 -278.848852) (xy 78.343772 -278.799798) (xy 77.054964 -278.799798)
			(xy 77.054469 -278.824405) (xy 77.046574 -278.872982) (xy 77.03099 -278.919663) (xy 77.008119 -278.96324)
			(xy 76.978554 -279.002584) (xy 76.943061 -279.036676) (xy 76.902558 -279.064632) (xy 76.858096 -279.08573)
			(xy 76.810825 -279.099422) (xy 76.76197 -279.105354) (xy 76.712795 -279.103373) (xy 76.664576 -279.093529)
			(xy 76.61856 -279.076077) (xy 76.575939 -279.05147) (xy 76.537818 -279.020345) (xy 76.505183 -278.983508)
			(xy 76.47888 -278.941912) (xy 76.459589 -278.896636) (xy 76.447812 -278.848852) (xy 76.443852 -278.799798)
			(xy 75.155044 -278.799798) (xy 75.154549 -278.824405) (xy 75.146654 -278.872982) (xy 75.13107 -278.919663)
			(xy 75.108199 -278.96324) (xy 75.078634 -279.002584) (xy 75.043141 -279.036676) (xy 75.002638 -279.064632)
			(xy 74.958176 -279.08573) (xy 74.910905 -279.099422) (xy 74.86205 -279.105354) (xy 74.812875 -279.103373)
			(xy 74.764656 -279.093529) (xy 74.71864 -279.076077) (xy 74.676019 -279.05147) (xy 74.637898 -279.020345)
			(xy 74.605263 -278.983508) (xy 74.57896 -278.941912) (xy 74.559669 -278.896636) (xy 74.547892 -278.848852)
			(xy 74.543932 -278.799798) (xy 73.25487 -278.799798) (xy 73.254375 -278.824405) (xy 73.24648 -278.872982)
			(xy 73.230896 -278.919663) (xy 73.208025 -278.96324) (xy 73.17846 -279.002584) (xy 73.142967 -279.036676)
			(xy 73.102464 -279.064632) (xy 73.058002 -279.08573) (xy 73.010731 -279.099422) (xy 72.961876 -279.105354)
			(xy 72.912701 -279.103373) (xy 72.864482 -279.093529) (xy 72.818466 -279.076077) (xy 72.775845 -279.05147)
			(xy 72.737724 -279.020345) (xy 72.705089 -278.983508) (xy 72.678786 -278.941912) (xy 72.659495 -278.896636)
			(xy 72.647718 -278.848852) (xy 72.643758 -278.799798) (xy 71.35495 -278.799798) (xy 71.354455 -278.824405)
			(xy 71.34656 -278.872982) (xy 71.330976 -278.919663) (xy 71.308105 -278.96324) (xy 71.27854 -279.002584)
			(xy 71.243047 -279.036676) (xy 71.202544 -279.064632) (xy 71.158082 -279.08573) (xy 71.110811 -279.099422)
			(xy 71.061956 -279.105354) (xy 71.012781 -279.103373) (xy 70.964562 -279.093529) (xy 70.918546 -279.076077)
			(xy 70.875925 -279.05147) (xy 70.837804 -279.020345) (xy 70.805169 -278.983508) (xy 70.778866 -278.941912)
			(xy 70.759575 -278.896636) (xy 70.747798 -278.848852) (xy 70.743838 -278.799798) (xy 69.45503 -278.799798)
			(xy 69.454535 -278.824405) (xy 69.44664 -278.872982) (xy 69.431056 -278.919663) (xy 69.408185 -278.96324)
			(xy 69.37862 -279.002584) (xy 69.343127 -279.036676) (xy 69.302624 -279.064632) (xy 69.258162 -279.08573)
			(xy 69.210891 -279.099422) (xy 69.162036 -279.105354) (xy 69.112861 -279.103373) (xy 69.064642 -279.093529)
			(xy 69.018626 -279.076077) (xy 68.976005 -279.05147) (xy 68.937884 -279.020345) (xy 68.905249 -278.983508)
			(xy 68.878946 -278.941912) (xy 68.859655 -278.896636) (xy 68.847878 -278.848852) (xy 68.843918 -278.799798)
			(xy 67.554856 -278.799798) (xy 67.554361 -278.824405) (xy 67.546466 -278.872982) (xy 67.530882 -278.919663)
			(xy 67.508011 -278.96324) (xy 67.478446 -279.002584) (xy 67.442953 -279.036676) (xy 67.40245 -279.064632)
			(xy 67.357988 -279.08573) (xy 67.310717 -279.099422) (xy 67.261862 -279.105354) (xy 67.212687 -279.103373)
			(xy 67.164468 -279.093529) (xy 67.118452 -279.076077) (xy 67.075831 -279.05147) (xy 67.03771 -279.020345)
			(xy 67.005075 -278.983508) (xy 66.978772 -278.941912) (xy 66.959481 -278.896636) (xy 66.947704 -278.848852)
			(xy 66.943744 -278.799798) (xy 65.654936 -278.799798) (xy 65.654441 -278.824405) (xy 65.646546 -278.872982)
			(xy 65.630962 -278.919663) (xy 65.608091 -278.96324) (xy 65.578526 -279.002584) (xy 65.543033 -279.036676)
			(xy 65.50253 -279.064632) (xy 65.458068 -279.08573) (xy 65.410797 -279.099422) (xy 65.361942 -279.105354)
			(xy 65.312767 -279.103373) (xy 65.264548 -279.093529) (xy 65.218532 -279.076077) (xy 65.175911 -279.05147)
			(xy 65.13779 -279.020345) (xy 65.105155 -278.983508) (xy 65.078852 -278.941912) (xy 65.059561 -278.896636)
			(xy 65.047784 -278.848852) (xy 65.043824 -278.799798) (xy 63.755016 -278.799798) (xy 63.754521 -278.824405)
			(xy 63.746626 -278.872982) (xy 63.731042 -278.919663) (xy 63.708171 -278.96324) (xy 63.678606 -279.002584)
			(xy 63.643113 -279.036676) (xy 63.60261 -279.064632) (xy 63.558148 -279.08573) (xy 63.510877 -279.099422)
			(xy 63.462022 -279.105354) (xy 63.412847 -279.103373) (xy 63.364628 -279.093529) (xy 63.318612 -279.076077)
			(xy 63.275991 -279.05147) (xy 63.23787 -279.020345) (xy 63.205235 -278.983508) (xy 63.178932 -278.941912)
			(xy 63.159641 -278.896636) (xy 63.147864 -278.848852) (xy 63.143904 -278.799798) (xy 61.854842 -278.799798)
			(xy 61.854347 -278.824405) (xy 61.846452 -278.872982) (xy 61.830868 -278.919663) (xy 61.807997 -278.96324)
			(xy 61.778432 -279.002584) (xy 61.742939 -279.036676) (xy 61.702436 -279.064632) (xy 61.657974 -279.08573)
			(xy 61.610703 -279.099422) (xy 61.561848 -279.105354) (xy 61.512673 -279.103373) (xy 61.464454 -279.093529)
			(xy 61.418438 -279.076077) (xy 61.375817 -279.05147) (xy 61.337696 -279.020345) (xy 61.305061 -278.983508)
			(xy 61.278758 -278.941912) (xy 61.259467 -278.896636) (xy 61.24769 -278.848852) (xy 61.24373 -278.799798)
			(xy 59.954922 -278.799798) (xy 59.954427 -278.824405) (xy 59.946532 -278.872982) (xy 59.930948 -278.919663)
			(xy 59.908077 -278.96324) (xy 59.878512 -279.002584) (xy 59.843019 -279.036676) (xy 59.802516 -279.064632)
			(xy 59.758054 -279.08573) (xy 59.710783 -279.099422) (xy 59.661928 -279.105354) (xy 59.612753 -279.103373)
			(xy 59.564534 -279.093529) (xy 59.518518 -279.076077) (xy 59.475897 -279.05147) (xy 59.437776 -279.020345)
			(xy 59.405141 -278.983508) (xy 59.378838 -278.941912) (xy 59.359547 -278.896636) (xy 59.34777 -278.848852)
			(xy 59.34381 -278.799798) (xy 58.055256 -278.799798) (xy 58.054761 -278.824405) (xy 58.046866 -278.872982)
			(xy 58.031282 -278.919663) (xy 58.008411 -278.96324) (xy 57.978846 -279.002584) (xy 57.943353 -279.036676)
			(xy 57.90285 -279.064632) (xy 57.858388 -279.08573) (xy 57.811117 -279.099422) (xy 57.762262 -279.105354)
			(xy 57.713087 -279.103373) (xy 57.664868 -279.093529) (xy 57.618852 -279.076077) (xy 57.576231 -279.05147)
			(xy 57.53811 -279.020345) (xy 57.505475 -278.983508) (xy 57.479172 -278.941912) (xy 57.459881 -278.896636)
			(xy 57.448104 -278.848852) (xy 57.444144 -278.799798) (xy 56.155082 -278.799798) (xy 56.154587 -278.824405)
			(xy 56.146692 -278.872982) (xy 56.131108 -278.919663) (xy 56.108237 -278.96324) (xy 56.078672 -279.002584)
			(xy 56.043179 -279.036676) (xy 56.002676 -279.064632) (xy 55.958214 -279.08573) (xy 55.910943 -279.099422)
			(xy 55.862088 -279.105354) (xy 55.812913 -279.103373) (xy 55.764694 -279.093529) (xy 55.718678 -279.076077)
			(xy 55.676057 -279.05147) (xy 55.637936 -279.020345) (xy 55.605301 -278.983508) (xy 55.578998 -278.941912)
			(xy 55.559707 -278.896636) (xy 55.54793 -278.848852) (xy 55.54397 -278.799798) (xy 54.255162 -278.799798)
			(xy 54.254667 -278.824405) (xy 54.246772 -278.872982) (xy 54.231188 -278.919663) (xy 54.208317 -278.96324)
			(xy 54.178752 -279.002584) (xy 54.143259 -279.036676) (xy 54.102756 -279.064632) (xy 54.058294 -279.08573)
			(xy 54.011023 -279.099422) (xy 53.962168 -279.105354) (xy 53.912993 -279.103373) (xy 53.864774 -279.093529)
			(xy 53.818758 -279.076077) (xy 53.776137 -279.05147) (xy 53.738016 -279.020345) (xy 53.705381 -278.983508)
			(xy 53.679078 -278.941912) (xy 53.659787 -278.896636) (xy 53.64801 -278.848852) (xy 53.64405 -278.799798)
			(xy 52.355242 -278.799798) (xy 52.354747 -278.824405) (xy 52.346852 -278.872982) (xy 52.331268 -278.919663)
			(xy 52.308397 -278.96324) (xy 52.278832 -279.002584) (xy 52.243339 -279.036676) (xy 52.202836 -279.064632)
			(xy 52.158374 -279.08573) (xy 52.111103 -279.099422) (xy 52.062248 -279.105354) (xy 52.013073 -279.103373)
			(xy 51.964854 -279.093529) (xy 51.918838 -279.076077) (xy 51.876217 -279.05147) (xy 51.838096 -279.020345)
			(xy 51.805461 -278.983508) (xy 51.779158 -278.941912) (xy 51.759867 -278.896636) (xy 51.74809 -278.848852)
			(xy 51.74413 -278.799798) (xy 50.455068 -278.799798) (xy 50.454573 -278.824405) (xy 50.446678 -278.872982)
			(xy 50.431094 -278.919663) (xy 50.408223 -278.96324) (xy 50.378658 -279.002584) (xy 50.343165 -279.036676)
			(xy 50.302662 -279.064632) (xy 50.2582 -279.08573) (xy 50.210929 -279.099422) (xy 50.162074 -279.105354)
			(xy 50.112899 -279.103373) (xy 50.06468 -279.093529) (xy 50.018664 -279.076077) (xy 49.976043 -279.05147)
			(xy 49.937922 -279.020345) (xy 49.905287 -278.983508) (xy 49.878984 -278.941912) (xy 49.859693 -278.896636)
			(xy 49.847916 -278.848852) (xy 49.843956 -278.799798) (xy 48.555148 -278.799798) (xy 48.554653 -278.824405)
			(xy 48.546758 -278.872982) (xy 48.531174 -278.919663) (xy 48.508303 -278.96324) (xy 48.478738 -279.002584)
			(xy 48.443245 -279.036676) (xy 48.402742 -279.064632) (xy 48.35828 -279.08573) (xy 48.311009 -279.099422)
			(xy 48.262154 -279.105354) (xy 48.212979 -279.103373) (xy 48.16476 -279.093529) (xy 48.118744 -279.076077)
			(xy 48.076123 -279.05147) (xy 48.038002 -279.020345) (xy 48.005367 -278.983508) (xy 47.979064 -278.941912)
			(xy 47.959773 -278.896636) (xy 47.947996 -278.848852) (xy 47.944036 -278.799798) (xy 46.655228 -278.799798)
			(xy 46.654733 -278.824405) (xy 46.646838 -278.872982) (xy 46.631254 -278.919663) (xy 46.608383 -278.96324)
			(xy 46.578818 -279.002584) (xy 46.543325 -279.036676) (xy 46.502822 -279.064632) (xy 46.45836 -279.08573)
			(xy 46.411089 -279.099422) (xy 46.362234 -279.105354) (xy 46.313059 -279.103373) (xy 46.26484 -279.093529)
			(xy 46.218824 -279.076077) (xy 46.176203 -279.05147) (xy 46.138082 -279.020345) (xy 46.105447 -278.983508)
			(xy 46.079144 -278.941912) (xy 46.059853 -278.896636) (xy 46.048076 -278.848852) (xy 46.044116 -278.799798)
			(xy 44.755054 -278.799798) (xy 44.754559 -278.824405) (xy 44.746664 -278.872982) (xy 44.73108 -278.919663)
			(xy 44.708209 -278.96324) (xy 44.678644 -279.002584) (xy 44.643151 -279.036676) (xy 44.602648 -279.064632)
			(xy 44.558186 -279.08573) (xy 44.510915 -279.099422) (xy 44.46206 -279.105354) (xy 44.412885 -279.103373)
			(xy 44.364666 -279.093529) (xy 44.31865 -279.076077) (xy 44.276029 -279.05147) (xy 44.237908 -279.020345)
			(xy 44.205273 -278.983508) (xy 44.17897 -278.941912) (xy 44.159679 -278.896636) (xy 44.147902 -278.848852)
			(xy 44.143942 -278.799798) (xy 0.508 -278.799798) (xy 0.508 -279.749504) (xy 45.094156 -279.749504)
			(xy 45.098116 -279.70045) (xy 45.109893 -279.652666) (xy 45.129184 -279.60739) (xy 45.155487 -279.565794)
			(xy 45.188122 -279.528957) (xy 45.226243 -279.497832) (xy 45.268864 -279.473225) (xy 45.31488 -279.455773)
			(xy 45.363099 -279.445929) (xy 45.412274 -279.443948) (xy 45.461129 -279.44988) (xy 45.5084 -279.463572)
			(xy 45.552862 -279.48467) (xy 45.593365 -279.512626) (xy 45.628858 -279.546718) (xy 45.658423 -279.586062)
			(xy 45.681294 -279.629639) (xy 45.696878 -279.67632) (xy 45.704773 -279.724897) (xy 45.705268 -279.749504)
			(xy 46.994076 -279.749504) (xy 46.998036 -279.70045) (xy 47.009813 -279.652666) (xy 47.029104 -279.60739)
			(xy 47.055407 -279.565794) (xy 47.088042 -279.528957) (xy 47.126163 -279.497832) (xy 47.168784 -279.473225)
			(xy 47.2148 -279.455773) (xy 47.263019 -279.445929) (xy 47.312194 -279.443948) (xy 47.361049 -279.44988)
			(xy 47.40832 -279.463572) (xy 47.452782 -279.48467) (xy 47.493285 -279.512626) (xy 47.528778 -279.546718)
			(xy 47.558343 -279.586062) (xy 47.581214 -279.629639) (xy 47.596798 -279.67632) (xy 47.604693 -279.724897)
			(xy 47.605188 -279.749504) (xy 48.893996 -279.749504) (xy 48.897956 -279.70045) (xy 48.909733 -279.652666)
			(xy 48.929024 -279.60739) (xy 48.955327 -279.565794) (xy 48.987962 -279.528957) (xy 49.026083 -279.497832)
			(xy 49.068704 -279.473225) (xy 49.11472 -279.455773) (xy 49.162939 -279.445929) (xy 49.212114 -279.443948)
			(xy 49.260969 -279.44988) (xy 49.30824 -279.463572) (xy 49.352702 -279.48467) (xy 49.393205 -279.512626)
			(xy 49.428698 -279.546718) (xy 49.458263 -279.586062) (xy 49.481134 -279.629639) (xy 49.496718 -279.67632)
			(xy 49.504613 -279.724897) (xy 49.505108 -279.749504) (xy 50.79417 -279.749504) (xy 50.79813 -279.70045)
			(xy 50.809907 -279.652666) (xy 50.829198 -279.60739) (xy 50.855501 -279.565794) (xy 50.888136 -279.528957)
			(xy 50.926257 -279.497832) (xy 50.968878 -279.473225) (xy 51.014894 -279.455773) (xy 51.063113 -279.445929)
			(xy 51.112288 -279.443948) (xy 51.161143 -279.44988) (xy 51.208414 -279.463572) (xy 51.252876 -279.48467)
			(xy 51.293379 -279.512626) (xy 51.328872 -279.546718) (xy 51.358437 -279.586062) (xy 51.381308 -279.629639)
			(xy 51.396892 -279.67632) (xy 51.404787 -279.724897) (xy 51.405282 -279.749504) (xy 52.69409 -279.749504)
			(xy 52.69805 -279.70045) (xy 52.709827 -279.652666) (xy 52.729118 -279.60739) (xy 52.755421 -279.565794)
			(xy 52.788056 -279.528957) (xy 52.826177 -279.497832) (xy 52.868798 -279.473225) (xy 52.914814 -279.455773)
			(xy 52.963033 -279.445929) (xy 53.012208 -279.443948) (xy 53.061063 -279.44988) (xy 53.108334 -279.463572)
			(xy 53.152796 -279.48467) (xy 53.193299 -279.512626) (xy 53.228792 -279.546718) (xy 53.258357 -279.586062)
			(xy 53.281228 -279.629639) (xy 53.296812 -279.67632) (xy 53.304707 -279.724897) (xy 53.305202 -279.749504)
			(xy 54.59401 -279.749504) (xy 54.59797 -279.70045) (xy 54.609747 -279.652666) (xy 54.629038 -279.60739)
			(xy 54.655341 -279.565794) (xy 54.687976 -279.528957) (xy 54.726097 -279.497832) (xy 54.768718 -279.473225)
			(xy 54.814734 -279.455773) (xy 54.862953 -279.445929) (xy 54.912128 -279.443948) (xy 54.960983 -279.44988)
			(xy 55.008254 -279.463572) (xy 55.052716 -279.48467) (xy 55.093219 -279.512626) (xy 55.128712 -279.546718)
			(xy 55.158277 -279.586062) (xy 55.181148 -279.629639) (xy 55.196732 -279.67632) (xy 55.204627 -279.724897)
			(xy 55.205122 -279.749504) (xy 56.49393 -279.749504) (xy 56.49789 -279.70045) (xy 56.509667 -279.652666)
			(xy 56.528958 -279.60739) (xy 56.555261 -279.565794) (xy 56.587896 -279.528957) (xy 56.626017 -279.497832)
			(xy 56.668638 -279.473225) (xy 56.714654 -279.455773) (xy 56.762873 -279.445929) (xy 56.812048 -279.443948)
			(xy 56.860903 -279.44988) (xy 56.908174 -279.463572) (xy 56.952636 -279.48467) (xy 56.993139 -279.512626)
			(xy 57.028632 -279.546718) (xy 57.058197 -279.586062) (xy 57.081068 -279.629639) (xy 57.096652 -279.67632)
			(xy 57.104547 -279.724897) (xy 57.105042 -279.749504) (xy 58.394104 -279.749504) (xy 58.398064 -279.70045)
			(xy 58.409841 -279.652666) (xy 58.429132 -279.60739) (xy 58.455435 -279.565794) (xy 58.48807 -279.528957)
			(xy 58.526191 -279.497832) (xy 58.568812 -279.473225) (xy 58.614828 -279.455773) (xy 58.663047 -279.445929)
			(xy 58.712222 -279.443948) (xy 58.761077 -279.44988) (xy 58.808348 -279.463572) (xy 58.85281 -279.48467)
			(xy 58.893313 -279.512626) (xy 58.928806 -279.546718) (xy 58.958371 -279.586062) (xy 58.981242 -279.629639)
			(xy 58.996826 -279.67632) (xy 59.004721 -279.724897) (xy 59.005216 -279.749504) (xy 60.294024 -279.749504)
			(xy 60.297984 -279.70045) (xy 60.309761 -279.652666) (xy 60.329052 -279.60739) (xy 60.355355 -279.565794)
			(xy 60.38799 -279.528957) (xy 60.426111 -279.497832) (xy 60.468732 -279.473225) (xy 60.514748 -279.455773)
			(xy 60.562967 -279.445929) (xy 60.612142 -279.443948) (xy 60.660997 -279.44988) (xy 60.708268 -279.463572)
			(xy 60.75273 -279.48467) (xy 60.793233 -279.512626) (xy 60.828726 -279.546718) (xy 60.858291 -279.586062)
			(xy 60.881162 -279.629639) (xy 60.896746 -279.67632) (xy 60.904641 -279.724897) (xy 60.905136 -279.749504)
			(xy 62.193944 -279.749504) (xy 62.197904 -279.70045) (xy 62.209681 -279.652666) (xy 62.228972 -279.60739)
			(xy 62.255275 -279.565794) (xy 62.28791 -279.528957) (xy 62.326031 -279.497832) (xy 62.368652 -279.473225)
			(xy 62.414668 -279.455773) (xy 62.462887 -279.445929) (xy 62.512062 -279.443948) (xy 62.560917 -279.44988)
			(xy 62.608188 -279.463572) (xy 62.65265 -279.48467) (xy 62.693153 -279.512626) (xy 62.728646 -279.546718)
			(xy 62.758211 -279.586062) (xy 62.781082 -279.629639) (xy 62.796666 -279.67632) (xy 62.804561 -279.724897)
			(xy 62.805056 -279.749504) (xy 64.094118 -279.749504) (xy 64.098078 -279.70045) (xy 64.109855 -279.652666)
			(xy 64.129146 -279.60739) (xy 64.155449 -279.565794) (xy 64.188084 -279.528957) (xy 64.226205 -279.497832)
			(xy 64.268826 -279.473225) (xy 64.314842 -279.455773) (xy 64.363061 -279.445929) (xy 64.412236 -279.443948)
			(xy 64.461091 -279.44988) (xy 64.508362 -279.463572) (xy 64.552824 -279.48467) (xy 64.593327 -279.512626)
			(xy 64.62882 -279.546718) (xy 64.658385 -279.586062) (xy 64.681256 -279.629639) (xy 64.69684 -279.67632)
			(xy 64.704735 -279.724897) (xy 64.70523 -279.749504) (xy 65.994038 -279.749504) (xy 65.997998 -279.70045)
			(xy 66.009775 -279.652666) (xy 66.029066 -279.60739) (xy 66.055369 -279.565794) (xy 66.088004 -279.528957)
			(xy 66.126125 -279.497832) (xy 66.168746 -279.473225) (xy 66.214762 -279.455773) (xy 66.262981 -279.445929)
			(xy 66.312156 -279.443948) (xy 66.361011 -279.44988) (xy 66.408282 -279.463572) (xy 66.452744 -279.48467)
			(xy 66.493247 -279.512626) (xy 66.52874 -279.546718) (xy 66.558305 -279.586062) (xy 66.581176 -279.629639)
			(xy 66.59676 -279.67632) (xy 66.604655 -279.724897) (xy 66.60515 -279.749504) (xy 67.893958 -279.749504)
			(xy 67.897918 -279.70045) (xy 67.909695 -279.652666) (xy 67.928986 -279.60739) (xy 67.955289 -279.565794)
			(xy 67.987924 -279.528957) (xy 68.026045 -279.497832) (xy 68.068666 -279.473225) (xy 68.114682 -279.455773)
			(xy 68.162901 -279.445929) (xy 68.212076 -279.443948) (xy 68.260931 -279.44988) (xy 68.308202 -279.463572)
			(xy 68.352664 -279.48467) (xy 68.393167 -279.512626) (xy 68.42866 -279.546718) (xy 68.458225 -279.586062)
			(xy 68.481096 -279.629639) (xy 68.49668 -279.67632) (xy 68.504575 -279.724897) (xy 68.50507 -279.749504)
			(xy 69.794132 -279.749504) (xy 69.798092 -279.70045) (xy 69.809869 -279.652666) (xy 69.82916 -279.60739)
			(xy 69.855463 -279.565794) (xy 69.888098 -279.528957) (xy 69.926219 -279.497832) (xy 69.96884 -279.473225)
			(xy 70.014856 -279.455773) (xy 70.063075 -279.445929) (xy 70.11225 -279.443948) (xy 70.161105 -279.44988)
			(xy 70.208376 -279.463572) (xy 70.252838 -279.48467) (xy 70.293341 -279.512626) (xy 70.328834 -279.546718)
			(xy 70.358399 -279.586062) (xy 70.38127 -279.629639) (xy 70.396854 -279.67632) (xy 70.404749 -279.724897)
			(xy 70.405244 -279.749504) (xy 71.694052 -279.749504) (xy 71.698012 -279.70045) (xy 71.709789 -279.652666)
			(xy 71.72908 -279.60739) (xy 71.755383 -279.565794) (xy 71.788018 -279.528957) (xy 71.826139 -279.497832)
			(xy 71.86876 -279.473225) (xy 71.914776 -279.455773) (xy 71.962995 -279.445929) (xy 72.01217 -279.443948)
			(xy 72.061025 -279.44988) (xy 72.108296 -279.463572) (xy 72.152758 -279.48467) (xy 72.193261 -279.512626)
			(xy 72.228754 -279.546718) (xy 72.258319 -279.586062) (xy 72.28119 -279.629639) (xy 72.296774 -279.67632)
			(xy 72.304669 -279.724897) (xy 72.305164 -279.749504) (xy 73.593972 -279.749504) (xy 73.597932 -279.70045)
			(xy 73.609709 -279.652666) (xy 73.629 -279.60739) (xy 73.655303 -279.565794) (xy 73.687938 -279.528957)
			(xy 73.726059 -279.497832) (xy 73.76868 -279.473225) (xy 73.814696 -279.455773) (xy 73.862915 -279.445929)
			(xy 73.91209 -279.443948) (xy 73.960945 -279.44988) (xy 74.008216 -279.463572) (xy 74.052678 -279.48467)
			(xy 74.093181 -279.512626) (xy 74.128674 -279.546718) (xy 74.158239 -279.586062) (xy 74.18111 -279.629639)
			(xy 74.196694 -279.67632) (xy 74.204589 -279.724897) (xy 74.205084 -279.749504) (xy 75.494146 -279.749504)
			(xy 75.498106 -279.70045) (xy 75.509883 -279.652666) (xy 75.529174 -279.60739) (xy 75.555477 -279.565794)
			(xy 75.588112 -279.528957) (xy 75.626233 -279.497832) (xy 75.668854 -279.473225) (xy 75.71487 -279.455773)
			(xy 75.763089 -279.445929) (xy 75.812264 -279.443948) (xy 75.861119 -279.44988) (xy 75.90839 -279.463572)
			(xy 75.952852 -279.48467) (xy 75.993355 -279.512626) (xy 76.028848 -279.546718) (xy 76.058413 -279.586062)
			(xy 76.081284 -279.629639) (xy 76.096868 -279.67632) (xy 76.104763 -279.724897) (xy 76.105258 -279.749504)
			(xy 77.394066 -279.749504) (xy 77.398026 -279.70045) (xy 77.409803 -279.652666) (xy 77.429094 -279.60739)
			(xy 77.455397 -279.565794) (xy 77.488032 -279.528957) (xy 77.526153 -279.497832) (xy 77.568774 -279.473225)
			(xy 77.61479 -279.455773) (xy 77.663009 -279.445929) (xy 77.712184 -279.443948) (xy 77.761039 -279.44988)
			(xy 77.80831 -279.463572) (xy 77.852772 -279.48467) (xy 77.893275 -279.512626) (xy 77.928768 -279.546718)
			(xy 77.958333 -279.586062) (xy 77.981204 -279.629639) (xy 77.996788 -279.67632) (xy 78.004683 -279.724897)
			(xy 78.005178 -279.749504) (xy 78.005173 -279.749758) (xy 79.293986 -279.749758) (xy 79.297946 -279.700704)
			(xy 79.309723 -279.65292) (xy 79.329014 -279.607644) (xy 79.355317 -279.566048) (xy 79.387952 -279.529211)
			(xy 79.426073 -279.498086) (xy 79.468694 -279.473479) (xy 79.51471 -279.456027) (xy 79.562929 -279.446183)
			(xy 79.612104 -279.444202) (xy 79.660959 -279.450134) (xy 79.70823 -279.463826) (xy 79.752692 -279.484924)
			(xy 79.793195 -279.51288) (xy 79.828688 -279.546972) (xy 79.858253 -279.586316) (xy 79.881124 -279.629893)
			(xy 79.896708 -279.676574) (xy 79.904603 -279.725151) (xy 79.905098 -279.749758) (xy 81.19416 -279.749758)
			(xy 81.19812 -279.700704) (xy 81.209897 -279.65292) (xy 81.229188 -279.607644) (xy 81.255491 -279.566048)
			(xy 81.288126 -279.529211) (xy 81.326247 -279.498086) (xy 81.368868 -279.473479) (xy 81.414884 -279.456027)
			(xy 81.463103 -279.446183) (xy 81.512278 -279.444202) (xy 81.561133 -279.450134) (xy 81.608404 -279.463826)
			(xy 81.652866 -279.484924) (xy 81.693369 -279.51288) (xy 81.728862 -279.546972) (xy 81.758427 -279.586316)
			(xy 81.781298 -279.629893) (xy 81.796882 -279.676574) (xy 81.804777 -279.725151) (xy 81.805272 -279.749758)
			(xy 82.14412 -279.749758) (xy 82.14808 -279.700704) (xy 82.159857 -279.65292) (xy 82.179148 -279.607644)
			(xy 82.205451 -279.566048) (xy 82.238086 -279.529211) (xy 82.276207 -279.498086) (xy 82.318828 -279.473479)
			(xy 82.364844 -279.456027) (xy 82.413063 -279.446183) (xy 82.462238 -279.444202) (xy 82.511093 -279.450134)
			(xy 82.558364 -279.463826) (xy 82.602826 -279.484924) (xy 82.643329 -279.51288) (xy 82.678822 -279.546972)
			(xy 82.708387 -279.586316) (xy 82.731258 -279.629893) (xy 82.746842 -279.676574) (xy 82.754737 -279.725151)
			(xy 82.755227 -279.749504) (xy 161.194254 -279.749504) (xy 161.198214 -279.70045) (xy 161.209991 -279.652666)
			(xy 161.229282 -279.60739) (xy 161.255585 -279.565794) (xy 161.28822 -279.528957) (xy 161.326341 -279.497832)
			(xy 161.368962 -279.473225) (xy 161.414978 -279.455773) (xy 161.463197 -279.445929) (xy 161.512372 -279.443948)
			(xy 161.561227 -279.44988) (xy 161.608498 -279.463572) (xy 161.65296 -279.48467) (xy 161.693463 -279.512626)
			(xy 161.728956 -279.546718) (xy 161.758521 -279.586062) (xy 161.781392 -279.629639) (xy 161.796976 -279.67632)
			(xy 161.804871 -279.724897) (xy 161.805366 -279.749504) (xy 163.094174 -279.749504) (xy 163.098134 -279.70045)
			(xy 163.109911 -279.652666) (xy 163.129202 -279.60739) (xy 163.155505 -279.565794) (xy 163.18814 -279.528957)
			(xy 163.226261 -279.497832) (xy 163.268882 -279.473225) (xy 163.314898 -279.455773) (xy 163.363117 -279.445929)
			(xy 163.412292 -279.443948) (xy 163.461147 -279.44988) (xy 163.508418 -279.463572) (xy 163.55288 -279.48467)
			(xy 163.593383 -279.512626) (xy 163.628876 -279.546718) (xy 163.658441 -279.586062) (xy 163.681312 -279.629639)
			(xy 163.696896 -279.67632) (xy 163.704791 -279.724897) (xy 163.705286 -279.749504) (xy 164.994094 -279.749504)
			(xy 164.998054 -279.70045) (xy 165.009831 -279.652666) (xy 165.029122 -279.60739) (xy 165.055425 -279.565794)
			(xy 165.08806 -279.528957) (xy 165.126181 -279.497832) (xy 165.168802 -279.473225) (xy 165.214818 -279.455773)
			(xy 165.263037 -279.445929) (xy 165.312212 -279.443948) (xy 165.361067 -279.44988) (xy 165.408338 -279.463572)
			(xy 165.4528 -279.48467) (xy 165.493303 -279.512626) (xy 165.528796 -279.546718) (xy 165.558361 -279.586062)
			(xy 165.581232 -279.629639) (xy 165.596816 -279.67632) (xy 165.604711 -279.724897) (xy 165.605206 -279.749504)
			(xy 166.894268 -279.749504) (xy 166.898228 -279.70045) (xy 166.910005 -279.652666) (xy 166.929296 -279.60739)
			(xy 166.955599 -279.565794) (xy 166.988234 -279.528957) (xy 167.026355 -279.497832) (xy 167.068976 -279.473225)
			(xy 167.114992 -279.455773) (xy 167.163211 -279.445929) (xy 167.212386 -279.443948) (xy 167.261241 -279.44988)
			(xy 167.308512 -279.463572) (xy 167.352974 -279.48467) (xy 167.393477 -279.512626) (xy 167.42897 -279.546718)
			(xy 167.458535 -279.586062) (xy 167.481406 -279.629639) (xy 167.49699 -279.67632) (xy 167.504885 -279.724897)
			(xy 167.50538 -279.749504) (xy 168.794188 -279.749504) (xy 168.798148 -279.70045) (xy 168.809925 -279.652666)
			(xy 168.829216 -279.60739) (xy 168.855519 -279.565794) (xy 168.888154 -279.528957) (xy 168.926275 -279.497832)
			(xy 168.968896 -279.473225) (xy 169.014912 -279.455773) (xy 169.063131 -279.445929) (xy 169.112306 -279.443948)
			(xy 169.161161 -279.44988) (xy 169.208432 -279.463572) (xy 169.252894 -279.48467) (xy 169.293397 -279.512626)
			(xy 169.32889 -279.546718) (xy 169.358455 -279.586062) (xy 169.381326 -279.629639) (xy 169.39691 -279.67632)
			(xy 169.404805 -279.724897) (xy 169.4053 -279.749504) (xy 170.694108 -279.749504) (xy 170.698068 -279.70045)
			(xy 170.709845 -279.652666) (xy 170.729136 -279.60739) (xy 170.755439 -279.565794) (xy 170.788074 -279.528957)
			(xy 170.826195 -279.497832) (xy 170.868816 -279.473225) (xy 170.914832 -279.455773) (xy 170.963051 -279.445929)
			(xy 171.012226 -279.443948) (xy 171.061081 -279.44988) (xy 171.108352 -279.463572) (xy 171.152814 -279.48467)
			(xy 171.193317 -279.512626) (xy 171.22881 -279.546718) (xy 171.258375 -279.586062) (xy 171.281246 -279.629639)
			(xy 171.29683 -279.67632) (xy 171.304725 -279.724897) (xy 171.30522 -279.749504) (xy 172.594028 -279.749504)
			(xy 172.597988 -279.70045) (xy 172.609765 -279.652666) (xy 172.629056 -279.60739) (xy 172.655359 -279.565794)
			(xy 172.687994 -279.528957) (xy 172.726115 -279.497832) (xy 172.768736 -279.473225) (xy 172.814752 -279.455773)
			(xy 172.862971 -279.445929) (xy 172.912146 -279.443948) (xy 172.961001 -279.44988) (xy 173.008272 -279.463572)
			(xy 173.052734 -279.48467) (xy 173.093237 -279.512626) (xy 173.12873 -279.546718) (xy 173.158295 -279.586062)
			(xy 173.181166 -279.629639) (xy 173.19675 -279.67632) (xy 173.204645 -279.724897) (xy 173.20514 -279.749504)
			(xy 174.494202 -279.749504) (xy 174.498162 -279.70045) (xy 174.509939 -279.652666) (xy 174.52923 -279.60739)
			(xy 174.555533 -279.565794) (xy 174.588168 -279.528957) (xy 174.626289 -279.497832) (xy 174.66891 -279.473225)
			(xy 174.714926 -279.455773) (xy 174.763145 -279.445929) (xy 174.81232 -279.443948) (xy 174.861175 -279.44988)
			(xy 174.908446 -279.463572) (xy 174.952908 -279.48467) (xy 174.993411 -279.512626) (xy 175.028904 -279.546718)
			(xy 175.058469 -279.586062) (xy 175.08134 -279.629639) (xy 175.096924 -279.67632) (xy 175.104819 -279.724897)
			(xy 175.105314 -279.749504) (xy 176.394122 -279.749504) (xy 176.398082 -279.70045) (xy 176.409859 -279.652666)
			(xy 176.42915 -279.60739) (xy 176.455453 -279.565794) (xy 176.488088 -279.528957) (xy 176.526209 -279.497832)
			(xy 176.56883 -279.473225) (xy 176.614846 -279.455773) (xy 176.663065 -279.445929) (xy 176.71224 -279.443948)
			(xy 176.761095 -279.44988) (xy 176.808366 -279.463572) (xy 176.852828 -279.48467) (xy 176.893331 -279.512626)
			(xy 176.928824 -279.546718) (xy 176.958389 -279.586062) (xy 176.98126 -279.629639) (xy 176.996844 -279.67632)
			(xy 177.004739 -279.724897) (xy 177.005234 -279.749504) (xy 178.294042 -279.749504) (xy 178.298002 -279.70045)
			(xy 178.309779 -279.652666) (xy 178.32907 -279.60739) (xy 178.355373 -279.565794) (xy 178.388008 -279.528957)
			(xy 178.426129 -279.497832) (xy 178.46875 -279.473225) (xy 178.514766 -279.455773) (xy 178.562985 -279.445929)
			(xy 178.61216 -279.443948) (xy 178.661015 -279.44988) (xy 178.708286 -279.463572) (xy 178.752748 -279.48467)
			(xy 178.793251 -279.512626) (xy 178.828744 -279.546718) (xy 178.858309 -279.586062) (xy 178.88118 -279.629639)
			(xy 178.896764 -279.67632) (xy 178.904659 -279.724897) (xy 178.905154 -279.749504) (xy 180.194216 -279.749504)
			(xy 180.198176 -279.70045) (xy 180.209953 -279.652666) (xy 180.229244 -279.60739) (xy 180.255547 -279.565794)
			(xy 180.288182 -279.528957) (xy 180.326303 -279.497832) (xy 180.368924 -279.473225) (xy 180.41494 -279.455773)
			(xy 180.463159 -279.445929) (xy 180.512334 -279.443948) (xy 180.561189 -279.44988) (xy 180.60846 -279.463572)
			(xy 180.652922 -279.48467) (xy 180.693425 -279.512626) (xy 180.728918 -279.546718) (xy 180.758483 -279.586062)
			(xy 180.781354 -279.629639) (xy 180.796938 -279.67632) (xy 180.804833 -279.724897) (xy 180.805328 -279.749504)
			(xy 182.094136 -279.749504) (xy 182.098096 -279.70045) (xy 182.109873 -279.652666) (xy 182.129164 -279.60739)
			(xy 182.155467 -279.565794) (xy 182.188102 -279.528957) (xy 182.226223 -279.497832) (xy 182.268844 -279.473225)
			(xy 182.31486 -279.455773) (xy 182.363079 -279.445929) (xy 182.412254 -279.443948) (xy 182.461109 -279.44988)
			(xy 182.50838 -279.463572) (xy 182.552842 -279.48467) (xy 182.593345 -279.512626) (xy 182.628838 -279.546718)
			(xy 182.658403 -279.586062) (xy 182.681274 -279.629639) (xy 182.696858 -279.67632) (xy 182.704753 -279.724897)
			(xy 182.705248 -279.749504) (xy 183.994056 -279.749504) (xy 183.998016 -279.70045) (xy 184.009793 -279.652666)
			(xy 184.029084 -279.60739) (xy 184.055387 -279.565794) (xy 184.088022 -279.528957) (xy 184.126143 -279.497832)
			(xy 184.168764 -279.473225) (xy 184.21478 -279.455773) (xy 184.262999 -279.445929) (xy 184.312174 -279.443948)
			(xy 184.361029 -279.44988) (xy 184.4083 -279.463572) (xy 184.452762 -279.48467) (xy 184.493265 -279.512626)
			(xy 184.528758 -279.546718) (xy 184.558323 -279.586062) (xy 184.581194 -279.629639) (xy 184.596778 -279.67632)
			(xy 184.604673 -279.724897) (xy 184.605168 -279.749504) (xy 185.89423 -279.749504) (xy 185.89819 -279.70045)
			(xy 185.909967 -279.652666) (xy 185.929258 -279.60739) (xy 185.955561 -279.565794) (xy 185.988196 -279.528957)
			(xy 186.026317 -279.497832) (xy 186.068938 -279.473225) (xy 186.114954 -279.455773) (xy 186.163173 -279.445929)
			(xy 186.212348 -279.443948) (xy 186.261203 -279.44988) (xy 186.308474 -279.463572) (xy 186.352936 -279.48467)
			(xy 186.393439 -279.512626) (xy 186.428932 -279.546718) (xy 186.458497 -279.586062) (xy 186.481368 -279.629639)
			(xy 186.496952 -279.67632) (xy 186.504847 -279.724897) (xy 186.505342 -279.749504) (xy 187.79415 -279.749504)
			(xy 187.79811 -279.70045) (xy 187.809887 -279.652666) (xy 187.829178 -279.60739) (xy 187.855481 -279.565794)
			(xy 187.888116 -279.528957) (xy 187.926237 -279.497832) (xy 187.968858 -279.473225) (xy 188.014874 -279.455773)
			(xy 188.063093 -279.445929) (xy 188.112268 -279.443948) (xy 188.161123 -279.44988) (xy 188.208394 -279.463572)
			(xy 188.252856 -279.48467) (xy 188.293359 -279.512626) (xy 188.328852 -279.546718) (xy 188.358417 -279.586062)
			(xy 188.381288 -279.629639) (xy 188.396872 -279.67632) (xy 188.404767 -279.724897) (xy 188.405262 -279.749504)
			(xy 189.69407 -279.749504) (xy 189.69803 -279.70045) (xy 189.709807 -279.652666) (xy 189.729098 -279.60739)
			(xy 189.755401 -279.565794) (xy 189.788036 -279.528957) (xy 189.826157 -279.497832) (xy 189.868778 -279.473225)
			(xy 189.914794 -279.455773) (xy 189.963013 -279.445929) (xy 190.012188 -279.443948) (xy 190.061043 -279.44988)
			(xy 190.108314 -279.463572) (xy 190.152776 -279.48467) (xy 190.193279 -279.512626) (xy 190.228772 -279.546718)
			(xy 190.258337 -279.586062) (xy 190.281208 -279.629639) (xy 190.296792 -279.67632) (xy 190.304687 -279.724897)
			(xy 190.305182 -279.749504) (xy 191.594244 -279.749504) (xy 191.598204 -279.70045) (xy 191.609981 -279.652666)
			(xy 191.629272 -279.60739) (xy 191.655575 -279.565794) (xy 191.68821 -279.528957) (xy 191.726331 -279.497832)
			(xy 191.768952 -279.473225) (xy 191.814968 -279.455773) (xy 191.863187 -279.445929) (xy 191.912362 -279.443948)
			(xy 191.961217 -279.44988) (xy 192.008488 -279.463572) (xy 192.05295 -279.48467) (xy 192.093453 -279.512626)
			(xy 192.128946 -279.546718) (xy 192.158511 -279.586062) (xy 192.181382 -279.629639) (xy 192.196966 -279.67632)
			(xy 192.204861 -279.724897) (xy 192.205356 -279.749504) (xy 193.494164 -279.749504) (xy 193.498124 -279.70045)
			(xy 193.509901 -279.652666) (xy 193.529192 -279.60739) (xy 193.555495 -279.565794) (xy 193.58813 -279.528957)
			(xy 193.626251 -279.497832) (xy 193.668872 -279.473225) (xy 193.714888 -279.455773) (xy 193.763107 -279.445929)
			(xy 193.812282 -279.443948) (xy 193.861137 -279.44988) (xy 193.908408 -279.463572) (xy 193.95287 -279.48467)
			(xy 193.993373 -279.512626) (xy 194.028866 -279.546718) (xy 194.058431 -279.586062) (xy 194.081302 -279.629639)
			(xy 194.096886 -279.67632) (xy 194.104781 -279.724897) (xy 194.105276 -279.749504) (xy 194.105271 -279.749758)
			(xy 195.394084 -279.749758) (xy 195.398044 -279.700704) (xy 195.409821 -279.65292) (xy 195.429112 -279.607644)
			(xy 195.455415 -279.566048) (xy 195.48805 -279.529211) (xy 195.526171 -279.498086) (xy 195.568792 -279.473479)
			(xy 195.614808 -279.456027) (xy 195.663027 -279.446183) (xy 195.712202 -279.444202) (xy 195.761057 -279.450134)
			(xy 195.808328 -279.463826) (xy 195.85279 -279.484924) (xy 195.893293 -279.51288) (xy 195.928786 -279.546972)
			(xy 195.958351 -279.586316) (xy 195.981222 -279.629893) (xy 195.996806 -279.676574) (xy 196.004701 -279.725151)
			(xy 196.005196 -279.749758) (xy 197.294258 -279.749758) (xy 197.298218 -279.700704) (xy 197.309995 -279.65292)
			(xy 197.329286 -279.607644) (xy 197.355589 -279.566048) (xy 197.388224 -279.529211) (xy 197.426345 -279.498086)
			(xy 197.468966 -279.473479) (xy 197.514982 -279.456027) (xy 197.563201 -279.446183) (xy 197.612376 -279.444202)
			(xy 197.661231 -279.450134) (xy 197.708502 -279.463826) (xy 197.752964 -279.484924) (xy 197.793467 -279.51288)
			(xy 197.82896 -279.546972) (xy 197.858525 -279.586316) (xy 197.881396 -279.629893) (xy 197.89698 -279.676574)
			(xy 197.904875 -279.725151) (xy 197.90537 -279.749758) (xy 198.244218 -279.749758) (xy 198.248178 -279.700704)
			(xy 198.259955 -279.65292) (xy 198.279246 -279.607644) (xy 198.305549 -279.566048) (xy 198.338184 -279.529211)
			(xy 198.376305 -279.498086) (xy 198.418926 -279.473479) (xy 198.464942 -279.456027) (xy 198.513161 -279.446183)
			(xy 198.562336 -279.444202) (xy 198.611191 -279.450134) (xy 198.658462 -279.463826) (xy 198.702924 -279.484924)
			(xy 198.743427 -279.51288) (xy 198.77892 -279.546972) (xy 198.808485 -279.586316) (xy 198.831356 -279.629893)
			(xy 198.84694 -279.676574) (xy 198.854835 -279.725151) (xy 198.855325 -279.749504) (xy 277.294098 -279.749504)
			(xy 277.298058 -279.70045) (xy 277.309835 -279.652666) (xy 277.329126 -279.60739) (xy 277.355429 -279.565794)
			(xy 277.388064 -279.528957) (xy 277.426185 -279.497832) (xy 277.468806 -279.473225) (xy 277.514822 -279.455773)
			(xy 277.563041 -279.445929) (xy 277.612216 -279.443948) (xy 277.661071 -279.44988) (xy 277.708342 -279.463572)
			(xy 277.752804 -279.48467) (xy 277.793307 -279.512626) (xy 277.8288 -279.546718) (xy 277.858365 -279.586062)
			(xy 277.881236 -279.629639) (xy 277.89682 -279.67632) (xy 277.904715 -279.724897) (xy 277.90521 -279.749504)
			(xy 279.194018 -279.749504) (xy 279.197978 -279.70045) (xy 279.209755 -279.652666) (xy 279.229046 -279.60739)
			(xy 279.255349 -279.565794) (xy 279.287984 -279.528957) (xy 279.326105 -279.497832) (xy 279.368726 -279.473225)
			(xy 279.414742 -279.455773) (xy 279.462961 -279.445929) (xy 279.512136 -279.443948) (xy 279.560991 -279.44988)
			(xy 279.608262 -279.463572) (xy 279.652724 -279.48467) (xy 279.693227 -279.512626) (xy 279.72872 -279.546718)
			(xy 279.758285 -279.586062) (xy 279.781156 -279.629639) (xy 279.79674 -279.67632) (xy 279.804635 -279.724897)
			(xy 279.80513 -279.749504) (xy 281.093938 -279.749504) (xy 281.097898 -279.70045) (xy 281.109675 -279.652666)
			(xy 281.128966 -279.60739) (xy 281.155269 -279.565794) (xy 281.187904 -279.528957) (xy 281.226025 -279.497832)
			(xy 281.268646 -279.473225) (xy 281.314662 -279.455773) (xy 281.362881 -279.445929) (xy 281.412056 -279.443948)
			(xy 281.460911 -279.44988) (xy 281.508182 -279.463572) (xy 281.552644 -279.48467) (xy 281.593147 -279.512626)
			(xy 281.62864 -279.546718) (xy 281.658205 -279.586062) (xy 281.681076 -279.629639) (xy 281.69666 -279.67632)
			(xy 281.704555 -279.724897) (xy 281.70505 -279.749504) (xy 282.994112 -279.749504) (xy 282.998072 -279.70045)
			(xy 283.009849 -279.652666) (xy 283.02914 -279.60739) (xy 283.055443 -279.565794) (xy 283.088078 -279.528957)
			(xy 283.126199 -279.497832) (xy 283.16882 -279.473225) (xy 283.214836 -279.455773) (xy 283.263055 -279.445929)
			(xy 283.31223 -279.443948) (xy 283.361085 -279.44988) (xy 283.408356 -279.463572) (xy 283.452818 -279.48467)
			(xy 283.493321 -279.512626) (xy 283.528814 -279.546718) (xy 283.558379 -279.586062) (xy 283.58125 -279.629639)
			(xy 283.596834 -279.67632) (xy 283.604729 -279.724897) (xy 283.605224 -279.749504) (xy 284.894032 -279.749504)
			(xy 284.897992 -279.70045) (xy 284.909769 -279.652666) (xy 284.92906 -279.60739) (xy 284.955363 -279.565794)
			(xy 284.987998 -279.528957) (xy 285.026119 -279.497832) (xy 285.06874 -279.473225) (xy 285.114756 -279.455773)
			(xy 285.162975 -279.445929) (xy 285.21215 -279.443948) (xy 285.261005 -279.44988) (xy 285.308276 -279.463572)
			(xy 285.352738 -279.48467) (xy 285.393241 -279.512626) (xy 285.428734 -279.546718) (xy 285.458299 -279.586062)
			(xy 285.48117 -279.629639) (xy 285.496754 -279.67632) (xy 285.504649 -279.724897) (xy 285.505144 -279.749504)
			(xy 286.793952 -279.749504) (xy 286.797912 -279.70045) (xy 286.809689 -279.652666) (xy 286.82898 -279.60739)
			(xy 286.855283 -279.565794) (xy 286.887918 -279.528957) (xy 286.926039 -279.497832) (xy 286.96866 -279.473225)
			(xy 287.014676 -279.455773) (xy 287.062895 -279.445929) (xy 287.11207 -279.443948) (xy 287.160925 -279.44988)
			(xy 287.208196 -279.463572) (xy 287.252658 -279.48467) (xy 287.293161 -279.512626) (xy 287.328654 -279.546718)
			(xy 287.358219 -279.586062) (xy 287.38109 -279.629639) (xy 287.396674 -279.67632) (xy 287.404569 -279.724897)
			(xy 287.405064 -279.749504) (xy 288.693872 -279.749504) (xy 288.697832 -279.70045) (xy 288.709609 -279.652666)
			(xy 288.7289 -279.60739) (xy 288.755203 -279.565794) (xy 288.787838 -279.528957) (xy 288.825959 -279.497832)
			(xy 288.86858 -279.473225) (xy 288.914596 -279.455773) (xy 288.962815 -279.445929) (xy 289.01199 -279.443948)
			(xy 289.060845 -279.44988) (xy 289.108116 -279.463572) (xy 289.152578 -279.48467) (xy 289.193081 -279.512626)
			(xy 289.228574 -279.546718) (xy 289.258139 -279.586062) (xy 289.28101 -279.629639) (xy 289.296594 -279.67632)
			(xy 289.304489 -279.724897) (xy 289.304984 -279.749504) (xy 290.594046 -279.749504) (xy 290.598006 -279.70045)
			(xy 290.609783 -279.652666) (xy 290.629074 -279.60739) (xy 290.655377 -279.565794) (xy 290.688012 -279.528957)
			(xy 290.726133 -279.497832) (xy 290.768754 -279.473225) (xy 290.81477 -279.455773) (xy 290.862989 -279.445929)
			(xy 290.912164 -279.443948) (xy 290.961019 -279.44988) (xy 291.00829 -279.463572) (xy 291.052752 -279.48467)
			(xy 291.093255 -279.512626) (xy 291.128748 -279.546718) (xy 291.158313 -279.586062) (xy 291.181184 -279.629639)
			(xy 291.196768 -279.67632) (xy 291.204663 -279.724897) (xy 291.205158 -279.749504) (xy 292.493966 -279.749504)
			(xy 292.497926 -279.70045) (xy 292.509703 -279.652666) (xy 292.528994 -279.60739) (xy 292.555297 -279.565794)
			(xy 292.587932 -279.528957) (xy 292.626053 -279.497832) (xy 292.668674 -279.473225) (xy 292.71469 -279.455773)
			(xy 292.762909 -279.445929) (xy 292.812084 -279.443948) (xy 292.860939 -279.44988) (xy 292.90821 -279.463572)
			(xy 292.952672 -279.48467) (xy 292.993175 -279.512626) (xy 293.028668 -279.546718) (xy 293.058233 -279.586062)
			(xy 293.081104 -279.629639) (xy 293.096688 -279.67632) (xy 293.104583 -279.724897) (xy 293.105078 -279.749504)
			(xy 294.393886 -279.749504) (xy 294.397846 -279.70045) (xy 294.409623 -279.652666) (xy 294.428914 -279.60739)
			(xy 294.455217 -279.565794) (xy 294.487852 -279.528957) (xy 294.525973 -279.497832) (xy 294.568594 -279.473225)
			(xy 294.61461 -279.455773) (xy 294.662829 -279.445929) (xy 294.712004 -279.443948) (xy 294.760859 -279.44988)
			(xy 294.80813 -279.463572) (xy 294.852592 -279.48467) (xy 294.893095 -279.512626) (xy 294.928588 -279.546718)
			(xy 294.958153 -279.586062) (xy 294.981024 -279.629639) (xy 294.996608 -279.67632) (xy 295.004503 -279.724897)
			(xy 295.004998 -279.749504) (xy 296.29406 -279.749504) (xy 296.29802 -279.70045) (xy 296.309797 -279.652666)
			(xy 296.329088 -279.60739) (xy 296.355391 -279.565794) (xy 296.388026 -279.528957) (xy 296.426147 -279.497832)
			(xy 296.468768 -279.473225) (xy 296.514784 -279.455773) (xy 296.563003 -279.445929) (xy 296.612178 -279.443948)
			(xy 296.661033 -279.44988) (xy 296.708304 -279.463572) (xy 296.752766 -279.48467) (xy 296.793269 -279.512626)
			(xy 296.828762 -279.546718) (xy 296.858327 -279.586062) (xy 296.881198 -279.629639) (xy 296.896782 -279.67632)
			(xy 296.904677 -279.724897) (xy 296.905172 -279.749504) (xy 298.19398 -279.749504) (xy 298.19794 -279.70045)
			(xy 298.209717 -279.652666) (xy 298.229008 -279.60739) (xy 298.255311 -279.565794) (xy 298.287946 -279.528957)
			(xy 298.326067 -279.497832) (xy 298.368688 -279.473225) (xy 298.414704 -279.455773) (xy 298.462923 -279.445929)
			(xy 298.512098 -279.443948) (xy 298.560953 -279.44988) (xy 298.608224 -279.463572) (xy 298.652686 -279.48467)
			(xy 298.693189 -279.512626) (xy 298.728682 -279.546718) (xy 298.758247 -279.586062) (xy 298.781118 -279.629639)
			(xy 298.796702 -279.67632) (xy 298.804597 -279.724897) (xy 298.805092 -279.749504) (xy 300.0939 -279.749504)
			(xy 300.09786 -279.70045) (xy 300.109637 -279.652666) (xy 300.128928 -279.60739) (xy 300.155231 -279.565794)
			(xy 300.187866 -279.528957) (xy 300.225987 -279.497832) (xy 300.268608 -279.473225) (xy 300.314624 -279.455773)
			(xy 300.362843 -279.445929) (xy 300.412018 -279.443948) (xy 300.460873 -279.44988) (xy 300.508144 -279.463572)
			(xy 300.552606 -279.48467) (xy 300.593109 -279.512626) (xy 300.628602 -279.546718) (xy 300.658167 -279.586062)
			(xy 300.681038 -279.629639) (xy 300.696622 -279.67632) (xy 300.704517 -279.724897) (xy 300.705012 -279.749504)
			(xy 301.994074 -279.749504) (xy 301.998034 -279.70045) (xy 302.009811 -279.652666) (xy 302.029102 -279.60739)
			(xy 302.055405 -279.565794) (xy 302.08804 -279.528957) (xy 302.126161 -279.497832) (xy 302.168782 -279.473225)
			(xy 302.214798 -279.455773) (xy 302.263017 -279.445929) (xy 302.312192 -279.443948) (xy 302.361047 -279.44988)
			(xy 302.408318 -279.463572) (xy 302.45278 -279.48467) (xy 302.493283 -279.512626) (xy 302.528776 -279.546718)
			(xy 302.558341 -279.586062) (xy 302.581212 -279.629639) (xy 302.596796 -279.67632) (xy 302.604691 -279.724897)
			(xy 302.605186 -279.749504) (xy 303.893994 -279.749504) (xy 303.897954 -279.70045) (xy 303.909731 -279.652666)
			(xy 303.929022 -279.60739) (xy 303.955325 -279.565794) (xy 303.98796 -279.528957) (xy 304.026081 -279.497832)
			(xy 304.068702 -279.473225) (xy 304.114718 -279.455773) (xy 304.162937 -279.445929) (xy 304.212112 -279.443948)
			(xy 304.260967 -279.44988) (xy 304.308238 -279.463572) (xy 304.3527 -279.48467) (xy 304.393203 -279.512626)
			(xy 304.428696 -279.546718) (xy 304.458261 -279.586062) (xy 304.481132 -279.629639) (xy 304.496716 -279.67632)
			(xy 304.504611 -279.724897) (xy 304.505106 -279.749504) (xy 305.793914 -279.749504) (xy 305.797874 -279.70045)
			(xy 305.809651 -279.652666) (xy 305.828942 -279.60739) (xy 305.855245 -279.565794) (xy 305.88788 -279.528957)
			(xy 305.926001 -279.497832) (xy 305.968622 -279.473225) (xy 306.014638 -279.455773) (xy 306.062857 -279.445929)
			(xy 306.112032 -279.443948) (xy 306.160887 -279.44988) (xy 306.208158 -279.463572) (xy 306.25262 -279.48467)
			(xy 306.293123 -279.512626) (xy 306.328616 -279.546718) (xy 306.358181 -279.586062) (xy 306.381052 -279.629639)
			(xy 306.396636 -279.67632) (xy 306.404531 -279.724897) (xy 306.405026 -279.749504) (xy 307.694088 -279.749504)
			(xy 307.698048 -279.70045) (xy 307.709825 -279.652666) (xy 307.729116 -279.60739) (xy 307.755419 -279.565794)
			(xy 307.788054 -279.528957) (xy 307.826175 -279.497832) (xy 307.868796 -279.473225) (xy 307.914812 -279.455773)
			(xy 307.963031 -279.445929) (xy 308.012206 -279.443948) (xy 308.061061 -279.44988) (xy 308.108332 -279.463572)
			(xy 308.152794 -279.48467) (xy 308.193297 -279.512626) (xy 308.22879 -279.546718) (xy 308.258355 -279.586062)
			(xy 308.281226 -279.629639) (xy 308.29681 -279.67632) (xy 308.304705 -279.724897) (xy 308.3052 -279.749504)
			(xy 309.594008 -279.749504) (xy 309.597968 -279.70045) (xy 309.609745 -279.652666) (xy 309.629036 -279.60739)
			(xy 309.655339 -279.565794) (xy 309.687974 -279.528957) (xy 309.726095 -279.497832) (xy 309.768716 -279.473225)
			(xy 309.814732 -279.455773) (xy 309.862951 -279.445929) (xy 309.912126 -279.443948) (xy 309.960981 -279.44988)
			(xy 310.008252 -279.463572) (xy 310.052714 -279.48467) (xy 310.093217 -279.512626) (xy 310.12871 -279.546718)
			(xy 310.158275 -279.586062) (xy 310.181146 -279.629639) (xy 310.19673 -279.67632) (xy 310.204625 -279.724897)
			(xy 310.20512 -279.749504) (xy 310.205115 -279.749758) (xy 311.493928 -279.749758) (xy 311.497888 -279.700704)
			(xy 311.509665 -279.65292) (xy 311.528956 -279.607644) (xy 311.555259 -279.566048) (xy 311.587894 -279.529211)
			(xy 311.626015 -279.498086) (xy 311.668636 -279.473479) (xy 311.714652 -279.456027) (xy 311.762871 -279.446183)
			(xy 311.812046 -279.444202) (xy 311.860901 -279.450134) (xy 311.908172 -279.463826) (xy 311.952634 -279.484924)
			(xy 311.993137 -279.51288) (xy 312.02863 -279.546972) (xy 312.058195 -279.586316) (xy 312.081066 -279.629893)
			(xy 312.09665 -279.676574) (xy 312.104545 -279.725151) (xy 312.10504 -279.749758) (xy 313.394102 -279.749758)
			(xy 313.398062 -279.700704) (xy 313.409839 -279.65292) (xy 313.42913 -279.607644) (xy 313.455433 -279.566048)
			(xy 313.488068 -279.529211) (xy 313.526189 -279.498086) (xy 313.56881 -279.473479) (xy 313.614826 -279.456027)
			(xy 313.663045 -279.446183) (xy 313.71222 -279.444202) (xy 313.761075 -279.450134) (xy 313.808346 -279.463826)
			(xy 313.852808 -279.484924) (xy 313.893311 -279.51288) (xy 313.928804 -279.546972) (xy 313.958369 -279.586316)
			(xy 313.98124 -279.629893) (xy 313.996824 -279.676574) (xy 314.004719 -279.725151) (xy 314.005214 -279.749758)
			(xy 314.344062 -279.749758) (xy 314.348022 -279.700704) (xy 314.359799 -279.65292) (xy 314.37909 -279.607644)
			(xy 314.405393 -279.566048) (xy 314.438028 -279.529211) (xy 314.476149 -279.498086) (xy 314.51877 -279.473479)
			(xy 314.564786 -279.456027) (xy 314.613005 -279.446183) (xy 314.66218 -279.444202) (xy 314.711035 -279.450134)
			(xy 314.758306 -279.463826) (xy 314.802768 -279.484924) (xy 314.843271 -279.51288) (xy 314.878764 -279.546972)
			(xy 314.908329 -279.586316) (xy 314.9312 -279.629893) (xy 314.946784 -279.676574) (xy 314.954679 -279.725151)
			(xy 314.955169 -279.749504) (xy 393.394196 -279.749504) (xy 393.398156 -279.70045) (xy 393.409933 -279.652666)
			(xy 393.429224 -279.60739) (xy 393.455527 -279.565794) (xy 393.488162 -279.528957) (xy 393.526283 -279.497832)
			(xy 393.568904 -279.473225) (xy 393.61492 -279.455773) (xy 393.663139 -279.445929) (xy 393.712314 -279.443948)
			(xy 393.761169 -279.44988) (xy 393.80844 -279.463572) (xy 393.852902 -279.48467) (xy 393.893405 -279.512626)
			(xy 393.928898 -279.546718) (xy 393.958463 -279.586062) (xy 393.981334 -279.629639) (xy 393.996918 -279.67632)
			(xy 394.004813 -279.724897) (xy 394.005308 -279.749504) (xy 395.294116 -279.749504) (xy 395.298076 -279.70045)
			(xy 395.309853 -279.652666) (xy 395.329144 -279.60739) (xy 395.355447 -279.565794) (xy 395.388082 -279.528957)
			(xy 395.426203 -279.497832) (xy 395.468824 -279.473225) (xy 395.51484 -279.455773) (xy 395.563059 -279.445929)
			(xy 395.612234 -279.443948) (xy 395.661089 -279.44988) (xy 395.70836 -279.463572) (xy 395.752822 -279.48467)
			(xy 395.793325 -279.512626) (xy 395.828818 -279.546718) (xy 395.858383 -279.586062) (xy 395.881254 -279.629639)
			(xy 395.896838 -279.67632) (xy 395.904733 -279.724897) (xy 395.905228 -279.749504) (xy 397.194036 -279.749504)
			(xy 397.197996 -279.70045) (xy 397.209773 -279.652666) (xy 397.229064 -279.60739) (xy 397.255367 -279.565794)
			(xy 397.288002 -279.528957) (xy 397.326123 -279.497832) (xy 397.368744 -279.473225) (xy 397.41476 -279.455773)
			(xy 397.462979 -279.445929) (xy 397.512154 -279.443948) (xy 397.561009 -279.44988) (xy 397.60828 -279.463572)
			(xy 397.652742 -279.48467) (xy 397.693245 -279.512626) (xy 397.728738 -279.546718) (xy 397.758303 -279.586062)
			(xy 397.781174 -279.629639) (xy 397.796758 -279.67632) (xy 397.804653 -279.724897) (xy 397.805148 -279.749504)
			(xy 399.09421 -279.749504) (xy 399.09817 -279.70045) (xy 399.109947 -279.652666) (xy 399.129238 -279.60739)
			(xy 399.155541 -279.565794) (xy 399.188176 -279.528957) (xy 399.226297 -279.497832) (xy 399.268918 -279.473225)
			(xy 399.314934 -279.455773) (xy 399.363153 -279.445929) (xy 399.412328 -279.443948) (xy 399.461183 -279.44988)
			(xy 399.508454 -279.463572) (xy 399.552916 -279.48467) (xy 399.593419 -279.512626) (xy 399.628912 -279.546718)
			(xy 399.658477 -279.586062) (xy 399.681348 -279.629639) (xy 399.696932 -279.67632) (xy 399.704827 -279.724897)
			(xy 399.705322 -279.749504) (xy 400.99413 -279.749504) (xy 400.99809 -279.70045) (xy 401.009867 -279.652666)
			(xy 401.029158 -279.60739) (xy 401.055461 -279.565794) (xy 401.088096 -279.528957) (xy 401.126217 -279.497832)
			(xy 401.168838 -279.473225) (xy 401.214854 -279.455773) (xy 401.263073 -279.445929) (xy 401.312248 -279.443948)
			(xy 401.361103 -279.44988) (xy 401.408374 -279.463572) (xy 401.452836 -279.48467) (xy 401.493339 -279.512626)
			(xy 401.528832 -279.546718) (xy 401.558397 -279.586062) (xy 401.581268 -279.629639) (xy 401.596852 -279.67632)
			(xy 401.604747 -279.724897) (xy 401.605242 -279.749504) (xy 402.89405 -279.749504) (xy 402.89801 -279.70045)
			(xy 402.909787 -279.652666) (xy 402.929078 -279.60739) (xy 402.955381 -279.565794) (xy 402.988016 -279.528957)
			(xy 403.026137 -279.497832) (xy 403.068758 -279.473225) (xy 403.114774 -279.455773) (xy 403.162993 -279.445929)
			(xy 403.212168 -279.443948) (xy 403.261023 -279.44988) (xy 403.308294 -279.463572) (xy 403.352756 -279.48467)
			(xy 403.393259 -279.512626) (xy 403.428752 -279.546718) (xy 403.458317 -279.586062) (xy 403.481188 -279.629639)
			(xy 403.496772 -279.67632) (xy 403.504667 -279.724897) (xy 403.505162 -279.749504) (xy 404.79397 -279.749504)
			(xy 404.79793 -279.70045) (xy 404.809707 -279.652666) (xy 404.828998 -279.60739) (xy 404.855301 -279.565794)
			(xy 404.887936 -279.528957) (xy 404.926057 -279.497832) (xy 404.968678 -279.473225) (xy 405.014694 -279.455773)
			(xy 405.062913 -279.445929) (xy 405.112088 -279.443948) (xy 405.160943 -279.44988) (xy 405.208214 -279.463572)
			(xy 405.252676 -279.48467) (xy 405.293179 -279.512626) (xy 405.328672 -279.546718) (xy 405.358237 -279.586062)
			(xy 405.381108 -279.629639) (xy 405.396692 -279.67632) (xy 405.404587 -279.724897) (xy 405.405082 -279.749504)
			(xy 406.694144 -279.749504) (xy 406.698104 -279.70045) (xy 406.709881 -279.652666) (xy 406.729172 -279.60739)
			(xy 406.755475 -279.565794) (xy 406.78811 -279.528957) (xy 406.826231 -279.497832) (xy 406.868852 -279.473225)
			(xy 406.914868 -279.455773) (xy 406.963087 -279.445929) (xy 407.012262 -279.443948) (xy 407.061117 -279.44988)
			(xy 407.108388 -279.463572) (xy 407.15285 -279.48467) (xy 407.193353 -279.512626) (xy 407.228846 -279.546718)
			(xy 407.258411 -279.586062) (xy 407.281282 -279.629639) (xy 407.296866 -279.67632) (xy 407.304761 -279.724897)
			(xy 407.305256 -279.749504) (xy 408.594064 -279.749504) (xy 408.598024 -279.70045) (xy 408.609801 -279.652666)
			(xy 408.629092 -279.60739) (xy 408.655395 -279.565794) (xy 408.68803 -279.528957) (xy 408.726151 -279.497832)
			(xy 408.768772 -279.473225) (xy 408.814788 -279.455773) (xy 408.863007 -279.445929) (xy 408.912182 -279.443948)
			(xy 408.961037 -279.44988) (xy 409.008308 -279.463572) (xy 409.05277 -279.48467) (xy 409.093273 -279.512626)
			(xy 409.128766 -279.546718) (xy 409.158331 -279.586062) (xy 409.181202 -279.629639) (xy 409.196786 -279.67632)
			(xy 409.204681 -279.724897) (xy 409.205176 -279.749504) (xy 410.493984 -279.749504) (xy 410.497944 -279.70045)
			(xy 410.509721 -279.652666) (xy 410.529012 -279.60739) (xy 410.555315 -279.565794) (xy 410.58795 -279.528957)
			(xy 410.626071 -279.497832) (xy 410.668692 -279.473225) (xy 410.714708 -279.455773) (xy 410.762927 -279.445929)
			(xy 410.812102 -279.443948) (xy 410.860957 -279.44988) (xy 410.908228 -279.463572) (xy 410.95269 -279.48467)
			(xy 410.993193 -279.512626) (xy 411.028686 -279.546718) (xy 411.058251 -279.586062) (xy 411.081122 -279.629639)
			(xy 411.096706 -279.67632) (xy 411.104601 -279.724897) (xy 411.105096 -279.749504) (xy 412.394158 -279.749504)
			(xy 412.398118 -279.70045) (xy 412.409895 -279.652666) (xy 412.429186 -279.60739) (xy 412.455489 -279.565794)
			(xy 412.488124 -279.528957) (xy 412.526245 -279.497832) (xy 412.568866 -279.473225) (xy 412.614882 -279.455773)
			(xy 412.663101 -279.445929) (xy 412.712276 -279.443948) (xy 412.761131 -279.44988) (xy 412.808402 -279.463572)
			(xy 412.852864 -279.48467) (xy 412.893367 -279.512626) (xy 412.92886 -279.546718) (xy 412.958425 -279.586062)
			(xy 412.981296 -279.629639) (xy 412.99688 -279.67632) (xy 413.004775 -279.724897) (xy 413.00527 -279.749504)
			(xy 414.294078 -279.749504) (xy 414.298038 -279.70045) (xy 414.309815 -279.652666) (xy 414.329106 -279.60739)
			(xy 414.355409 -279.565794) (xy 414.388044 -279.528957) (xy 414.426165 -279.497832) (xy 414.468786 -279.473225)
			(xy 414.514802 -279.455773) (xy 414.563021 -279.445929) (xy 414.612196 -279.443948) (xy 414.661051 -279.44988)
			(xy 414.708322 -279.463572) (xy 414.752784 -279.48467) (xy 414.793287 -279.512626) (xy 414.82878 -279.546718)
			(xy 414.858345 -279.586062) (xy 414.881216 -279.629639) (xy 414.8968 -279.67632) (xy 414.904695 -279.724897)
			(xy 414.90519 -279.749504) (xy 416.193998 -279.749504) (xy 416.197958 -279.70045) (xy 416.209735 -279.652666)
			(xy 416.229026 -279.60739) (xy 416.255329 -279.565794) (xy 416.287964 -279.528957) (xy 416.326085 -279.497832)
			(xy 416.368706 -279.473225) (xy 416.414722 -279.455773) (xy 416.462941 -279.445929) (xy 416.512116 -279.443948)
			(xy 416.560971 -279.44988) (xy 416.608242 -279.463572) (xy 416.652704 -279.48467) (xy 416.693207 -279.512626)
			(xy 416.7287 -279.546718) (xy 416.758265 -279.586062) (xy 416.781136 -279.629639) (xy 416.79672 -279.67632)
			(xy 416.804615 -279.724897) (xy 416.80511 -279.749504) (xy 418.094172 -279.749504) (xy 418.098132 -279.70045)
			(xy 418.109909 -279.652666) (xy 418.1292 -279.60739) (xy 418.155503 -279.565794) (xy 418.188138 -279.528957)
			(xy 418.226259 -279.497832) (xy 418.26888 -279.473225) (xy 418.314896 -279.455773) (xy 418.363115 -279.445929)
			(xy 418.41229 -279.443948) (xy 418.461145 -279.44988) (xy 418.508416 -279.463572) (xy 418.552878 -279.48467)
			(xy 418.593381 -279.512626) (xy 418.628874 -279.546718) (xy 418.658439 -279.586062) (xy 418.68131 -279.629639)
			(xy 418.696894 -279.67632) (xy 418.704789 -279.724897) (xy 418.705284 -279.749504) (xy 419.994092 -279.749504)
			(xy 419.998052 -279.70045) (xy 420.009829 -279.652666) (xy 420.02912 -279.60739) (xy 420.055423 -279.565794)
			(xy 420.088058 -279.528957) (xy 420.126179 -279.497832) (xy 420.1688 -279.473225) (xy 420.214816 -279.455773)
			(xy 420.263035 -279.445929) (xy 420.31221 -279.443948) (xy 420.361065 -279.44988) (xy 420.408336 -279.463572)
			(xy 420.452798 -279.48467) (xy 420.493301 -279.512626) (xy 420.528794 -279.546718) (xy 420.558359 -279.586062)
			(xy 420.58123 -279.629639) (xy 420.596814 -279.67632) (xy 420.604709 -279.724897) (xy 420.605204 -279.749504)
			(xy 421.894012 -279.749504) (xy 421.897972 -279.70045) (xy 421.909749 -279.652666) (xy 421.92904 -279.60739)
			(xy 421.955343 -279.565794) (xy 421.987978 -279.528957) (xy 422.026099 -279.497832) (xy 422.06872 -279.473225)
			(xy 422.114736 -279.455773) (xy 422.162955 -279.445929) (xy 422.21213 -279.443948) (xy 422.260985 -279.44988)
			(xy 422.308256 -279.463572) (xy 422.352718 -279.48467) (xy 422.393221 -279.512626) (xy 422.428714 -279.546718)
			(xy 422.458279 -279.586062) (xy 422.48115 -279.629639) (xy 422.496734 -279.67632) (xy 422.504629 -279.724897)
			(xy 422.505124 -279.749504) (xy 423.794186 -279.749504) (xy 423.798146 -279.70045) (xy 423.809923 -279.652666)
			(xy 423.829214 -279.60739) (xy 423.855517 -279.565794) (xy 423.888152 -279.528957) (xy 423.926273 -279.497832)
			(xy 423.968894 -279.473225) (xy 424.01491 -279.455773) (xy 424.063129 -279.445929) (xy 424.112304 -279.443948)
			(xy 424.161159 -279.44988) (xy 424.20843 -279.463572) (xy 424.252892 -279.48467) (xy 424.293395 -279.512626)
			(xy 424.328888 -279.546718) (xy 424.358453 -279.586062) (xy 424.381324 -279.629639) (xy 424.396908 -279.67632)
			(xy 424.404803 -279.724897) (xy 424.405298 -279.749504) (xy 425.694106 -279.749504) (xy 425.698066 -279.70045)
			(xy 425.709843 -279.652666) (xy 425.729134 -279.60739) (xy 425.755437 -279.565794) (xy 425.788072 -279.528957)
			(xy 425.826193 -279.497832) (xy 425.868814 -279.473225) (xy 425.91483 -279.455773) (xy 425.963049 -279.445929)
			(xy 426.012224 -279.443948) (xy 426.061079 -279.44988) (xy 426.10835 -279.463572) (xy 426.152812 -279.48467)
			(xy 426.193315 -279.512626) (xy 426.228808 -279.546718) (xy 426.258373 -279.586062) (xy 426.281244 -279.629639)
			(xy 426.296828 -279.67632) (xy 426.304723 -279.724897) (xy 426.305218 -279.749504) (xy 426.305213 -279.749758)
			(xy 427.594026 -279.749758) (xy 427.597986 -279.700704) (xy 427.609763 -279.65292) (xy 427.629054 -279.607644)
			(xy 427.655357 -279.566048) (xy 427.687992 -279.529211) (xy 427.726113 -279.498086) (xy 427.768734 -279.473479)
			(xy 427.81475 -279.456027) (xy 427.862969 -279.446183) (xy 427.912144 -279.444202) (xy 427.960999 -279.450134)
			(xy 428.00827 -279.463826) (xy 428.052732 -279.484924) (xy 428.093235 -279.51288) (xy 428.128728 -279.546972)
			(xy 428.158293 -279.586316) (xy 428.181164 -279.629893) (xy 428.196748 -279.676574) (xy 428.204643 -279.725151)
			(xy 428.205138 -279.749758) (xy 429.4942 -279.749758) (xy 429.49816 -279.700704) (xy 429.509937 -279.65292)
			(xy 429.529228 -279.607644) (xy 429.555531 -279.566048) (xy 429.588166 -279.529211) (xy 429.626287 -279.498086)
			(xy 429.668908 -279.473479) (xy 429.714924 -279.456027) (xy 429.763143 -279.446183) (xy 429.812318 -279.444202)
			(xy 429.861173 -279.450134) (xy 429.908444 -279.463826) (xy 429.952906 -279.484924) (xy 429.993409 -279.51288)
			(xy 430.028902 -279.546972) (xy 430.058467 -279.586316) (xy 430.081338 -279.629893) (xy 430.096922 -279.676574)
			(xy 430.104817 -279.725151) (xy 430.105312 -279.749758) (xy 430.44416 -279.749758) (xy 430.44812 -279.700704)
			(xy 430.459897 -279.65292) (xy 430.479188 -279.607644) (xy 430.505491 -279.566048) (xy 430.538126 -279.529211)
			(xy 430.576247 -279.498086) (xy 430.618868 -279.473479) (xy 430.664884 -279.456027) (xy 430.713103 -279.446183)
			(xy 430.762278 -279.444202) (xy 430.811133 -279.450134) (xy 430.858404 -279.463826) (xy 430.902866 -279.484924)
			(xy 430.943369 -279.51288) (xy 430.978862 -279.546972) (xy 431.008427 -279.586316) (xy 431.031298 -279.629893)
			(xy 431.046882 -279.676574) (xy 431.054777 -279.725151) (xy 431.055272 -279.749758) (xy 431.054777 -279.774365)
			(xy 431.046882 -279.822942) (xy 431.031298 -279.869623) (xy 431.008427 -279.9132) (xy 430.978862 -279.952544)
			(xy 430.943369 -279.986636) (xy 430.902866 -280.014592) (xy 430.858404 -280.03569) (xy 430.811133 -280.049382)
			(xy 430.762278 -280.055314) (xy 430.713103 -280.053333) (xy 430.664884 -280.043489) (xy 430.618868 -280.026037)
			(xy 430.576247 -280.00143) (xy 430.538126 -279.970305) (xy 430.505491 -279.933468) (xy 430.479188 -279.891872)
			(xy 430.459897 -279.846596) (xy 430.44812 -279.798812) (xy 430.44416 -279.749758) (xy 430.105312 -279.749758)
			(xy 430.104817 -279.774365) (xy 430.096922 -279.822942) (xy 430.081338 -279.869623) (xy 430.058467 -279.9132)
			(xy 430.028902 -279.952544) (xy 429.993409 -279.986636) (xy 429.952906 -280.014592) (xy 429.908444 -280.03569)
			(xy 429.861173 -280.049382) (xy 429.812318 -280.055314) (xy 429.763143 -280.053333) (xy 429.714924 -280.043489)
			(xy 429.668908 -280.026037) (xy 429.626287 -280.00143) (xy 429.588166 -279.970305) (xy 429.555531 -279.933468)
			(xy 429.529228 -279.891872) (xy 429.509937 -279.846596) (xy 429.49816 -279.798812) (xy 429.4942 -279.749758)
			(xy 428.205138 -279.749758) (xy 428.204643 -279.774365) (xy 428.196748 -279.822942) (xy 428.181164 -279.869623)
			(xy 428.158293 -279.9132) (xy 428.128728 -279.952544) (xy 428.093235 -279.986636) (xy 428.052732 -280.014592)
			(xy 428.00827 -280.03569) (xy 427.960999 -280.049382) (xy 427.912144 -280.055314) (xy 427.862969 -280.053333)
			(xy 427.81475 -280.043489) (xy 427.768734 -280.026037) (xy 427.726113 -280.00143) (xy 427.687992 -279.970305)
			(xy 427.655357 -279.933468) (xy 427.629054 -279.891872) (xy 427.609763 -279.846596) (xy 427.597986 -279.798812)
			(xy 427.594026 -279.749758) (xy 426.305213 -279.749758) (xy 426.304723 -279.774111) (xy 426.296828 -279.822688)
			(xy 426.281244 -279.869369) (xy 426.258373 -279.912946) (xy 426.228808 -279.95229) (xy 426.193315 -279.986382)
			(xy 426.152812 -280.014338) (xy 426.10835 -280.035436) (xy 426.061079 -280.049128) (xy 426.012224 -280.05506)
			(xy 425.963049 -280.053079) (xy 425.91483 -280.043235) (xy 425.868814 -280.025783) (xy 425.826193 -280.001176)
			(xy 425.788072 -279.970051) (xy 425.755437 -279.933214) (xy 425.729134 -279.891618) (xy 425.709843 -279.846342)
			(xy 425.698066 -279.798558) (xy 425.694106 -279.749504) (xy 424.405298 -279.749504) (xy 424.404803 -279.774111)
			(xy 424.396908 -279.822688) (xy 424.381324 -279.869369) (xy 424.358453 -279.912946) (xy 424.328888 -279.95229)
			(xy 424.293395 -279.986382) (xy 424.252892 -280.014338) (xy 424.20843 -280.035436) (xy 424.161159 -280.049128)
			(xy 424.112304 -280.05506) (xy 424.063129 -280.053079) (xy 424.01491 -280.043235) (xy 423.968894 -280.025783)
			(xy 423.926273 -280.001176) (xy 423.888152 -279.970051) (xy 423.855517 -279.933214) (xy 423.829214 -279.891618)
			(xy 423.809923 -279.846342) (xy 423.798146 -279.798558) (xy 423.794186 -279.749504) (xy 422.505124 -279.749504)
			(xy 422.504629 -279.774111) (xy 422.496734 -279.822688) (xy 422.48115 -279.869369) (xy 422.458279 -279.912946)
			(xy 422.428714 -279.95229) (xy 422.393221 -279.986382) (xy 422.352718 -280.014338) (xy 422.308256 -280.035436)
			(xy 422.260985 -280.049128) (xy 422.21213 -280.05506) (xy 422.162955 -280.053079) (xy 422.114736 -280.043235)
			(xy 422.06872 -280.025783) (xy 422.026099 -280.001176) (xy 421.987978 -279.970051) (xy 421.955343 -279.933214)
			(xy 421.92904 -279.891618) (xy 421.909749 -279.846342) (xy 421.897972 -279.798558) (xy 421.894012 -279.749504)
			(xy 420.605204 -279.749504) (xy 420.604709 -279.774111) (xy 420.596814 -279.822688) (xy 420.58123 -279.869369)
			(xy 420.558359 -279.912946) (xy 420.528794 -279.95229) (xy 420.493301 -279.986382) (xy 420.452798 -280.014338)
			(xy 420.408336 -280.035436) (xy 420.361065 -280.049128) (xy 420.31221 -280.05506) (xy 420.263035 -280.053079)
			(xy 420.214816 -280.043235) (xy 420.1688 -280.025783) (xy 420.126179 -280.001176) (xy 420.088058 -279.970051)
			(xy 420.055423 -279.933214) (xy 420.02912 -279.891618) (xy 420.009829 -279.846342) (xy 419.998052 -279.798558)
			(xy 419.994092 -279.749504) (xy 418.705284 -279.749504) (xy 418.704789 -279.774111) (xy 418.696894 -279.822688)
			(xy 418.68131 -279.869369) (xy 418.658439 -279.912946) (xy 418.628874 -279.95229) (xy 418.593381 -279.986382)
			(xy 418.552878 -280.014338) (xy 418.508416 -280.035436) (xy 418.461145 -280.049128) (xy 418.41229 -280.05506)
			(xy 418.363115 -280.053079) (xy 418.314896 -280.043235) (xy 418.26888 -280.025783) (xy 418.226259 -280.001176)
			(xy 418.188138 -279.970051) (xy 418.155503 -279.933214) (xy 418.1292 -279.891618) (xy 418.109909 -279.846342)
			(xy 418.098132 -279.798558) (xy 418.094172 -279.749504) (xy 416.80511 -279.749504) (xy 416.804615 -279.774111)
			(xy 416.79672 -279.822688) (xy 416.781136 -279.869369) (xy 416.758265 -279.912946) (xy 416.7287 -279.95229)
			(xy 416.693207 -279.986382) (xy 416.652704 -280.014338) (xy 416.608242 -280.035436) (xy 416.560971 -280.049128)
			(xy 416.512116 -280.05506) (xy 416.462941 -280.053079) (xy 416.414722 -280.043235) (xy 416.368706 -280.025783)
			(xy 416.326085 -280.001176) (xy 416.287964 -279.970051) (xy 416.255329 -279.933214) (xy 416.229026 -279.891618)
			(xy 416.209735 -279.846342) (xy 416.197958 -279.798558) (xy 416.193998 -279.749504) (xy 414.90519 -279.749504)
			(xy 414.904695 -279.774111) (xy 414.8968 -279.822688) (xy 414.881216 -279.869369) (xy 414.858345 -279.912946)
			(xy 414.82878 -279.95229) (xy 414.793287 -279.986382) (xy 414.752784 -280.014338) (xy 414.708322 -280.035436)
			(xy 414.661051 -280.049128) (xy 414.612196 -280.05506) (xy 414.563021 -280.053079) (xy 414.514802 -280.043235)
			(xy 414.468786 -280.025783) (xy 414.426165 -280.001176) (xy 414.388044 -279.970051) (xy 414.355409 -279.933214)
			(xy 414.329106 -279.891618) (xy 414.309815 -279.846342) (xy 414.298038 -279.798558) (xy 414.294078 -279.749504)
			(xy 413.00527 -279.749504) (xy 413.004775 -279.774111) (xy 412.99688 -279.822688) (xy 412.981296 -279.869369)
			(xy 412.958425 -279.912946) (xy 412.92886 -279.95229) (xy 412.893367 -279.986382) (xy 412.852864 -280.014338)
			(xy 412.808402 -280.035436) (xy 412.761131 -280.049128) (xy 412.712276 -280.05506) (xy 412.663101 -280.053079)
			(xy 412.614882 -280.043235) (xy 412.568866 -280.025783) (xy 412.526245 -280.001176) (xy 412.488124 -279.970051)
			(xy 412.455489 -279.933214) (xy 412.429186 -279.891618) (xy 412.409895 -279.846342) (xy 412.398118 -279.798558)
			(xy 412.394158 -279.749504) (xy 411.105096 -279.749504) (xy 411.104601 -279.774111) (xy 411.096706 -279.822688)
			(xy 411.081122 -279.869369) (xy 411.058251 -279.912946) (xy 411.028686 -279.95229) (xy 410.993193 -279.986382)
			(xy 410.95269 -280.014338) (xy 410.908228 -280.035436) (xy 410.860957 -280.049128) (xy 410.812102 -280.05506)
			(xy 410.762927 -280.053079) (xy 410.714708 -280.043235) (xy 410.668692 -280.025783) (xy 410.626071 -280.001176)
			(xy 410.58795 -279.970051) (xy 410.555315 -279.933214) (xy 410.529012 -279.891618) (xy 410.509721 -279.846342)
			(xy 410.497944 -279.798558) (xy 410.493984 -279.749504) (xy 409.205176 -279.749504) (xy 409.204681 -279.774111)
			(xy 409.196786 -279.822688) (xy 409.181202 -279.869369) (xy 409.158331 -279.912946) (xy 409.128766 -279.95229)
			(xy 409.093273 -279.986382) (xy 409.05277 -280.014338) (xy 409.008308 -280.035436) (xy 408.961037 -280.049128)
			(xy 408.912182 -280.05506) (xy 408.863007 -280.053079) (xy 408.814788 -280.043235) (xy 408.768772 -280.025783)
			(xy 408.726151 -280.001176) (xy 408.68803 -279.970051) (xy 408.655395 -279.933214) (xy 408.629092 -279.891618)
			(xy 408.609801 -279.846342) (xy 408.598024 -279.798558) (xy 408.594064 -279.749504) (xy 407.305256 -279.749504)
			(xy 407.304761 -279.774111) (xy 407.296866 -279.822688) (xy 407.281282 -279.869369) (xy 407.258411 -279.912946)
			(xy 407.228846 -279.95229) (xy 407.193353 -279.986382) (xy 407.15285 -280.014338) (xy 407.108388 -280.035436)
			(xy 407.061117 -280.049128) (xy 407.012262 -280.05506) (xy 406.963087 -280.053079) (xy 406.914868 -280.043235)
			(xy 406.868852 -280.025783) (xy 406.826231 -280.001176) (xy 406.78811 -279.970051) (xy 406.755475 -279.933214)
			(xy 406.729172 -279.891618) (xy 406.709881 -279.846342) (xy 406.698104 -279.798558) (xy 406.694144 -279.749504)
			(xy 405.405082 -279.749504) (xy 405.404587 -279.774111) (xy 405.396692 -279.822688) (xy 405.381108 -279.869369)
			(xy 405.358237 -279.912946) (xy 405.328672 -279.95229) (xy 405.293179 -279.986382) (xy 405.252676 -280.014338)
			(xy 405.208214 -280.035436) (xy 405.160943 -280.049128) (xy 405.112088 -280.05506) (xy 405.062913 -280.053079)
			(xy 405.014694 -280.043235) (xy 404.968678 -280.025783) (xy 404.926057 -280.001176) (xy 404.887936 -279.970051)
			(xy 404.855301 -279.933214) (xy 404.828998 -279.891618) (xy 404.809707 -279.846342) (xy 404.79793 -279.798558)
			(xy 404.79397 -279.749504) (xy 403.505162 -279.749504) (xy 403.504667 -279.774111) (xy 403.496772 -279.822688)
			(xy 403.481188 -279.869369) (xy 403.458317 -279.912946) (xy 403.428752 -279.95229) (xy 403.393259 -279.986382)
			(xy 403.352756 -280.014338) (xy 403.308294 -280.035436) (xy 403.261023 -280.049128) (xy 403.212168 -280.05506)
			(xy 403.162993 -280.053079) (xy 403.114774 -280.043235) (xy 403.068758 -280.025783) (xy 403.026137 -280.001176)
			(xy 402.988016 -279.970051) (xy 402.955381 -279.933214) (xy 402.929078 -279.891618) (xy 402.909787 -279.846342)
			(xy 402.89801 -279.798558) (xy 402.89405 -279.749504) (xy 401.605242 -279.749504) (xy 401.604747 -279.774111)
			(xy 401.596852 -279.822688) (xy 401.581268 -279.869369) (xy 401.558397 -279.912946) (xy 401.528832 -279.95229)
			(xy 401.493339 -279.986382) (xy 401.452836 -280.014338) (xy 401.408374 -280.035436) (xy 401.361103 -280.049128)
			(xy 401.312248 -280.05506) (xy 401.263073 -280.053079) (xy 401.214854 -280.043235) (xy 401.168838 -280.025783)
			(xy 401.126217 -280.001176) (xy 401.088096 -279.970051) (xy 401.055461 -279.933214) (xy 401.029158 -279.891618)
			(xy 401.009867 -279.846342) (xy 400.99809 -279.798558) (xy 400.99413 -279.749504) (xy 399.705322 -279.749504)
			(xy 399.704827 -279.774111) (xy 399.696932 -279.822688) (xy 399.681348 -279.869369) (xy 399.658477 -279.912946)
			(xy 399.628912 -279.95229) (xy 399.593419 -279.986382) (xy 399.552916 -280.014338) (xy 399.508454 -280.035436)
			(xy 399.461183 -280.049128) (xy 399.412328 -280.05506) (xy 399.363153 -280.053079) (xy 399.314934 -280.043235)
			(xy 399.268918 -280.025783) (xy 399.226297 -280.001176) (xy 399.188176 -279.970051) (xy 399.155541 -279.933214)
			(xy 399.129238 -279.891618) (xy 399.109947 -279.846342) (xy 399.09817 -279.798558) (xy 399.09421 -279.749504)
			(xy 397.805148 -279.749504) (xy 397.804653 -279.774111) (xy 397.796758 -279.822688) (xy 397.781174 -279.869369)
			(xy 397.758303 -279.912946) (xy 397.728738 -279.95229) (xy 397.693245 -279.986382) (xy 397.652742 -280.014338)
			(xy 397.60828 -280.035436) (xy 397.561009 -280.049128) (xy 397.512154 -280.05506) (xy 397.462979 -280.053079)
			(xy 397.41476 -280.043235) (xy 397.368744 -280.025783) (xy 397.326123 -280.001176) (xy 397.288002 -279.970051)
			(xy 397.255367 -279.933214) (xy 397.229064 -279.891618) (xy 397.209773 -279.846342) (xy 397.197996 -279.798558)
			(xy 397.194036 -279.749504) (xy 395.905228 -279.749504) (xy 395.904733 -279.774111) (xy 395.896838 -279.822688)
			(xy 395.881254 -279.869369) (xy 395.858383 -279.912946) (xy 395.828818 -279.95229) (xy 395.793325 -279.986382)
			(xy 395.752822 -280.014338) (xy 395.70836 -280.035436) (xy 395.661089 -280.049128) (xy 395.612234 -280.05506)
			(xy 395.563059 -280.053079) (xy 395.51484 -280.043235) (xy 395.468824 -280.025783) (xy 395.426203 -280.001176)
			(xy 395.388082 -279.970051) (xy 395.355447 -279.933214) (xy 395.329144 -279.891618) (xy 395.309853 -279.846342)
			(xy 395.298076 -279.798558) (xy 395.294116 -279.749504) (xy 394.005308 -279.749504) (xy 394.004813 -279.774111)
			(xy 393.996918 -279.822688) (xy 393.981334 -279.869369) (xy 393.958463 -279.912946) (xy 393.928898 -279.95229)
			(xy 393.893405 -279.986382) (xy 393.852902 -280.014338) (xy 393.80844 -280.035436) (xy 393.761169 -280.049128)
			(xy 393.712314 -280.05506) (xy 393.663139 -280.053079) (xy 393.61492 -280.043235) (xy 393.568904 -280.025783)
			(xy 393.526283 -280.001176) (xy 393.488162 -279.970051) (xy 393.455527 -279.933214) (xy 393.429224 -279.891618)
			(xy 393.409933 -279.846342) (xy 393.398156 -279.798558) (xy 393.394196 -279.749504) (xy 314.955169 -279.749504)
			(xy 314.955174 -279.749758) (xy 314.954679 -279.774365) (xy 314.946784 -279.822942) (xy 314.9312 -279.869623)
			(xy 314.908329 -279.9132) (xy 314.878764 -279.952544) (xy 314.843271 -279.986636) (xy 314.802768 -280.014592)
			(xy 314.758306 -280.03569) (xy 314.711035 -280.049382) (xy 314.66218 -280.055314) (xy 314.613005 -280.053333)
			(xy 314.564786 -280.043489) (xy 314.51877 -280.026037) (xy 314.476149 -280.00143) (xy 314.438028 -279.970305)
			(xy 314.405393 -279.933468) (xy 314.37909 -279.891872) (xy 314.359799 -279.846596) (xy 314.348022 -279.798812)
			(xy 314.344062 -279.749758) (xy 314.005214 -279.749758) (xy 314.004719 -279.774365) (xy 313.996824 -279.822942)
			(xy 313.98124 -279.869623) (xy 313.958369 -279.9132) (xy 313.928804 -279.952544) (xy 313.893311 -279.986636)
			(xy 313.852808 -280.014592) (xy 313.808346 -280.03569) (xy 313.761075 -280.049382) (xy 313.71222 -280.055314)
			(xy 313.663045 -280.053333) (xy 313.614826 -280.043489) (xy 313.56881 -280.026037) (xy 313.526189 -280.00143)
			(xy 313.488068 -279.970305) (xy 313.455433 -279.933468) (xy 313.42913 -279.891872) (xy 313.409839 -279.846596)
			(xy 313.398062 -279.798812) (xy 313.394102 -279.749758) (xy 312.10504 -279.749758) (xy 312.104545 -279.774365)
			(xy 312.09665 -279.822942) (xy 312.081066 -279.869623) (xy 312.058195 -279.9132) (xy 312.02863 -279.952544)
			(xy 311.993137 -279.986636) (xy 311.952634 -280.014592) (xy 311.908172 -280.03569) (xy 311.860901 -280.049382)
			(xy 311.812046 -280.055314) (xy 311.762871 -280.053333) (xy 311.714652 -280.043489) (xy 311.668636 -280.026037)
			(xy 311.626015 -280.00143) (xy 311.587894 -279.970305) (xy 311.555259 -279.933468) (xy 311.528956 -279.891872)
			(xy 311.509665 -279.846596) (xy 311.497888 -279.798812) (xy 311.493928 -279.749758) (xy 310.205115 -279.749758)
			(xy 310.204625 -279.774111) (xy 310.19673 -279.822688) (xy 310.181146 -279.869369) (xy 310.158275 -279.912946)
			(xy 310.12871 -279.95229) (xy 310.093217 -279.986382) (xy 310.052714 -280.014338) (xy 310.008252 -280.035436)
			(xy 309.960981 -280.049128) (xy 309.912126 -280.05506) (xy 309.862951 -280.053079) (xy 309.814732 -280.043235)
			(xy 309.768716 -280.025783) (xy 309.726095 -280.001176) (xy 309.687974 -279.970051) (xy 309.655339 -279.933214)
			(xy 309.629036 -279.891618) (xy 309.609745 -279.846342) (xy 309.597968 -279.798558) (xy 309.594008 -279.749504)
			(xy 308.3052 -279.749504) (xy 308.304705 -279.774111) (xy 308.29681 -279.822688) (xy 308.281226 -279.869369)
			(xy 308.258355 -279.912946) (xy 308.22879 -279.95229) (xy 308.193297 -279.986382) (xy 308.152794 -280.014338)
			(xy 308.108332 -280.035436) (xy 308.061061 -280.049128) (xy 308.012206 -280.05506) (xy 307.963031 -280.053079)
			(xy 307.914812 -280.043235) (xy 307.868796 -280.025783) (xy 307.826175 -280.001176) (xy 307.788054 -279.970051)
			(xy 307.755419 -279.933214) (xy 307.729116 -279.891618) (xy 307.709825 -279.846342) (xy 307.698048 -279.798558)
			(xy 307.694088 -279.749504) (xy 306.405026 -279.749504) (xy 306.404531 -279.774111) (xy 306.396636 -279.822688)
			(xy 306.381052 -279.869369) (xy 306.358181 -279.912946) (xy 306.328616 -279.95229) (xy 306.293123 -279.986382)
			(xy 306.25262 -280.014338) (xy 306.208158 -280.035436) (xy 306.160887 -280.049128) (xy 306.112032 -280.05506)
			(xy 306.062857 -280.053079) (xy 306.014638 -280.043235) (xy 305.968622 -280.025783) (xy 305.926001 -280.001176)
			(xy 305.88788 -279.970051) (xy 305.855245 -279.933214) (xy 305.828942 -279.891618) (xy 305.809651 -279.846342)
			(xy 305.797874 -279.798558) (xy 305.793914 -279.749504) (xy 304.505106 -279.749504) (xy 304.504611 -279.774111)
			(xy 304.496716 -279.822688) (xy 304.481132 -279.869369) (xy 304.458261 -279.912946) (xy 304.428696 -279.95229)
			(xy 304.393203 -279.986382) (xy 304.3527 -280.014338) (xy 304.308238 -280.035436) (xy 304.260967 -280.049128)
			(xy 304.212112 -280.05506) (xy 304.162937 -280.053079) (xy 304.114718 -280.043235) (xy 304.068702 -280.025783)
			(xy 304.026081 -280.001176) (xy 303.98796 -279.970051) (xy 303.955325 -279.933214) (xy 303.929022 -279.891618)
			(xy 303.909731 -279.846342) (xy 303.897954 -279.798558) (xy 303.893994 -279.749504) (xy 302.605186 -279.749504)
			(xy 302.604691 -279.774111) (xy 302.596796 -279.822688) (xy 302.581212 -279.869369) (xy 302.558341 -279.912946)
			(xy 302.528776 -279.95229) (xy 302.493283 -279.986382) (xy 302.45278 -280.014338) (xy 302.408318 -280.035436)
			(xy 302.361047 -280.049128) (xy 302.312192 -280.05506) (xy 302.263017 -280.053079) (xy 302.214798 -280.043235)
			(xy 302.168782 -280.025783) (xy 302.126161 -280.001176) (xy 302.08804 -279.970051) (xy 302.055405 -279.933214)
			(xy 302.029102 -279.891618) (xy 302.009811 -279.846342) (xy 301.998034 -279.798558) (xy 301.994074 -279.749504)
			(xy 300.705012 -279.749504) (xy 300.704517 -279.774111) (xy 300.696622 -279.822688) (xy 300.681038 -279.869369)
			(xy 300.658167 -279.912946) (xy 300.628602 -279.95229) (xy 300.593109 -279.986382) (xy 300.552606 -280.014338)
			(xy 300.508144 -280.035436) (xy 300.460873 -280.049128) (xy 300.412018 -280.05506) (xy 300.362843 -280.053079)
			(xy 300.314624 -280.043235) (xy 300.268608 -280.025783) (xy 300.225987 -280.001176) (xy 300.187866 -279.970051)
			(xy 300.155231 -279.933214) (xy 300.128928 -279.891618) (xy 300.109637 -279.846342) (xy 300.09786 -279.798558)
			(xy 300.0939 -279.749504) (xy 298.805092 -279.749504) (xy 298.804597 -279.774111) (xy 298.796702 -279.822688)
			(xy 298.781118 -279.869369) (xy 298.758247 -279.912946) (xy 298.728682 -279.95229) (xy 298.693189 -279.986382)
			(xy 298.652686 -280.014338) (xy 298.608224 -280.035436) (xy 298.560953 -280.049128) (xy 298.512098 -280.05506)
			(xy 298.462923 -280.053079) (xy 298.414704 -280.043235) (xy 298.368688 -280.025783) (xy 298.326067 -280.001176)
			(xy 298.287946 -279.970051) (xy 298.255311 -279.933214) (xy 298.229008 -279.891618) (xy 298.209717 -279.846342)
			(xy 298.19794 -279.798558) (xy 298.19398 -279.749504) (xy 296.905172 -279.749504) (xy 296.904677 -279.774111)
			(xy 296.896782 -279.822688) (xy 296.881198 -279.869369) (xy 296.858327 -279.912946) (xy 296.828762 -279.95229)
			(xy 296.793269 -279.986382) (xy 296.752766 -280.014338) (xy 296.708304 -280.035436) (xy 296.661033 -280.049128)
			(xy 296.612178 -280.05506) (xy 296.563003 -280.053079) (xy 296.514784 -280.043235) (xy 296.468768 -280.025783)
			(xy 296.426147 -280.001176) (xy 296.388026 -279.970051) (xy 296.355391 -279.933214) (xy 296.329088 -279.891618)
			(xy 296.309797 -279.846342) (xy 296.29802 -279.798558) (xy 296.29406 -279.749504) (xy 295.004998 -279.749504)
			(xy 295.004503 -279.774111) (xy 294.996608 -279.822688) (xy 294.981024 -279.869369) (xy 294.958153 -279.912946)
			(xy 294.928588 -279.95229) (xy 294.893095 -279.986382) (xy 294.852592 -280.014338) (xy 294.80813 -280.035436)
			(xy 294.760859 -280.049128) (xy 294.712004 -280.05506) (xy 294.662829 -280.053079) (xy 294.61461 -280.043235)
			(xy 294.568594 -280.025783) (xy 294.525973 -280.001176) (xy 294.487852 -279.970051) (xy 294.455217 -279.933214)
			(xy 294.428914 -279.891618) (xy 294.409623 -279.846342) (xy 294.397846 -279.798558) (xy 294.393886 -279.749504)
			(xy 293.105078 -279.749504) (xy 293.104583 -279.774111) (xy 293.096688 -279.822688) (xy 293.081104 -279.869369)
			(xy 293.058233 -279.912946) (xy 293.028668 -279.95229) (xy 292.993175 -279.986382) (xy 292.952672 -280.014338)
			(xy 292.90821 -280.035436) (xy 292.860939 -280.049128) (xy 292.812084 -280.05506) (xy 292.762909 -280.053079)
			(xy 292.71469 -280.043235) (xy 292.668674 -280.025783) (xy 292.626053 -280.001176) (xy 292.587932 -279.970051)
			(xy 292.555297 -279.933214) (xy 292.528994 -279.891618) (xy 292.509703 -279.846342) (xy 292.497926 -279.798558)
			(xy 292.493966 -279.749504) (xy 291.205158 -279.749504) (xy 291.204663 -279.774111) (xy 291.196768 -279.822688)
			(xy 291.181184 -279.869369) (xy 291.158313 -279.912946) (xy 291.128748 -279.95229) (xy 291.093255 -279.986382)
			(xy 291.052752 -280.014338) (xy 291.00829 -280.035436) (xy 290.961019 -280.049128) (xy 290.912164 -280.05506)
			(xy 290.862989 -280.053079) (xy 290.81477 -280.043235) (xy 290.768754 -280.025783) (xy 290.726133 -280.001176)
			(xy 290.688012 -279.970051) (xy 290.655377 -279.933214) (xy 290.629074 -279.891618) (xy 290.609783 -279.846342)
			(xy 290.598006 -279.798558) (xy 290.594046 -279.749504) (xy 289.304984 -279.749504) (xy 289.304489 -279.774111)
			(xy 289.296594 -279.822688) (xy 289.28101 -279.869369) (xy 289.258139 -279.912946) (xy 289.228574 -279.95229)
			(xy 289.193081 -279.986382) (xy 289.152578 -280.014338) (xy 289.108116 -280.035436) (xy 289.060845 -280.049128)
			(xy 289.01199 -280.05506) (xy 288.962815 -280.053079) (xy 288.914596 -280.043235) (xy 288.86858 -280.025783)
			(xy 288.825959 -280.001176) (xy 288.787838 -279.970051) (xy 288.755203 -279.933214) (xy 288.7289 -279.891618)
			(xy 288.709609 -279.846342) (xy 288.697832 -279.798558) (xy 288.693872 -279.749504) (xy 287.405064 -279.749504)
			(xy 287.404569 -279.774111) (xy 287.396674 -279.822688) (xy 287.38109 -279.869369) (xy 287.358219 -279.912946)
			(xy 287.328654 -279.95229) (xy 287.293161 -279.986382) (xy 287.252658 -280.014338) (xy 287.208196 -280.035436)
			(xy 287.160925 -280.049128) (xy 287.11207 -280.05506) (xy 287.062895 -280.053079) (xy 287.014676 -280.043235)
			(xy 286.96866 -280.025783) (xy 286.926039 -280.001176) (xy 286.887918 -279.970051) (xy 286.855283 -279.933214)
			(xy 286.82898 -279.891618) (xy 286.809689 -279.846342) (xy 286.797912 -279.798558) (xy 286.793952 -279.749504)
			(xy 285.505144 -279.749504) (xy 285.504649 -279.774111) (xy 285.496754 -279.822688) (xy 285.48117 -279.869369)
			(xy 285.458299 -279.912946) (xy 285.428734 -279.95229) (xy 285.393241 -279.986382) (xy 285.352738 -280.014338)
			(xy 285.308276 -280.035436) (xy 285.261005 -280.049128) (xy 285.21215 -280.05506) (xy 285.162975 -280.053079)
			(xy 285.114756 -280.043235) (xy 285.06874 -280.025783) (xy 285.026119 -280.001176) (xy 284.987998 -279.970051)
			(xy 284.955363 -279.933214) (xy 284.92906 -279.891618) (xy 284.909769 -279.846342) (xy 284.897992 -279.798558)
			(xy 284.894032 -279.749504) (xy 283.605224 -279.749504) (xy 283.604729 -279.774111) (xy 283.596834 -279.822688)
			(xy 283.58125 -279.869369) (xy 283.558379 -279.912946) (xy 283.528814 -279.95229) (xy 283.493321 -279.986382)
			(xy 283.452818 -280.014338) (xy 283.408356 -280.035436) (xy 283.361085 -280.049128) (xy 283.31223 -280.05506)
			(xy 283.263055 -280.053079) (xy 283.214836 -280.043235) (xy 283.16882 -280.025783) (xy 283.126199 -280.001176)
			(xy 283.088078 -279.970051) (xy 283.055443 -279.933214) (xy 283.02914 -279.891618) (xy 283.009849 -279.846342)
			(xy 282.998072 -279.798558) (xy 282.994112 -279.749504) (xy 281.70505 -279.749504) (xy 281.704555 -279.774111)
			(xy 281.69666 -279.822688) (xy 281.681076 -279.869369) (xy 281.658205 -279.912946) (xy 281.62864 -279.95229)
			(xy 281.593147 -279.986382) (xy 281.552644 -280.014338) (xy 281.508182 -280.035436) (xy 281.460911 -280.049128)
			(xy 281.412056 -280.05506) (xy 281.362881 -280.053079) (xy 281.314662 -280.043235) (xy 281.268646 -280.025783)
			(xy 281.226025 -280.001176) (xy 281.187904 -279.970051) (xy 281.155269 -279.933214) (xy 281.128966 -279.891618)
			(xy 281.109675 -279.846342) (xy 281.097898 -279.798558) (xy 281.093938 -279.749504) (xy 279.80513 -279.749504)
			(xy 279.804635 -279.774111) (xy 279.79674 -279.822688) (xy 279.781156 -279.869369) (xy 279.758285 -279.912946)
			(xy 279.72872 -279.95229) (xy 279.693227 -279.986382) (xy 279.652724 -280.014338) (xy 279.608262 -280.035436)
			(xy 279.560991 -280.049128) (xy 279.512136 -280.05506) (xy 279.462961 -280.053079) (xy 279.414742 -280.043235)
			(xy 279.368726 -280.025783) (xy 279.326105 -280.001176) (xy 279.287984 -279.970051) (xy 279.255349 -279.933214)
			(xy 279.229046 -279.891618) (xy 279.209755 -279.846342) (xy 279.197978 -279.798558) (xy 279.194018 -279.749504)
			(xy 277.90521 -279.749504) (xy 277.904715 -279.774111) (xy 277.89682 -279.822688) (xy 277.881236 -279.869369)
			(xy 277.858365 -279.912946) (xy 277.8288 -279.95229) (xy 277.793307 -279.986382) (xy 277.752804 -280.014338)
			(xy 277.708342 -280.035436) (xy 277.661071 -280.049128) (xy 277.612216 -280.05506) (xy 277.563041 -280.053079)
			(xy 277.514822 -280.043235) (xy 277.468806 -280.025783) (xy 277.426185 -280.001176) (xy 277.388064 -279.970051)
			(xy 277.355429 -279.933214) (xy 277.329126 -279.891618) (xy 277.309835 -279.846342) (xy 277.298058 -279.798558)
			(xy 277.294098 -279.749504) (xy 198.855325 -279.749504) (xy 198.85533 -279.749758) (xy 198.854835 -279.774365)
			(xy 198.84694 -279.822942) (xy 198.831356 -279.869623) (xy 198.808485 -279.9132) (xy 198.77892 -279.952544)
			(xy 198.743427 -279.986636) (xy 198.702924 -280.014592) (xy 198.658462 -280.03569) (xy 198.611191 -280.049382)
			(xy 198.562336 -280.055314) (xy 198.513161 -280.053333) (xy 198.464942 -280.043489) (xy 198.418926 -280.026037)
			(xy 198.376305 -280.00143) (xy 198.338184 -279.970305) (xy 198.305549 -279.933468) (xy 198.279246 -279.891872)
			(xy 198.259955 -279.846596) (xy 198.248178 -279.798812) (xy 198.244218 -279.749758) (xy 197.90537 -279.749758)
			(xy 197.904875 -279.774365) (xy 197.89698 -279.822942) (xy 197.881396 -279.869623) (xy 197.858525 -279.9132)
			(xy 197.82896 -279.952544) (xy 197.793467 -279.986636) (xy 197.752964 -280.014592) (xy 197.708502 -280.03569)
			(xy 197.661231 -280.049382) (xy 197.612376 -280.055314) (xy 197.563201 -280.053333) (xy 197.514982 -280.043489)
			(xy 197.468966 -280.026037) (xy 197.426345 -280.00143) (xy 197.388224 -279.970305) (xy 197.355589 -279.933468)
			(xy 197.329286 -279.891872) (xy 197.309995 -279.846596) (xy 197.298218 -279.798812) (xy 197.294258 -279.749758)
			(xy 196.005196 -279.749758) (xy 196.004701 -279.774365) (xy 195.996806 -279.822942) (xy 195.981222 -279.869623)
			(xy 195.958351 -279.9132) (xy 195.928786 -279.952544) (xy 195.893293 -279.986636) (xy 195.85279 -280.014592)
			(xy 195.808328 -280.03569) (xy 195.761057 -280.049382) (xy 195.712202 -280.055314) (xy 195.663027 -280.053333)
			(xy 195.614808 -280.043489) (xy 195.568792 -280.026037) (xy 195.526171 -280.00143) (xy 195.48805 -279.970305)
			(xy 195.455415 -279.933468) (xy 195.429112 -279.891872) (xy 195.409821 -279.846596) (xy 195.398044 -279.798812)
			(xy 195.394084 -279.749758) (xy 194.105271 -279.749758) (xy 194.104781 -279.774111) (xy 194.096886 -279.822688)
			(xy 194.081302 -279.869369) (xy 194.058431 -279.912946) (xy 194.028866 -279.95229) (xy 193.993373 -279.986382)
			(xy 193.95287 -280.014338) (xy 193.908408 -280.035436) (xy 193.861137 -280.049128) (xy 193.812282 -280.05506)
			(xy 193.763107 -280.053079) (xy 193.714888 -280.043235) (xy 193.668872 -280.025783) (xy 193.626251 -280.001176)
			(xy 193.58813 -279.970051) (xy 193.555495 -279.933214) (xy 193.529192 -279.891618) (xy 193.509901 -279.846342)
			(xy 193.498124 -279.798558) (xy 193.494164 -279.749504) (xy 192.205356 -279.749504) (xy 192.204861 -279.774111)
			(xy 192.196966 -279.822688) (xy 192.181382 -279.869369) (xy 192.158511 -279.912946) (xy 192.128946 -279.95229)
			(xy 192.093453 -279.986382) (xy 192.05295 -280.014338) (xy 192.008488 -280.035436) (xy 191.961217 -280.049128)
			(xy 191.912362 -280.05506) (xy 191.863187 -280.053079) (xy 191.814968 -280.043235) (xy 191.768952 -280.025783)
			(xy 191.726331 -280.001176) (xy 191.68821 -279.970051) (xy 191.655575 -279.933214) (xy 191.629272 -279.891618)
			(xy 191.609981 -279.846342) (xy 191.598204 -279.798558) (xy 191.594244 -279.749504) (xy 190.305182 -279.749504)
			(xy 190.304687 -279.774111) (xy 190.296792 -279.822688) (xy 190.281208 -279.869369) (xy 190.258337 -279.912946)
			(xy 190.228772 -279.95229) (xy 190.193279 -279.986382) (xy 190.152776 -280.014338) (xy 190.108314 -280.035436)
			(xy 190.061043 -280.049128) (xy 190.012188 -280.05506) (xy 189.963013 -280.053079) (xy 189.914794 -280.043235)
			(xy 189.868778 -280.025783) (xy 189.826157 -280.001176) (xy 189.788036 -279.970051) (xy 189.755401 -279.933214)
			(xy 189.729098 -279.891618) (xy 189.709807 -279.846342) (xy 189.69803 -279.798558) (xy 189.69407 -279.749504)
			(xy 188.405262 -279.749504) (xy 188.404767 -279.774111) (xy 188.396872 -279.822688) (xy 188.381288 -279.869369)
			(xy 188.358417 -279.912946) (xy 188.328852 -279.95229) (xy 188.293359 -279.986382) (xy 188.252856 -280.014338)
			(xy 188.208394 -280.035436) (xy 188.161123 -280.049128) (xy 188.112268 -280.05506) (xy 188.063093 -280.053079)
			(xy 188.014874 -280.043235) (xy 187.968858 -280.025783) (xy 187.926237 -280.001176) (xy 187.888116 -279.970051)
			(xy 187.855481 -279.933214) (xy 187.829178 -279.891618) (xy 187.809887 -279.846342) (xy 187.79811 -279.798558)
			(xy 187.79415 -279.749504) (xy 186.505342 -279.749504) (xy 186.504847 -279.774111) (xy 186.496952 -279.822688)
			(xy 186.481368 -279.869369) (xy 186.458497 -279.912946) (xy 186.428932 -279.95229) (xy 186.393439 -279.986382)
			(xy 186.352936 -280.014338) (xy 186.308474 -280.035436) (xy 186.261203 -280.049128) (xy 186.212348 -280.05506)
			(xy 186.163173 -280.053079) (xy 186.114954 -280.043235) (xy 186.068938 -280.025783) (xy 186.026317 -280.001176)
			(xy 185.988196 -279.970051) (xy 185.955561 -279.933214) (xy 185.929258 -279.891618) (xy 185.909967 -279.846342)
			(xy 185.89819 -279.798558) (xy 185.89423 -279.749504) (xy 184.605168 -279.749504) (xy 184.604673 -279.774111)
			(xy 184.596778 -279.822688) (xy 184.581194 -279.869369) (xy 184.558323 -279.912946) (xy 184.528758 -279.95229)
			(xy 184.493265 -279.986382) (xy 184.452762 -280.014338) (xy 184.4083 -280.035436) (xy 184.361029 -280.049128)
			(xy 184.312174 -280.05506) (xy 184.262999 -280.053079) (xy 184.21478 -280.043235) (xy 184.168764 -280.025783)
			(xy 184.126143 -280.001176) (xy 184.088022 -279.970051) (xy 184.055387 -279.933214) (xy 184.029084 -279.891618)
			(xy 184.009793 -279.846342) (xy 183.998016 -279.798558) (xy 183.994056 -279.749504) (xy 182.705248 -279.749504)
			(xy 182.704753 -279.774111) (xy 182.696858 -279.822688) (xy 182.681274 -279.869369) (xy 182.658403 -279.912946)
			(xy 182.628838 -279.95229) (xy 182.593345 -279.986382) (xy 182.552842 -280.014338) (xy 182.50838 -280.035436)
			(xy 182.461109 -280.049128) (xy 182.412254 -280.05506) (xy 182.363079 -280.053079) (xy 182.31486 -280.043235)
			(xy 182.268844 -280.025783) (xy 182.226223 -280.001176) (xy 182.188102 -279.970051) (xy 182.155467 -279.933214)
			(xy 182.129164 -279.891618) (xy 182.109873 -279.846342) (xy 182.098096 -279.798558) (xy 182.094136 -279.749504)
			(xy 180.805328 -279.749504) (xy 180.804833 -279.774111) (xy 180.796938 -279.822688) (xy 180.781354 -279.869369)
			(xy 180.758483 -279.912946) (xy 180.728918 -279.95229) (xy 180.693425 -279.986382) (xy 180.652922 -280.014338)
			(xy 180.60846 -280.035436) (xy 180.561189 -280.049128) (xy 180.512334 -280.05506) (xy 180.463159 -280.053079)
			(xy 180.41494 -280.043235) (xy 180.368924 -280.025783) (xy 180.326303 -280.001176) (xy 180.288182 -279.970051)
			(xy 180.255547 -279.933214) (xy 180.229244 -279.891618) (xy 180.209953 -279.846342) (xy 180.198176 -279.798558)
			(xy 180.194216 -279.749504) (xy 178.905154 -279.749504) (xy 178.904659 -279.774111) (xy 178.896764 -279.822688)
			(xy 178.88118 -279.869369) (xy 178.858309 -279.912946) (xy 178.828744 -279.95229) (xy 178.793251 -279.986382)
			(xy 178.752748 -280.014338) (xy 178.708286 -280.035436) (xy 178.661015 -280.049128) (xy 178.61216 -280.05506)
			(xy 178.562985 -280.053079) (xy 178.514766 -280.043235) (xy 178.46875 -280.025783) (xy 178.426129 -280.001176)
			(xy 178.388008 -279.970051) (xy 178.355373 -279.933214) (xy 178.32907 -279.891618) (xy 178.309779 -279.846342)
			(xy 178.298002 -279.798558) (xy 178.294042 -279.749504) (xy 177.005234 -279.749504) (xy 177.004739 -279.774111)
			(xy 176.996844 -279.822688) (xy 176.98126 -279.869369) (xy 176.958389 -279.912946) (xy 176.928824 -279.95229)
			(xy 176.893331 -279.986382) (xy 176.852828 -280.014338) (xy 176.808366 -280.035436) (xy 176.761095 -280.049128)
			(xy 176.71224 -280.05506) (xy 176.663065 -280.053079) (xy 176.614846 -280.043235) (xy 176.56883 -280.025783)
			(xy 176.526209 -280.001176) (xy 176.488088 -279.970051) (xy 176.455453 -279.933214) (xy 176.42915 -279.891618)
			(xy 176.409859 -279.846342) (xy 176.398082 -279.798558) (xy 176.394122 -279.749504) (xy 175.105314 -279.749504)
			(xy 175.104819 -279.774111) (xy 175.096924 -279.822688) (xy 175.08134 -279.869369) (xy 175.058469 -279.912946)
			(xy 175.028904 -279.95229) (xy 174.993411 -279.986382) (xy 174.952908 -280.014338) (xy 174.908446 -280.035436)
			(xy 174.861175 -280.049128) (xy 174.81232 -280.05506) (xy 174.763145 -280.053079) (xy 174.714926 -280.043235)
			(xy 174.66891 -280.025783) (xy 174.626289 -280.001176) (xy 174.588168 -279.970051) (xy 174.555533 -279.933214)
			(xy 174.52923 -279.891618) (xy 174.509939 -279.846342) (xy 174.498162 -279.798558) (xy 174.494202 -279.749504)
			(xy 173.20514 -279.749504) (xy 173.204645 -279.774111) (xy 173.19675 -279.822688) (xy 173.181166 -279.869369)
			(xy 173.158295 -279.912946) (xy 173.12873 -279.95229) (xy 173.093237 -279.986382) (xy 173.052734 -280.014338)
			(xy 173.008272 -280.035436) (xy 172.961001 -280.049128) (xy 172.912146 -280.05506) (xy 172.862971 -280.053079)
			(xy 172.814752 -280.043235) (xy 172.768736 -280.025783) (xy 172.726115 -280.001176) (xy 172.687994 -279.970051)
			(xy 172.655359 -279.933214) (xy 172.629056 -279.891618) (xy 172.609765 -279.846342) (xy 172.597988 -279.798558)
			(xy 172.594028 -279.749504) (xy 171.30522 -279.749504) (xy 171.304725 -279.774111) (xy 171.29683 -279.822688)
			(xy 171.281246 -279.869369) (xy 171.258375 -279.912946) (xy 171.22881 -279.95229) (xy 171.193317 -279.986382)
			(xy 171.152814 -280.014338) (xy 171.108352 -280.035436) (xy 171.061081 -280.049128) (xy 171.012226 -280.05506)
			(xy 170.963051 -280.053079) (xy 170.914832 -280.043235) (xy 170.868816 -280.025783) (xy 170.826195 -280.001176)
			(xy 170.788074 -279.970051) (xy 170.755439 -279.933214) (xy 170.729136 -279.891618) (xy 170.709845 -279.846342)
			(xy 170.698068 -279.798558) (xy 170.694108 -279.749504) (xy 169.4053 -279.749504) (xy 169.404805 -279.774111)
			(xy 169.39691 -279.822688) (xy 169.381326 -279.869369) (xy 169.358455 -279.912946) (xy 169.32889 -279.95229)
			(xy 169.293397 -279.986382) (xy 169.252894 -280.014338) (xy 169.208432 -280.035436) (xy 169.161161 -280.049128)
			(xy 169.112306 -280.05506) (xy 169.063131 -280.053079) (xy 169.014912 -280.043235) (xy 168.968896 -280.025783)
			(xy 168.926275 -280.001176) (xy 168.888154 -279.970051) (xy 168.855519 -279.933214) (xy 168.829216 -279.891618)
			(xy 168.809925 -279.846342) (xy 168.798148 -279.798558) (xy 168.794188 -279.749504) (xy 167.50538 -279.749504)
			(xy 167.504885 -279.774111) (xy 167.49699 -279.822688) (xy 167.481406 -279.869369) (xy 167.458535 -279.912946)
			(xy 167.42897 -279.95229) (xy 167.393477 -279.986382) (xy 167.352974 -280.014338) (xy 167.308512 -280.035436)
			(xy 167.261241 -280.049128) (xy 167.212386 -280.05506) (xy 167.163211 -280.053079) (xy 167.114992 -280.043235)
			(xy 167.068976 -280.025783) (xy 167.026355 -280.001176) (xy 166.988234 -279.970051) (xy 166.955599 -279.933214)
			(xy 166.929296 -279.891618) (xy 166.910005 -279.846342) (xy 166.898228 -279.798558) (xy 166.894268 -279.749504)
			(xy 165.605206 -279.749504) (xy 165.604711 -279.774111) (xy 165.596816 -279.822688) (xy 165.581232 -279.869369)
			(xy 165.558361 -279.912946) (xy 165.528796 -279.95229) (xy 165.493303 -279.986382) (xy 165.4528 -280.014338)
			(xy 165.408338 -280.035436) (xy 165.361067 -280.049128) (xy 165.312212 -280.05506) (xy 165.263037 -280.053079)
			(xy 165.214818 -280.043235) (xy 165.168802 -280.025783) (xy 165.126181 -280.001176) (xy 165.08806 -279.970051)
			(xy 165.055425 -279.933214) (xy 165.029122 -279.891618) (xy 165.009831 -279.846342) (xy 164.998054 -279.798558)
			(xy 164.994094 -279.749504) (xy 163.705286 -279.749504) (xy 163.704791 -279.774111) (xy 163.696896 -279.822688)
			(xy 163.681312 -279.869369) (xy 163.658441 -279.912946) (xy 163.628876 -279.95229) (xy 163.593383 -279.986382)
			(xy 163.55288 -280.014338) (xy 163.508418 -280.035436) (xy 163.461147 -280.049128) (xy 163.412292 -280.05506)
			(xy 163.363117 -280.053079) (xy 163.314898 -280.043235) (xy 163.268882 -280.025783) (xy 163.226261 -280.001176)
			(xy 163.18814 -279.970051) (xy 163.155505 -279.933214) (xy 163.129202 -279.891618) (xy 163.109911 -279.846342)
			(xy 163.098134 -279.798558) (xy 163.094174 -279.749504) (xy 161.805366 -279.749504) (xy 161.804871 -279.774111)
			(xy 161.796976 -279.822688) (xy 161.781392 -279.869369) (xy 161.758521 -279.912946) (xy 161.728956 -279.95229)
			(xy 161.693463 -279.986382) (xy 161.65296 -280.014338) (xy 161.608498 -280.035436) (xy 161.561227 -280.049128)
			(xy 161.512372 -280.05506) (xy 161.463197 -280.053079) (xy 161.414978 -280.043235) (xy 161.368962 -280.025783)
			(xy 161.326341 -280.001176) (xy 161.28822 -279.970051) (xy 161.255585 -279.933214) (xy 161.229282 -279.891618)
			(xy 161.209991 -279.846342) (xy 161.198214 -279.798558) (xy 161.194254 -279.749504) (xy 82.755227 -279.749504)
			(xy 82.755232 -279.749758) (xy 82.754737 -279.774365) (xy 82.746842 -279.822942) (xy 82.731258 -279.869623)
			(xy 82.708387 -279.9132) (xy 82.678822 -279.952544) (xy 82.643329 -279.986636) (xy 82.602826 -280.014592)
			(xy 82.558364 -280.03569) (xy 82.511093 -280.049382) (xy 82.462238 -280.055314) (xy 82.413063 -280.053333)
			(xy 82.364844 -280.043489) (xy 82.318828 -280.026037) (xy 82.276207 -280.00143) (xy 82.238086 -279.970305)
			(xy 82.205451 -279.933468) (xy 82.179148 -279.891872) (xy 82.159857 -279.846596) (xy 82.14808 -279.798812)
			(xy 82.14412 -279.749758) (xy 81.805272 -279.749758) (xy 81.804777 -279.774365) (xy 81.796882 -279.822942)
			(xy 81.781298 -279.869623) (xy 81.758427 -279.9132) (xy 81.728862 -279.952544) (xy 81.693369 -279.986636)
			(xy 81.652866 -280.014592) (xy 81.608404 -280.03569) (xy 81.561133 -280.049382) (xy 81.512278 -280.055314)
			(xy 81.463103 -280.053333) (xy 81.414884 -280.043489) (xy 81.368868 -280.026037) (xy 81.326247 -280.00143)
			(xy 81.288126 -279.970305) (xy 81.255491 -279.933468) (xy 81.229188 -279.891872) (xy 81.209897 -279.846596)
			(xy 81.19812 -279.798812) (xy 81.19416 -279.749758) (xy 79.905098 -279.749758) (xy 79.904603 -279.774365)
			(xy 79.896708 -279.822942) (xy 79.881124 -279.869623) (xy 79.858253 -279.9132) (xy 79.828688 -279.952544)
			(xy 79.793195 -279.986636) (xy 79.752692 -280.014592) (xy 79.70823 -280.03569) (xy 79.660959 -280.049382)
			(xy 79.612104 -280.055314) (xy 79.562929 -280.053333) (xy 79.51471 -280.043489) (xy 79.468694 -280.026037)
			(xy 79.426073 -280.00143) (xy 79.387952 -279.970305) (xy 79.355317 -279.933468) (xy 79.329014 -279.891872)
			(xy 79.309723 -279.846596) (xy 79.297946 -279.798812) (xy 79.293986 -279.749758) (xy 78.005173 -279.749758)
			(xy 78.004683 -279.774111) (xy 77.996788 -279.822688) (xy 77.981204 -279.869369) (xy 77.958333 -279.912946)
			(xy 77.928768 -279.95229) (xy 77.893275 -279.986382) (xy 77.852772 -280.014338) (xy 77.80831 -280.035436)
			(xy 77.761039 -280.049128) (xy 77.712184 -280.05506) (xy 77.663009 -280.053079) (xy 77.61479 -280.043235)
			(xy 77.568774 -280.025783) (xy 77.526153 -280.001176) (xy 77.488032 -279.970051) (xy 77.455397 -279.933214)
			(xy 77.429094 -279.891618) (xy 77.409803 -279.846342) (xy 77.398026 -279.798558) (xy 77.394066 -279.749504)
			(xy 76.105258 -279.749504) (xy 76.104763 -279.774111) (xy 76.096868 -279.822688) (xy 76.081284 -279.869369)
			(xy 76.058413 -279.912946) (xy 76.028848 -279.95229) (xy 75.993355 -279.986382) (xy 75.952852 -280.014338)
			(xy 75.90839 -280.035436) (xy 75.861119 -280.049128) (xy 75.812264 -280.05506) (xy 75.763089 -280.053079)
			(xy 75.71487 -280.043235) (xy 75.668854 -280.025783) (xy 75.626233 -280.001176) (xy 75.588112 -279.970051)
			(xy 75.555477 -279.933214) (xy 75.529174 -279.891618) (xy 75.509883 -279.846342) (xy 75.498106 -279.798558)
			(xy 75.494146 -279.749504) (xy 74.205084 -279.749504) (xy 74.204589 -279.774111) (xy 74.196694 -279.822688)
			(xy 74.18111 -279.869369) (xy 74.158239 -279.912946) (xy 74.128674 -279.95229) (xy 74.093181 -279.986382)
			(xy 74.052678 -280.014338) (xy 74.008216 -280.035436) (xy 73.960945 -280.049128) (xy 73.91209 -280.05506)
			(xy 73.862915 -280.053079) (xy 73.814696 -280.043235) (xy 73.76868 -280.025783) (xy 73.726059 -280.001176)
			(xy 73.687938 -279.970051) (xy 73.655303 -279.933214) (xy 73.629 -279.891618) (xy 73.609709 -279.846342)
			(xy 73.597932 -279.798558) (xy 73.593972 -279.749504) (xy 72.305164 -279.749504) (xy 72.304669 -279.774111)
			(xy 72.296774 -279.822688) (xy 72.28119 -279.869369) (xy 72.258319 -279.912946) (xy 72.228754 -279.95229)
			(xy 72.193261 -279.986382) (xy 72.152758 -280.014338) (xy 72.108296 -280.035436) (xy 72.061025 -280.049128)
			(xy 72.01217 -280.05506) (xy 71.962995 -280.053079) (xy 71.914776 -280.043235) (xy 71.86876 -280.025783)
			(xy 71.826139 -280.001176) (xy 71.788018 -279.970051) (xy 71.755383 -279.933214) (xy 71.72908 -279.891618)
			(xy 71.709789 -279.846342) (xy 71.698012 -279.798558) (xy 71.694052 -279.749504) (xy 70.405244 -279.749504)
			(xy 70.404749 -279.774111) (xy 70.396854 -279.822688) (xy 70.38127 -279.869369) (xy 70.358399 -279.912946)
			(xy 70.328834 -279.95229) (xy 70.293341 -279.986382) (xy 70.252838 -280.014338) (xy 70.208376 -280.035436)
			(xy 70.161105 -280.049128) (xy 70.11225 -280.05506) (xy 70.063075 -280.053079) (xy 70.014856 -280.043235)
			(xy 69.96884 -280.025783) (xy 69.926219 -280.001176) (xy 69.888098 -279.970051) (xy 69.855463 -279.933214)
			(xy 69.82916 -279.891618) (xy 69.809869 -279.846342) (xy 69.798092 -279.798558) (xy 69.794132 -279.749504)
			(xy 68.50507 -279.749504) (xy 68.504575 -279.774111) (xy 68.49668 -279.822688) (xy 68.481096 -279.869369)
			(xy 68.458225 -279.912946) (xy 68.42866 -279.95229) (xy 68.393167 -279.986382) (xy 68.352664 -280.014338)
			(xy 68.308202 -280.035436) (xy 68.260931 -280.049128) (xy 68.212076 -280.05506) (xy 68.162901 -280.053079)
			(xy 68.114682 -280.043235) (xy 68.068666 -280.025783) (xy 68.026045 -280.001176) (xy 67.987924 -279.970051)
			(xy 67.955289 -279.933214) (xy 67.928986 -279.891618) (xy 67.909695 -279.846342) (xy 67.897918 -279.798558)
			(xy 67.893958 -279.749504) (xy 66.60515 -279.749504) (xy 66.604655 -279.774111) (xy 66.59676 -279.822688)
			(xy 66.581176 -279.869369) (xy 66.558305 -279.912946) (xy 66.52874 -279.95229) (xy 66.493247 -279.986382)
			(xy 66.452744 -280.014338) (xy 66.408282 -280.035436) (xy 66.361011 -280.049128) (xy 66.312156 -280.05506)
			(xy 66.262981 -280.053079) (xy 66.214762 -280.043235) (xy 66.168746 -280.025783) (xy 66.126125 -280.001176)
			(xy 66.088004 -279.970051) (xy 66.055369 -279.933214) (xy 66.029066 -279.891618) (xy 66.009775 -279.846342)
			(xy 65.997998 -279.798558) (xy 65.994038 -279.749504) (xy 64.70523 -279.749504) (xy 64.704735 -279.774111)
			(xy 64.69684 -279.822688) (xy 64.681256 -279.869369) (xy 64.658385 -279.912946) (xy 64.62882 -279.95229)
			(xy 64.593327 -279.986382) (xy 64.552824 -280.014338) (xy 64.508362 -280.035436) (xy 64.461091 -280.049128)
			(xy 64.412236 -280.05506) (xy 64.363061 -280.053079) (xy 64.314842 -280.043235) (xy 64.268826 -280.025783)
			(xy 64.226205 -280.001176) (xy 64.188084 -279.970051) (xy 64.155449 -279.933214) (xy 64.129146 -279.891618)
			(xy 64.109855 -279.846342) (xy 64.098078 -279.798558) (xy 64.094118 -279.749504) (xy 62.805056 -279.749504)
			(xy 62.804561 -279.774111) (xy 62.796666 -279.822688) (xy 62.781082 -279.869369) (xy 62.758211 -279.912946)
			(xy 62.728646 -279.95229) (xy 62.693153 -279.986382) (xy 62.65265 -280.014338) (xy 62.608188 -280.035436)
			(xy 62.560917 -280.049128) (xy 62.512062 -280.05506) (xy 62.462887 -280.053079) (xy 62.414668 -280.043235)
			(xy 62.368652 -280.025783) (xy 62.326031 -280.001176) (xy 62.28791 -279.970051) (xy 62.255275 -279.933214)
			(xy 62.228972 -279.891618) (xy 62.209681 -279.846342) (xy 62.197904 -279.798558) (xy 62.193944 -279.749504)
			(xy 60.905136 -279.749504) (xy 60.904641 -279.774111) (xy 60.896746 -279.822688) (xy 60.881162 -279.869369)
			(xy 60.858291 -279.912946) (xy 60.828726 -279.95229) (xy 60.793233 -279.986382) (xy 60.75273 -280.014338)
			(xy 60.708268 -280.035436) (xy 60.660997 -280.049128) (xy 60.612142 -280.05506) (xy 60.562967 -280.053079)
			(xy 60.514748 -280.043235) (xy 60.468732 -280.025783) (xy 60.426111 -280.001176) (xy 60.38799 -279.970051)
			(xy 60.355355 -279.933214) (xy 60.329052 -279.891618) (xy 60.309761 -279.846342) (xy 60.297984 -279.798558)
			(xy 60.294024 -279.749504) (xy 59.005216 -279.749504) (xy 59.004721 -279.774111) (xy 58.996826 -279.822688)
			(xy 58.981242 -279.869369) (xy 58.958371 -279.912946) (xy 58.928806 -279.95229) (xy 58.893313 -279.986382)
			(xy 58.85281 -280.014338) (xy 58.808348 -280.035436) (xy 58.761077 -280.049128) (xy 58.712222 -280.05506)
			(xy 58.663047 -280.053079) (xy 58.614828 -280.043235) (xy 58.568812 -280.025783) (xy 58.526191 -280.001176)
			(xy 58.48807 -279.970051) (xy 58.455435 -279.933214) (xy 58.429132 -279.891618) (xy 58.409841 -279.846342)
			(xy 58.398064 -279.798558) (xy 58.394104 -279.749504) (xy 57.105042 -279.749504) (xy 57.104547 -279.774111)
			(xy 57.096652 -279.822688) (xy 57.081068 -279.869369) (xy 57.058197 -279.912946) (xy 57.028632 -279.95229)
			(xy 56.993139 -279.986382) (xy 56.952636 -280.014338) (xy 56.908174 -280.035436) (xy 56.860903 -280.049128)
			(xy 56.812048 -280.05506) (xy 56.762873 -280.053079) (xy 56.714654 -280.043235) (xy 56.668638 -280.025783)
			(xy 56.626017 -280.001176) (xy 56.587896 -279.970051) (xy 56.555261 -279.933214) (xy 56.528958 -279.891618)
			(xy 56.509667 -279.846342) (xy 56.49789 -279.798558) (xy 56.49393 -279.749504) (xy 55.205122 -279.749504)
			(xy 55.204627 -279.774111) (xy 55.196732 -279.822688) (xy 55.181148 -279.869369) (xy 55.158277 -279.912946)
			(xy 55.128712 -279.95229) (xy 55.093219 -279.986382) (xy 55.052716 -280.014338) (xy 55.008254 -280.035436)
			(xy 54.960983 -280.049128) (xy 54.912128 -280.05506) (xy 54.862953 -280.053079) (xy 54.814734 -280.043235)
			(xy 54.768718 -280.025783) (xy 54.726097 -280.001176) (xy 54.687976 -279.970051) (xy 54.655341 -279.933214)
			(xy 54.629038 -279.891618) (xy 54.609747 -279.846342) (xy 54.59797 -279.798558) (xy 54.59401 -279.749504)
			(xy 53.305202 -279.749504) (xy 53.304707 -279.774111) (xy 53.296812 -279.822688) (xy 53.281228 -279.869369)
			(xy 53.258357 -279.912946) (xy 53.228792 -279.95229) (xy 53.193299 -279.986382) (xy 53.152796 -280.014338)
			(xy 53.108334 -280.035436) (xy 53.061063 -280.049128) (xy 53.012208 -280.05506) (xy 52.963033 -280.053079)
			(xy 52.914814 -280.043235) (xy 52.868798 -280.025783) (xy 52.826177 -280.001176) (xy 52.788056 -279.970051)
			(xy 52.755421 -279.933214) (xy 52.729118 -279.891618) (xy 52.709827 -279.846342) (xy 52.69805 -279.798558)
			(xy 52.69409 -279.749504) (xy 51.405282 -279.749504) (xy 51.404787 -279.774111) (xy 51.396892 -279.822688)
			(xy 51.381308 -279.869369) (xy 51.358437 -279.912946) (xy 51.328872 -279.95229) (xy 51.293379 -279.986382)
			(xy 51.252876 -280.014338) (xy 51.208414 -280.035436) (xy 51.161143 -280.049128) (xy 51.112288 -280.05506)
			(xy 51.063113 -280.053079) (xy 51.014894 -280.043235) (xy 50.968878 -280.025783) (xy 50.926257 -280.001176)
			(xy 50.888136 -279.970051) (xy 50.855501 -279.933214) (xy 50.829198 -279.891618) (xy 50.809907 -279.846342)
			(xy 50.79813 -279.798558) (xy 50.79417 -279.749504) (xy 49.505108 -279.749504) (xy 49.504613 -279.774111)
			(xy 49.496718 -279.822688) (xy 49.481134 -279.869369) (xy 49.458263 -279.912946) (xy 49.428698 -279.95229)
			(xy 49.393205 -279.986382) (xy 49.352702 -280.014338) (xy 49.30824 -280.035436) (xy 49.260969 -280.049128)
			(xy 49.212114 -280.05506) (xy 49.162939 -280.053079) (xy 49.11472 -280.043235) (xy 49.068704 -280.025783)
			(xy 49.026083 -280.001176) (xy 48.987962 -279.970051) (xy 48.955327 -279.933214) (xy 48.929024 -279.891618)
			(xy 48.909733 -279.846342) (xy 48.897956 -279.798558) (xy 48.893996 -279.749504) (xy 47.605188 -279.749504)
			(xy 47.604693 -279.774111) (xy 47.596798 -279.822688) (xy 47.581214 -279.869369) (xy 47.558343 -279.912946)
			(xy 47.528778 -279.95229) (xy 47.493285 -279.986382) (xy 47.452782 -280.014338) (xy 47.40832 -280.035436)
			(xy 47.361049 -280.049128) (xy 47.312194 -280.05506) (xy 47.263019 -280.053079) (xy 47.2148 -280.043235)
			(xy 47.168784 -280.025783) (xy 47.126163 -280.001176) (xy 47.088042 -279.970051) (xy 47.055407 -279.933214)
			(xy 47.029104 -279.891618) (xy 47.009813 -279.846342) (xy 46.998036 -279.798558) (xy 46.994076 -279.749504)
			(xy 45.705268 -279.749504) (xy 45.704773 -279.774111) (xy 45.696878 -279.822688) (xy 45.681294 -279.869369)
			(xy 45.658423 -279.912946) (xy 45.628858 -279.95229) (xy 45.593365 -279.986382) (xy 45.552862 -280.014338)
			(xy 45.5084 -280.035436) (xy 45.461129 -280.049128) (xy 45.412274 -280.05506) (xy 45.363099 -280.053079)
			(xy 45.31488 -280.043235) (xy 45.268864 -280.025783) (xy 45.226243 -280.001176) (xy 45.188122 -279.970051)
			(xy 45.155487 -279.933214) (xy 45.129184 -279.891618) (xy 45.109893 -279.846342) (xy 45.098116 -279.798558)
			(xy 45.094156 -279.749504) (xy 0.508 -279.749504) (xy 0.508 -280.699718) (xy 45.094156 -280.699718)
			(xy 45.098116 -280.650664) (xy 45.109893 -280.60288) (xy 45.129184 -280.557604) (xy 45.155487 -280.516008)
			(xy 45.188122 -280.479171) (xy 45.226243 -280.448046) (xy 45.268864 -280.423439) (xy 45.31488 -280.405987)
			(xy 45.363099 -280.396143) (xy 45.412274 -280.394162) (xy 45.461129 -280.400094) (xy 45.5084 -280.413786)
			(xy 45.552862 -280.434884) (xy 45.593365 -280.46284) (xy 45.628858 -280.496932) (xy 45.658423 -280.536276)
			(xy 45.681294 -280.579853) (xy 45.696878 -280.626534) (xy 45.704773 -280.675111) (xy 45.705268 -280.699718)
			(xy 46.994076 -280.699718) (xy 46.998036 -280.650664) (xy 47.009813 -280.60288) (xy 47.029104 -280.557604)
			(xy 47.055407 -280.516008) (xy 47.088042 -280.479171) (xy 47.126163 -280.448046) (xy 47.168784 -280.423439)
			(xy 47.2148 -280.405987) (xy 47.263019 -280.396143) (xy 47.312194 -280.394162) (xy 47.361049 -280.400094)
			(xy 47.40832 -280.413786) (xy 47.452782 -280.434884) (xy 47.493285 -280.46284) (xy 47.528778 -280.496932)
			(xy 47.558343 -280.536276) (xy 47.581214 -280.579853) (xy 47.596798 -280.626534) (xy 47.604693 -280.675111)
			(xy 47.605188 -280.699718) (xy 48.893996 -280.699718) (xy 48.897956 -280.650664) (xy 48.909733 -280.60288)
			(xy 48.929024 -280.557604) (xy 48.955327 -280.516008) (xy 48.987962 -280.479171) (xy 49.026083 -280.448046)
			(xy 49.068704 -280.423439) (xy 49.11472 -280.405987) (xy 49.162939 -280.396143) (xy 49.212114 -280.394162)
			(xy 49.260969 -280.400094) (xy 49.30824 -280.413786) (xy 49.352702 -280.434884) (xy 49.393205 -280.46284)
			(xy 49.428698 -280.496932) (xy 49.458263 -280.536276) (xy 49.481134 -280.579853) (xy 49.496718 -280.626534)
			(xy 49.504613 -280.675111) (xy 49.505108 -280.699718) (xy 50.79417 -280.699718) (xy 50.79813 -280.650664)
			(xy 50.809907 -280.60288) (xy 50.829198 -280.557604) (xy 50.855501 -280.516008) (xy 50.888136 -280.479171)
			(xy 50.926257 -280.448046) (xy 50.968878 -280.423439) (xy 51.014894 -280.405987) (xy 51.063113 -280.396143)
			(xy 51.112288 -280.394162) (xy 51.161143 -280.400094) (xy 51.208414 -280.413786) (xy 51.252876 -280.434884)
			(xy 51.293379 -280.46284) (xy 51.328872 -280.496932) (xy 51.358437 -280.536276) (xy 51.381308 -280.579853)
			(xy 51.396892 -280.626534) (xy 51.404787 -280.675111) (xy 51.405282 -280.699718) (xy 52.69409 -280.699718)
			(xy 52.69805 -280.650664) (xy 52.709827 -280.60288) (xy 52.729118 -280.557604) (xy 52.755421 -280.516008)
			(xy 52.788056 -280.479171) (xy 52.826177 -280.448046) (xy 52.868798 -280.423439) (xy 52.914814 -280.405987)
			(xy 52.963033 -280.396143) (xy 53.012208 -280.394162) (xy 53.061063 -280.400094) (xy 53.108334 -280.413786)
			(xy 53.152796 -280.434884) (xy 53.193299 -280.46284) (xy 53.228792 -280.496932) (xy 53.258357 -280.536276)
			(xy 53.281228 -280.579853) (xy 53.296812 -280.626534) (xy 53.304707 -280.675111) (xy 53.305202 -280.699718)
			(xy 54.59401 -280.699718) (xy 54.59797 -280.650664) (xy 54.609747 -280.60288) (xy 54.629038 -280.557604)
			(xy 54.655341 -280.516008) (xy 54.687976 -280.479171) (xy 54.726097 -280.448046) (xy 54.768718 -280.423439)
			(xy 54.814734 -280.405987) (xy 54.862953 -280.396143) (xy 54.912128 -280.394162) (xy 54.960983 -280.400094)
			(xy 55.008254 -280.413786) (xy 55.052716 -280.434884) (xy 55.093219 -280.46284) (xy 55.128712 -280.496932)
			(xy 55.158277 -280.536276) (xy 55.181148 -280.579853) (xy 55.196732 -280.626534) (xy 55.204627 -280.675111)
			(xy 55.205122 -280.699718) (xy 56.49393 -280.699718) (xy 56.49789 -280.650664) (xy 56.509667 -280.60288)
			(xy 56.528958 -280.557604) (xy 56.555261 -280.516008) (xy 56.587896 -280.479171) (xy 56.626017 -280.448046)
			(xy 56.668638 -280.423439) (xy 56.714654 -280.405987) (xy 56.762873 -280.396143) (xy 56.812048 -280.394162)
			(xy 56.860903 -280.400094) (xy 56.908174 -280.413786) (xy 56.952636 -280.434884) (xy 56.993139 -280.46284)
			(xy 57.028632 -280.496932) (xy 57.058197 -280.536276) (xy 57.081068 -280.579853) (xy 57.096652 -280.626534)
			(xy 57.104547 -280.675111) (xy 57.105042 -280.699718) (xy 58.394104 -280.699718) (xy 58.398064 -280.650664)
			(xy 58.409841 -280.60288) (xy 58.429132 -280.557604) (xy 58.455435 -280.516008) (xy 58.48807 -280.479171)
			(xy 58.526191 -280.448046) (xy 58.568812 -280.423439) (xy 58.614828 -280.405987) (xy 58.663047 -280.396143)
			(xy 58.712222 -280.394162) (xy 58.761077 -280.400094) (xy 58.808348 -280.413786) (xy 58.85281 -280.434884)
			(xy 58.893313 -280.46284) (xy 58.928806 -280.496932) (xy 58.958371 -280.536276) (xy 58.981242 -280.579853)
			(xy 58.996826 -280.626534) (xy 59.004721 -280.675111) (xy 59.005216 -280.699718) (xy 60.294024 -280.699718)
			(xy 60.297984 -280.650664) (xy 60.309761 -280.60288) (xy 60.329052 -280.557604) (xy 60.355355 -280.516008)
			(xy 60.38799 -280.479171) (xy 60.426111 -280.448046) (xy 60.468732 -280.423439) (xy 60.514748 -280.405987)
			(xy 60.562967 -280.396143) (xy 60.612142 -280.394162) (xy 60.660997 -280.400094) (xy 60.708268 -280.413786)
			(xy 60.75273 -280.434884) (xy 60.793233 -280.46284) (xy 60.828726 -280.496932) (xy 60.858291 -280.536276)
			(xy 60.881162 -280.579853) (xy 60.896746 -280.626534) (xy 60.904641 -280.675111) (xy 60.905136 -280.699718)
			(xy 62.193944 -280.699718) (xy 62.197904 -280.650664) (xy 62.209681 -280.60288) (xy 62.228972 -280.557604)
			(xy 62.255275 -280.516008) (xy 62.28791 -280.479171) (xy 62.326031 -280.448046) (xy 62.368652 -280.423439)
			(xy 62.414668 -280.405987) (xy 62.462887 -280.396143) (xy 62.512062 -280.394162) (xy 62.560917 -280.400094)
			(xy 62.608188 -280.413786) (xy 62.65265 -280.434884) (xy 62.693153 -280.46284) (xy 62.728646 -280.496932)
			(xy 62.758211 -280.536276) (xy 62.781082 -280.579853) (xy 62.796666 -280.626534) (xy 62.804561 -280.675111)
			(xy 62.805056 -280.699718) (xy 64.094118 -280.699718) (xy 64.098078 -280.650664) (xy 64.109855 -280.60288)
			(xy 64.129146 -280.557604) (xy 64.155449 -280.516008) (xy 64.188084 -280.479171) (xy 64.226205 -280.448046)
			(xy 64.268826 -280.423439) (xy 64.314842 -280.405987) (xy 64.363061 -280.396143) (xy 64.412236 -280.394162)
			(xy 64.461091 -280.400094) (xy 64.508362 -280.413786) (xy 64.552824 -280.434884) (xy 64.593327 -280.46284)
			(xy 64.62882 -280.496932) (xy 64.658385 -280.536276) (xy 64.681256 -280.579853) (xy 64.69684 -280.626534)
			(xy 64.704735 -280.675111) (xy 64.70523 -280.699718) (xy 65.994038 -280.699718) (xy 65.997998 -280.650664)
			(xy 66.009775 -280.60288) (xy 66.029066 -280.557604) (xy 66.055369 -280.516008) (xy 66.088004 -280.479171)
			(xy 66.126125 -280.448046) (xy 66.168746 -280.423439) (xy 66.214762 -280.405987) (xy 66.262981 -280.396143)
			(xy 66.312156 -280.394162) (xy 66.361011 -280.400094) (xy 66.408282 -280.413786) (xy 66.452744 -280.434884)
			(xy 66.493247 -280.46284) (xy 66.52874 -280.496932) (xy 66.558305 -280.536276) (xy 66.581176 -280.579853)
			(xy 66.59676 -280.626534) (xy 66.604655 -280.675111) (xy 66.60515 -280.699718) (xy 67.893958 -280.699718)
			(xy 67.897918 -280.650664) (xy 67.909695 -280.60288) (xy 67.928986 -280.557604) (xy 67.955289 -280.516008)
			(xy 67.987924 -280.479171) (xy 68.026045 -280.448046) (xy 68.068666 -280.423439) (xy 68.114682 -280.405987)
			(xy 68.162901 -280.396143) (xy 68.212076 -280.394162) (xy 68.260931 -280.400094) (xy 68.308202 -280.413786)
			(xy 68.352664 -280.434884) (xy 68.393167 -280.46284) (xy 68.42866 -280.496932) (xy 68.458225 -280.536276)
			(xy 68.481096 -280.579853) (xy 68.49668 -280.626534) (xy 68.504575 -280.675111) (xy 68.50507 -280.699718)
			(xy 69.794132 -280.699718) (xy 69.798092 -280.650664) (xy 69.809869 -280.60288) (xy 69.82916 -280.557604)
			(xy 69.855463 -280.516008) (xy 69.888098 -280.479171) (xy 69.926219 -280.448046) (xy 69.96884 -280.423439)
			(xy 70.014856 -280.405987) (xy 70.063075 -280.396143) (xy 70.11225 -280.394162) (xy 70.161105 -280.400094)
			(xy 70.208376 -280.413786) (xy 70.252838 -280.434884) (xy 70.293341 -280.46284) (xy 70.328834 -280.496932)
			(xy 70.358399 -280.536276) (xy 70.38127 -280.579853) (xy 70.396854 -280.626534) (xy 70.404749 -280.675111)
			(xy 70.405244 -280.699718) (xy 71.694052 -280.699718) (xy 71.698012 -280.650664) (xy 71.709789 -280.60288)
			(xy 71.72908 -280.557604) (xy 71.755383 -280.516008) (xy 71.788018 -280.479171) (xy 71.826139 -280.448046)
			(xy 71.86876 -280.423439) (xy 71.914776 -280.405987) (xy 71.962995 -280.396143) (xy 72.01217 -280.394162)
			(xy 72.061025 -280.400094) (xy 72.108296 -280.413786) (xy 72.152758 -280.434884) (xy 72.193261 -280.46284)
			(xy 72.228754 -280.496932) (xy 72.258319 -280.536276) (xy 72.28119 -280.579853) (xy 72.296774 -280.626534)
			(xy 72.304669 -280.675111) (xy 72.305164 -280.699718) (xy 73.593972 -280.699718) (xy 73.597932 -280.650664)
			(xy 73.609709 -280.60288) (xy 73.629 -280.557604) (xy 73.655303 -280.516008) (xy 73.687938 -280.479171)
			(xy 73.726059 -280.448046) (xy 73.76868 -280.423439) (xy 73.814696 -280.405987) (xy 73.862915 -280.396143)
			(xy 73.91209 -280.394162) (xy 73.960945 -280.400094) (xy 74.008216 -280.413786) (xy 74.052678 -280.434884)
			(xy 74.093181 -280.46284) (xy 74.128674 -280.496932) (xy 74.158239 -280.536276) (xy 74.18111 -280.579853)
			(xy 74.196694 -280.626534) (xy 74.204589 -280.675111) (xy 74.205084 -280.699718) (xy 75.494146 -280.699718)
			(xy 75.498106 -280.650664) (xy 75.509883 -280.60288) (xy 75.529174 -280.557604) (xy 75.555477 -280.516008)
			(xy 75.588112 -280.479171) (xy 75.626233 -280.448046) (xy 75.668854 -280.423439) (xy 75.71487 -280.405987)
			(xy 75.763089 -280.396143) (xy 75.812264 -280.394162) (xy 75.861119 -280.400094) (xy 75.90839 -280.413786)
			(xy 75.952852 -280.434884) (xy 75.993355 -280.46284) (xy 76.028848 -280.496932) (xy 76.058413 -280.536276)
			(xy 76.081284 -280.579853) (xy 76.096868 -280.626534) (xy 76.104763 -280.675111) (xy 76.105258 -280.699718)
			(xy 77.394066 -280.699718) (xy 77.398026 -280.650664) (xy 77.409803 -280.60288) (xy 77.429094 -280.557604)
			(xy 77.455397 -280.516008) (xy 77.488032 -280.479171) (xy 77.526153 -280.448046) (xy 77.568774 -280.423439)
			(xy 77.61479 -280.405987) (xy 77.663009 -280.396143) (xy 77.712184 -280.394162) (xy 77.761039 -280.400094)
			(xy 77.80831 -280.413786) (xy 77.852772 -280.434884) (xy 77.893275 -280.46284) (xy 77.928768 -280.496932)
			(xy 77.958333 -280.536276) (xy 77.981204 -280.579853) (xy 77.996788 -280.626534) (xy 78.004683 -280.675111)
			(xy 78.005178 -280.699718) (xy 79.293986 -280.699718) (xy 79.297946 -280.650664) (xy 79.309723 -280.60288)
			(xy 79.329014 -280.557604) (xy 79.355317 -280.516008) (xy 79.387952 -280.479171) (xy 79.426073 -280.448046)
			(xy 79.468694 -280.423439) (xy 79.51471 -280.405987) (xy 79.562929 -280.396143) (xy 79.612104 -280.394162)
			(xy 79.660959 -280.400094) (xy 79.70823 -280.413786) (xy 79.752692 -280.434884) (xy 79.793195 -280.46284)
			(xy 79.828688 -280.496932) (xy 79.858253 -280.536276) (xy 79.881124 -280.579853) (xy 79.896708 -280.626534)
			(xy 79.904603 -280.675111) (xy 79.905098 -280.699718) (xy 161.194254 -280.699718) (xy 161.198214 -280.650664)
			(xy 161.209991 -280.60288) (xy 161.229282 -280.557604) (xy 161.255585 -280.516008) (xy 161.28822 -280.479171)
			(xy 161.326341 -280.448046) (xy 161.368962 -280.423439) (xy 161.414978 -280.405987) (xy 161.463197 -280.396143)
			(xy 161.512372 -280.394162) (xy 161.561227 -280.400094) (xy 161.608498 -280.413786) (xy 161.65296 -280.434884)
			(xy 161.693463 -280.46284) (xy 161.728956 -280.496932) (xy 161.758521 -280.536276) (xy 161.781392 -280.579853)
			(xy 161.796976 -280.626534) (xy 161.804871 -280.675111) (xy 161.805366 -280.699718) (xy 163.094174 -280.699718)
			(xy 163.098134 -280.650664) (xy 163.109911 -280.60288) (xy 163.129202 -280.557604) (xy 163.155505 -280.516008)
			(xy 163.18814 -280.479171) (xy 163.226261 -280.448046) (xy 163.268882 -280.423439) (xy 163.314898 -280.405987)
			(xy 163.363117 -280.396143) (xy 163.412292 -280.394162) (xy 163.461147 -280.400094) (xy 163.508418 -280.413786)
			(xy 163.55288 -280.434884) (xy 163.593383 -280.46284) (xy 163.628876 -280.496932) (xy 163.658441 -280.536276)
			(xy 163.681312 -280.579853) (xy 163.696896 -280.626534) (xy 163.704791 -280.675111) (xy 163.705286 -280.699718)
			(xy 164.994094 -280.699718) (xy 164.998054 -280.650664) (xy 165.009831 -280.60288) (xy 165.029122 -280.557604)
			(xy 165.055425 -280.516008) (xy 165.08806 -280.479171) (xy 165.126181 -280.448046) (xy 165.168802 -280.423439)
			(xy 165.214818 -280.405987) (xy 165.263037 -280.396143) (xy 165.312212 -280.394162) (xy 165.361067 -280.400094)
			(xy 165.408338 -280.413786) (xy 165.4528 -280.434884) (xy 165.493303 -280.46284) (xy 165.528796 -280.496932)
			(xy 165.558361 -280.536276) (xy 165.581232 -280.579853) (xy 165.596816 -280.626534) (xy 165.604711 -280.675111)
			(xy 165.605206 -280.699718) (xy 166.894268 -280.699718) (xy 166.898228 -280.650664) (xy 166.910005 -280.60288)
			(xy 166.929296 -280.557604) (xy 166.955599 -280.516008) (xy 166.988234 -280.479171) (xy 167.026355 -280.448046)
			(xy 167.068976 -280.423439) (xy 167.114992 -280.405987) (xy 167.163211 -280.396143) (xy 167.212386 -280.394162)
			(xy 167.261241 -280.400094) (xy 167.308512 -280.413786) (xy 167.352974 -280.434884) (xy 167.393477 -280.46284)
			(xy 167.42897 -280.496932) (xy 167.458535 -280.536276) (xy 167.481406 -280.579853) (xy 167.49699 -280.626534)
			(xy 167.504885 -280.675111) (xy 167.50538 -280.699718) (xy 168.794188 -280.699718) (xy 168.798148 -280.650664)
			(xy 168.809925 -280.60288) (xy 168.829216 -280.557604) (xy 168.855519 -280.516008) (xy 168.888154 -280.479171)
			(xy 168.926275 -280.448046) (xy 168.968896 -280.423439) (xy 169.014912 -280.405987) (xy 169.063131 -280.396143)
			(xy 169.112306 -280.394162) (xy 169.161161 -280.400094) (xy 169.208432 -280.413786) (xy 169.252894 -280.434884)
			(xy 169.293397 -280.46284) (xy 169.32889 -280.496932) (xy 169.358455 -280.536276) (xy 169.381326 -280.579853)
			(xy 169.39691 -280.626534) (xy 169.404805 -280.675111) (xy 169.4053 -280.699718) (xy 170.694108 -280.699718)
			(xy 170.698068 -280.650664) (xy 170.709845 -280.60288) (xy 170.729136 -280.557604) (xy 170.755439 -280.516008)
			(xy 170.788074 -280.479171) (xy 170.826195 -280.448046) (xy 170.868816 -280.423439) (xy 170.914832 -280.405987)
			(xy 170.963051 -280.396143) (xy 171.012226 -280.394162) (xy 171.061081 -280.400094) (xy 171.108352 -280.413786)
			(xy 171.152814 -280.434884) (xy 171.193317 -280.46284) (xy 171.22881 -280.496932) (xy 171.258375 -280.536276)
			(xy 171.281246 -280.579853) (xy 171.29683 -280.626534) (xy 171.304725 -280.675111) (xy 171.30522 -280.699718)
			(xy 172.594028 -280.699718) (xy 172.597988 -280.650664) (xy 172.609765 -280.60288) (xy 172.629056 -280.557604)
			(xy 172.655359 -280.516008) (xy 172.687994 -280.479171) (xy 172.726115 -280.448046) (xy 172.768736 -280.423439)
			(xy 172.814752 -280.405987) (xy 172.862971 -280.396143) (xy 172.912146 -280.394162) (xy 172.961001 -280.400094)
			(xy 173.008272 -280.413786) (xy 173.052734 -280.434884) (xy 173.093237 -280.46284) (xy 173.12873 -280.496932)
			(xy 173.158295 -280.536276) (xy 173.181166 -280.579853) (xy 173.19675 -280.626534) (xy 173.204645 -280.675111)
			(xy 173.20514 -280.699718) (xy 174.494202 -280.699718) (xy 174.498162 -280.650664) (xy 174.509939 -280.60288)
			(xy 174.52923 -280.557604) (xy 174.555533 -280.516008) (xy 174.588168 -280.479171) (xy 174.626289 -280.448046)
			(xy 174.66891 -280.423439) (xy 174.714926 -280.405987) (xy 174.763145 -280.396143) (xy 174.81232 -280.394162)
			(xy 174.861175 -280.400094) (xy 174.908446 -280.413786) (xy 174.952908 -280.434884) (xy 174.993411 -280.46284)
			(xy 175.028904 -280.496932) (xy 175.058469 -280.536276) (xy 175.08134 -280.579853) (xy 175.096924 -280.626534)
			(xy 175.104819 -280.675111) (xy 175.105314 -280.699718) (xy 176.394122 -280.699718) (xy 176.398082 -280.650664)
			(xy 176.409859 -280.60288) (xy 176.42915 -280.557604) (xy 176.455453 -280.516008) (xy 176.488088 -280.479171)
			(xy 176.526209 -280.448046) (xy 176.56883 -280.423439) (xy 176.614846 -280.405987) (xy 176.663065 -280.396143)
			(xy 176.71224 -280.394162) (xy 176.761095 -280.400094) (xy 176.808366 -280.413786) (xy 176.852828 -280.434884)
			(xy 176.893331 -280.46284) (xy 176.928824 -280.496932) (xy 176.958389 -280.536276) (xy 176.98126 -280.579853)
			(xy 176.996844 -280.626534) (xy 177.004739 -280.675111) (xy 177.005234 -280.699718) (xy 178.294042 -280.699718)
			(xy 178.298002 -280.650664) (xy 178.309779 -280.60288) (xy 178.32907 -280.557604) (xy 178.355373 -280.516008)
			(xy 178.388008 -280.479171) (xy 178.426129 -280.448046) (xy 178.46875 -280.423439) (xy 178.514766 -280.405987)
			(xy 178.562985 -280.396143) (xy 178.61216 -280.394162) (xy 178.661015 -280.400094) (xy 178.708286 -280.413786)
			(xy 178.752748 -280.434884) (xy 178.793251 -280.46284) (xy 178.828744 -280.496932) (xy 178.858309 -280.536276)
			(xy 178.88118 -280.579853) (xy 178.896764 -280.626534) (xy 178.904659 -280.675111) (xy 178.905154 -280.699718)
			(xy 180.194216 -280.699718) (xy 180.198176 -280.650664) (xy 180.209953 -280.60288) (xy 180.229244 -280.557604)
			(xy 180.255547 -280.516008) (xy 180.288182 -280.479171) (xy 180.326303 -280.448046) (xy 180.368924 -280.423439)
			(xy 180.41494 -280.405987) (xy 180.463159 -280.396143) (xy 180.512334 -280.394162) (xy 180.561189 -280.400094)
			(xy 180.60846 -280.413786) (xy 180.652922 -280.434884) (xy 180.693425 -280.46284) (xy 180.728918 -280.496932)
			(xy 180.758483 -280.536276) (xy 180.781354 -280.579853) (xy 180.796938 -280.626534) (xy 180.804833 -280.675111)
			(xy 180.805328 -280.699718) (xy 182.094136 -280.699718) (xy 182.098096 -280.650664) (xy 182.109873 -280.60288)
			(xy 182.129164 -280.557604) (xy 182.155467 -280.516008) (xy 182.188102 -280.479171) (xy 182.226223 -280.448046)
			(xy 182.268844 -280.423439) (xy 182.31486 -280.405987) (xy 182.363079 -280.396143) (xy 182.412254 -280.394162)
			(xy 182.461109 -280.400094) (xy 182.50838 -280.413786) (xy 182.552842 -280.434884) (xy 182.593345 -280.46284)
			(xy 182.628838 -280.496932) (xy 182.658403 -280.536276) (xy 182.681274 -280.579853) (xy 182.696858 -280.626534)
			(xy 182.704753 -280.675111) (xy 182.705248 -280.699718) (xy 183.994056 -280.699718) (xy 183.998016 -280.650664)
			(xy 184.009793 -280.60288) (xy 184.029084 -280.557604) (xy 184.055387 -280.516008) (xy 184.088022 -280.479171)
			(xy 184.126143 -280.448046) (xy 184.168764 -280.423439) (xy 184.21478 -280.405987) (xy 184.262999 -280.396143)
			(xy 184.312174 -280.394162) (xy 184.361029 -280.400094) (xy 184.4083 -280.413786) (xy 184.452762 -280.434884)
			(xy 184.493265 -280.46284) (xy 184.528758 -280.496932) (xy 184.558323 -280.536276) (xy 184.581194 -280.579853)
			(xy 184.596778 -280.626534) (xy 184.604673 -280.675111) (xy 184.605168 -280.699718) (xy 185.89423 -280.699718)
			(xy 185.89819 -280.650664) (xy 185.909967 -280.60288) (xy 185.929258 -280.557604) (xy 185.955561 -280.516008)
			(xy 185.988196 -280.479171) (xy 186.026317 -280.448046) (xy 186.068938 -280.423439) (xy 186.114954 -280.405987)
			(xy 186.163173 -280.396143) (xy 186.212348 -280.394162) (xy 186.261203 -280.400094) (xy 186.308474 -280.413786)
			(xy 186.352936 -280.434884) (xy 186.393439 -280.46284) (xy 186.428932 -280.496932) (xy 186.458497 -280.536276)
			(xy 186.481368 -280.579853) (xy 186.496952 -280.626534) (xy 186.504847 -280.675111) (xy 186.505342 -280.699718)
			(xy 187.79415 -280.699718) (xy 187.79811 -280.650664) (xy 187.809887 -280.60288) (xy 187.829178 -280.557604)
			(xy 187.855481 -280.516008) (xy 187.888116 -280.479171) (xy 187.926237 -280.448046) (xy 187.968858 -280.423439)
			(xy 188.014874 -280.405987) (xy 188.063093 -280.396143) (xy 188.112268 -280.394162) (xy 188.161123 -280.400094)
			(xy 188.208394 -280.413786) (xy 188.252856 -280.434884) (xy 188.293359 -280.46284) (xy 188.328852 -280.496932)
			(xy 188.358417 -280.536276) (xy 188.381288 -280.579853) (xy 188.396872 -280.626534) (xy 188.404767 -280.675111)
			(xy 188.405262 -280.699718) (xy 189.69407 -280.699718) (xy 189.69803 -280.650664) (xy 189.709807 -280.60288)
			(xy 189.729098 -280.557604) (xy 189.755401 -280.516008) (xy 189.788036 -280.479171) (xy 189.826157 -280.448046)
			(xy 189.868778 -280.423439) (xy 189.914794 -280.405987) (xy 189.963013 -280.396143) (xy 190.012188 -280.394162)
			(xy 190.061043 -280.400094) (xy 190.108314 -280.413786) (xy 190.152776 -280.434884) (xy 190.193279 -280.46284)
			(xy 190.228772 -280.496932) (xy 190.258337 -280.536276) (xy 190.281208 -280.579853) (xy 190.296792 -280.626534)
			(xy 190.304687 -280.675111) (xy 190.305182 -280.699718) (xy 191.594244 -280.699718) (xy 191.598204 -280.650664)
			(xy 191.609981 -280.60288) (xy 191.629272 -280.557604) (xy 191.655575 -280.516008) (xy 191.68821 -280.479171)
			(xy 191.726331 -280.448046) (xy 191.768952 -280.423439) (xy 191.814968 -280.405987) (xy 191.863187 -280.396143)
			(xy 191.912362 -280.394162) (xy 191.961217 -280.400094) (xy 192.008488 -280.413786) (xy 192.05295 -280.434884)
			(xy 192.093453 -280.46284) (xy 192.128946 -280.496932) (xy 192.158511 -280.536276) (xy 192.181382 -280.579853)
			(xy 192.196966 -280.626534) (xy 192.204861 -280.675111) (xy 192.205356 -280.699718) (xy 193.494164 -280.699718)
			(xy 193.498124 -280.650664) (xy 193.509901 -280.60288) (xy 193.529192 -280.557604) (xy 193.555495 -280.516008)
			(xy 193.58813 -280.479171) (xy 193.626251 -280.448046) (xy 193.668872 -280.423439) (xy 193.714888 -280.405987)
			(xy 193.763107 -280.396143) (xy 193.812282 -280.394162) (xy 193.861137 -280.400094) (xy 193.908408 -280.413786)
			(xy 193.95287 -280.434884) (xy 193.993373 -280.46284) (xy 194.028866 -280.496932) (xy 194.058431 -280.536276)
			(xy 194.081302 -280.579853) (xy 194.096886 -280.626534) (xy 194.104781 -280.675111) (xy 194.105276 -280.699718)
			(xy 195.394084 -280.699718) (xy 195.398044 -280.650664) (xy 195.409821 -280.60288) (xy 195.429112 -280.557604)
			(xy 195.455415 -280.516008) (xy 195.48805 -280.479171) (xy 195.526171 -280.448046) (xy 195.568792 -280.423439)
			(xy 195.614808 -280.405987) (xy 195.663027 -280.396143) (xy 195.712202 -280.394162) (xy 195.761057 -280.400094)
			(xy 195.808328 -280.413786) (xy 195.85279 -280.434884) (xy 195.893293 -280.46284) (xy 195.928786 -280.496932)
			(xy 195.958351 -280.536276) (xy 195.981222 -280.579853) (xy 195.996806 -280.626534) (xy 196.004701 -280.675111)
			(xy 196.005191 -280.699464) (xy 277.294098 -280.699464) (xy 277.298058 -280.65041) (xy 277.309835 -280.602626)
			(xy 277.329126 -280.55735) (xy 277.355429 -280.515754) (xy 277.388064 -280.478917) (xy 277.426185 -280.447792)
			(xy 277.468806 -280.423185) (xy 277.514822 -280.405733) (xy 277.563041 -280.395889) (xy 277.612216 -280.393908)
			(xy 277.661071 -280.39984) (xy 277.708342 -280.413532) (xy 277.752804 -280.43463) (xy 277.793307 -280.462586)
			(xy 277.8288 -280.496678) (xy 277.858365 -280.536022) (xy 277.881236 -280.579599) (xy 277.89682 -280.62628)
			(xy 277.904715 -280.674857) (xy 277.90521 -280.699464) (xy 279.194018 -280.699464) (xy 279.197978 -280.65041)
			(xy 279.209755 -280.602626) (xy 279.229046 -280.55735) (xy 279.255349 -280.515754) (xy 279.287984 -280.478917)
			(xy 279.326105 -280.447792) (xy 279.368726 -280.423185) (xy 279.414742 -280.405733) (xy 279.462961 -280.395889)
			(xy 279.512136 -280.393908) (xy 279.560991 -280.39984) (xy 279.608262 -280.413532) (xy 279.652724 -280.43463)
			(xy 279.693227 -280.462586) (xy 279.72872 -280.496678) (xy 279.758285 -280.536022) (xy 279.781156 -280.579599)
			(xy 279.79674 -280.62628) (xy 279.804635 -280.674857) (xy 279.80513 -280.699464) (xy 281.093938 -280.699464)
			(xy 281.097898 -280.65041) (xy 281.109675 -280.602626) (xy 281.128966 -280.55735) (xy 281.155269 -280.515754)
			(xy 281.187904 -280.478917) (xy 281.226025 -280.447792) (xy 281.268646 -280.423185) (xy 281.314662 -280.405733)
			(xy 281.362881 -280.395889) (xy 281.412056 -280.393908) (xy 281.460911 -280.39984) (xy 281.508182 -280.413532)
			(xy 281.552644 -280.43463) (xy 281.593147 -280.462586) (xy 281.62864 -280.496678) (xy 281.658205 -280.536022)
			(xy 281.681076 -280.579599) (xy 281.69666 -280.62628) (xy 281.704555 -280.674857) (xy 281.70505 -280.699464)
			(xy 282.994112 -280.699464) (xy 282.998072 -280.65041) (xy 283.009849 -280.602626) (xy 283.02914 -280.55735)
			(xy 283.055443 -280.515754) (xy 283.088078 -280.478917) (xy 283.126199 -280.447792) (xy 283.16882 -280.423185)
			(xy 283.214836 -280.405733) (xy 283.263055 -280.395889) (xy 283.31223 -280.393908) (xy 283.361085 -280.39984)
			(xy 283.408356 -280.413532) (xy 283.452818 -280.43463) (xy 283.493321 -280.462586) (xy 283.528814 -280.496678)
			(xy 283.558379 -280.536022) (xy 283.58125 -280.579599) (xy 283.596834 -280.62628) (xy 283.604729 -280.674857)
			(xy 283.605224 -280.699464) (xy 284.894032 -280.699464) (xy 284.897992 -280.65041) (xy 284.909769 -280.602626)
			(xy 284.92906 -280.55735) (xy 284.955363 -280.515754) (xy 284.987998 -280.478917) (xy 285.026119 -280.447792)
			(xy 285.06874 -280.423185) (xy 285.114756 -280.405733) (xy 285.162975 -280.395889) (xy 285.21215 -280.393908)
			(xy 285.261005 -280.39984) (xy 285.308276 -280.413532) (xy 285.352738 -280.43463) (xy 285.393241 -280.462586)
			(xy 285.428734 -280.496678) (xy 285.458299 -280.536022) (xy 285.48117 -280.579599) (xy 285.496754 -280.62628)
			(xy 285.504649 -280.674857) (xy 285.505144 -280.699464) (xy 286.793952 -280.699464) (xy 286.797912 -280.65041)
			(xy 286.809689 -280.602626) (xy 286.82898 -280.55735) (xy 286.855283 -280.515754) (xy 286.887918 -280.478917)
			(xy 286.926039 -280.447792) (xy 286.96866 -280.423185) (xy 287.014676 -280.405733) (xy 287.062895 -280.395889)
			(xy 287.11207 -280.393908) (xy 287.160925 -280.39984) (xy 287.208196 -280.413532) (xy 287.252658 -280.43463)
			(xy 287.293161 -280.462586) (xy 287.328654 -280.496678) (xy 287.358219 -280.536022) (xy 287.38109 -280.579599)
			(xy 287.396674 -280.62628) (xy 287.404569 -280.674857) (xy 287.405064 -280.699464) (xy 288.693872 -280.699464)
			(xy 288.697832 -280.65041) (xy 288.709609 -280.602626) (xy 288.7289 -280.55735) (xy 288.755203 -280.515754)
			(xy 288.787838 -280.478917) (xy 288.825959 -280.447792) (xy 288.86858 -280.423185) (xy 288.914596 -280.405733)
			(xy 288.962815 -280.395889) (xy 289.01199 -280.393908) (xy 289.060845 -280.39984) (xy 289.108116 -280.413532)
			(xy 289.152578 -280.43463) (xy 289.193081 -280.462586) (xy 289.228574 -280.496678) (xy 289.258139 -280.536022)
			(xy 289.28101 -280.579599) (xy 289.296594 -280.62628) (xy 289.304489 -280.674857) (xy 289.304984 -280.699464)
			(xy 290.594046 -280.699464) (xy 290.598006 -280.65041) (xy 290.609783 -280.602626) (xy 290.629074 -280.55735)
			(xy 290.655377 -280.515754) (xy 290.688012 -280.478917) (xy 290.726133 -280.447792) (xy 290.768754 -280.423185)
			(xy 290.81477 -280.405733) (xy 290.862989 -280.395889) (xy 290.912164 -280.393908) (xy 290.961019 -280.39984)
			(xy 291.00829 -280.413532) (xy 291.052752 -280.43463) (xy 291.093255 -280.462586) (xy 291.128748 -280.496678)
			(xy 291.158313 -280.536022) (xy 291.181184 -280.579599) (xy 291.196768 -280.62628) (xy 291.204663 -280.674857)
			(xy 291.205158 -280.699464) (xy 292.493966 -280.699464) (xy 292.497926 -280.65041) (xy 292.509703 -280.602626)
			(xy 292.528994 -280.55735) (xy 292.555297 -280.515754) (xy 292.587932 -280.478917) (xy 292.626053 -280.447792)
			(xy 292.668674 -280.423185) (xy 292.71469 -280.405733) (xy 292.762909 -280.395889) (xy 292.812084 -280.393908)
			(xy 292.860939 -280.39984) (xy 292.90821 -280.413532) (xy 292.952672 -280.43463) (xy 292.993175 -280.462586)
			(xy 293.028668 -280.496678) (xy 293.058233 -280.536022) (xy 293.081104 -280.579599) (xy 293.096688 -280.62628)
			(xy 293.104583 -280.674857) (xy 293.105078 -280.699464) (xy 294.393886 -280.699464) (xy 294.397846 -280.65041)
			(xy 294.409623 -280.602626) (xy 294.428914 -280.55735) (xy 294.455217 -280.515754) (xy 294.487852 -280.478917)
			(xy 294.525973 -280.447792) (xy 294.568594 -280.423185) (xy 294.61461 -280.405733) (xy 294.662829 -280.395889)
			(xy 294.712004 -280.393908) (xy 294.760859 -280.39984) (xy 294.80813 -280.413532) (xy 294.852592 -280.43463)
			(xy 294.893095 -280.462586) (xy 294.928588 -280.496678) (xy 294.958153 -280.536022) (xy 294.981024 -280.579599)
			(xy 294.996608 -280.62628) (xy 295.004503 -280.674857) (xy 295.004998 -280.699464) (xy 296.29406 -280.699464)
			(xy 296.29802 -280.65041) (xy 296.309797 -280.602626) (xy 296.329088 -280.55735) (xy 296.355391 -280.515754)
			(xy 296.388026 -280.478917) (xy 296.426147 -280.447792) (xy 296.468768 -280.423185) (xy 296.514784 -280.405733)
			(xy 296.563003 -280.395889) (xy 296.612178 -280.393908) (xy 296.661033 -280.39984) (xy 296.708304 -280.413532)
			(xy 296.752766 -280.43463) (xy 296.793269 -280.462586) (xy 296.828762 -280.496678) (xy 296.858327 -280.536022)
			(xy 296.881198 -280.579599) (xy 296.896782 -280.62628) (xy 296.904677 -280.674857) (xy 296.905172 -280.699464)
			(xy 298.19398 -280.699464) (xy 298.19794 -280.65041) (xy 298.209717 -280.602626) (xy 298.229008 -280.55735)
			(xy 298.255311 -280.515754) (xy 298.287946 -280.478917) (xy 298.326067 -280.447792) (xy 298.368688 -280.423185)
			(xy 298.414704 -280.405733) (xy 298.462923 -280.395889) (xy 298.512098 -280.393908) (xy 298.560953 -280.39984)
			(xy 298.608224 -280.413532) (xy 298.652686 -280.43463) (xy 298.693189 -280.462586) (xy 298.728682 -280.496678)
			(xy 298.758247 -280.536022) (xy 298.781118 -280.579599) (xy 298.796702 -280.62628) (xy 298.804597 -280.674857)
			(xy 298.805092 -280.699464) (xy 300.0939 -280.699464) (xy 300.09786 -280.65041) (xy 300.109637 -280.602626)
			(xy 300.128928 -280.55735) (xy 300.155231 -280.515754) (xy 300.187866 -280.478917) (xy 300.225987 -280.447792)
			(xy 300.268608 -280.423185) (xy 300.314624 -280.405733) (xy 300.362843 -280.395889) (xy 300.412018 -280.393908)
			(xy 300.460873 -280.39984) (xy 300.508144 -280.413532) (xy 300.552606 -280.43463) (xy 300.593109 -280.462586)
			(xy 300.628602 -280.496678) (xy 300.658167 -280.536022) (xy 300.681038 -280.579599) (xy 300.696622 -280.62628)
			(xy 300.704517 -280.674857) (xy 300.705012 -280.699464) (xy 301.994074 -280.699464) (xy 301.998034 -280.65041)
			(xy 302.009811 -280.602626) (xy 302.029102 -280.55735) (xy 302.055405 -280.515754) (xy 302.08804 -280.478917)
			(xy 302.126161 -280.447792) (xy 302.168782 -280.423185) (xy 302.214798 -280.405733) (xy 302.263017 -280.395889)
			(xy 302.312192 -280.393908) (xy 302.361047 -280.39984) (xy 302.408318 -280.413532) (xy 302.45278 -280.43463)
			(xy 302.493283 -280.462586) (xy 302.528776 -280.496678) (xy 302.558341 -280.536022) (xy 302.581212 -280.579599)
			(xy 302.596796 -280.62628) (xy 302.604691 -280.674857) (xy 302.605186 -280.699464) (xy 303.893994 -280.699464)
			(xy 303.897954 -280.65041) (xy 303.909731 -280.602626) (xy 303.929022 -280.55735) (xy 303.955325 -280.515754)
			(xy 303.98796 -280.478917) (xy 304.026081 -280.447792) (xy 304.068702 -280.423185) (xy 304.114718 -280.405733)
			(xy 304.162937 -280.395889) (xy 304.212112 -280.393908) (xy 304.260967 -280.39984) (xy 304.308238 -280.413532)
			(xy 304.3527 -280.43463) (xy 304.393203 -280.462586) (xy 304.428696 -280.496678) (xy 304.458261 -280.536022)
			(xy 304.481132 -280.579599) (xy 304.496716 -280.62628) (xy 304.504611 -280.674857) (xy 304.505106 -280.699464)
			(xy 305.793914 -280.699464) (xy 305.797874 -280.65041) (xy 305.809651 -280.602626) (xy 305.828942 -280.55735)
			(xy 305.855245 -280.515754) (xy 305.88788 -280.478917) (xy 305.926001 -280.447792) (xy 305.968622 -280.423185)
			(xy 306.014638 -280.405733) (xy 306.062857 -280.395889) (xy 306.112032 -280.393908) (xy 306.160887 -280.39984)
			(xy 306.208158 -280.413532) (xy 306.25262 -280.43463) (xy 306.293123 -280.462586) (xy 306.328616 -280.496678)
			(xy 306.358181 -280.536022) (xy 306.381052 -280.579599) (xy 306.396636 -280.62628) (xy 306.404531 -280.674857)
			(xy 306.405026 -280.699464) (xy 307.694088 -280.699464) (xy 307.698048 -280.65041) (xy 307.709825 -280.602626)
			(xy 307.729116 -280.55735) (xy 307.755419 -280.515754) (xy 307.788054 -280.478917) (xy 307.826175 -280.447792)
			(xy 307.868796 -280.423185) (xy 307.914812 -280.405733) (xy 307.963031 -280.395889) (xy 308.012206 -280.393908)
			(xy 308.061061 -280.39984) (xy 308.108332 -280.413532) (xy 308.152794 -280.43463) (xy 308.193297 -280.462586)
			(xy 308.22879 -280.496678) (xy 308.258355 -280.536022) (xy 308.281226 -280.579599) (xy 308.29681 -280.62628)
			(xy 308.304705 -280.674857) (xy 308.3052 -280.699464) (xy 309.594008 -280.699464) (xy 309.597968 -280.65041)
			(xy 309.609745 -280.602626) (xy 309.629036 -280.55735) (xy 309.655339 -280.515754) (xy 309.687974 -280.478917)
			(xy 309.726095 -280.447792) (xy 309.768716 -280.423185) (xy 309.814732 -280.405733) (xy 309.862951 -280.395889)
			(xy 309.912126 -280.393908) (xy 309.960981 -280.39984) (xy 310.008252 -280.413532) (xy 310.052714 -280.43463)
			(xy 310.093217 -280.462586) (xy 310.12871 -280.496678) (xy 310.158275 -280.536022) (xy 310.181146 -280.579599)
			(xy 310.19673 -280.62628) (xy 310.204625 -280.674857) (xy 310.20512 -280.699464) (xy 310.205115 -280.699718)
			(xy 311.493928 -280.699718) (xy 311.497888 -280.650664) (xy 311.509665 -280.60288) (xy 311.528956 -280.557604)
			(xy 311.555259 -280.516008) (xy 311.587894 -280.479171) (xy 311.626015 -280.448046) (xy 311.668636 -280.423439)
			(xy 311.714652 -280.405987) (xy 311.762871 -280.396143) (xy 311.812046 -280.394162) (xy 311.860901 -280.400094)
			(xy 311.908172 -280.413786) (xy 311.952634 -280.434884) (xy 311.993137 -280.46284) (xy 312.02863 -280.496932)
			(xy 312.058195 -280.536276) (xy 312.081066 -280.579853) (xy 312.09665 -280.626534) (xy 312.104545 -280.675111)
			(xy 312.105035 -280.699464) (xy 393.394196 -280.699464) (xy 393.398156 -280.65041) (xy 393.409933 -280.602626)
			(xy 393.429224 -280.55735) (xy 393.455527 -280.515754) (xy 393.488162 -280.478917) (xy 393.526283 -280.447792)
			(xy 393.568904 -280.423185) (xy 393.61492 -280.405733) (xy 393.663139 -280.395889) (xy 393.712314 -280.393908)
			(xy 393.761169 -280.39984) (xy 393.80844 -280.413532) (xy 393.852902 -280.43463) (xy 393.893405 -280.462586)
			(xy 393.928898 -280.496678) (xy 393.958463 -280.536022) (xy 393.981334 -280.579599) (xy 393.996918 -280.62628)
			(xy 394.004813 -280.674857) (xy 394.005308 -280.699464) (xy 395.294116 -280.699464) (xy 395.298076 -280.65041)
			(xy 395.309853 -280.602626) (xy 395.329144 -280.55735) (xy 395.355447 -280.515754) (xy 395.388082 -280.478917)
			(xy 395.426203 -280.447792) (xy 395.468824 -280.423185) (xy 395.51484 -280.405733) (xy 395.563059 -280.395889)
			(xy 395.612234 -280.393908) (xy 395.661089 -280.39984) (xy 395.70836 -280.413532) (xy 395.752822 -280.43463)
			(xy 395.793325 -280.462586) (xy 395.828818 -280.496678) (xy 395.858383 -280.536022) (xy 395.881254 -280.579599)
			(xy 395.896838 -280.62628) (xy 395.904733 -280.674857) (xy 395.905228 -280.699464) (xy 397.194036 -280.699464)
			(xy 397.197996 -280.65041) (xy 397.209773 -280.602626) (xy 397.229064 -280.55735) (xy 397.255367 -280.515754)
			(xy 397.288002 -280.478917) (xy 397.326123 -280.447792) (xy 397.368744 -280.423185) (xy 397.41476 -280.405733)
			(xy 397.462979 -280.395889) (xy 397.512154 -280.393908) (xy 397.561009 -280.39984) (xy 397.60828 -280.413532)
			(xy 397.652742 -280.43463) (xy 397.693245 -280.462586) (xy 397.728738 -280.496678) (xy 397.758303 -280.536022)
			(xy 397.781174 -280.579599) (xy 397.796758 -280.62628) (xy 397.804653 -280.674857) (xy 397.805148 -280.699464)
			(xy 399.09421 -280.699464) (xy 399.09817 -280.65041) (xy 399.109947 -280.602626) (xy 399.129238 -280.55735)
			(xy 399.155541 -280.515754) (xy 399.188176 -280.478917) (xy 399.226297 -280.447792) (xy 399.268918 -280.423185)
			(xy 399.314934 -280.405733) (xy 399.363153 -280.395889) (xy 399.412328 -280.393908) (xy 399.461183 -280.39984)
			(xy 399.508454 -280.413532) (xy 399.552916 -280.43463) (xy 399.593419 -280.462586) (xy 399.628912 -280.496678)
			(xy 399.658477 -280.536022) (xy 399.681348 -280.579599) (xy 399.696932 -280.62628) (xy 399.704827 -280.674857)
			(xy 399.705322 -280.699464) (xy 400.99413 -280.699464) (xy 400.99809 -280.65041) (xy 401.009867 -280.602626)
			(xy 401.029158 -280.55735) (xy 401.055461 -280.515754) (xy 401.088096 -280.478917) (xy 401.126217 -280.447792)
			(xy 401.168838 -280.423185) (xy 401.214854 -280.405733) (xy 401.263073 -280.395889) (xy 401.312248 -280.393908)
			(xy 401.361103 -280.39984) (xy 401.408374 -280.413532) (xy 401.452836 -280.43463) (xy 401.493339 -280.462586)
			(xy 401.528832 -280.496678) (xy 401.558397 -280.536022) (xy 401.581268 -280.579599) (xy 401.596852 -280.62628)
			(xy 401.604747 -280.674857) (xy 401.605242 -280.699464) (xy 402.89405 -280.699464) (xy 402.89801 -280.65041)
			(xy 402.909787 -280.602626) (xy 402.929078 -280.55735) (xy 402.955381 -280.515754) (xy 402.988016 -280.478917)
			(xy 403.026137 -280.447792) (xy 403.068758 -280.423185) (xy 403.114774 -280.405733) (xy 403.162993 -280.395889)
			(xy 403.212168 -280.393908) (xy 403.261023 -280.39984) (xy 403.308294 -280.413532) (xy 403.352756 -280.43463)
			(xy 403.393259 -280.462586) (xy 403.428752 -280.496678) (xy 403.458317 -280.536022) (xy 403.481188 -280.579599)
			(xy 403.496772 -280.62628) (xy 403.504667 -280.674857) (xy 403.505162 -280.699464) (xy 404.79397 -280.699464)
			(xy 404.79793 -280.65041) (xy 404.809707 -280.602626) (xy 404.828998 -280.55735) (xy 404.855301 -280.515754)
			(xy 404.887936 -280.478917) (xy 404.926057 -280.447792) (xy 404.968678 -280.423185) (xy 405.014694 -280.405733)
			(xy 405.062913 -280.395889) (xy 405.112088 -280.393908) (xy 405.160943 -280.39984) (xy 405.208214 -280.413532)
			(xy 405.252676 -280.43463) (xy 405.293179 -280.462586) (xy 405.328672 -280.496678) (xy 405.358237 -280.536022)
			(xy 405.381108 -280.579599) (xy 405.396692 -280.62628) (xy 405.404587 -280.674857) (xy 405.405082 -280.699464)
			(xy 406.694144 -280.699464) (xy 406.698104 -280.65041) (xy 406.709881 -280.602626) (xy 406.729172 -280.55735)
			(xy 406.755475 -280.515754) (xy 406.78811 -280.478917) (xy 406.826231 -280.447792) (xy 406.868852 -280.423185)
			(xy 406.914868 -280.405733) (xy 406.963087 -280.395889) (xy 407.012262 -280.393908) (xy 407.061117 -280.39984)
			(xy 407.108388 -280.413532) (xy 407.15285 -280.43463) (xy 407.193353 -280.462586) (xy 407.228846 -280.496678)
			(xy 407.258411 -280.536022) (xy 407.281282 -280.579599) (xy 407.296866 -280.62628) (xy 407.304761 -280.674857)
			(xy 407.305256 -280.699464) (xy 408.594064 -280.699464) (xy 408.598024 -280.65041) (xy 408.609801 -280.602626)
			(xy 408.629092 -280.55735) (xy 408.655395 -280.515754) (xy 408.68803 -280.478917) (xy 408.726151 -280.447792)
			(xy 408.768772 -280.423185) (xy 408.814788 -280.405733) (xy 408.863007 -280.395889) (xy 408.912182 -280.393908)
			(xy 408.961037 -280.39984) (xy 409.008308 -280.413532) (xy 409.05277 -280.43463) (xy 409.093273 -280.462586)
			(xy 409.128766 -280.496678) (xy 409.158331 -280.536022) (xy 409.181202 -280.579599) (xy 409.196786 -280.62628)
			(xy 409.204681 -280.674857) (xy 409.205176 -280.699464) (xy 410.493984 -280.699464) (xy 410.497944 -280.65041)
			(xy 410.509721 -280.602626) (xy 410.529012 -280.55735) (xy 410.555315 -280.515754) (xy 410.58795 -280.478917)
			(xy 410.626071 -280.447792) (xy 410.668692 -280.423185) (xy 410.714708 -280.405733) (xy 410.762927 -280.395889)
			(xy 410.812102 -280.393908) (xy 410.860957 -280.39984) (xy 410.908228 -280.413532) (xy 410.95269 -280.43463)
			(xy 410.993193 -280.462586) (xy 411.028686 -280.496678) (xy 411.058251 -280.536022) (xy 411.081122 -280.579599)
			(xy 411.096706 -280.62628) (xy 411.104601 -280.674857) (xy 411.105096 -280.699464) (xy 412.394158 -280.699464)
			(xy 412.398118 -280.65041) (xy 412.409895 -280.602626) (xy 412.429186 -280.55735) (xy 412.455489 -280.515754)
			(xy 412.488124 -280.478917) (xy 412.526245 -280.447792) (xy 412.568866 -280.423185) (xy 412.614882 -280.405733)
			(xy 412.663101 -280.395889) (xy 412.712276 -280.393908) (xy 412.761131 -280.39984) (xy 412.808402 -280.413532)
			(xy 412.852864 -280.43463) (xy 412.893367 -280.462586) (xy 412.92886 -280.496678) (xy 412.958425 -280.536022)
			(xy 412.981296 -280.579599) (xy 412.99688 -280.62628) (xy 413.004775 -280.674857) (xy 413.00527 -280.699464)
			(xy 414.294078 -280.699464) (xy 414.298038 -280.65041) (xy 414.309815 -280.602626) (xy 414.329106 -280.55735)
			(xy 414.355409 -280.515754) (xy 414.388044 -280.478917) (xy 414.426165 -280.447792) (xy 414.468786 -280.423185)
			(xy 414.514802 -280.405733) (xy 414.563021 -280.395889) (xy 414.612196 -280.393908) (xy 414.661051 -280.39984)
			(xy 414.708322 -280.413532) (xy 414.752784 -280.43463) (xy 414.793287 -280.462586) (xy 414.82878 -280.496678)
			(xy 414.858345 -280.536022) (xy 414.881216 -280.579599) (xy 414.8968 -280.62628) (xy 414.904695 -280.674857)
			(xy 414.90519 -280.699464) (xy 416.193998 -280.699464) (xy 416.197958 -280.65041) (xy 416.209735 -280.602626)
			(xy 416.229026 -280.55735) (xy 416.255329 -280.515754) (xy 416.287964 -280.478917) (xy 416.326085 -280.447792)
			(xy 416.368706 -280.423185) (xy 416.414722 -280.405733) (xy 416.462941 -280.395889) (xy 416.512116 -280.393908)
			(xy 416.560971 -280.39984) (xy 416.608242 -280.413532) (xy 416.652704 -280.43463) (xy 416.693207 -280.462586)
			(xy 416.7287 -280.496678) (xy 416.758265 -280.536022) (xy 416.781136 -280.579599) (xy 416.79672 -280.62628)
			(xy 416.804615 -280.674857) (xy 416.80511 -280.699464) (xy 418.094172 -280.699464) (xy 418.098132 -280.65041)
			(xy 418.109909 -280.602626) (xy 418.1292 -280.55735) (xy 418.155503 -280.515754) (xy 418.188138 -280.478917)
			(xy 418.226259 -280.447792) (xy 418.26888 -280.423185) (xy 418.314896 -280.405733) (xy 418.363115 -280.395889)
			(xy 418.41229 -280.393908) (xy 418.461145 -280.39984) (xy 418.508416 -280.413532) (xy 418.552878 -280.43463)
			(xy 418.593381 -280.462586) (xy 418.628874 -280.496678) (xy 418.658439 -280.536022) (xy 418.68131 -280.579599)
			(xy 418.696894 -280.62628) (xy 418.704789 -280.674857) (xy 418.705284 -280.699464) (xy 419.994092 -280.699464)
			(xy 419.998052 -280.65041) (xy 420.009829 -280.602626) (xy 420.02912 -280.55735) (xy 420.055423 -280.515754)
			(xy 420.088058 -280.478917) (xy 420.126179 -280.447792) (xy 420.1688 -280.423185) (xy 420.214816 -280.405733)
			(xy 420.263035 -280.395889) (xy 420.31221 -280.393908) (xy 420.361065 -280.39984) (xy 420.408336 -280.413532)
			(xy 420.452798 -280.43463) (xy 420.493301 -280.462586) (xy 420.528794 -280.496678) (xy 420.558359 -280.536022)
			(xy 420.58123 -280.579599) (xy 420.596814 -280.62628) (xy 420.604709 -280.674857) (xy 420.605204 -280.699464)
			(xy 421.894012 -280.699464) (xy 421.897972 -280.65041) (xy 421.909749 -280.602626) (xy 421.92904 -280.55735)
			(xy 421.955343 -280.515754) (xy 421.987978 -280.478917) (xy 422.026099 -280.447792) (xy 422.06872 -280.423185)
			(xy 422.114736 -280.405733) (xy 422.162955 -280.395889) (xy 422.21213 -280.393908) (xy 422.260985 -280.39984)
			(xy 422.308256 -280.413532) (xy 422.352718 -280.43463) (xy 422.393221 -280.462586) (xy 422.428714 -280.496678)
			(xy 422.458279 -280.536022) (xy 422.48115 -280.579599) (xy 422.496734 -280.62628) (xy 422.504629 -280.674857)
			(xy 422.505124 -280.699464) (xy 423.794186 -280.699464) (xy 423.798146 -280.65041) (xy 423.809923 -280.602626)
			(xy 423.829214 -280.55735) (xy 423.855517 -280.515754) (xy 423.888152 -280.478917) (xy 423.926273 -280.447792)
			(xy 423.968894 -280.423185) (xy 424.01491 -280.405733) (xy 424.063129 -280.395889) (xy 424.112304 -280.393908)
			(xy 424.161159 -280.39984) (xy 424.20843 -280.413532) (xy 424.252892 -280.43463) (xy 424.293395 -280.462586)
			(xy 424.328888 -280.496678) (xy 424.358453 -280.536022) (xy 424.381324 -280.579599) (xy 424.396908 -280.62628)
			(xy 424.404803 -280.674857) (xy 424.405298 -280.699464) (xy 425.694106 -280.699464) (xy 425.698066 -280.65041)
			(xy 425.709843 -280.602626) (xy 425.729134 -280.55735) (xy 425.755437 -280.515754) (xy 425.788072 -280.478917)
			(xy 425.826193 -280.447792) (xy 425.868814 -280.423185) (xy 425.91483 -280.405733) (xy 425.963049 -280.395889)
			(xy 426.012224 -280.393908) (xy 426.061079 -280.39984) (xy 426.10835 -280.413532) (xy 426.152812 -280.43463)
			(xy 426.193315 -280.462586) (xy 426.228808 -280.496678) (xy 426.258373 -280.536022) (xy 426.281244 -280.579599)
			(xy 426.296828 -280.62628) (xy 426.304723 -280.674857) (xy 426.305218 -280.699464) (xy 426.305213 -280.699718)
			(xy 427.594026 -280.699718) (xy 427.597986 -280.650664) (xy 427.609763 -280.60288) (xy 427.629054 -280.557604)
			(xy 427.655357 -280.516008) (xy 427.687992 -280.479171) (xy 427.726113 -280.448046) (xy 427.768734 -280.423439)
			(xy 427.81475 -280.405987) (xy 427.862969 -280.396143) (xy 427.912144 -280.394162) (xy 427.960999 -280.400094)
			(xy 428.00827 -280.413786) (xy 428.052732 -280.434884) (xy 428.093235 -280.46284) (xy 428.128728 -280.496932)
			(xy 428.158293 -280.536276) (xy 428.181164 -280.579853) (xy 428.196748 -280.626534) (xy 428.204643 -280.675111)
			(xy 428.205138 -280.699718) (xy 428.204643 -280.724325) (xy 428.196748 -280.772902) (xy 428.181164 -280.819583)
			(xy 428.158293 -280.86316) (xy 428.128728 -280.902504) (xy 428.093235 -280.936596) (xy 428.052732 -280.964552)
			(xy 428.00827 -280.98565) (xy 427.960999 -280.999342) (xy 427.912144 -281.005274) (xy 427.862969 -281.003293)
			(xy 427.81475 -280.993449) (xy 427.768734 -280.975997) (xy 427.726113 -280.95139) (xy 427.687992 -280.920265)
			(xy 427.655357 -280.883428) (xy 427.629054 -280.841832) (xy 427.609763 -280.796556) (xy 427.597986 -280.748772)
			(xy 427.594026 -280.699718) (xy 426.305213 -280.699718) (xy 426.304723 -280.724071) (xy 426.296828 -280.772648)
			(xy 426.281244 -280.819329) (xy 426.258373 -280.862906) (xy 426.228808 -280.90225) (xy 426.193315 -280.936342)
			(xy 426.152812 -280.964298) (xy 426.10835 -280.985396) (xy 426.061079 -280.999088) (xy 426.012224 -281.00502)
			(xy 425.963049 -281.003039) (xy 425.91483 -280.993195) (xy 425.868814 -280.975743) (xy 425.826193 -280.951136)
			(xy 425.788072 -280.920011) (xy 425.755437 -280.883174) (xy 425.729134 -280.841578) (xy 425.709843 -280.796302)
			(xy 425.698066 -280.748518) (xy 425.694106 -280.699464) (xy 424.405298 -280.699464) (xy 424.404803 -280.724071)
			(xy 424.396908 -280.772648) (xy 424.381324 -280.819329) (xy 424.358453 -280.862906) (xy 424.328888 -280.90225)
			(xy 424.293395 -280.936342) (xy 424.252892 -280.964298) (xy 424.20843 -280.985396) (xy 424.161159 -280.999088)
			(xy 424.112304 -281.00502) (xy 424.063129 -281.003039) (xy 424.01491 -280.993195) (xy 423.968894 -280.975743)
			(xy 423.926273 -280.951136) (xy 423.888152 -280.920011) (xy 423.855517 -280.883174) (xy 423.829214 -280.841578)
			(xy 423.809923 -280.796302) (xy 423.798146 -280.748518) (xy 423.794186 -280.699464) (xy 422.505124 -280.699464)
			(xy 422.504629 -280.724071) (xy 422.496734 -280.772648) (xy 422.48115 -280.819329) (xy 422.458279 -280.862906)
			(xy 422.428714 -280.90225) (xy 422.393221 -280.936342) (xy 422.352718 -280.964298) (xy 422.308256 -280.985396)
			(xy 422.260985 -280.999088) (xy 422.21213 -281.00502) (xy 422.162955 -281.003039) (xy 422.114736 -280.993195)
			(xy 422.06872 -280.975743) (xy 422.026099 -280.951136) (xy 421.987978 -280.920011) (xy 421.955343 -280.883174)
			(xy 421.92904 -280.841578) (xy 421.909749 -280.796302) (xy 421.897972 -280.748518) (xy 421.894012 -280.699464)
			(xy 420.605204 -280.699464) (xy 420.604709 -280.724071) (xy 420.596814 -280.772648) (xy 420.58123 -280.819329)
			(xy 420.558359 -280.862906) (xy 420.528794 -280.90225) (xy 420.493301 -280.936342) (xy 420.452798 -280.964298)
			(xy 420.408336 -280.985396) (xy 420.361065 -280.999088) (xy 420.31221 -281.00502) (xy 420.263035 -281.003039)
			(xy 420.214816 -280.993195) (xy 420.1688 -280.975743) (xy 420.126179 -280.951136) (xy 420.088058 -280.920011)
			(xy 420.055423 -280.883174) (xy 420.02912 -280.841578) (xy 420.009829 -280.796302) (xy 419.998052 -280.748518)
			(xy 419.994092 -280.699464) (xy 418.705284 -280.699464) (xy 418.704789 -280.724071) (xy 418.696894 -280.772648)
			(xy 418.68131 -280.819329) (xy 418.658439 -280.862906) (xy 418.628874 -280.90225) (xy 418.593381 -280.936342)
			(xy 418.552878 -280.964298) (xy 418.508416 -280.985396) (xy 418.461145 -280.999088) (xy 418.41229 -281.00502)
			(xy 418.363115 -281.003039) (xy 418.314896 -280.993195) (xy 418.26888 -280.975743) (xy 418.226259 -280.951136)
			(xy 418.188138 -280.920011) (xy 418.155503 -280.883174) (xy 418.1292 -280.841578) (xy 418.109909 -280.796302)
			(xy 418.098132 -280.748518) (xy 418.094172 -280.699464) (xy 416.80511 -280.699464) (xy 416.804615 -280.724071)
			(xy 416.79672 -280.772648) (xy 416.781136 -280.819329) (xy 416.758265 -280.862906) (xy 416.7287 -280.90225)
			(xy 416.693207 -280.936342) (xy 416.652704 -280.964298) (xy 416.608242 -280.985396) (xy 416.560971 -280.999088)
			(xy 416.512116 -281.00502) (xy 416.462941 -281.003039) (xy 416.414722 -280.993195) (xy 416.368706 -280.975743)
			(xy 416.326085 -280.951136) (xy 416.287964 -280.920011) (xy 416.255329 -280.883174) (xy 416.229026 -280.841578)
			(xy 416.209735 -280.796302) (xy 416.197958 -280.748518) (xy 416.193998 -280.699464) (xy 414.90519 -280.699464)
			(xy 414.904695 -280.724071) (xy 414.8968 -280.772648) (xy 414.881216 -280.819329) (xy 414.858345 -280.862906)
			(xy 414.82878 -280.90225) (xy 414.793287 -280.936342) (xy 414.752784 -280.964298) (xy 414.708322 -280.985396)
			(xy 414.661051 -280.999088) (xy 414.612196 -281.00502) (xy 414.563021 -281.003039) (xy 414.514802 -280.993195)
			(xy 414.468786 -280.975743) (xy 414.426165 -280.951136) (xy 414.388044 -280.920011) (xy 414.355409 -280.883174)
			(xy 414.329106 -280.841578) (xy 414.309815 -280.796302) (xy 414.298038 -280.748518) (xy 414.294078 -280.699464)
			(xy 413.00527 -280.699464) (xy 413.004775 -280.724071) (xy 412.99688 -280.772648) (xy 412.981296 -280.819329)
			(xy 412.958425 -280.862906) (xy 412.92886 -280.90225) (xy 412.893367 -280.936342) (xy 412.852864 -280.964298)
			(xy 412.808402 -280.985396) (xy 412.761131 -280.999088) (xy 412.712276 -281.00502) (xy 412.663101 -281.003039)
			(xy 412.614882 -280.993195) (xy 412.568866 -280.975743) (xy 412.526245 -280.951136) (xy 412.488124 -280.920011)
			(xy 412.455489 -280.883174) (xy 412.429186 -280.841578) (xy 412.409895 -280.796302) (xy 412.398118 -280.748518)
			(xy 412.394158 -280.699464) (xy 411.105096 -280.699464) (xy 411.104601 -280.724071) (xy 411.096706 -280.772648)
			(xy 411.081122 -280.819329) (xy 411.058251 -280.862906) (xy 411.028686 -280.90225) (xy 410.993193 -280.936342)
			(xy 410.95269 -280.964298) (xy 410.908228 -280.985396) (xy 410.860957 -280.999088) (xy 410.812102 -281.00502)
			(xy 410.762927 -281.003039) (xy 410.714708 -280.993195) (xy 410.668692 -280.975743) (xy 410.626071 -280.951136)
			(xy 410.58795 -280.920011) (xy 410.555315 -280.883174) (xy 410.529012 -280.841578) (xy 410.509721 -280.796302)
			(xy 410.497944 -280.748518) (xy 410.493984 -280.699464) (xy 409.205176 -280.699464) (xy 409.204681 -280.724071)
			(xy 409.196786 -280.772648) (xy 409.181202 -280.819329) (xy 409.158331 -280.862906) (xy 409.128766 -280.90225)
			(xy 409.093273 -280.936342) (xy 409.05277 -280.964298) (xy 409.008308 -280.985396) (xy 408.961037 -280.999088)
			(xy 408.912182 -281.00502) (xy 408.863007 -281.003039) (xy 408.814788 -280.993195) (xy 408.768772 -280.975743)
			(xy 408.726151 -280.951136) (xy 408.68803 -280.920011) (xy 408.655395 -280.883174) (xy 408.629092 -280.841578)
			(xy 408.609801 -280.796302) (xy 408.598024 -280.748518) (xy 408.594064 -280.699464) (xy 407.305256 -280.699464)
			(xy 407.304761 -280.724071) (xy 407.296866 -280.772648) (xy 407.281282 -280.819329) (xy 407.258411 -280.862906)
			(xy 407.228846 -280.90225) (xy 407.193353 -280.936342) (xy 407.15285 -280.964298) (xy 407.108388 -280.985396)
			(xy 407.061117 -280.999088) (xy 407.012262 -281.00502) (xy 406.963087 -281.003039) (xy 406.914868 -280.993195)
			(xy 406.868852 -280.975743) (xy 406.826231 -280.951136) (xy 406.78811 -280.920011) (xy 406.755475 -280.883174)
			(xy 406.729172 -280.841578) (xy 406.709881 -280.796302) (xy 406.698104 -280.748518) (xy 406.694144 -280.699464)
			(xy 405.405082 -280.699464) (xy 405.404587 -280.724071) (xy 405.396692 -280.772648) (xy 405.381108 -280.819329)
			(xy 405.358237 -280.862906) (xy 405.328672 -280.90225) (xy 405.293179 -280.936342) (xy 405.252676 -280.964298)
			(xy 405.208214 -280.985396) (xy 405.160943 -280.999088) (xy 405.112088 -281.00502) (xy 405.062913 -281.003039)
			(xy 405.014694 -280.993195) (xy 404.968678 -280.975743) (xy 404.926057 -280.951136) (xy 404.887936 -280.920011)
			(xy 404.855301 -280.883174) (xy 404.828998 -280.841578) (xy 404.809707 -280.796302) (xy 404.79793 -280.748518)
			(xy 404.79397 -280.699464) (xy 403.505162 -280.699464) (xy 403.504667 -280.724071) (xy 403.496772 -280.772648)
			(xy 403.481188 -280.819329) (xy 403.458317 -280.862906) (xy 403.428752 -280.90225) (xy 403.393259 -280.936342)
			(xy 403.352756 -280.964298) (xy 403.308294 -280.985396) (xy 403.261023 -280.999088) (xy 403.212168 -281.00502)
			(xy 403.162993 -281.003039) (xy 403.114774 -280.993195) (xy 403.068758 -280.975743) (xy 403.026137 -280.951136)
			(xy 402.988016 -280.920011) (xy 402.955381 -280.883174) (xy 402.929078 -280.841578) (xy 402.909787 -280.796302)
			(xy 402.89801 -280.748518) (xy 402.89405 -280.699464) (xy 401.605242 -280.699464) (xy 401.604747 -280.724071)
			(xy 401.596852 -280.772648) (xy 401.581268 -280.819329) (xy 401.558397 -280.862906) (xy 401.528832 -280.90225)
			(xy 401.493339 -280.936342) (xy 401.452836 -280.964298) (xy 401.408374 -280.985396) (xy 401.361103 -280.999088)
			(xy 401.312248 -281.00502) (xy 401.263073 -281.003039) (xy 401.214854 -280.993195) (xy 401.168838 -280.975743)
			(xy 401.126217 -280.951136) (xy 401.088096 -280.920011) (xy 401.055461 -280.883174) (xy 401.029158 -280.841578)
			(xy 401.009867 -280.796302) (xy 400.99809 -280.748518) (xy 400.99413 -280.699464) (xy 399.705322 -280.699464)
			(xy 399.704827 -280.724071) (xy 399.696932 -280.772648) (xy 399.681348 -280.819329) (xy 399.658477 -280.862906)
			(xy 399.628912 -280.90225) (xy 399.593419 -280.936342) (xy 399.552916 -280.964298) (xy 399.508454 -280.985396)
			(xy 399.461183 -280.999088) (xy 399.412328 -281.00502) (xy 399.363153 -281.003039) (xy 399.314934 -280.993195)
			(xy 399.268918 -280.975743) (xy 399.226297 -280.951136) (xy 399.188176 -280.920011) (xy 399.155541 -280.883174)
			(xy 399.129238 -280.841578) (xy 399.109947 -280.796302) (xy 399.09817 -280.748518) (xy 399.09421 -280.699464)
			(xy 397.805148 -280.699464) (xy 397.804653 -280.724071) (xy 397.796758 -280.772648) (xy 397.781174 -280.819329)
			(xy 397.758303 -280.862906) (xy 397.728738 -280.90225) (xy 397.693245 -280.936342) (xy 397.652742 -280.964298)
			(xy 397.60828 -280.985396) (xy 397.561009 -280.999088) (xy 397.512154 -281.00502) (xy 397.462979 -281.003039)
			(xy 397.41476 -280.993195) (xy 397.368744 -280.975743) (xy 397.326123 -280.951136) (xy 397.288002 -280.920011)
			(xy 397.255367 -280.883174) (xy 397.229064 -280.841578) (xy 397.209773 -280.796302) (xy 397.197996 -280.748518)
			(xy 397.194036 -280.699464) (xy 395.905228 -280.699464) (xy 395.904733 -280.724071) (xy 395.896838 -280.772648)
			(xy 395.881254 -280.819329) (xy 395.858383 -280.862906) (xy 395.828818 -280.90225) (xy 395.793325 -280.936342)
			(xy 395.752822 -280.964298) (xy 395.70836 -280.985396) (xy 395.661089 -280.999088) (xy 395.612234 -281.00502)
			(xy 395.563059 -281.003039) (xy 395.51484 -280.993195) (xy 395.468824 -280.975743) (xy 395.426203 -280.951136)
			(xy 395.388082 -280.920011) (xy 395.355447 -280.883174) (xy 395.329144 -280.841578) (xy 395.309853 -280.796302)
			(xy 395.298076 -280.748518) (xy 395.294116 -280.699464) (xy 394.005308 -280.699464) (xy 394.004813 -280.724071)
			(xy 393.996918 -280.772648) (xy 393.981334 -280.819329) (xy 393.958463 -280.862906) (xy 393.928898 -280.90225)
			(xy 393.893405 -280.936342) (xy 393.852902 -280.964298) (xy 393.80844 -280.985396) (xy 393.761169 -280.999088)
			(xy 393.712314 -281.00502) (xy 393.663139 -281.003039) (xy 393.61492 -280.993195) (xy 393.568904 -280.975743)
			(xy 393.526283 -280.951136) (xy 393.488162 -280.920011) (xy 393.455527 -280.883174) (xy 393.429224 -280.841578)
			(xy 393.409933 -280.796302) (xy 393.398156 -280.748518) (xy 393.394196 -280.699464) (xy 312.105035 -280.699464)
			(xy 312.10504 -280.699718) (xy 312.104545 -280.724325) (xy 312.09665 -280.772902) (xy 312.081066 -280.819583)
			(xy 312.058195 -280.86316) (xy 312.02863 -280.902504) (xy 311.993137 -280.936596) (xy 311.952634 -280.964552)
			(xy 311.908172 -280.98565) (xy 311.860901 -280.999342) (xy 311.812046 -281.005274) (xy 311.762871 -281.003293)
			(xy 311.714652 -280.993449) (xy 311.668636 -280.975997) (xy 311.626015 -280.95139) (xy 311.587894 -280.920265)
			(xy 311.555259 -280.883428) (xy 311.528956 -280.841832) (xy 311.509665 -280.796556) (xy 311.497888 -280.748772)
			(xy 311.493928 -280.699718) (xy 310.205115 -280.699718) (xy 310.204625 -280.724071) (xy 310.19673 -280.772648)
			(xy 310.181146 -280.819329) (xy 310.158275 -280.862906) (xy 310.12871 -280.90225) (xy 310.093217 -280.936342)
			(xy 310.052714 -280.964298) (xy 310.008252 -280.985396) (xy 309.960981 -280.999088) (xy 309.912126 -281.00502)
			(xy 309.862951 -281.003039) (xy 309.814732 -280.993195) (xy 309.768716 -280.975743) (xy 309.726095 -280.951136)
			(xy 309.687974 -280.920011) (xy 309.655339 -280.883174) (xy 309.629036 -280.841578) (xy 309.609745 -280.796302)
			(xy 309.597968 -280.748518) (xy 309.594008 -280.699464) (xy 308.3052 -280.699464) (xy 308.304705 -280.724071)
			(xy 308.29681 -280.772648) (xy 308.281226 -280.819329) (xy 308.258355 -280.862906) (xy 308.22879 -280.90225)
			(xy 308.193297 -280.936342) (xy 308.152794 -280.964298) (xy 308.108332 -280.985396) (xy 308.061061 -280.999088)
			(xy 308.012206 -281.00502) (xy 307.963031 -281.003039) (xy 307.914812 -280.993195) (xy 307.868796 -280.975743)
			(xy 307.826175 -280.951136) (xy 307.788054 -280.920011) (xy 307.755419 -280.883174) (xy 307.729116 -280.841578)
			(xy 307.709825 -280.796302) (xy 307.698048 -280.748518) (xy 307.694088 -280.699464) (xy 306.405026 -280.699464)
			(xy 306.404531 -280.724071) (xy 306.396636 -280.772648) (xy 306.381052 -280.819329) (xy 306.358181 -280.862906)
			(xy 306.328616 -280.90225) (xy 306.293123 -280.936342) (xy 306.25262 -280.964298) (xy 306.208158 -280.985396)
			(xy 306.160887 -280.999088) (xy 306.112032 -281.00502) (xy 306.062857 -281.003039) (xy 306.014638 -280.993195)
			(xy 305.968622 -280.975743) (xy 305.926001 -280.951136) (xy 305.88788 -280.920011) (xy 305.855245 -280.883174)
			(xy 305.828942 -280.841578) (xy 305.809651 -280.796302) (xy 305.797874 -280.748518) (xy 305.793914 -280.699464)
			(xy 304.505106 -280.699464) (xy 304.504611 -280.724071) (xy 304.496716 -280.772648) (xy 304.481132 -280.819329)
			(xy 304.458261 -280.862906) (xy 304.428696 -280.90225) (xy 304.393203 -280.936342) (xy 304.3527 -280.964298)
			(xy 304.308238 -280.985396) (xy 304.260967 -280.999088) (xy 304.212112 -281.00502) (xy 304.162937 -281.003039)
			(xy 304.114718 -280.993195) (xy 304.068702 -280.975743) (xy 304.026081 -280.951136) (xy 303.98796 -280.920011)
			(xy 303.955325 -280.883174) (xy 303.929022 -280.841578) (xy 303.909731 -280.796302) (xy 303.897954 -280.748518)
			(xy 303.893994 -280.699464) (xy 302.605186 -280.699464) (xy 302.604691 -280.724071) (xy 302.596796 -280.772648)
			(xy 302.581212 -280.819329) (xy 302.558341 -280.862906) (xy 302.528776 -280.90225) (xy 302.493283 -280.936342)
			(xy 302.45278 -280.964298) (xy 302.408318 -280.985396) (xy 302.361047 -280.999088) (xy 302.312192 -281.00502)
			(xy 302.263017 -281.003039) (xy 302.214798 -280.993195) (xy 302.168782 -280.975743) (xy 302.126161 -280.951136)
			(xy 302.08804 -280.920011) (xy 302.055405 -280.883174) (xy 302.029102 -280.841578) (xy 302.009811 -280.796302)
			(xy 301.998034 -280.748518) (xy 301.994074 -280.699464) (xy 300.705012 -280.699464) (xy 300.704517 -280.724071)
			(xy 300.696622 -280.772648) (xy 300.681038 -280.819329) (xy 300.658167 -280.862906) (xy 300.628602 -280.90225)
			(xy 300.593109 -280.936342) (xy 300.552606 -280.964298) (xy 300.508144 -280.985396) (xy 300.460873 -280.999088)
			(xy 300.412018 -281.00502) (xy 300.362843 -281.003039) (xy 300.314624 -280.993195) (xy 300.268608 -280.975743)
			(xy 300.225987 -280.951136) (xy 300.187866 -280.920011) (xy 300.155231 -280.883174) (xy 300.128928 -280.841578)
			(xy 300.109637 -280.796302) (xy 300.09786 -280.748518) (xy 300.0939 -280.699464) (xy 298.805092 -280.699464)
			(xy 298.804597 -280.724071) (xy 298.796702 -280.772648) (xy 298.781118 -280.819329) (xy 298.758247 -280.862906)
			(xy 298.728682 -280.90225) (xy 298.693189 -280.936342) (xy 298.652686 -280.964298) (xy 298.608224 -280.985396)
			(xy 298.560953 -280.999088) (xy 298.512098 -281.00502) (xy 298.462923 -281.003039) (xy 298.414704 -280.993195)
			(xy 298.368688 -280.975743) (xy 298.326067 -280.951136) (xy 298.287946 -280.920011) (xy 298.255311 -280.883174)
			(xy 298.229008 -280.841578) (xy 298.209717 -280.796302) (xy 298.19794 -280.748518) (xy 298.19398 -280.699464)
			(xy 296.905172 -280.699464) (xy 296.904677 -280.724071) (xy 296.896782 -280.772648) (xy 296.881198 -280.819329)
			(xy 296.858327 -280.862906) (xy 296.828762 -280.90225) (xy 296.793269 -280.936342) (xy 296.752766 -280.964298)
			(xy 296.708304 -280.985396) (xy 296.661033 -280.999088) (xy 296.612178 -281.00502) (xy 296.563003 -281.003039)
			(xy 296.514784 -280.993195) (xy 296.468768 -280.975743) (xy 296.426147 -280.951136) (xy 296.388026 -280.920011)
			(xy 296.355391 -280.883174) (xy 296.329088 -280.841578) (xy 296.309797 -280.796302) (xy 296.29802 -280.748518)
			(xy 296.29406 -280.699464) (xy 295.004998 -280.699464) (xy 295.004503 -280.724071) (xy 294.996608 -280.772648)
			(xy 294.981024 -280.819329) (xy 294.958153 -280.862906) (xy 294.928588 -280.90225) (xy 294.893095 -280.936342)
			(xy 294.852592 -280.964298) (xy 294.80813 -280.985396) (xy 294.760859 -280.999088) (xy 294.712004 -281.00502)
			(xy 294.662829 -281.003039) (xy 294.61461 -280.993195) (xy 294.568594 -280.975743) (xy 294.525973 -280.951136)
			(xy 294.487852 -280.920011) (xy 294.455217 -280.883174) (xy 294.428914 -280.841578) (xy 294.409623 -280.796302)
			(xy 294.397846 -280.748518) (xy 294.393886 -280.699464) (xy 293.105078 -280.699464) (xy 293.104583 -280.724071)
			(xy 293.096688 -280.772648) (xy 293.081104 -280.819329) (xy 293.058233 -280.862906) (xy 293.028668 -280.90225)
			(xy 292.993175 -280.936342) (xy 292.952672 -280.964298) (xy 292.90821 -280.985396) (xy 292.860939 -280.999088)
			(xy 292.812084 -281.00502) (xy 292.762909 -281.003039) (xy 292.71469 -280.993195) (xy 292.668674 -280.975743)
			(xy 292.626053 -280.951136) (xy 292.587932 -280.920011) (xy 292.555297 -280.883174) (xy 292.528994 -280.841578)
			(xy 292.509703 -280.796302) (xy 292.497926 -280.748518) (xy 292.493966 -280.699464) (xy 291.205158 -280.699464)
			(xy 291.204663 -280.724071) (xy 291.196768 -280.772648) (xy 291.181184 -280.819329) (xy 291.158313 -280.862906)
			(xy 291.128748 -280.90225) (xy 291.093255 -280.936342) (xy 291.052752 -280.964298) (xy 291.00829 -280.985396)
			(xy 290.961019 -280.999088) (xy 290.912164 -281.00502) (xy 290.862989 -281.003039) (xy 290.81477 -280.993195)
			(xy 290.768754 -280.975743) (xy 290.726133 -280.951136) (xy 290.688012 -280.920011) (xy 290.655377 -280.883174)
			(xy 290.629074 -280.841578) (xy 290.609783 -280.796302) (xy 290.598006 -280.748518) (xy 290.594046 -280.699464)
			(xy 289.304984 -280.699464) (xy 289.304489 -280.724071) (xy 289.296594 -280.772648) (xy 289.28101 -280.819329)
			(xy 289.258139 -280.862906) (xy 289.228574 -280.90225) (xy 289.193081 -280.936342) (xy 289.152578 -280.964298)
			(xy 289.108116 -280.985396) (xy 289.060845 -280.999088) (xy 289.01199 -281.00502) (xy 288.962815 -281.003039)
			(xy 288.914596 -280.993195) (xy 288.86858 -280.975743) (xy 288.825959 -280.951136) (xy 288.787838 -280.920011)
			(xy 288.755203 -280.883174) (xy 288.7289 -280.841578) (xy 288.709609 -280.796302) (xy 288.697832 -280.748518)
			(xy 288.693872 -280.699464) (xy 287.405064 -280.699464) (xy 287.404569 -280.724071) (xy 287.396674 -280.772648)
			(xy 287.38109 -280.819329) (xy 287.358219 -280.862906) (xy 287.328654 -280.90225) (xy 287.293161 -280.936342)
			(xy 287.252658 -280.964298) (xy 287.208196 -280.985396) (xy 287.160925 -280.999088) (xy 287.11207 -281.00502)
			(xy 287.062895 -281.003039) (xy 287.014676 -280.993195) (xy 286.96866 -280.975743) (xy 286.926039 -280.951136)
			(xy 286.887918 -280.920011) (xy 286.855283 -280.883174) (xy 286.82898 -280.841578) (xy 286.809689 -280.796302)
			(xy 286.797912 -280.748518) (xy 286.793952 -280.699464) (xy 285.505144 -280.699464) (xy 285.504649 -280.724071)
			(xy 285.496754 -280.772648) (xy 285.48117 -280.819329) (xy 285.458299 -280.862906) (xy 285.428734 -280.90225)
			(xy 285.393241 -280.936342) (xy 285.352738 -280.964298) (xy 285.308276 -280.985396) (xy 285.261005 -280.999088)
			(xy 285.21215 -281.00502) (xy 285.162975 -281.003039) (xy 285.114756 -280.993195) (xy 285.06874 -280.975743)
			(xy 285.026119 -280.951136) (xy 284.987998 -280.920011) (xy 284.955363 -280.883174) (xy 284.92906 -280.841578)
			(xy 284.909769 -280.796302) (xy 284.897992 -280.748518) (xy 284.894032 -280.699464) (xy 283.605224 -280.699464)
			(xy 283.604729 -280.724071) (xy 283.596834 -280.772648) (xy 283.58125 -280.819329) (xy 283.558379 -280.862906)
			(xy 283.528814 -280.90225) (xy 283.493321 -280.936342) (xy 283.452818 -280.964298) (xy 283.408356 -280.985396)
			(xy 283.361085 -280.999088) (xy 283.31223 -281.00502) (xy 283.263055 -281.003039) (xy 283.214836 -280.993195)
			(xy 283.16882 -280.975743) (xy 283.126199 -280.951136) (xy 283.088078 -280.920011) (xy 283.055443 -280.883174)
			(xy 283.02914 -280.841578) (xy 283.009849 -280.796302) (xy 282.998072 -280.748518) (xy 282.994112 -280.699464)
			(xy 281.70505 -280.699464) (xy 281.704555 -280.724071) (xy 281.69666 -280.772648) (xy 281.681076 -280.819329)
			(xy 281.658205 -280.862906) (xy 281.62864 -280.90225) (xy 281.593147 -280.936342) (xy 281.552644 -280.964298)
			(xy 281.508182 -280.985396) (xy 281.460911 -280.999088) (xy 281.412056 -281.00502) (xy 281.362881 -281.003039)
			(xy 281.314662 -280.993195) (xy 281.268646 -280.975743) (xy 281.226025 -280.951136) (xy 281.187904 -280.920011)
			(xy 281.155269 -280.883174) (xy 281.128966 -280.841578) (xy 281.109675 -280.796302) (xy 281.097898 -280.748518)
			(xy 281.093938 -280.699464) (xy 279.80513 -280.699464) (xy 279.804635 -280.724071) (xy 279.79674 -280.772648)
			(xy 279.781156 -280.819329) (xy 279.758285 -280.862906) (xy 279.72872 -280.90225) (xy 279.693227 -280.936342)
			(xy 279.652724 -280.964298) (xy 279.608262 -280.985396) (xy 279.560991 -280.999088) (xy 279.512136 -281.00502)
			(xy 279.462961 -281.003039) (xy 279.414742 -280.993195) (xy 279.368726 -280.975743) (xy 279.326105 -280.951136)
			(xy 279.287984 -280.920011) (xy 279.255349 -280.883174) (xy 279.229046 -280.841578) (xy 279.209755 -280.796302)
			(xy 279.197978 -280.748518) (xy 279.194018 -280.699464) (xy 277.90521 -280.699464) (xy 277.904715 -280.724071)
			(xy 277.89682 -280.772648) (xy 277.881236 -280.819329) (xy 277.858365 -280.862906) (xy 277.8288 -280.90225)
			(xy 277.793307 -280.936342) (xy 277.752804 -280.964298) (xy 277.708342 -280.985396) (xy 277.661071 -280.999088)
			(xy 277.612216 -281.00502) (xy 277.563041 -281.003039) (xy 277.514822 -280.993195) (xy 277.468806 -280.975743)
			(xy 277.426185 -280.951136) (xy 277.388064 -280.920011) (xy 277.355429 -280.883174) (xy 277.329126 -280.841578)
			(xy 277.309835 -280.796302) (xy 277.298058 -280.748518) (xy 277.294098 -280.699464) (xy 196.005191 -280.699464)
			(xy 196.005196 -280.699718) (xy 196.004701 -280.724325) (xy 195.996806 -280.772902) (xy 195.981222 -280.819583)
			(xy 195.958351 -280.86316) (xy 195.928786 -280.902504) (xy 195.893293 -280.936596) (xy 195.85279 -280.964552)
			(xy 195.808328 -280.98565) (xy 195.761057 -280.999342) (xy 195.712202 -281.005274) (xy 195.663027 -281.003293)
			(xy 195.614808 -280.993449) (xy 195.568792 -280.975997) (xy 195.526171 -280.95139) (xy 195.48805 -280.920265)
			(xy 195.455415 -280.883428) (xy 195.429112 -280.841832) (xy 195.409821 -280.796556) (xy 195.398044 -280.748772)
			(xy 195.394084 -280.699718) (xy 194.105276 -280.699718) (xy 194.104781 -280.724325) (xy 194.096886 -280.772902)
			(xy 194.081302 -280.819583) (xy 194.058431 -280.86316) (xy 194.028866 -280.902504) (xy 193.993373 -280.936596)
			(xy 193.95287 -280.964552) (xy 193.908408 -280.98565) (xy 193.861137 -280.999342) (xy 193.812282 -281.005274)
			(xy 193.763107 -281.003293) (xy 193.714888 -280.993449) (xy 193.668872 -280.975997) (xy 193.626251 -280.95139)
			(xy 193.58813 -280.920265) (xy 193.555495 -280.883428) (xy 193.529192 -280.841832) (xy 193.509901 -280.796556)
			(xy 193.498124 -280.748772) (xy 193.494164 -280.699718) (xy 192.205356 -280.699718) (xy 192.204861 -280.724325)
			(xy 192.196966 -280.772902) (xy 192.181382 -280.819583) (xy 192.158511 -280.86316) (xy 192.128946 -280.902504)
			(xy 192.093453 -280.936596) (xy 192.05295 -280.964552) (xy 192.008488 -280.98565) (xy 191.961217 -280.999342)
			(xy 191.912362 -281.005274) (xy 191.863187 -281.003293) (xy 191.814968 -280.993449) (xy 191.768952 -280.975997)
			(xy 191.726331 -280.95139) (xy 191.68821 -280.920265) (xy 191.655575 -280.883428) (xy 191.629272 -280.841832)
			(xy 191.609981 -280.796556) (xy 191.598204 -280.748772) (xy 191.594244 -280.699718) (xy 190.305182 -280.699718)
			(xy 190.304687 -280.724325) (xy 190.296792 -280.772902) (xy 190.281208 -280.819583) (xy 190.258337 -280.86316)
			(xy 190.228772 -280.902504) (xy 190.193279 -280.936596) (xy 190.152776 -280.964552) (xy 190.108314 -280.98565)
			(xy 190.061043 -280.999342) (xy 190.012188 -281.005274) (xy 189.963013 -281.003293) (xy 189.914794 -280.993449)
			(xy 189.868778 -280.975997) (xy 189.826157 -280.95139) (xy 189.788036 -280.920265) (xy 189.755401 -280.883428)
			(xy 189.729098 -280.841832) (xy 189.709807 -280.796556) (xy 189.69803 -280.748772) (xy 189.69407 -280.699718)
			(xy 188.405262 -280.699718) (xy 188.404767 -280.724325) (xy 188.396872 -280.772902) (xy 188.381288 -280.819583)
			(xy 188.358417 -280.86316) (xy 188.328852 -280.902504) (xy 188.293359 -280.936596) (xy 188.252856 -280.964552)
			(xy 188.208394 -280.98565) (xy 188.161123 -280.999342) (xy 188.112268 -281.005274) (xy 188.063093 -281.003293)
			(xy 188.014874 -280.993449) (xy 187.968858 -280.975997) (xy 187.926237 -280.95139) (xy 187.888116 -280.920265)
			(xy 187.855481 -280.883428) (xy 187.829178 -280.841832) (xy 187.809887 -280.796556) (xy 187.79811 -280.748772)
			(xy 187.79415 -280.699718) (xy 186.505342 -280.699718) (xy 186.504847 -280.724325) (xy 186.496952 -280.772902)
			(xy 186.481368 -280.819583) (xy 186.458497 -280.86316) (xy 186.428932 -280.902504) (xy 186.393439 -280.936596)
			(xy 186.352936 -280.964552) (xy 186.308474 -280.98565) (xy 186.261203 -280.999342) (xy 186.212348 -281.005274)
			(xy 186.163173 -281.003293) (xy 186.114954 -280.993449) (xy 186.068938 -280.975997) (xy 186.026317 -280.95139)
			(xy 185.988196 -280.920265) (xy 185.955561 -280.883428) (xy 185.929258 -280.841832) (xy 185.909967 -280.796556)
			(xy 185.89819 -280.748772) (xy 185.89423 -280.699718) (xy 184.605168 -280.699718) (xy 184.604673 -280.724325)
			(xy 184.596778 -280.772902) (xy 184.581194 -280.819583) (xy 184.558323 -280.86316) (xy 184.528758 -280.902504)
			(xy 184.493265 -280.936596) (xy 184.452762 -280.964552) (xy 184.4083 -280.98565) (xy 184.361029 -280.999342)
			(xy 184.312174 -281.005274) (xy 184.262999 -281.003293) (xy 184.21478 -280.993449) (xy 184.168764 -280.975997)
			(xy 184.126143 -280.95139) (xy 184.088022 -280.920265) (xy 184.055387 -280.883428) (xy 184.029084 -280.841832)
			(xy 184.009793 -280.796556) (xy 183.998016 -280.748772) (xy 183.994056 -280.699718) (xy 182.705248 -280.699718)
			(xy 182.704753 -280.724325) (xy 182.696858 -280.772902) (xy 182.681274 -280.819583) (xy 182.658403 -280.86316)
			(xy 182.628838 -280.902504) (xy 182.593345 -280.936596) (xy 182.552842 -280.964552) (xy 182.50838 -280.98565)
			(xy 182.461109 -280.999342) (xy 182.412254 -281.005274) (xy 182.363079 -281.003293) (xy 182.31486 -280.993449)
			(xy 182.268844 -280.975997) (xy 182.226223 -280.95139) (xy 182.188102 -280.920265) (xy 182.155467 -280.883428)
			(xy 182.129164 -280.841832) (xy 182.109873 -280.796556) (xy 182.098096 -280.748772) (xy 182.094136 -280.699718)
			(xy 180.805328 -280.699718) (xy 180.804833 -280.724325) (xy 180.796938 -280.772902) (xy 180.781354 -280.819583)
			(xy 180.758483 -280.86316) (xy 180.728918 -280.902504) (xy 180.693425 -280.936596) (xy 180.652922 -280.964552)
			(xy 180.60846 -280.98565) (xy 180.561189 -280.999342) (xy 180.512334 -281.005274) (xy 180.463159 -281.003293)
			(xy 180.41494 -280.993449) (xy 180.368924 -280.975997) (xy 180.326303 -280.95139) (xy 180.288182 -280.920265)
			(xy 180.255547 -280.883428) (xy 180.229244 -280.841832) (xy 180.209953 -280.796556) (xy 180.198176 -280.748772)
			(xy 180.194216 -280.699718) (xy 178.905154 -280.699718) (xy 178.904659 -280.724325) (xy 178.896764 -280.772902)
			(xy 178.88118 -280.819583) (xy 178.858309 -280.86316) (xy 178.828744 -280.902504) (xy 178.793251 -280.936596)
			(xy 178.752748 -280.964552) (xy 178.708286 -280.98565) (xy 178.661015 -280.999342) (xy 178.61216 -281.005274)
			(xy 178.562985 -281.003293) (xy 178.514766 -280.993449) (xy 178.46875 -280.975997) (xy 178.426129 -280.95139)
			(xy 178.388008 -280.920265) (xy 178.355373 -280.883428) (xy 178.32907 -280.841832) (xy 178.309779 -280.796556)
			(xy 178.298002 -280.748772) (xy 178.294042 -280.699718) (xy 177.005234 -280.699718) (xy 177.004739 -280.724325)
			(xy 176.996844 -280.772902) (xy 176.98126 -280.819583) (xy 176.958389 -280.86316) (xy 176.928824 -280.902504)
			(xy 176.893331 -280.936596) (xy 176.852828 -280.964552) (xy 176.808366 -280.98565) (xy 176.761095 -280.999342)
			(xy 176.71224 -281.005274) (xy 176.663065 -281.003293) (xy 176.614846 -280.993449) (xy 176.56883 -280.975997)
			(xy 176.526209 -280.95139) (xy 176.488088 -280.920265) (xy 176.455453 -280.883428) (xy 176.42915 -280.841832)
			(xy 176.409859 -280.796556) (xy 176.398082 -280.748772) (xy 176.394122 -280.699718) (xy 175.105314 -280.699718)
			(xy 175.104819 -280.724325) (xy 175.096924 -280.772902) (xy 175.08134 -280.819583) (xy 175.058469 -280.86316)
			(xy 175.028904 -280.902504) (xy 174.993411 -280.936596) (xy 174.952908 -280.964552) (xy 174.908446 -280.98565)
			(xy 174.861175 -280.999342) (xy 174.81232 -281.005274) (xy 174.763145 -281.003293) (xy 174.714926 -280.993449)
			(xy 174.66891 -280.975997) (xy 174.626289 -280.95139) (xy 174.588168 -280.920265) (xy 174.555533 -280.883428)
			(xy 174.52923 -280.841832) (xy 174.509939 -280.796556) (xy 174.498162 -280.748772) (xy 174.494202 -280.699718)
			(xy 173.20514 -280.699718) (xy 173.204645 -280.724325) (xy 173.19675 -280.772902) (xy 173.181166 -280.819583)
			(xy 173.158295 -280.86316) (xy 173.12873 -280.902504) (xy 173.093237 -280.936596) (xy 173.052734 -280.964552)
			(xy 173.008272 -280.98565) (xy 172.961001 -280.999342) (xy 172.912146 -281.005274) (xy 172.862971 -281.003293)
			(xy 172.814752 -280.993449) (xy 172.768736 -280.975997) (xy 172.726115 -280.95139) (xy 172.687994 -280.920265)
			(xy 172.655359 -280.883428) (xy 172.629056 -280.841832) (xy 172.609765 -280.796556) (xy 172.597988 -280.748772)
			(xy 172.594028 -280.699718) (xy 171.30522 -280.699718) (xy 171.304725 -280.724325) (xy 171.29683 -280.772902)
			(xy 171.281246 -280.819583) (xy 171.258375 -280.86316) (xy 171.22881 -280.902504) (xy 171.193317 -280.936596)
			(xy 171.152814 -280.964552) (xy 171.108352 -280.98565) (xy 171.061081 -280.999342) (xy 171.012226 -281.005274)
			(xy 170.963051 -281.003293) (xy 170.914832 -280.993449) (xy 170.868816 -280.975997) (xy 170.826195 -280.95139)
			(xy 170.788074 -280.920265) (xy 170.755439 -280.883428) (xy 170.729136 -280.841832) (xy 170.709845 -280.796556)
			(xy 170.698068 -280.748772) (xy 170.694108 -280.699718) (xy 169.4053 -280.699718) (xy 169.404805 -280.724325)
			(xy 169.39691 -280.772902) (xy 169.381326 -280.819583) (xy 169.358455 -280.86316) (xy 169.32889 -280.902504)
			(xy 169.293397 -280.936596) (xy 169.252894 -280.964552) (xy 169.208432 -280.98565) (xy 169.161161 -280.999342)
			(xy 169.112306 -281.005274) (xy 169.063131 -281.003293) (xy 169.014912 -280.993449) (xy 168.968896 -280.975997)
			(xy 168.926275 -280.95139) (xy 168.888154 -280.920265) (xy 168.855519 -280.883428) (xy 168.829216 -280.841832)
			(xy 168.809925 -280.796556) (xy 168.798148 -280.748772) (xy 168.794188 -280.699718) (xy 167.50538 -280.699718)
			(xy 167.504885 -280.724325) (xy 167.49699 -280.772902) (xy 167.481406 -280.819583) (xy 167.458535 -280.86316)
			(xy 167.42897 -280.902504) (xy 167.393477 -280.936596) (xy 167.352974 -280.964552) (xy 167.308512 -280.98565)
			(xy 167.261241 -280.999342) (xy 167.212386 -281.005274) (xy 167.163211 -281.003293) (xy 167.114992 -280.993449)
			(xy 167.068976 -280.975997) (xy 167.026355 -280.95139) (xy 166.988234 -280.920265) (xy 166.955599 -280.883428)
			(xy 166.929296 -280.841832) (xy 166.910005 -280.796556) (xy 166.898228 -280.748772) (xy 166.894268 -280.699718)
			(xy 165.605206 -280.699718) (xy 165.604711 -280.724325) (xy 165.596816 -280.772902) (xy 165.581232 -280.819583)
			(xy 165.558361 -280.86316) (xy 165.528796 -280.902504) (xy 165.493303 -280.936596) (xy 165.4528 -280.964552)
			(xy 165.408338 -280.98565) (xy 165.361067 -280.999342) (xy 165.312212 -281.005274) (xy 165.263037 -281.003293)
			(xy 165.214818 -280.993449) (xy 165.168802 -280.975997) (xy 165.126181 -280.95139) (xy 165.08806 -280.920265)
			(xy 165.055425 -280.883428) (xy 165.029122 -280.841832) (xy 165.009831 -280.796556) (xy 164.998054 -280.748772)
			(xy 164.994094 -280.699718) (xy 163.705286 -280.699718) (xy 163.704791 -280.724325) (xy 163.696896 -280.772902)
			(xy 163.681312 -280.819583) (xy 163.658441 -280.86316) (xy 163.628876 -280.902504) (xy 163.593383 -280.936596)
			(xy 163.55288 -280.964552) (xy 163.508418 -280.98565) (xy 163.461147 -280.999342) (xy 163.412292 -281.005274)
			(xy 163.363117 -281.003293) (xy 163.314898 -280.993449) (xy 163.268882 -280.975997) (xy 163.226261 -280.95139)
			(xy 163.18814 -280.920265) (xy 163.155505 -280.883428) (xy 163.129202 -280.841832) (xy 163.109911 -280.796556)
			(xy 163.098134 -280.748772) (xy 163.094174 -280.699718) (xy 161.805366 -280.699718) (xy 161.804871 -280.724325)
			(xy 161.796976 -280.772902) (xy 161.781392 -280.819583) (xy 161.758521 -280.86316) (xy 161.728956 -280.902504)
			(xy 161.693463 -280.936596) (xy 161.65296 -280.964552) (xy 161.608498 -280.98565) (xy 161.561227 -280.999342)
			(xy 161.512372 -281.005274) (xy 161.463197 -281.003293) (xy 161.414978 -280.993449) (xy 161.368962 -280.975997)
			(xy 161.326341 -280.95139) (xy 161.28822 -280.920265) (xy 161.255585 -280.883428) (xy 161.229282 -280.841832)
			(xy 161.209991 -280.796556) (xy 161.198214 -280.748772) (xy 161.194254 -280.699718) (xy 79.905098 -280.699718)
			(xy 79.904603 -280.724325) (xy 79.896708 -280.772902) (xy 79.881124 -280.819583) (xy 79.858253 -280.86316)
			(xy 79.828688 -280.902504) (xy 79.793195 -280.936596) (xy 79.752692 -280.964552) (xy 79.70823 -280.98565)
			(xy 79.660959 -280.999342) (xy 79.612104 -281.005274) (xy 79.562929 -281.003293) (xy 79.51471 -280.993449)
			(xy 79.468694 -280.975997) (xy 79.426073 -280.95139) (xy 79.387952 -280.920265) (xy 79.355317 -280.883428)
			(xy 79.329014 -280.841832) (xy 79.309723 -280.796556) (xy 79.297946 -280.748772) (xy 79.293986 -280.699718)
			(xy 78.005178 -280.699718) (xy 78.004683 -280.724325) (xy 77.996788 -280.772902) (xy 77.981204 -280.819583)
			(xy 77.958333 -280.86316) (xy 77.928768 -280.902504) (xy 77.893275 -280.936596) (xy 77.852772 -280.964552)
			(xy 77.80831 -280.98565) (xy 77.761039 -280.999342) (xy 77.712184 -281.005274) (xy 77.663009 -281.003293)
			(xy 77.61479 -280.993449) (xy 77.568774 -280.975997) (xy 77.526153 -280.95139) (xy 77.488032 -280.920265)
			(xy 77.455397 -280.883428) (xy 77.429094 -280.841832) (xy 77.409803 -280.796556) (xy 77.398026 -280.748772)
			(xy 77.394066 -280.699718) (xy 76.105258 -280.699718) (xy 76.104763 -280.724325) (xy 76.096868 -280.772902)
			(xy 76.081284 -280.819583) (xy 76.058413 -280.86316) (xy 76.028848 -280.902504) (xy 75.993355 -280.936596)
			(xy 75.952852 -280.964552) (xy 75.90839 -280.98565) (xy 75.861119 -280.999342) (xy 75.812264 -281.005274)
			(xy 75.763089 -281.003293) (xy 75.71487 -280.993449) (xy 75.668854 -280.975997) (xy 75.626233 -280.95139)
			(xy 75.588112 -280.920265) (xy 75.555477 -280.883428) (xy 75.529174 -280.841832) (xy 75.509883 -280.796556)
			(xy 75.498106 -280.748772) (xy 75.494146 -280.699718) (xy 74.205084 -280.699718) (xy 74.204589 -280.724325)
			(xy 74.196694 -280.772902) (xy 74.18111 -280.819583) (xy 74.158239 -280.86316) (xy 74.128674 -280.902504)
			(xy 74.093181 -280.936596) (xy 74.052678 -280.964552) (xy 74.008216 -280.98565) (xy 73.960945 -280.999342)
			(xy 73.91209 -281.005274) (xy 73.862915 -281.003293) (xy 73.814696 -280.993449) (xy 73.76868 -280.975997)
			(xy 73.726059 -280.95139) (xy 73.687938 -280.920265) (xy 73.655303 -280.883428) (xy 73.629 -280.841832)
			(xy 73.609709 -280.796556) (xy 73.597932 -280.748772) (xy 73.593972 -280.699718) (xy 72.305164 -280.699718)
			(xy 72.304669 -280.724325) (xy 72.296774 -280.772902) (xy 72.28119 -280.819583) (xy 72.258319 -280.86316)
			(xy 72.228754 -280.902504) (xy 72.193261 -280.936596) (xy 72.152758 -280.964552) (xy 72.108296 -280.98565)
			(xy 72.061025 -280.999342) (xy 72.01217 -281.005274) (xy 71.962995 -281.003293) (xy 71.914776 -280.993449)
			(xy 71.86876 -280.975997) (xy 71.826139 -280.95139) (xy 71.788018 -280.920265) (xy 71.755383 -280.883428)
			(xy 71.72908 -280.841832) (xy 71.709789 -280.796556) (xy 71.698012 -280.748772) (xy 71.694052 -280.699718)
			(xy 70.405244 -280.699718) (xy 70.404749 -280.724325) (xy 70.396854 -280.772902) (xy 70.38127 -280.819583)
			(xy 70.358399 -280.86316) (xy 70.328834 -280.902504) (xy 70.293341 -280.936596) (xy 70.252838 -280.964552)
			(xy 70.208376 -280.98565) (xy 70.161105 -280.999342) (xy 70.11225 -281.005274) (xy 70.063075 -281.003293)
			(xy 70.014856 -280.993449) (xy 69.96884 -280.975997) (xy 69.926219 -280.95139) (xy 69.888098 -280.920265)
			(xy 69.855463 -280.883428) (xy 69.82916 -280.841832) (xy 69.809869 -280.796556) (xy 69.798092 -280.748772)
			(xy 69.794132 -280.699718) (xy 68.50507 -280.699718) (xy 68.504575 -280.724325) (xy 68.49668 -280.772902)
			(xy 68.481096 -280.819583) (xy 68.458225 -280.86316) (xy 68.42866 -280.902504) (xy 68.393167 -280.936596)
			(xy 68.352664 -280.964552) (xy 68.308202 -280.98565) (xy 68.260931 -280.999342) (xy 68.212076 -281.005274)
			(xy 68.162901 -281.003293) (xy 68.114682 -280.993449) (xy 68.068666 -280.975997) (xy 68.026045 -280.95139)
			(xy 67.987924 -280.920265) (xy 67.955289 -280.883428) (xy 67.928986 -280.841832) (xy 67.909695 -280.796556)
			(xy 67.897918 -280.748772) (xy 67.893958 -280.699718) (xy 66.60515 -280.699718) (xy 66.604655 -280.724325)
			(xy 66.59676 -280.772902) (xy 66.581176 -280.819583) (xy 66.558305 -280.86316) (xy 66.52874 -280.902504)
			(xy 66.493247 -280.936596) (xy 66.452744 -280.964552) (xy 66.408282 -280.98565) (xy 66.361011 -280.999342)
			(xy 66.312156 -281.005274) (xy 66.262981 -281.003293) (xy 66.214762 -280.993449) (xy 66.168746 -280.975997)
			(xy 66.126125 -280.95139) (xy 66.088004 -280.920265) (xy 66.055369 -280.883428) (xy 66.029066 -280.841832)
			(xy 66.009775 -280.796556) (xy 65.997998 -280.748772) (xy 65.994038 -280.699718) (xy 64.70523 -280.699718)
			(xy 64.704735 -280.724325) (xy 64.69684 -280.772902) (xy 64.681256 -280.819583) (xy 64.658385 -280.86316)
			(xy 64.62882 -280.902504) (xy 64.593327 -280.936596) (xy 64.552824 -280.964552) (xy 64.508362 -280.98565)
			(xy 64.461091 -280.999342) (xy 64.412236 -281.005274) (xy 64.363061 -281.003293) (xy 64.314842 -280.993449)
			(xy 64.268826 -280.975997) (xy 64.226205 -280.95139) (xy 64.188084 -280.920265) (xy 64.155449 -280.883428)
			(xy 64.129146 -280.841832) (xy 64.109855 -280.796556) (xy 64.098078 -280.748772) (xy 64.094118 -280.699718)
			(xy 62.805056 -280.699718) (xy 62.804561 -280.724325) (xy 62.796666 -280.772902) (xy 62.781082 -280.819583)
			(xy 62.758211 -280.86316) (xy 62.728646 -280.902504) (xy 62.693153 -280.936596) (xy 62.65265 -280.964552)
			(xy 62.608188 -280.98565) (xy 62.560917 -280.999342) (xy 62.512062 -281.005274) (xy 62.462887 -281.003293)
			(xy 62.414668 -280.993449) (xy 62.368652 -280.975997) (xy 62.326031 -280.95139) (xy 62.28791 -280.920265)
			(xy 62.255275 -280.883428) (xy 62.228972 -280.841832) (xy 62.209681 -280.796556) (xy 62.197904 -280.748772)
			(xy 62.193944 -280.699718) (xy 60.905136 -280.699718) (xy 60.904641 -280.724325) (xy 60.896746 -280.772902)
			(xy 60.881162 -280.819583) (xy 60.858291 -280.86316) (xy 60.828726 -280.902504) (xy 60.793233 -280.936596)
			(xy 60.75273 -280.964552) (xy 60.708268 -280.98565) (xy 60.660997 -280.999342) (xy 60.612142 -281.005274)
			(xy 60.562967 -281.003293) (xy 60.514748 -280.993449) (xy 60.468732 -280.975997) (xy 60.426111 -280.95139)
			(xy 60.38799 -280.920265) (xy 60.355355 -280.883428) (xy 60.329052 -280.841832) (xy 60.309761 -280.796556)
			(xy 60.297984 -280.748772) (xy 60.294024 -280.699718) (xy 59.005216 -280.699718) (xy 59.004721 -280.724325)
			(xy 58.996826 -280.772902) (xy 58.981242 -280.819583) (xy 58.958371 -280.86316) (xy 58.928806 -280.902504)
			(xy 58.893313 -280.936596) (xy 58.85281 -280.964552) (xy 58.808348 -280.98565) (xy 58.761077 -280.999342)
			(xy 58.712222 -281.005274) (xy 58.663047 -281.003293) (xy 58.614828 -280.993449) (xy 58.568812 -280.975997)
			(xy 58.526191 -280.95139) (xy 58.48807 -280.920265) (xy 58.455435 -280.883428) (xy 58.429132 -280.841832)
			(xy 58.409841 -280.796556) (xy 58.398064 -280.748772) (xy 58.394104 -280.699718) (xy 57.105042 -280.699718)
			(xy 57.104547 -280.724325) (xy 57.096652 -280.772902) (xy 57.081068 -280.819583) (xy 57.058197 -280.86316)
			(xy 57.028632 -280.902504) (xy 56.993139 -280.936596) (xy 56.952636 -280.964552) (xy 56.908174 -280.98565)
			(xy 56.860903 -280.999342) (xy 56.812048 -281.005274) (xy 56.762873 -281.003293) (xy 56.714654 -280.993449)
			(xy 56.668638 -280.975997) (xy 56.626017 -280.95139) (xy 56.587896 -280.920265) (xy 56.555261 -280.883428)
			(xy 56.528958 -280.841832) (xy 56.509667 -280.796556) (xy 56.49789 -280.748772) (xy 56.49393 -280.699718)
			(xy 55.205122 -280.699718) (xy 55.204627 -280.724325) (xy 55.196732 -280.772902) (xy 55.181148 -280.819583)
			(xy 55.158277 -280.86316) (xy 55.128712 -280.902504) (xy 55.093219 -280.936596) (xy 55.052716 -280.964552)
			(xy 55.008254 -280.98565) (xy 54.960983 -280.999342) (xy 54.912128 -281.005274) (xy 54.862953 -281.003293)
			(xy 54.814734 -280.993449) (xy 54.768718 -280.975997) (xy 54.726097 -280.95139) (xy 54.687976 -280.920265)
			(xy 54.655341 -280.883428) (xy 54.629038 -280.841832) (xy 54.609747 -280.796556) (xy 54.59797 -280.748772)
			(xy 54.59401 -280.699718) (xy 53.305202 -280.699718) (xy 53.304707 -280.724325) (xy 53.296812 -280.772902)
			(xy 53.281228 -280.819583) (xy 53.258357 -280.86316) (xy 53.228792 -280.902504) (xy 53.193299 -280.936596)
			(xy 53.152796 -280.964552) (xy 53.108334 -280.98565) (xy 53.061063 -280.999342) (xy 53.012208 -281.005274)
			(xy 52.963033 -281.003293) (xy 52.914814 -280.993449) (xy 52.868798 -280.975997) (xy 52.826177 -280.95139)
			(xy 52.788056 -280.920265) (xy 52.755421 -280.883428) (xy 52.729118 -280.841832) (xy 52.709827 -280.796556)
			(xy 52.69805 -280.748772) (xy 52.69409 -280.699718) (xy 51.405282 -280.699718) (xy 51.404787 -280.724325)
			(xy 51.396892 -280.772902) (xy 51.381308 -280.819583) (xy 51.358437 -280.86316) (xy 51.328872 -280.902504)
			(xy 51.293379 -280.936596) (xy 51.252876 -280.964552) (xy 51.208414 -280.98565) (xy 51.161143 -280.999342)
			(xy 51.112288 -281.005274) (xy 51.063113 -281.003293) (xy 51.014894 -280.993449) (xy 50.968878 -280.975997)
			(xy 50.926257 -280.95139) (xy 50.888136 -280.920265) (xy 50.855501 -280.883428) (xy 50.829198 -280.841832)
			(xy 50.809907 -280.796556) (xy 50.79813 -280.748772) (xy 50.79417 -280.699718) (xy 49.505108 -280.699718)
			(xy 49.504613 -280.724325) (xy 49.496718 -280.772902) (xy 49.481134 -280.819583) (xy 49.458263 -280.86316)
			(xy 49.428698 -280.902504) (xy 49.393205 -280.936596) (xy 49.352702 -280.964552) (xy 49.30824 -280.98565)
			(xy 49.260969 -280.999342) (xy 49.212114 -281.005274) (xy 49.162939 -281.003293) (xy 49.11472 -280.993449)
			(xy 49.068704 -280.975997) (xy 49.026083 -280.95139) (xy 48.987962 -280.920265) (xy 48.955327 -280.883428)
			(xy 48.929024 -280.841832) (xy 48.909733 -280.796556) (xy 48.897956 -280.748772) (xy 48.893996 -280.699718)
			(xy 47.605188 -280.699718) (xy 47.604693 -280.724325) (xy 47.596798 -280.772902) (xy 47.581214 -280.819583)
			(xy 47.558343 -280.86316) (xy 47.528778 -280.902504) (xy 47.493285 -280.936596) (xy 47.452782 -280.964552)
			(xy 47.40832 -280.98565) (xy 47.361049 -280.999342) (xy 47.312194 -281.005274) (xy 47.263019 -281.003293)
			(xy 47.2148 -280.993449) (xy 47.168784 -280.975997) (xy 47.126163 -280.95139) (xy 47.088042 -280.920265)
			(xy 47.055407 -280.883428) (xy 47.029104 -280.841832) (xy 47.009813 -280.796556) (xy 46.998036 -280.748772)
			(xy 46.994076 -280.699718) (xy 45.705268 -280.699718) (xy 45.704773 -280.724325) (xy 45.696878 -280.772902)
			(xy 45.681294 -280.819583) (xy 45.658423 -280.86316) (xy 45.628858 -280.902504) (xy 45.593365 -280.936596)
			(xy 45.552862 -280.964552) (xy 45.5084 -280.98565) (xy 45.461129 -280.999342) (xy 45.412274 -281.005274)
			(xy 45.363099 -281.003293) (xy 45.31488 -280.993449) (xy 45.268864 -280.975997) (xy 45.226243 -280.95139)
			(xy 45.188122 -280.920265) (xy 45.155487 -280.883428) (xy 45.129184 -280.841832) (xy 45.109893 -280.796556)
			(xy 45.098116 -280.748772) (xy 45.094156 -280.699718) (xy 0.508 -280.699718) (xy 0.508 -282.599892)
			(xy 76.444106 -282.599892) (xy 76.448066 -282.550838) (xy 76.459843 -282.503054) (xy 76.479134 -282.457778)
			(xy 76.505437 -282.416182) (xy 76.538072 -282.379345) (xy 76.576193 -282.34822) (xy 76.618814 -282.323613)
			(xy 76.66483 -282.306161) (xy 76.713049 -282.296317) (xy 76.762224 -282.294336) (xy 76.811079 -282.300268)
			(xy 76.85835 -282.31396) (xy 76.902812 -282.335058) (xy 76.943315 -282.363014) (xy 76.978808 -282.397106)
			(xy 77.008373 -282.43645) (xy 77.031244 -282.480027) (xy 77.046828 -282.526708) (xy 77.054723 -282.575285)
			(xy 77.055218 -282.599892) (xy 77.394066 -282.599892) (xy 77.398026 -282.550838) (xy 77.409803 -282.503054)
			(xy 77.429094 -282.457778) (xy 77.455397 -282.416182) (xy 77.488032 -282.379345) (xy 77.526153 -282.34822)
			(xy 77.568774 -282.323613) (xy 77.61479 -282.306161) (xy 77.663009 -282.296317) (xy 77.712184 -282.294336)
			(xy 77.761039 -282.300268) (xy 77.80831 -282.31396) (xy 77.852772 -282.335058) (xy 77.893275 -282.363014)
			(xy 77.928768 -282.397106) (xy 77.958333 -282.43645) (xy 77.981204 -282.480027) (xy 77.996788 -282.526708)
			(xy 78.004683 -282.575285) (xy 78.005178 -282.599892) (xy 192.544204 -282.599892) (xy 192.548164 -282.550838)
			(xy 192.559941 -282.503054) (xy 192.579232 -282.457778) (xy 192.605535 -282.416182) (xy 192.63817 -282.379345)
			(xy 192.676291 -282.34822) (xy 192.718912 -282.323613) (xy 192.764928 -282.306161) (xy 192.813147 -282.296317)
			(xy 192.862322 -282.294336) (xy 192.911177 -282.300268) (xy 192.958448 -282.31396) (xy 193.00291 -282.335058)
			(xy 193.043413 -282.363014) (xy 193.078906 -282.397106) (xy 193.108471 -282.43645) (xy 193.131342 -282.480027)
			(xy 193.146926 -282.526708) (xy 193.154821 -282.575285) (xy 193.155316 -282.599892) (xy 193.494164 -282.599892)
			(xy 193.498124 -282.550838) (xy 193.509901 -282.503054) (xy 193.529192 -282.457778) (xy 193.555495 -282.416182)
			(xy 193.58813 -282.379345) (xy 193.626251 -282.34822) (xy 193.668872 -282.323613) (xy 193.714888 -282.306161)
			(xy 193.763107 -282.296317) (xy 193.812282 -282.294336) (xy 193.861137 -282.300268) (xy 193.908408 -282.31396)
			(xy 193.95287 -282.335058) (xy 193.993373 -282.363014) (xy 194.028866 -282.397106) (xy 194.058431 -282.43645)
			(xy 194.081302 -282.480027) (xy 194.096886 -282.526708) (xy 194.104781 -282.575285) (xy 194.105276 -282.599892)
			(xy 308.644048 -282.599892) (xy 308.648008 -282.550838) (xy 308.659785 -282.503054) (xy 308.679076 -282.457778)
			(xy 308.705379 -282.416182) (xy 308.738014 -282.379345) (xy 308.776135 -282.34822) (xy 308.818756 -282.323613)
			(xy 308.864772 -282.306161) (xy 308.912991 -282.296317) (xy 308.962166 -282.294336) (xy 309.011021 -282.300268)
			(xy 309.058292 -282.31396) (xy 309.102754 -282.335058) (xy 309.143257 -282.363014) (xy 309.17875 -282.397106)
			(xy 309.208315 -282.43645) (xy 309.231186 -282.480027) (xy 309.24677 -282.526708) (xy 309.254665 -282.575285)
			(xy 309.25516 -282.599892) (xy 309.594008 -282.599892) (xy 309.597968 -282.550838) (xy 309.609745 -282.503054)
			(xy 309.629036 -282.457778) (xy 309.655339 -282.416182) (xy 309.687974 -282.379345) (xy 309.726095 -282.34822)
			(xy 309.768716 -282.323613) (xy 309.814732 -282.306161) (xy 309.862951 -282.296317) (xy 309.912126 -282.294336)
			(xy 309.960981 -282.300268) (xy 310.008252 -282.31396) (xy 310.052714 -282.335058) (xy 310.093217 -282.363014)
			(xy 310.12871 -282.397106) (xy 310.158275 -282.43645) (xy 310.181146 -282.480027) (xy 310.19673 -282.526708)
			(xy 310.204625 -282.575285) (xy 310.20512 -282.599892) (xy 424.744146 -282.599892) (xy 424.748106 -282.550838)
			(xy 424.759883 -282.503054) (xy 424.779174 -282.457778) (xy 424.805477 -282.416182) (xy 424.838112 -282.379345)
			(xy 424.876233 -282.34822) (xy 424.918854 -282.323613) (xy 424.96487 -282.306161) (xy 425.013089 -282.296317)
			(xy 425.062264 -282.294336) (xy 425.111119 -282.300268) (xy 425.15839 -282.31396) (xy 425.202852 -282.335058)
			(xy 425.243355 -282.363014) (xy 425.278848 -282.397106) (xy 425.308413 -282.43645) (xy 425.331284 -282.480027)
			(xy 425.346868 -282.526708) (xy 425.354763 -282.575285) (xy 425.355258 -282.599892) (xy 425.694106 -282.599892)
			(xy 425.698066 -282.550838) (xy 425.709843 -282.503054) (xy 425.729134 -282.457778) (xy 425.755437 -282.416182)
			(xy 425.788072 -282.379345) (xy 425.826193 -282.34822) (xy 425.868814 -282.323613) (xy 425.91483 -282.306161)
			(xy 425.963049 -282.296317) (xy 426.012224 -282.294336) (xy 426.061079 -282.300268) (xy 426.10835 -282.31396)
			(xy 426.152812 -282.335058) (xy 426.193315 -282.363014) (xy 426.228808 -282.397106) (xy 426.258373 -282.43645)
			(xy 426.281244 -282.480027) (xy 426.296828 -282.526708) (xy 426.304723 -282.575285) (xy 426.305218 -282.599892)
			(xy 426.304723 -282.624499) (xy 426.296828 -282.673076) (xy 426.281244 -282.719757) (xy 426.258373 -282.763334)
			(xy 426.228808 -282.802678) (xy 426.193315 -282.83677) (xy 426.152812 -282.864726) (xy 426.10835 -282.885824)
			(xy 426.061079 -282.899516) (xy 426.012224 -282.905448) (xy 425.963049 -282.903467) (xy 425.91483 -282.893623)
			(xy 425.868814 -282.876171) (xy 425.826193 -282.851564) (xy 425.788072 -282.820439) (xy 425.755437 -282.783602)
			(xy 425.729134 -282.742006) (xy 425.709843 -282.69673) (xy 425.698066 -282.648946) (xy 425.694106 -282.599892)
			(xy 425.355258 -282.599892) (xy 425.354763 -282.624499) (xy 425.346868 -282.673076) (xy 425.331284 -282.719757)
			(xy 425.308413 -282.763334) (xy 425.278848 -282.802678) (xy 425.243355 -282.83677) (xy 425.202852 -282.864726)
			(xy 425.15839 -282.885824) (xy 425.111119 -282.899516) (xy 425.062264 -282.905448) (xy 425.013089 -282.903467)
			(xy 424.96487 -282.893623) (xy 424.918854 -282.876171) (xy 424.876233 -282.851564) (xy 424.838112 -282.820439)
			(xy 424.805477 -282.783602) (xy 424.779174 -282.742006) (xy 424.759883 -282.69673) (xy 424.748106 -282.648946)
			(xy 424.744146 -282.599892) (xy 310.20512 -282.599892) (xy 310.204625 -282.624499) (xy 310.19673 -282.673076)
			(xy 310.181146 -282.719757) (xy 310.158275 -282.763334) (xy 310.12871 -282.802678) (xy 310.093217 -282.83677)
			(xy 310.052714 -282.864726) (xy 310.008252 -282.885824) (xy 309.960981 -282.899516) (xy 309.912126 -282.905448)
			(xy 309.862951 -282.903467) (xy 309.814732 -282.893623) (xy 309.768716 -282.876171) (xy 309.726095 -282.851564)
			(xy 309.687974 -282.820439) (xy 309.655339 -282.783602) (xy 309.629036 -282.742006) (xy 309.609745 -282.69673)
			(xy 309.597968 -282.648946) (xy 309.594008 -282.599892) (xy 309.25516 -282.599892) (xy 309.254665 -282.624499)
			(xy 309.24677 -282.673076) (xy 309.231186 -282.719757) (xy 309.208315 -282.763334) (xy 309.17875 -282.802678)
			(xy 309.143257 -282.83677) (xy 309.102754 -282.864726) (xy 309.058292 -282.885824) (xy 309.011021 -282.899516)
			(xy 308.962166 -282.905448) (xy 308.912991 -282.903467) (xy 308.864772 -282.893623) (xy 308.818756 -282.876171)
			(xy 308.776135 -282.851564) (xy 308.738014 -282.820439) (xy 308.705379 -282.783602) (xy 308.679076 -282.742006)
			(xy 308.659785 -282.69673) (xy 308.648008 -282.648946) (xy 308.644048 -282.599892) (xy 194.105276 -282.599892)
			(xy 194.104781 -282.624499) (xy 194.096886 -282.673076) (xy 194.081302 -282.719757) (xy 194.058431 -282.763334)
			(xy 194.028866 -282.802678) (xy 193.993373 -282.83677) (xy 193.95287 -282.864726) (xy 193.908408 -282.885824)
			(xy 193.861137 -282.899516) (xy 193.812282 -282.905448) (xy 193.763107 -282.903467) (xy 193.714888 -282.893623)
			(xy 193.668872 -282.876171) (xy 193.626251 -282.851564) (xy 193.58813 -282.820439) (xy 193.555495 -282.783602)
			(xy 193.529192 -282.742006) (xy 193.509901 -282.69673) (xy 193.498124 -282.648946) (xy 193.494164 -282.599892)
			(xy 193.155316 -282.599892) (xy 193.154821 -282.624499) (xy 193.146926 -282.673076) (xy 193.131342 -282.719757)
			(xy 193.108471 -282.763334) (xy 193.078906 -282.802678) (xy 193.043413 -282.83677) (xy 193.00291 -282.864726)
			(xy 192.958448 -282.885824) (xy 192.911177 -282.899516) (xy 192.862322 -282.905448) (xy 192.813147 -282.903467)
			(xy 192.764928 -282.893623) (xy 192.718912 -282.876171) (xy 192.676291 -282.851564) (xy 192.63817 -282.820439)
			(xy 192.605535 -282.783602) (xy 192.579232 -282.742006) (xy 192.559941 -282.69673) (xy 192.548164 -282.648946)
			(xy 192.544204 -282.599892) (xy 78.005178 -282.599892) (xy 78.004683 -282.624499) (xy 77.996788 -282.673076)
			(xy 77.981204 -282.719757) (xy 77.958333 -282.763334) (xy 77.928768 -282.802678) (xy 77.893275 -282.83677)
			(xy 77.852772 -282.864726) (xy 77.80831 -282.885824) (xy 77.761039 -282.899516) (xy 77.712184 -282.905448)
			(xy 77.663009 -282.903467) (xy 77.61479 -282.893623) (xy 77.568774 -282.876171) (xy 77.526153 -282.851564)
			(xy 77.488032 -282.820439) (xy 77.455397 -282.783602) (xy 77.429094 -282.742006) (xy 77.409803 -282.69673)
			(xy 77.398026 -282.648946) (xy 77.394066 -282.599892) (xy 77.055218 -282.599892) (xy 77.054723 -282.624499)
			(xy 77.046828 -282.673076) (xy 77.031244 -282.719757) (xy 77.008373 -282.763334) (xy 76.978808 -282.802678)
			(xy 76.943315 -282.83677) (xy 76.902812 -282.864726) (xy 76.85835 -282.885824) (xy 76.811079 -282.899516)
			(xy 76.762224 -282.905448) (xy 76.713049 -282.903467) (xy 76.66483 -282.893623) (xy 76.618814 -282.876171)
			(xy 76.576193 -282.851564) (xy 76.538072 -282.820439) (xy 76.505437 -282.783602) (xy 76.479134 -282.742006)
			(xy 76.459843 -282.69673) (xy 76.448066 -282.648946) (xy 76.444106 -282.599892) (xy 0.508 -282.599892)
			(xy 0.508 -283.549852) (xy 74.543932 -283.549852) (xy 74.547892 -283.500798) (xy 74.559669 -283.453014)
			(xy 74.57896 -283.407738) (xy 74.605263 -283.366142) (xy 74.637898 -283.329305) (xy 74.676019 -283.29818)
			(xy 74.71864 -283.273573) (xy 74.764656 -283.256121) (xy 74.812875 -283.246277) (xy 74.86205 -283.244296)
			(xy 74.910905 -283.250228) (xy 74.958176 -283.26392) (xy 75.002638 -283.285018) (xy 75.043141 -283.312974)
			(xy 75.078634 -283.347066) (xy 75.108199 -283.38641) (xy 75.13107 -283.429987) (xy 75.146654 -283.476668)
			(xy 75.154549 -283.525245) (xy 75.155044 -283.549852) (xy 75.494146 -283.549852) (xy 75.498106 -283.500798)
			(xy 75.509883 -283.453014) (xy 75.529174 -283.407738) (xy 75.555477 -283.366142) (xy 75.588112 -283.329305)
			(xy 75.626233 -283.29818) (xy 75.668854 -283.273573) (xy 75.71487 -283.256121) (xy 75.763089 -283.246277)
			(xy 75.812264 -283.244296) (xy 75.861119 -283.250228) (xy 75.90839 -283.26392) (xy 75.952852 -283.285018)
			(xy 75.993355 -283.312974) (xy 76.028848 -283.347066) (xy 76.058413 -283.38641) (xy 76.081284 -283.429987)
			(xy 76.096868 -283.476668) (xy 76.104763 -283.525245) (xy 76.105258 -283.549852) (xy 190.64403 -283.549852)
			(xy 190.64799 -283.500798) (xy 190.659767 -283.453014) (xy 190.679058 -283.407738) (xy 190.705361 -283.366142)
			(xy 190.737996 -283.329305) (xy 190.776117 -283.29818) (xy 190.818738 -283.273573) (xy 190.864754 -283.256121)
			(xy 190.912973 -283.246277) (xy 190.962148 -283.244296) (xy 191.011003 -283.250228) (xy 191.058274 -283.26392)
			(xy 191.102736 -283.285018) (xy 191.143239 -283.312974) (xy 191.178732 -283.347066) (xy 191.208297 -283.38641)
			(xy 191.231168 -283.429987) (xy 191.246752 -283.476668) (xy 191.254647 -283.525245) (xy 191.255142 -283.549852)
			(xy 191.594244 -283.549852) (xy 191.598204 -283.500798) (xy 191.609981 -283.453014) (xy 191.629272 -283.407738)
			(xy 191.655575 -283.366142) (xy 191.68821 -283.329305) (xy 191.726331 -283.29818) (xy 191.768952 -283.273573)
			(xy 191.814968 -283.256121) (xy 191.863187 -283.246277) (xy 191.912362 -283.244296) (xy 191.961217 -283.250228)
			(xy 192.008488 -283.26392) (xy 192.05295 -283.285018) (xy 192.093453 -283.312974) (xy 192.128946 -283.347066)
			(xy 192.158511 -283.38641) (xy 192.181382 -283.429987) (xy 192.196966 -283.476668) (xy 192.204861 -283.525245)
			(xy 192.205356 -283.549852) (xy 306.744128 -283.549852) (xy 306.748088 -283.500798) (xy 306.759865 -283.453014)
			(xy 306.779156 -283.407738) (xy 306.805459 -283.366142) (xy 306.838094 -283.329305) (xy 306.876215 -283.29818)
			(xy 306.918836 -283.273573) (xy 306.964852 -283.256121) (xy 307.013071 -283.246277) (xy 307.062246 -283.244296)
			(xy 307.111101 -283.250228) (xy 307.158372 -283.26392) (xy 307.202834 -283.285018) (xy 307.243337 -283.312974)
			(xy 307.27883 -283.347066) (xy 307.308395 -283.38641) (xy 307.331266 -283.429987) (xy 307.34685 -283.476668)
			(xy 307.354745 -283.525245) (xy 307.35524 -283.549852) (xy 307.694088 -283.549852) (xy 307.698048 -283.500798)
			(xy 307.709825 -283.453014) (xy 307.729116 -283.407738) (xy 307.755419 -283.366142) (xy 307.788054 -283.329305)
			(xy 307.826175 -283.29818) (xy 307.868796 -283.273573) (xy 307.914812 -283.256121) (xy 307.963031 -283.246277)
			(xy 308.012206 -283.244296) (xy 308.061061 -283.250228) (xy 308.108332 -283.26392) (xy 308.152794 -283.285018)
			(xy 308.193297 -283.312974) (xy 308.22879 -283.347066) (xy 308.258355 -283.38641) (xy 308.281226 -283.429987)
			(xy 308.29681 -283.476668) (xy 308.304705 -283.525245) (xy 308.3052 -283.549852) (xy 422.844226 -283.549852)
			(xy 422.848186 -283.500798) (xy 422.859963 -283.453014) (xy 422.879254 -283.407738) (xy 422.905557 -283.366142)
			(xy 422.938192 -283.329305) (xy 422.976313 -283.29818) (xy 423.018934 -283.273573) (xy 423.06495 -283.256121)
			(xy 423.113169 -283.246277) (xy 423.162344 -283.244296) (xy 423.211199 -283.250228) (xy 423.25847 -283.26392)
			(xy 423.302932 -283.285018) (xy 423.343435 -283.312974) (xy 423.378928 -283.347066) (xy 423.408493 -283.38641)
			(xy 423.431364 -283.429987) (xy 423.446948 -283.476668) (xy 423.454843 -283.525245) (xy 423.455338 -283.549852)
			(xy 423.794186 -283.549852) (xy 423.798146 -283.500798) (xy 423.809923 -283.453014) (xy 423.829214 -283.407738)
			(xy 423.855517 -283.366142) (xy 423.888152 -283.329305) (xy 423.926273 -283.29818) (xy 423.968894 -283.273573)
			(xy 424.01491 -283.256121) (xy 424.063129 -283.246277) (xy 424.112304 -283.244296) (xy 424.161159 -283.250228)
			(xy 424.20843 -283.26392) (xy 424.252892 -283.285018) (xy 424.293395 -283.312974) (xy 424.328888 -283.347066)
			(xy 424.358453 -283.38641) (xy 424.381324 -283.429987) (xy 424.396908 -283.476668) (xy 424.404803 -283.525245)
			(xy 424.405298 -283.549852) (xy 424.404803 -283.574459) (xy 424.396908 -283.623036) (xy 424.381324 -283.669717)
			(xy 424.358453 -283.713294) (xy 424.328888 -283.752638) (xy 424.293395 -283.78673) (xy 424.252892 -283.814686)
			(xy 424.20843 -283.835784) (xy 424.161159 -283.849476) (xy 424.112304 -283.855408) (xy 424.063129 -283.853427)
			(xy 424.01491 -283.843583) (xy 423.968894 -283.826131) (xy 423.926273 -283.801524) (xy 423.888152 -283.770399)
			(xy 423.855517 -283.733562) (xy 423.829214 -283.691966) (xy 423.809923 -283.64669) (xy 423.798146 -283.598906)
			(xy 423.794186 -283.549852) (xy 423.455338 -283.549852) (xy 423.454843 -283.574459) (xy 423.446948 -283.623036)
			(xy 423.431364 -283.669717) (xy 423.408493 -283.713294) (xy 423.378928 -283.752638) (xy 423.343435 -283.78673)
			(xy 423.302932 -283.814686) (xy 423.25847 -283.835784) (xy 423.211199 -283.849476) (xy 423.162344 -283.855408)
			(xy 423.113169 -283.853427) (xy 423.06495 -283.843583) (xy 423.018934 -283.826131) (xy 422.976313 -283.801524)
			(xy 422.938192 -283.770399) (xy 422.905557 -283.733562) (xy 422.879254 -283.691966) (xy 422.859963 -283.64669)
			(xy 422.848186 -283.598906) (xy 422.844226 -283.549852) (xy 308.3052 -283.549852) (xy 308.304705 -283.574459)
			(xy 308.29681 -283.623036) (xy 308.281226 -283.669717) (xy 308.258355 -283.713294) (xy 308.22879 -283.752638)
			(xy 308.193297 -283.78673) (xy 308.152794 -283.814686) (xy 308.108332 -283.835784) (xy 308.061061 -283.849476)
			(xy 308.012206 -283.855408) (xy 307.963031 -283.853427) (xy 307.914812 -283.843583) (xy 307.868796 -283.826131)
			(xy 307.826175 -283.801524) (xy 307.788054 -283.770399) (xy 307.755419 -283.733562) (xy 307.729116 -283.691966)
			(xy 307.709825 -283.64669) (xy 307.698048 -283.598906) (xy 307.694088 -283.549852) (xy 307.35524 -283.549852)
			(xy 307.354745 -283.574459) (xy 307.34685 -283.623036) (xy 307.331266 -283.669717) (xy 307.308395 -283.713294)
			(xy 307.27883 -283.752638) (xy 307.243337 -283.78673) (xy 307.202834 -283.814686) (xy 307.158372 -283.835784)
			(xy 307.111101 -283.849476) (xy 307.062246 -283.855408) (xy 307.013071 -283.853427) (xy 306.964852 -283.843583)
			(xy 306.918836 -283.826131) (xy 306.876215 -283.801524) (xy 306.838094 -283.770399) (xy 306.805459 -283.733562)
			(xy 306.779156 -283.691966) (xy 306.759865 -283.64669) (xy 306.748088 -283.598906) (xy 306.744128 -283.549852)
			(xy 192.205356 -283.549852) (xy 192.204861 -283.574459) (xy 192.196966 -283.623036) (xy 192.181382 -283.669717)
			(xy 192.158511 -283.713294) (xy 192.128946 -283.752638) (xy 192.093453 -283.78673) (xy 192.05295 -283.814686)
			(xy 192.008488 -283.835784) (xy 191.961217 -283.849476) (xy 191.912362 -283.855408) (xy 191.863187 -283.853427)
			(xy 191.814968 -283.843583) (xy 191.768952 -283.826131) (xy 191.726331 -283.801524) (xy 191.68821 -283.770399)
			(xy 191.655575 -283.733562) (xy 191.629272 -283.691966) (xy 191.609981 -283.64669) (xy 191.598204 -283.598906)
			(xy 191.594244 -283.549852) (xy 191.255142 -283.549852) (xy 191.254647 -283.574459) (xy 191.246752 -283.623036)
			(xy 191.231168 -283.669717) (xy 191.208297 -283.713294) (xy 191.178732 -283.752638) (xy 191.143239 -283.78673)
			(xy 191.102736 -283.814686) (xy 191.058274 -283.835784) (xy 191.011003 -283.849476) (xy 190.962148 -283.855408)
			(xy 190.912973 -283.853427) (xy 190.864754 -283.843583) (xy 190.818738 -283.826131) (xy 190.776117 -283.801524)
			(xy 190.737996 -283.770399) (xy 190.705361 -283.733562) (xy 190.679058 -283.691966) (xy 190.659767 -283.64669)
			(xy 190.64799 -283.598906) (xy 190.64403 -283.549852) (xy 76.105258 -283.549852) (xy 76.104763 -283.574459)
			(xy 76.096868 -283.623036) (xy 76.081284 -283.669717) (xy 76.058413 -283.713294) (xy 76.028848 -283.752638)
			(xy 75.993355 -283.78673) (xy 75.952852 -283.814686) (xy 75.90839 -283.835784) (xy 75.861119 -283.849476)
			(xy 75.812264 -283.855408) (xy 75.763089 -283.853427) (xy 75.71487 -283.843583) (xy 75.668854 -283.826131)
			(xy 75.626233 -283.801524) (xy 75.588112 -283.770399) (xy 75.555477 -283.733562) (xy 75.529174 -283.691966)
			(xy 75.509883 -283.64669) (xy 75.498106 -283.598906) (xy 75.494146 -283.549852) (xy 75.155044 -283.549852)
			(xy 75.154549 -283.574459) (xy 75.146654 -283.623036) (xy 75.13107 -283.669717) (xy 75.108199 -283.713294)
			(xy 75.078634 -283.752638) (xy 75.043141 -283.78673) (xy 75.002638 -283.814686) (xy 74.958176 -283.835784)
			(xy 74.910905 -283.849476) (xy 74.86205 -283.855408) (xy 74.812875 -283.853427) (xy 74.764656 -283.843583)
			(xy 74.71864 -283.826131) (xy 74.676019 -283.801524) (xy 74.637898 -283.770399) (xy 74.605263 -283.733562)
			(xy 74.57896 -283.691966) (xy 74.559669 -283.64669) (xy 74.547892 -283.598906) (xy 74.543932 -283.549852)
			(xy 0.508 -283.549852) (xy 0.508 -284.499812) (xy 76.444106 -284.499812) (xy 76.448066 -284.450758)
			(xy 76.459843 -284.402974) (xy 76.479134 -284.357698) (xy 76.505437 -284.316102) (xy 76.538072 -284.279265)
			(xy 76.576193 -284.24814) (xy 76.618814 -284.223533) (xy 76.66483 -284.206081) (xy 76.713049 -284.196237)
			(xy 76.762224 -284.194256) (xy 76.811079 -284.200188) (xy 76.85835 -284.21388) (xy 76.902812 -284.234978)
			(xy 76.943315 -284.262934) (xy 76.978808 -284.297026) (xy 77.008373 -284.33637) (xy 77.031244 -284.379947)
			(xy 77.046828 -284.426628) (xy 77.054723 -284.475205) (xy 77.055218 -284.499812) (xy 77.394066 -284.499812)
			(xy 77.398026 -284.450758) (xy 77.409803 -284.402974) (xy 77.429094 -284.357698) (xy 77.455397 -284.316102)
			(xy 77.488032 -284.279265) (xy 77.526153 -284.24814) (xy 77.568774 -284.223533) (xy 77.61479 -284.206081)
			(xy 77.663009 -284.196237) (xy 77.712184 -284.194256) (xy 77.761039 -284.200188) (xy 77.80831 -284.21388)
			(xy 77.852772 -284.234978) (xy 77.893275 -284.262934) (xy 77.928768 -284.297026) (xy 77.958333 -284.33637)
			(xy 77.981204 -284.379947) (xy 77.996788 -284.426628) (xy 78.004683 -284.475205) (xy 78.005178 -284.499812)
			(xy 192.544204 -284.499812) (xy 192.548164 -284.450758) (xy 192.559941 -284.402974) (xy 192.579232 -284.357698)
			(xy 192.605535 -284.316102) (xy 192.63817 -284.279265) (xy 192.676291 -284.24814) (xy 192.718912 -284.223533)
			(xy 192.764928 -284.206081) (xy 192.813147 -284.196237) (xy 192.862322 -284.194256) (xy 192.911177 -284.200188)
			(xy 192.958448 -284.21388) (xy 193.00291 -284.234978) (xy 193.043413 -284.262934) (xy 193.078906 -284.297026)
			(xy 193.108471 -284.33637) (xy 193.131342 -284.379947) (xy 193.146926 -284.426628) (xy 193.154821 -284.475205)
			(xy 193.155316 -284.499812) (xy 193.494164 -284.499812) (xy 193.498124 -284.450758) (xy 193.509901 -284.402974)
			(xy 193.529192 -284.357698) (xy 193.555495 -284.316102) (xy 193.58813 -284.279265) (xy 193.626251 -284.24814)
			(xy 193.668872 -284.223533) (xy 193.714888 -284.206081) (xy 193.763107 -284.196237) (xy 193.812282 -284.194256)
			(xy 193.861137 -284.200188) (xy 193.908408 -284.21388) (xy 193.95287 -284.234978) (xy 193.993373 -284.262934)
			(xy 194.028866 -284.297026) (xy 194.058431 -284.33637) (xy 194.081302 -284.379947) (xy 194.096886 -284.426628)
			(xy 194.104781 -284.475205) (xy 194.105276 -284.499812) (xy 308.644048 -284.499812) (xy 308.648008 -284.450758)
			(xy 308.659785 -284.402974) (xy 308.679076 -284.357698) (xy 308.705379 -284.316102) (xy 308.738014 -284.279265)
			(xy 308.776135 -284.24814) (xy 308.818756 -284.223533) (xy 308.864772 -284.206081) (xy 308.912991 -284.196237)
			(xy 308.962166 -284.194256) (xy 309.011021 -284.200188) (xy 309.058292 -284.21388) (xy 309.102754 -284.234978)
			(xy 309.143257 -284.262934) (xy 309.17875 -284.297026) (xy 309.208315 -284.33637) (xy 309.231186 -284.379947)
			(xy 309.24677 -284.426628) (xy 309.254665 -284.475205) (xy 309.25516 -284.499812) (xy 309.594008 -284.499812)
			(xy 309.597968 -284.450758) (xy 309.609745 -284.402974) (xy 309.629036 -284.357698) (xy 309.655339 -284.316102)
			(xy 309.687974 -284.279265) (xy 309.726095 -284.24814) (xy 309.768716 -284.223533) (xy 309.814732 -284.206081)
			(xy 309.862951 -284.196237) (xy 309.912126 -284.194256) (xy 309.960981 -284.200188) (xy 310.008252 -284.21388)
			(xy 310.052714 -284.234978) (xy 310.093217 -284.262934) (xy 310.12871 -284.297026) (xy 310.158275 -284.33637)
			(xy 310.181146 -284.379947) (xy 310.19673 -284.426628) (xy 310.204625 -284.475205) (xy 310.20512 -284.499812)
			(xy 424.744146 -284.499812) (xy 424.748106 -284.450758) (xy 424.759883 -284.402974) (xy 424.779174 -284.357698)
			(xy 424.805477 -284.316102) (xy 424.838112 -284.279265) (xy 424.876233 -284.24814) (xy 424.918854 -284.223533)
			(xy 424.96487 -284.206081) (xy 425.013089 -284.196237) (xy 425.062264 -284.194256) (xy 425.111119 -284.200188)
			(xy 425.15839 -284.21388) (xy 425.202852 -284.234978) (xy 425.243355 -284.262934) (xy 425.278848 -284.297026)
			(xy 425.308413 -284.33637) (xy 425.331284 -284.379947) (xy 425.346868 -284.426628) (xy 425.354763 -284.475205)
			(xy 425.355258 -284.499812) (xy 425.694106 -284.499812) (xy 425.698066 -284.450758) (xy 425.709843 -284.402974)
			(xy 425.729134 -284.357698) (xy 425.755437 -284.316102) (xy 425.788072 -284.279265) (xy 425.826193 -284.24814)
			(xy 425.868814 -284.223533) (xy 425.91483 -284.206081) (xy 425.963049 -284.196237) (xy 426.012224 -284.194256)
			(xy 426.061079 -284.200188) (xy 426.10835 -284.21388) (xy 426.152812 -284.234978) (xy 426.193315 -284.262934)
			(xy 426.228808 -284.297026) (xy 426.258373 -284.33637) (xy 426.281244 -284.379947) (xy 426.296828 -284.426628)
			(xy 426.304723 -284.475205) (xy 426.305218 -284.499812) (xy 426.304723 -284.524419) (xy 426.296828 -284.572996)
			(xy 426.281244 -284.619677) (xy 426.258373 -284.663254) (xy 426.228808 -284.702598) (xy 426.193315 -284.73669)
			(xy 426.152812 -284.764646) (xy 426.10835 -284.785744) (xy 426.061079 -284.799436) (xy 426.012224 -284.805368)
			(xy 425.963049 -284.803387) (xy 425.91483 -284.793543) (xy 425.868814 -284.776091) (xy 425.826193 -284.751484)
			(xy 425.788072 -284.720359) (xy 425.755437 -284.683522) (xy 425.729134 -284.641926) (xy 425.709843 -284.59665)
			(xy 425.698066 -284.548866) (xy 425.694106 -284.499812) (xy 425.355258 -284.499812) (xy 425.354763 -284.524419)
			(xy 425.346868 -284.572996) (xy 425.331284 -284.619677) (xy 425.308413 -284.663254) (xy 425.278848 -284.702598)
			(xy 425.243355 -284.73669) (xy 425.202852 -284.764646) (xy 425.15839 -284.785744) (xy 425.111119 -284.799436)
			(xy 425.062264 -284.805368) (xy 425.013089 -284.803387) (xy 424.96487 -284.793543) (xy 424.918854 -284.776091)
			(xy 424.876233 -284.751484) (xy 424.838112 -284.720359) (xy 424.805477 -284.683522) (xy 424.779174 -284.641926)
			(xy 424.759883 -284.59665) (xy 424.748106 -284.548866) (xy 424.744146 -284.499812) (xy 310.20512 -284.499812)
			(xy 310.204625 -284.524419) (xy 310.19673 -284.572996) (xy 310.181146 -284.619677) (xy 310.158275 -284.663254)
			(xy 310.12871 -284.702598) (xy 310.093217 -284.73669) (xy 310.052714 -284.764646) (xy 310.008252 -284.785744)
			(xy 309.960981 -284.799436) (xy 309.912126 -284.805368) (xy 309.862951 -284.803387) (xy 309.814732 -284.793543)
			(xy 309.768716 -284.776091) (xy 309.726095 -284.751484) (xy 309.687974 -284.720359) (xy 309.655339 -284.683522)
			(xy 309.629036 -284.641926) (xy 309.609745 -284.59665) (xy 309.597968 -284.548866) (xy 309.594008 -284.499812)
			(xy 309.25516 -284.499812) (xy 309.254665 -284.524419) (xy 309.24677 -284.572996) (xy 309.231186 -284.619677)
			(xy 309.208315 -284.663254) (xy 309.17875 -284.702598) (xy 309.143257 -284.73669) (xy 309.102754 -284.764646)
			(xy 309.058292 -284.785744) (xy 309.011021 -284.799436) (xy 308.962166 -284.805368) (xy 308.912991 -284.803387)
			(xy 308.864772 -284.793543) (xy 308.818756 -284.776091) (xy 308.776135 -284.751484) (xy 308.738014 -284.720359)
			(xy 308.705379 -284.683522) (xy 308.679076 -284.641926) (xy 308.659785 -284.59665) (xy 308.648008 -284.548866)
			(xy 308.644048 -284.499812) (xy 194.105276 -284.499812) (xy 194.104781 -284.524419) (xy 194.096886 -284.572996)
			(xy 194.081302 -284.619677) (xy 194.058431 -284.663254) (xy 194.028866 -284.702598) (xy 193.993373 -284.73669)
			(xy 193.95287 -284.764646) (xy 193.908408 -284.785744) (xy 193.861137 -284.799436) (xy 193.812282 -284.805368)
			(xy 193.763107 -284.803387) (xy 193.714888 -284.793543) (xy 193.668872 -284.776091) (xy 193.626251 -284.751484)
			(xy 193.58813 -284.720359) (xy 193.555495 -284.683522) (xy 193.529192 -284.641926) (xy 193.509901 -284.59665)
			(xy 193.498124 -284.548866) (xy 193.494164 -284.499812) (xy 193.155316 -284.499812) (xy 193.154821 -284.524419)
			(xy 193.146926 -284.572996) (xy 193.131342 -284.619677) (xy 193.108471 -284.663254) (xy 193.078906 -284.702598)
			(xy 193.043413 -284.73669) (xy 193.00291 -284.764646) (xy 192.958448 -284.785744) (xy 192.911177 -284.799436)
			(xy 192.862322 -284.805368) (xy 192.813147 -284.803387) (xy 192.764928 -284.793543) (xy 192.718912 -284.776091)
			(xy 192.676291 -284.751484) (xy 192.63817 -284.720359) (xy 192.605535 -284.683522) (xy 192.579232 -284.641926)
			(xy 192.559941 -284.59665) (xy 192.548164 -284.548866) (xy 192.544204 -284.499812) (xy 78.005178 -284.499812)
			(xy 78.004683 -284.524419) (xy 77.996788 -284.572996) (xy 77.981204 -284.619677) (xy 77.958333 -284.663254)
			(xy 77.928768 -284.702598) (xy 77.893275 -284.73669) (xy 77.852772 -284.764646) (xy 77.80831 -284.785744)
			(xy 77.761039 -284.799436) (xy 77.712184 -284.805368) (xy 77.663009 -284.803387) (xy 77.61479 -284.793543)
			(xy 77.568774 -284.776091) (xy 77.526153 -284.751484) (xy 77.488032 -284.720359) (xy 77.455397 -284.683522)
			(xy 77.429094 -284.641926) (xy 77.409803 -284.59665) (xy 77.398026 -284.548866) (xy 77.394066 -284.499812)
			(xy 77.055218 -284.499812) (xy 77.054723 -284.524419) (xy 77.046828 -284.572996) (xy 77.031244 -284.619677)
			(xy 77.008373 -284.663254) (xy 76.978808 -284.702598) (xy 76.943315 -284.73669) (xy 76.902812 -284.764646)
			(xy 76.85835 -284.785744) (xy 76.811079 -284.799436) (xy 76.762224 -284.805368) (xy 76.713049 -284.803387)
			(xy 76.66483 -284.793543) (xy 76.618814 -284.776091) (xy 76.576193 -284.751484) (xy 76.538072 -284.720359)
			(xy 76.505437 -284.683522) (xy 76.479134 -284.641926) (xy 76.459843 -284.59665) (xy 76.448066 -284.548866)
			(xy 76.444106 -284.499812) (xy 0.508 -284.499812) (xy 0.508 -285.449772) (xy 74.543932 -285.449772)
			(xy 74.547892 -285.400718) (xy 74.559669 -285.352934) (xy 74.57896 -285.307658) (xy 74.605263 -285.266062)
			(xy 74.637898 -285.229225) (xy 74.676019 -285.1981) (xy 74.71864 -285.173493) (xy 74.764656 -285.156041)
			(xy 74.812875 -285.146197) (xy 74.86205 -285.144216) (xy 74.910905 -285.150148) (xy 74.958176 -285.16384)
			(xy 75.002638 -285.184938) (xy 75.043141 -285.212894) (xy 75.078634 -285.246986) (xy 75.108199 -285.28633)
			(xy 75.13107 -285.329907) (xy 75.146654 -285.376588) (xy 75.154549 -285.425165) (xy 75.155044 -285.449772)
			(xy 75.494146 -285.449772) (xy 75.498106 -285.400718) (xy 75.509883 -285.352934) (xy 75.529174 -285.307658)
			(xy 75.555477 -285.266062) (xy 75.588112 -285.229225) (xy 75.626233 -285.1981) (xy 75.668854 -285.173493)
			(xy 75.71487 -285.156041) (xy 75.763089 -285.146197) (xy 75.812264 -285.144216) (xy 75.861119 -285.150148)
			(xy 75.90839 -285.16384) (xy 75.952852 -285.184938) (xy 75.993355 -285.212894) (xy 76.028848 -285.246986)
			(xy 76.058413 -285.28633) (xy 76.081284 -285.329907) (xy 76.096868 -285.376588) (xy 76.104763 -285.425165)
			(xy 76.105258 -285.449772) (xy 190.64403 -285.449772) (xy 190.64799 -285.400718) (xy 190.659767 -285.352934)
			(xy 190.679058 -285.307658) (xy 190.705361 -285.266062) (xy 190.737996 -285.229225) (xy 190.776117 -285.1981)
			(xy 190.818738 -285.173493) (xy 190.864754 -285.156041) (xy 190.912973 -285.146197) (xy 190.962148 -285.144216)
			(xy 191.011003 -285.150148) (xy 191.058274 -285.16384) (xy 191.102736 -285.184938) (xy 191.143239 -285.212894)
			(xy 191.178732 -285.246986) (xy 191.208297 -285.28633) (xy 191.231168 -285.329907) (xy 191.246752 -285.376588)
			(xy 191.254647 -285.425165) (xy 191.255142 -285.449772) (xy 191.594244 -285.449772) (xy 191.598204 -285.400718)
			(xy 191.609981 -285.352934) (xy 191.629272 -285.307658) (xy 191.655575 -285.266062) (xy 191.68821 -285.229225)
			(xy 191.726331 -285.1981) (xy 191.768952 -285.173493) (xy 191.814968 -285.156041) (xy 191.863187 -285.146197)
			(xy 191.912362 -285.144216) (xy 191.961217 -285.150148) (xy 192.008488 -285.16384) (xy 192.05295 -285.184938)
			(xy 192.093453 -285.212894) (xy 192.128946 -285.246986) (xy 192.158511 -285.28633) (xy 192.181382 -285.329907)
			(xy 192.196966 -285.376588) (xy 192.204861 -285.425165) (xy 192.205356 -285.449772) (xy 306.744128 -285.449772)
			(xy 306.748088 -285.400718) (xy 306.759865 -285.352934) (xy 306.779156 -285.307658) (xy 306.805459 -285.266062)
			(xy 306.838094 -285.229225) (xy 306.876215 -285.1981) (xy 306.918836 -285.173493) (xy 306.964852 -285.156041)
			(xy 307.013071 -285.146197) (xy 307.062246 -285.144216) (xy 307.111101 -285.150148) (xy 307.158372 -285.16384)
			(xy 307.202834 -285.184938) (xy 307.243337 -285.212894) (xy 307.27883 -285.246986) (xy 307.308395 -285.28633)
			(xy 307.331266 -285.329907) (xy 307.34685 -285.376588) (xy 307.354745 -285.425165) (xy 307.35524 -285.449772)
			(xy 307.694088 -285.449772) (xy 307.698048 -285.400718) (xy 307.709825 -285.352934) (xy 307.729116 -285.307658)
			(xy 307.755419 -285.266062) (xy 307.788054 -285.229225) (xy 307.826175 -285.1981) (xy 307.868796 -285.173493)
			(xy 307.914812 -285.156041) (xy 307.963031 -285.146197) (xy 308.012206 -285.144216) (xy 308.061061 -285.150148)
			(xy 308.108332 -285.16384) (xy 308.152794 -285.184938) (xy 308.193297 -285.212894) (xy 308.22879 -285.246986)
			(xy 308.258355 -285.28633) (xy 308.281226 -285.329907) (xy 308.29681 -285.376588) (xy 308.304705 -285.425165)
			(xy 308.3052 -285.449772) (xy 422.844226 -285.449772) (xy 422.848186 -285.400718) (xy 422.859963 -285.352934)
			(xy 422.879254 -285.307658) (xy 422.905557 -285.266062) (xy 422.938192 -285.229225) (xy 422.976313 -285.1981)
			(xy 423.018934 -285.173493) (xy 423.06495 -285.156041) (xy 423.113169 -285.146197) (xy 423.162344 -285.144216)
			(xy 423.211199 -285.150148) (xy 423.25847 -285.16384) (xy 423.302932 -285.184938) (xy 423.343435 -285.212894)
			(xy 423.378928 -285.246986) (xy 423.408493 -285.28633) (xy 423.431364 -285.329907) (xy 423.446948 -285.376588)
			(xy 423.454843 -285.425165) (xy 423.455338 -285.449772) (xy 423.794186 -285.449772) (xy 423.798146 -285.400718)
			(xy 423.809923 -285.352934) (xy 423.829214 -285.307658) (xy 423.855517 -285.266062) (xy 423.888152 -285.229225)
			(xy 423.926273 -285.1981) (xy 423.968894 -285.173493) (xy 424.01491 -285.156041) (xy 424.063129 -285.146197)
			(xy 424.112304 -285.144216) (xy 424.161159 -285.150148) (xy 424.20843 -285.16384) (xy 424.252892 -285.184938)
			(xy 424.293395 -285.212894) (xy 424.328888 -285.246986) (xy 424.358453 -285.28633) (xy 424.381324 -285.329907)
			(xy 424.396908 -285.376588) (xy 424.404803 -285.425165) (xy 424.405298 -285.449772) (xy 424.404803 -285.474379)
			(xy 424.396908 -285.522956) (xy 424.381324 -285.569637) (xy 424.358453 -285.613214) (xy 424.328888 -285.652558)
			(xy 424.293395 -285.68665) (xy 424.252892 -285.714606) (xy 424.20843 -285.735704) (xy 424.161159 -285.749396)
			(xy 424.112304 -285.755328) (xy 424.063129 -285.753347) (xy 424.01491 -285.743503) (xy 423.968894 -285.726051)
			(xy 423.926273 -285.701444) (xy 423.888152 -285.670319) (xy 423.855517 -285.633482) (xy 423.829214 -285.591886)
			(xy 423.809923 -285.54661) (xy 423.798146 -285.498826) (xy 423.794186 -285.449772) (xy 423.455338 -285.449772)
			(xy 423.454843 -285.474379) (xy 423.446948 -285.522956) (xy 423.431364 -285.569637) (xy 423.408493 -285.613214)
			(xy 423.378928 -285.652558) (xy 423.343435 -285.68665) (xy 423.302932 -285.714606) (xy 423.25847 -285.735704)
			(xy 423.211199 -285.749396) (xy 423.162344 -285.755328) (xy 423.113169 -285.753347) (xy 423.06495 -285.743503)
			(xy 423.018934 -285.726051) (xy 422.976313 -285.701444) (xy 422.938192 -285.670319) (xy 422.905557 -285.633482)
			(xy 422.879254 -285.591886) (xy 422.859963 -285.54661) (xy 422.848186 -285.498826) (xy 422.844226 -285.449772)
			(xy 308.3052 -285.449772) (xy 308.304705 -285.474379) (xy 308.29681 -285.522956) (xy 308.281226 -285.569637)
			(xy 308.258355 -285.613214) (xy 308.22879 -285.652558) (xy 308.193297 -285.68665) (xy 308.152794 -285.714606)
			(xy 308.108332 -285.735704) (xy 308.061061 -285.749396) (xy 308.012206 -285.755328) (xy 307.963031 -285.753347)
			(xy 307.914812 -285.743503) (xy 307.868796 -285.726051) (xy 307.826175 -285.701444) (xy 307.788054 -285.670319)
			(xy 307.755419 -285.633482) (xy 307.729116 -285.591886) (xy 307.709825 -285.54661) (xy 307.698048 -285.498826)
			(xy 307.694088 -285.449772) (xy 307.35524 -285.449772) (xy 307.354745 -285.474379) (xy 307.34685 -285.522956)
			(xy 307.331266 -285.569637) (xy 307.308395 -285.613214) (xy 307.27883 -285.652558) (xy 307.243337 -285.68665)
			(xy 307.202834 -285.714606) (xy 307.158372 -285.735704) (xy 307.111101 -285.749396) (xy 307.062246 -285.755328)
			(xy 307.013071 -285.753347) (xy 306.964852 -285.743503) (xy 306.918836 -285.726051) (xy 306.876215 -285.701444)
			(xy 306.838094 -285.670319) (xy 306.805459 -285.633482) (xy 306.779156 -285.591886) (xy 306.759865 -285.54661)
			(xy 306.748088 -285.498826) (xy 306.744128 -285.449772) (xy 192.205356 -285.449772) (xy 192.204861 -285.474379)
			(xy 192.196966 -285.522956) (xy 192.181382 -285.569637) (xy 192.158511 -285.613214) (xy 192.128946 -285.652558)
			(xy 192.093453 -285.68665) (xy 192.05295 -285.714606) (xy 192.008488 -285.735704) (xy 191.961217 -285.749396)
			(xy 191.912362 -285.755328) (xy 191.863187 -285.753347) (xy 191.814968 -285.743503) (xy 191.768952 -285.726051)
			(xy 191.726331 -285.701444) (xy 191.68821 -285.670319) (xy 191.655575 -285.633482) (xy 191.629272 -285.591886)
			(xy 191.609981 -285.54661) (xy 191.598204 -285.498826) (xy 191.594244 -285.449772) (xy 191.255142 -285.449772)
			(xy 191.254647 -285.474379) (xy 191.246752 -285.522956) (xy 191.231168 -285.569637) (xy 191.208297 -285.613214)
			(xy 191.178732 -285.652558) (xy 191.143239 -285.68665) (xy 191.102736 -285.714606) (xy 191.058274 -285.735704)
			(xy 191.011003 -285.749396) (xy 190.962148 -285.755328) (xy 190.912973 -285.753347) (xy 190.864754 -285.743503)
			(xy 190.818738 -285.726051) (xy 190.776117 -285.701444) (xy 190.737996 -285.670319) (xy 190.705361 -285.633482)
			(xy 190.679058 -285.591886) (xy 190.659767 -285.54661) (xy 190.64799 -285.498826) (xy 190.64403 -285.449772)
			(xy 76.105258 -285.449772) (xy 76.104763 -285.474379) (xy 76.096868 -285.522956) (xy 76.081284 -285.569637)
			(xy 76.058413 -285.613214) (xy 76.028848 -285.652558) (xy 75.993355 -285.68665) (xy 75.952852 -285.714606)
			(xy 75.90839 -285.735704) (xy 75.861119 -285.749396) (xy 75.812264 -285.755328) (xy 75.763089 -285.753347)
			(xy 75.71487 -285.743503) (xy 75.668854 -285.726051) (xy 75.626233 -285.701444) (xy 75.588112 -285.670319)
			(xy 75.555477 -285.633482) (xy 75.529174 -285.591886) (xy 75.509883 -285.54661) (xy 75.498106 -285.498826)
			(xy 75.494146 -285.449772) (xy 75.155044 -285.449772) (xy 75.154549 -285.474379) (xy 75.146654 -285.522956)
			(xy 75.13107 -285.569637) (xy 75.108199 -285.613214) (xy 75.078634 -285.652558) (xy 75.043141 -285.68665)
			(xy 75.002638 -285.714606) (xy 74.958176 -285.735704) (xy 74.910905 -285.749396) (xy 74.86205 -285.755328)
			(xy 74.812875 -285.753347) (xy 74.764656 -285.743503) (xy 74.71864 -285.726051) (xy 74.676019 -285.701444)
			(xy 74.637898 -285.670319) (xy 74.605263 -285.633482) (xy 74.57896 -285.591886) (xy 74.559669 -285.54661)
			(xy 74.547892 -285.498826) (xy 74.543932 -285.449772) (xy 0.508 -285.449772) (xy 0.508 -286.399986)
			(xy 76.444106 -286.399986) (xy 76.448066 -286.350932) (xy 76.459843 -286.303148) (xy 76.479134 -286.257872)
			(xy 76.505437 -286.216276) (xy 76.538072 -286.179439) (xy 76.576193 -286.148314) (xy 76.618814 -286.123707)
			(xy 76.66483 -286.106255) (xy 76.713049 -286.096411) (xy 76.762224 -286.09443) (xy 76.811079 -286.100362)
			(xy 76.85835 -286.114054) (xy 76.902812 -286.135152) (xy 76.943315 -286.163108) (xy 76.978808 -286.1972)
			(xy 77.008373 -286.236544) (xy 77.031244 -286.280121) (xy 77.046828 -286.326802) (xy 77.054723 -286.375379)
			(xy 77.055218 -286.399986) (xy 77.394066 -286.399986) (xy 77.398026 -286.350932) (xy 77.409803 -286.303148)
			(xy 77.429094 -286.257872) (xy 77.455397 -286.216276) (xy 77.488032 -286.179439) (xy 77.526153 -286.148314)
			(xy 77.568774 -286.123707) (xy 77.61479 -286.106255) (xy 77.663009 -286.096411) (xy 77.712184 -286.09443)
			(xy 77.761039 -286.100362) (xy 77.80831 -286.114054) (xy 77.852772 -286.135152) (xy 77.893275 -286.163108)
			(xy 77.928768 -286.1972) (xy 77.958333 -286.236544) (xy 77.981204 -286.280121) (xy 77.996788 -286.326802)
			(xy 78.004683 -286.375379) (xy 78.005178 -286.399986) (xy 192.544204 -286.399986) (xy 192.548164 -286.350932)
			(xy 192.559941 -286.303148) (xy 192.579232 -286.257872) (xy 192.605535 -286.216276) (xy 192.63817 -286.179439)
			(xy 192.676291 -286.148314) (xy 192.718912 -286.123707) (xy 192.764928 -286.106255) (xy 192.813147 -286.096411)
			(xy 192.862322 -286.09443) (xy 192.911177 -286.100362) (xy 192.958448 -286.114054) (xy 193.00291 -286.135152)
			(xy 193.043413 -286.163108) (xy 193.078906 -286.1972) (xy 193.108471 -286.236544) (xy 193.131342 -286.280121)
			(xy 193.146926 -286.326802) (xy 193.154821 -286.375379) (xy 193.155316 -286.399986) (xy 193.494164 -286.399986)
			(xy 193.498124 -286.350932) (xy 193.509901 -286.303148) (xy 193.529192 -286.257872) (xy 193.555495 -286.216276)
			(xy 193.58813 -286.179439) (xy 193.626251 -286.148314) (xy 193.668872 -286.123707) (xy 193.714888 -286.106255)
			(xy 193.763107 -286.096411) (xy 193.812282 -286.09443) (xy 193.861137 -286.100362) (xy 193.908408 -286.114054)
			(xy 193.95287 -286.135152) (xy 193.993373 -286.163108) (xy 194.028866 -286.1972) (xy 194.058431 -286.236544)
			(xy 194.081302 -286.280121) (xy 194.096886 -286.326802) (xy 194.104781 -286.375379) (xy 194.105276 -286.399986)
			(xy 308.644048 -286.399986) (xy 308.648008 -286.350932) (xy 308.659785 -286.303148) (xy 308.679076 -286.257872)
			(xy 308.705379 -286.216276) (xy 308.738014 -286.179439) (xy 308.776135 -286.148314) (xy 308.818756 -286.123707)
			(xy 308.864772 -286.106255) (xy 308.912991 -286.096411) (xy 308.962166 -286.09443) (xy 309.011021 -286.100362)
			(xy 309.058292 -286.114054) (xy 309.102754 -286.135152) (xy 309.143257 -286.163108) (xy 309.17875 -286.1972)
			(xy 309.208315 -286.236544) (xy 309.231186 -286.280121) (xy 309.24677 -286.326802) (xy 309.254665 -286.375379)
			(xy 309.25516 -286.399986) (xy 309.594008 -286.399986) (xy 309.597968 -286.350932) (xy 309.609745 -286.303148)
			(xy 309.629036 -286.257872) (xy 309.655339 -286.216276) (xy 309.687974 -286.179439) (xy 309.726095 -286.148314)
			(xy 309.768716 -286.123707) (xy 309.814732 -286.106255) (xy 309.862951 -286.096411) (xy 309.912126 -286.09443)
			(xy 309.960981 -286.100362) (xy 310.008252 -286.114054) (xy 310.052714 -286.135152) (xy 310.093217 -286.163108)
			(xy 310.12871 -286.1972) (xy 310.158275 -286.236544) (xy 310.181146 -286.280121) (xy 310.19673 -286.326802)
			(xy 310.204625 -286.375379) (xy 310.20512 -286.399986) (xy 424.744146 -286.399986) (xy 424.748106 -286.350932)
			(xy 424.759883 -286.303148) (xy 424.779174 -286.257872) (xy 424.805477 -286.216276) (xy 424.838112 -286.179439)
			(xy 424.876233 -286.148314) (xy 424.918854 -286.123707) (xy 424.96487 -286.106255) (xy 425.013089 -286.096411)
			(xy 425.062264 -286.09443) (xy 425.111119 -286.100362) (xy 425.15839 -286.114054) (xy 425.202852 -286.135152)
			(xy 425.243355 -286.163108) (xy 425.278848 -286.1972) (xy 425.308413 -286.236544) (xy 425.331284 -286.280121)
			(xy 425.346868 -286.326802) (xy 425.354763 -286.375379) (xy 425.355258 -286.399986) (xy 425.694106 -286.399986)
			(xy 425.698066 -286.350932) (xy 425.709843 -286.303148) (xy 425.729134 -286.257872) (xy 425.755437 -286.216276)
			(xy 425.788072 -286.179439) (xy 425.826193 -286.148314) (xy 425.868814 -286.123707) (xy 425.91483 -286.106255)
			(xy 425.963049 -286.096411) (xy 426.012224 -286.09443) (xy 426.061079 -286.100362) (xy 426.10835 -286.114054)
			(xy 426.152812 -286.135152) (xy 426.193315 -286.163108) (xy 426.228808 -286.1972) (xy 426.258373 -286.236544)
			(xy 426.281244 -286.280121) (xy 426.296828 -286.326802) (xy 426.304723 -286.375379) (xy 426.305218 -286.399986)
			(xy 426.304723 -286.424593) (xy 426.296828 -286.47317) (xy 426.281244 -286.519851) (xy 426.258373 -286.563428)
			(xy 426.228808 -286.602772) (xy 426.193315 -286.636864) (xy 426.152812 -286.66482) (xy 426.10835 -286.685918)
			(xy 426.061079 -286.69961) (xy 426.012224 -286.705542) (xy 425.963049 -286.703561) (xy 425.91483 -286.693717)
			(xy 425.868814 -286.676265) (xy 425.826193 -286.651658) (xy 425.788072 -286.620533) (xy 425.755437 -286.583696)
			(xy 425.729134 -286.5421) (xy 425.709843 -286.496824) (xy 425.698066 -286.44904) (xy 425.694106 -286.399986)
			(xy 425.355258 -286.399986) (xy 425.354763 -286.424593) (xy 425.346868 -286.47317) (xy 425.331284 -286.519851)
			(xy 425.308413 -286.563428) (xy 425.278848 -286.602772) (xy 425.243355 -286.636864) (xy 425.202852 -286.66482)
			(xy 425.15839 -286.685918) (xy 425.111119 -286.69961) (xy 425.062264 -286.705542) (xy 425.013089 -286.703561)
			(xy 424.96487 -286.693717) (xy 424.918854 -286.676265) (xy 424.876233 -286.651658) (xy 424.838112 -286.620533)
			(xy 424.805477 -286.583696) (xy 424.779174 -286.5421) (xy 424.759883 -286.496824) (xy 424.748106 -286.44904)
			(xy 424.744146 -286.399986) (xy 310.20512 -286.399986) (xy 310.204625 -286.424593) (xy 310.19673 -286.47317)
			(xy 310.181146 -286.519851) (xy 310.158275 -286.563428) (xy 310.12871 -286.602772) (xy 310.093217 -286.636864)
			(xy 310.052714 -286.66482) (xy 310.008252 -286.685918) (xy 309.960981 -286.69961) (xy 309.912126 -286.705542)
			(xy 309.862951 -286.703561) (xy 309.814732 -286.693717) (xy 309.768716 -286.676265) (xy 309.726095 -286.651658)
			(xy 309.687974 -286.620533) (xy 309.655339 -286.583696) (xy 309.629036 -286.5421) (xy 309.609745 -286.496824)
			(xy 309.597968 -286.44904) (xy 309.594008 -286.399986) (xy 309.25516 -286.399986) (xy 309.254665 -286.424593)
			(xy 309.24677 -286.47317) (xy 309.231186 -286.519851) (xy 309.208315 -286.563428) (xy 309.17875 -286.602772)
			(xy 309.143257 -286.636864) (xy 309.102754 -286.66482) (xy 309.058292 -286.685918) (xy 309.011021 -286.69961)
			(xy 308.962166 -286.705542) (xy 308.912991 -286.703561) (xy 308.864772 -286.693717) (xy 308.818756 -286.676265)
			(xy 308.776135 -286.651658) (xy 308.738014 -286.620533) (xy 308.705379 -286.583696) (xy 308.679076 -286.5421)
			(xy 308.659785 -286.496824) (xy 308.648008 -286.44904) (xy 308.644048 -286.399986) (xy 194.105276 -286.399986)
			(xy 194.104781 -286.424593) (xy 194.096886 -286.47317) (xy 194.081302 -286.519851) (xy 194.058431 -286.563428)
			(xy 194.028866 -286.602772) (xy 193.993373 -286.636864) (xy 193.95287 -286.66482) (xy 193.908408 -286.685918)
			(xy 193.861137 -286.69961) (xy 193.812282 -286.705542) (xy 193.763107 -286.703561) (xy 193.714888 -286.693717)
			(xy 193.668872 -286.676265) (xy 193.626251 -286.651658) (xy 193.58813 -286.620533) (xy 193.555495 -286.583696)
			(xy 193.529192 -286.5421) (xy 193.509901 -286.496824) (xy 193.498124 -286.44904) (xy 193.494164 -286.399986)
			(xy 193.155316 -286.399986) (xy 193.154821 -286.424593) (xy 193.146926 -286.47317) (xy 193.131342 -286.519851)
			(xy 193.108471 -286.563428) (xy 193.078906 -286.602772) (xy 193.043413 -286.636864) (xy 193.00291 -286.66482)
			(xy 192.958448 -286.685918) (xy 192.911177 -286.69961) (xy 192.862322 -286.705542) (xy 192.813147 -286.703561)
			(xy 192.764928 -286.693717) (xy 192.718912 -286.676265) (xy 192.676291 -286.651658) (xy 192.63817 -286.620533)
			(xy 192.605535 -286.583696) (xy 192.579232 -286.5421) (xy 192.559941 -286.496824) (xy 192.548164 -286.44904)
			(xy 192.544204 -286.399986) (xy 78.005178 -286.399986) (xy 78.004683 -286.424593) (xy 77.996788 -286.47317)
			(xy 77.981204 -286.519851) (xy 77.958333 -286.563428) (xy 77.928768 -286.602772) (xy 77.893275 -286.636864)
			(xy 77.852772 -286.66482) (xy 77.80831 -286.685918) (xy 77.761039 -286.69961) (xy 77.712184 -286.705542)
			(xy 77.663009 -286.703561) (xy 77.61479 -286.693717) (xy 77.568774 -286.676265) (xy 77.526153 -286.651658)
			(xy 77.488032 -286.620533) (xy 77.455397 -286.583696) (xy 77.429094 -286.5421) (xy 77.409803 -286.496824)
			(xy 77.398026 -286.44904) (xy 77.394066 -286.399986) (xy 77.055218 -286.399986) (xy 77.054723 -286.424593)
			(xy 77.046828 -286.47317) (xy 77.031244 -286.519851) (xy 77.008373 -286.563428) (xy 76.978808 -286.602772)
			(xy 76.943315 -286.636864) (xy 76.902812 -286.66482) (xy 76.85835 -286.685918) (xy 76.811079 -286.69961)
			(xy 76.762224 -286.705542) (xy 76.713049 -286.703561) (xy 76.66483 -286.693717) (xy 76.618814 -286.676265)
			(xy 76.576193 -286.651658) (xy 76.538072 -286.620533) (xy 76.505437 -286.583696) (xy 76.479134 -286.5421)
			(xy 76.459843 -286.496824) (xy 76.448066 -286.44904) (xy 76.444106 -286.399986) (xy 0.508 -286.399986)
			(xy 0.508 -287.349946) (xy 74.543932 -287.349946) (xy 74.547892 -287.300892) (xy 74.559669 -287.253108)
			(xy 74.57896 -287.207832) (xy 74.605263 -287.166236) (xy 74.637898 -287.129399) (xy 74.676019 -287.098274)
			(xy 74.71864 -287.073667) (xy 74.764656 -287.056215) (xy 74.812875 -287.046371) (xy 74.86205 -287.04439)
			(xy 74.910905 -287.050322) (xy 74.958176 -287.064014) (xy 75.002638 -287.085112) (xy 75.043141 -287.113068)
			(xy 75.078634 -287.14716) (xy 75.108199 -287.186504) (xy 75.13107 -287.230081) (xy 75.146654 -287.276762)
			(xy 75.154549 -287.325339) (xy 75.155044 -287.349946) (xy 75.494146 -287.349946) (xy 75.498106 -287.300892)
			(xy 75.509883 -287.253108) (xy 75.529174 -287.207832) (xy 75.555477 -287.166236) (xy 75.588112 -287.129399)
			(xy 75.626233 -287.098274) (xy 75.668854 -287.073667) (xy 75.71487 -287.056215) (xy 75.763089 -287.046371)
			(xy 75.812264 -287.04439) (xy 75.861119 -287.050322) (xy 75.90839 -287.064014) (xy 75.952852 -287.085112)
			(xy 75.993355 -287.113068) (xy 76.028848 -287.14716) (xy 76.058413 -287.186504) (xy 76.081284 -287.230081)
			(xy 76.096868 -287.276762) (xy 76.104763 -287.325339) (xy 76.105258 -287.349946) (xy 190.64403 -287.349946)
			(xy 190.64799 -287.300892) (xy 190.659767 -287.253108) (xy 190.679058 -287.207832) (xy 190.705361 -287.166236)
			(xy 190.737996 -287.129399) (xy 190.776117 -287.098274) (xy 190.818738 -287.073667) (xy 190.864754 -287.056215)
			(xy 190.912973 -287.046371) (xy 190.962148 -287.04439) (xy 191.011003 -287.050322) (xy 191.058274 -287.064014)
			(xy 191.102736 -287.085112) (xy 191.143239 -287.113068) (xy 191.178732 -287.14716) (xy 191.208297 -287.186504)
			(xy 191.231168 -287.230081) (xy 191.246752 -287.276762) (xy 191.254647 -287.325339) (xy 191.255142 -287.349946)
			(xy 191.594244 -287.349946) (xy 191.598204 -287.300892) (xy 191.609981 -287.253108) (xy 191.629272 -287.207832)
			(xy 191.655575 -287.166236) (xy 191.68821 -287.129399) (xy 191.726331 -287.098274) (xy 191.768952 -287.073667)
			(xy 191.814968 -287.056215) (xy 191.863187 -287.046371) (xy 191.912362 -287.04439) (xy 191.961217 -287.050322)
			(xy 192.008488 -287.064014) (xy 192.05295 -287.085112) (xy 192.093453 -287.113068) (xy 192.128946 -287.14716)
			(xy 192.158511 -287.186504) (xy 192.181382 -287.230081) (xy 192.196966 -287.276762) (xy 192.204861 -287.325339)
			(xy 192.205356 -287.349946) (xy 306.744128 -287.349946) (xy 306.748088 -287.300892) (xy 306.759865 -287.253108)
			(xy 306.779156 -287.207832) (xy 306.805459 -287.166236) (xy 306.838094 -287.129399) (xy 306.876215 -287.098274)
			(xy 306.918836 -287.073667) (xy 306.964852 -287.056215) (xy 307.013071 -287.046371) (xy 307.062246 -287.04439)
			(xy 307.111101 -287.050322) (xy 307.158372 -287.064014) (xy 307.202834 -287.085112) (xy 307.243337 -287.113068)
			(xy 307.27883 -287.14716) (xy 307.308395 -287.186504) (xy 307.331266 -287.230081) (xy 307.34685 -287.276762)
			(xy 307.354745 -287.325339) (xy 307.35524 -287.349946) (xy 307.694088 -287.349946) (xy 307.698048 -287.300892)
			(xy 307.709825 -287.253108) (xy 307.729116 -287.207832) (xy 307.755419 -287.166236) (xy 307.788054 -287.129399)
			(xy 307.826175 -287.098274) (xy 307.868796 -287.073667) (xy 307.914812 -287.056215) (xy 307.963031 -287.046371)
			(xy 308.012206 -287.04439) (xy 308.061061 -287.050322) (xy 308.108332 -287.064014) (xy 308.152794 -287.085112)
			(xy 308.193297 -287.113068) (xy 308.22879 -287.14716) (xy 308.258355 -287.186504) (xy 308.281226 -287.230081)
			(xy 308.29681 -287.276762) (xy 308.304705 -287.325339) (xy 308.3052 -287.349946) (xy 422.844226 -287.349946)
			(xy 422.848186 -287.300892) (xy 422.859963 -287.253108) (xy 422.879254 -287.207832) (xy 422.905557 -287.166236)
			(xy 422.938192 -287.129399) (xy 422.976313 -287.098274) (xy 423.018934 -287.073667) (xy 423.06495 -287.056215)
			(xy 423.113169 -287.046371) (xy 423.162344 -287.04439) (xy 423.211199 -287.050322) (xy 423.25847 -287.064014)
			(xy 423.302932 -287.085112) (xy 423.343435 -287.113068) (xy 423.378928 -287.14716) (xy 423.408493 -287.186504)
			(xy 423.431364 -287.230081) (xy 423.446948 -287.276762) (xy 423.454843 -287.325339) (xy 423.455338 -287.349946)
			(xy 423.794186 -287.349946) (xy 423.798146 -287.300892) (xy 423.809923 -287.253108) (xy 423.829214 -287.207832)
			(xy 423.855517 -287.166236) (xy 423.888152 -287.129399) (xy 423.926273 -287.098274) (xy 423.968894 -287.073667)
			(xy 424.01491 -287.056215) (xy 424.063129 -287.046371) (xy 424.112304 -287.04439) (xy 424.161159 -287.050322)
			(xy 424.20843 -287.064014) (xy 424.252892 -287.085112) (xy 424.293395 -287.113068) (xy 424.328888 -287.14716)
			(xy 424.358453 -287.186504) (xy 424.381324 -287.230081) (xy 424.396908 -287.276762) (xy 424.404803 -287.325339)
			(xy 424.405298 -287.349946) (xy 424.404803 -287.374553) (xy 424.396908 -287.42313) (xy 424.381324 -287.469811)
			(xy 424.358453 -287.513388) (xy 424.328888 -287.552732) (xy 424.293395 -287.586824) (xy 424.252892 -287.61478)
			(xy 424.20843 -287.635878) (xy 424.161159 -287.64957) (xy 424.112304 -287.655502) (xy 424.063129 -287.653521)
			(xy 424.01491 -287.643677) (xy 423.968894 -287.626225) (xy 423.926273 -287.601618) (xy 423.888152 -287.570493)
			(xy 423.855517 -287.533656) (xy 423.829214 -287.49206) (xy 423.809923 -287.446784) (xy 423.798146 -287.399)
			(xy 423.794186 -287.349946) (xy 423.455338 -287.349946) (xy 423.454843 -287.374553) (xy 423.446948 -287.42313)
			(xy 423.431364 -287.469811) (xy 423.408493 -287.513388) (xy 423.378928 -287.552732) (xy 423.343435 -287.586824)
			(xy 423.302932 -287.61478) (xy 423.25847 -287.635878) (xy 423.211199 -287.64957) (xy 423.162344 -287.655502)
			(xy 423.113169 -287.653521) (xy 423.06495 -287.643677) (xy 423.018934 -287.626225) (xy 422.976313 -287.601618)
			(xy 422.938192 -287.570493) (xy 422.905557 -287.533656) (xy 422.879254 -287.49206) (xy 422.859963 -287.446784)
			(xy 422.848186 -287.399) (xy 422.844226 -287.349946) (xy 308.3052 -287.349946) (xy 308.304705 -287.374553)
			(xy 308.29681 -287.42313) (xy 308.281226 -287.469811) (xy 308.258355 -287.513388) (xy 308.22879 -287.552732)
			(xy 308.193297 -287.586824) (xy 308.152794 -287.61478) (xy 308.108332 -287.635878) (xy 308.061061 -287.64957)
			(xy 308.012206 -287.655502) (xy 307.963031 -287.653521) (xy 307.914812 -287.643677) (xy 307.868796 -287.626225)
			(xy 307.826175 -287.601618) (xy 307.788054 -287.570493) (xy 307.755419 -287.533656) (xy 307.729116 -287.49206)
			(xy 307.709825 -287.446784) (xy 307.698048 -287.399) (xy 307.694088 -287.349946) (xy 307.35524 -287.349946)
			(xy 307.354745 -287.374553) (xy 307.34685 -287.42313) (xy 307.331266 -287.469811) (xy 307.308395 -287.513388)
			(xy 307.27883 -287.552732) (xy 307.243337 -287.586824) (xy 307.202834 -287.61478) (xy 307.158372 -287.635878)
			(xy 307.111101 -287.64957) (xy 307.062246 -287.655502) (xy 307.013071 -287.653521) (xy 306.964852 -287.643677)
			(xy 306.918836 -287.626225) (xy 306.876215 -287.601618) (xy 306.838094 -287.570493) (xy 306.805459 -287.533656)
			(xy 306.779156 -287.49206) (xy 306.759865 -287.446784) (xy 306.748088 -287.399) (xy 306.744128 -287.349946)
			(xy 192.205356 -287.349946) (xy 192.204861 -287.374553) (xy 192.196966 -287.42313) (xy 192.181382 -287.469811)
			(xy 192.158511 -287.513388) (xy 192.128946 -287.552732) (xy 192.093453 -287.586824) (xy 192.05295 -287.61478)
			(xy 192.008488 -287.635878) (xy 191.961217 -287.64957) (xy 191.912362 -287.655502) (xy 191.863187 -287.653521)
			(xy 191.814968 -287.643677) (xy 191.768952 -287.626225) (xy 191.726331 -287.601618) (xy 191.68821 -287.570493)
			(xy 191.655575 -287.533656) (xy 191.629272 -287.49206) (xy 191.609981 -287.446784) (xy 191.598204 -287.399)
			(xy 191.594244 -287.349946) (xy 191.255142 -287.349946) (xy 191.254647 -287.374553) (xy 191.246752 -287.42313)
			(xy 191.231168 -287.469811) (xy 191.208297 -287.513388) (xy 191.178732 -287.552732) (xy 191.143239 -287.586824)
			(xy 191.102736 -287.61478) (xy 191.058274 -287.635878) (xy 191.011003 -287.64957) (xy 190.962148 -287.655502)
			(xy 190.912973 -287.653521) (xy 190.864754 -287.643677) (xy 190.818738 -287.626225) (xy 190.776117 -287.601618)
			(xy 190.737996 -287.570493) (xy 190.705361 -287.533656) (xy 190.679058 -287.49206) (xy 190.659767 -287.446784)
			(xy 190.64799 -287.399) (xy 190.64403 -287.349946) (xy 76.105258 -287.349946) (xy 76.104763 -287.374553)
			(xy 76.096868 -287.42313) (xy 76.081284 -287.469811) (xy 76.058413 -287.513388) (xy 76.028848 -287.552732)
			(xy 75.993355 -287.586824) (xy 75.952852 -287.61478) (xy 75.90839 -287.635878) (xy 75.861119 -287.64957)
			(xy 75.812264 -287.655502) (xy 75.763089 -287.653521) (xy 75.71487 -287.643677) (xy 75.668854 -287.626225)
			(xy 75.626233 -287.601618) (xy 75.588112 -287.570493) (xy 75.555477 -287.533656) (xy 75.529174 -287.49206)
			(xy 75.509883 -287.446784) (xy 75.498106 -287.399) (xy 75.494146 -287.349946) (xy 75.155044 -287.349946)
			(xy 75.154549 -287.374553) (xy 75.146654 -287.42313) (xy 75.13107 -287.469811) (xy 75.108199 -287.513388)
			(xy 75.078634 -287.552732) (xy 75.043141 -287.586824) (xy 75.002638 -287.61478) (xy 74.958176 -287.635878)
			(xy 74.910905 -287.64957) (xy 74.86205 -287.655502) (xy 74.812875 -287.653521) (xy 74.764656 -287.643677)
			(xy 74.71864 -287.626225) (xy 74.676019 -287.601618) (xy 74.637898 -287.570493) (xy 74.605263 -287.533656)
			(xy 74.57896 -287.49206) (xy 74.559669 -287.446784) (xy 74.547892 -287.399) (xy 74.543932 -287.349946)
			(xy 0.508 -287.349946) (xy 0.508 -287.850408) (xy 37.944539 -287.850408) (xy 37.944539 -287.798392)
			(xy 37.952677 -287.747016) (xy 37.968751 -287.697546) (xy 37.992366 -287.651199) (xy 38.02294 -287.609117)
			(xy 38.059722 -287.572337) (xy 38.101804 -287.541763) (xy 38.148151 -287.518148) (xy 38.197622 -287.502075)
			(xy 38.248998 -287.493939) (xy 38.275006 -287.493456) (xy 39.224966 -287.493456) (xy 39.250978 -287.493901)
			(xy 39.302363 -287.502035) (xy 39.351843 -287.518107) (xy 39.398199 -287.541722) (xy 39.44029 -287.572299)
			(xy 39.477079 -287.609084) (xy 39.50766 -287.651172) (xy 39.53128 -287.697525) (xy 39.547357 -287.747004)
			(xy 39.555496 -287.798388) (xy 39.555496 -287.850405) (xy 40.794466 -287.850405) (xy 40.794466 -287.798395)
			(xy 40.802602 -287.747025) (xy 40.818674 -287.697561) (xy 40.842285 -287.651219) (xy 40.872855 -287.609142)
			(xy 40.909631 -287.572364) (xy 40.951707 -287.541792) (xy 40.998048 -287.518179) (xy 41.047512 -287.502105)
			(xy 41.098881 -287.493967) (xy 41.124886 -287.493456) (xy 42.074846 -287.493456) (xy 42.100852 -287.493934)
			(xy 42.152223 -287.502077) (xy 42.201688 -287.518155) (xy 42.248029 -287.541773) (xy 42.290106 -287.572348)
			(xy 42.326882 -287.609129) (xy 42.357451 -287.65121) (xy 42.381063 -287.697554) (xy 42.397134 -287.747022)
			(xy 42.40527 -287.798394) (xy 42.40527 -287.850406) (xy 42.397134 -287.901778) (xy 42.381063 -287.951246)
			(xy 42.357451 -287.99759) (xy 42.326882 -288.039671) (xy 42.290106 -288.076452) (xy 42.248029 -288.107027)
			(xy 42.201688 -288.130645) (xy 42.152223 -288.146723) (xy 42.100852 -288.154866) (xy 42.074846 -288.15538)
			(xy 41.124886 -288.15538) (xy 41.098881 -288.154833) (xy 41.047512 -288.146695) (xy 40.998048 -288.130621)
			(xy 40.951707 -288.107008) (xy 40.909631 -288.076436) (xy 40.872855 -288.039658) (xy 40.842285 -287.997581)
			(xy 40.818674 -287.951239) (xy 40.802602 -287.901775) (xy 40.794466 -287.850405) (xy 39.555496 -287.850405)
			(xy 39.555496 -287.850412) (xy 39.547357 -287.901796) (xy 39.53128 -287.951275) (xy 39.50766 -287.997628)
			(xy 39.477079 -288.039716) (xy 39.44029 -288.076501) (xy 39.398199 -288.107078) (xy 39.351843 -288.130693)
			(xy 39.302363 -288.146765) (xy 39.250978 -288.154899) (xy 39.224966 -288.15538) (xy 38.275006 -288.15538)
			(xy 38.248998 -288.154861) (xy 38.197622 -288.146725) (xy 38.148151 -288.130652) (xy 38.101804 -288.107037)
			(xy 38.059722 -288.076463) (xy 38.02294 -288.039683) (xy 37.992366 -287.997601) (xy 37.968751 -287.951254)
			(xy 37.952677 -287.901784) (xy 37.944539 -287.850408) (xy 0.508 -287.850408) (xy 0.508 -288.299906)
			(xy 76.444106 -288.299906) (xy 76.448066 -288.250852) (xy 76.459843 -288.203068) (xy 76.479134 -288.157792)
			(xy 76.505437 -288.116196) (xy 76.538072 -288.079359) (xy 76.576193 -288.048234) (xy 76.618814 -288.023627)
			(xy 76.66483 -288.006175) (xy 76.713049 -287.996331) (xy 76.762224 -287.99435) (xy 76.811079 -288.000282)
			(xy 76.85835 -288.013974) (xy 76.902812 -288.035072) (xy 76.943315 -288.063028) (xy 76.978808 -288.09712)
			(xy 77.008373 -288.136464) (xy 77.031244 -288.180041) (xy 77.046828 -288.226722) (xy 77.054723 -288.275299)
			(xy 77.055218 -288.299906) (xy 77.394066 -288.299906) (xy 77.398026 -288.250852) (xy 77.409803 -288.203068)
			(xy 77.429094 -288.157792) (xy 77.455397 -288.116196) (xy 77.488032 -288.079359) (xy 77.526153 -288.048234)
			(xy 77.568774 -288.023627) (xy 77.61479 -288.006175) (xy 77.663009 -287.996331) (xy 77.712184 -287.99435)
			(xy 77.761039 -288.000282) (xy 77.80831 -288.013974) (xy 77.852772 -288.035072) (xy 77.893275 -288.063028)
			(xy 77.928768 -288.09712) (xy 77.958333 -288.136464) (xy 77.981204 -288.180041) (xy 77.996788 -288.226722)
			(xy 78.004683 -288.275299) (xy 78.005178 -288.299906) (xy 192.544204 -288.299906) (xy 192.548164 -288.250852)
			(xy 192.559941 -288.203068) (xy 192.579232 -288.157792) (xy 192.605535 -288.116196) (xy 192.63817 -288.079359)
			(xy 192.676291 -288.048234) (xy 192.718912 -288.023627) (xy 192.764928 -288.006175) (xy 192.813147 -287.996331)
			(xy 192.862322 -287.99435) (xy 192.911177 -288.000282) (xy 192.958448 -288.013974) (xy 193.00291 -288.035072)
			(xy 193.043413 -288.063028) (xy 193.078906 -288.09712) (xy 193.108471 -288.136464) (xy 193.131342 -288.180041)
			(xy 193.146926 -288.226722) (xy 193.154821 -288.275299) (xy 193.155316 -288.299906) (xy 193.494164 -288.299906)
			(xy 193.498124 -288.250852) (xy 193.509901 -288.203068) (xy 193.529192 -288.157792) (xy 193.555495 -288.116196)
			(xy 193.58813 -288.079359) (xy 193.626251 -288.048234) (xy 193.668872 -288.023627) (xy 193.714888 -288.006175)
			(xy 193.763107 -287.996331) (xy 193.812282 -287.99435) (xy 193.861137 -288.000282) (xy 193.908408 -288.013974)
			(xy 193.95287 -288.035072) (xy 193.993373 -288.063028) (xy 194.028866 -288.09712) (xy 194.058431 -288.136464)
			(xy 194.081302 -288.180041) (xy 194.096886 -288.226722) (xy 194.104781 -288.275299) (xy 194.105276 -288.299906)
			(xy 308.644048 -288.299906) (xy 308.648008 -288.250852) (xy 308.659785 -288.203068) (xy 308.679076 -288.157792)
			(xy 308.705379 -288.116196) (xy 308.738014 -288.079359) (xy 308.776135 -288.048234) (xy 308.818756 -288.023627)
			(xy 308.864772 -288.006175) (xy 308.912991 -287.996331) (xy 308.962166 -287.99435) (xy 309.011021 -288.000282)
			(xy 309.058292 -288.013974) (xy 309.102754 -288.035072) (xy 309.143257 -288.063028) (xy 309.17875 -288.09712)
			(xy 309.208315 -288.136464) (xy 309.231186 -288.180041) (xy 309.24677 -288.226722) (xy 309.254665 -288.275299)
			(xy 309.25516 -288.299906) (xy 309.594008 -288.299906) (xy 309.597968 -288.250852) (xy 309.609745 -288.203068)
			(xy 309.629036 -288.157792) (xy 309.655339 -288.116196) (xy 309.687974 -288.079359) (xy 309.726095 -288.048234)
			(xy 309.768716 -288.023627) (xy 309.814732 -288.006175) (xy 309.862951 -287.996331) (xy 309.912126 -287.99435)
			(xy 309.960981 -288.000282) (xy 310.008252 -288.013974) (xy 310.052714 -288.035072) (xy 310.093217 -288.063028)
			(xy 310.12871 -288.09712) (xy 310.158275 -288.136464) (xy 310.181146 -288.180041) (xy 310.19673 -288.226722)
			(xy 310.204625 -288.275299) (xy 310.20512 -288.299906) (xy 424.744146 -288.299906) (xy 424.748106 -288.250852)
			(xy 424.759883 -288.203068) (xy 424.779174 -288.157792) (xy 424.805477 -288.116196) (xy 424.838112 -288.079359)
			(xy 424.876233 -288.048234) (xy 424.918854 -288.023627) (xy 424.96487 -288.006175) (xy 425.013089 -287.996331)
			(xy 425.062264 -287.99435) (xy 425.111119 -288.000282) (xy 425.15839 -288.013974) (xy 425.202852 -288.035072)
			(xy 425.243355 -288.063028) (xy 425.278848 -288.09712) (xy 425.308413 -288.136464) (xy 425.331284 -288.180041)
			(xy 425.346868 -288.226722) (xy 425.354763 -288.275299) (xy 425.355258 -288.299906) (xy 425.694106 -288.299906)
			(xy 425.698066 -288.250852) (xy 425.709843 -288.203068) (xy 425.729134 -288.157792) (xy 425.755437 -288.116196)
			(xy 425.788072 -288.079359) (xy 425.826193 -288.048234) (xy 425.868814 -288.023627) (xy 425.91483 -288.006175)
			(xy 425.963049 -287.996331) (xy 426.012224 -287.99435) (xy 426.061079 -288.000282) (xy 426.10835 -288.013974)
			(xy 426.152812 -288.035072) (xy 426.193315 -288.063028) (xy 426.228808 -288.09712) (xy 426.258373 -288.136464)
			(xy 426.281244 -288.180041) (xy 426.296828 -288.226722) (xy 426.304723 -288.275299) (xy 426.305218 -288.299906)
			(xy 426.304723 -288.324513) (xy 426.296828 -288.37309) (xy 426.281244 -288.419771) (xy 426.258373 -288.463348)
			(xy 426.228808 -288.502692) (xy 426.193315 -288.536784) (xy 426.152812 -288.56474) (xy 426.10835 -288.585838)
			(xy 426.061079 -288.59953) (xy 426.012224 -288.605462) (xy 425.963049 -288.603481) (xy 425.91483 -288.593637)
			(xy 425.868814 -288.576185) (xy 425.826193 -288.551578) (xy 425.788072 -288.520453) (xy 425.755437 -288.483616)
			(xy 425.729134 -288.44202) (xy 425.709843 -288.396744) (xy 425.698066 -288.34896) (xy 425.694106 -288.299906)
			(xy 425.355258 -288.299906) (xy 425.354763 -288.324513) (xy 425.346868 -288.37309) (xy 425.331284 -288.419771)
			(xy 425.308413 -288.463348) (xy 425.278848 -288.502692) (xy 425.243355 -288.536784) (xy 425.202852 -288.56474)
			(xy 425.15839 -288.585838) (xy 425.111119 -288.59953) (xy 425.062264 -288.605462) (xy 425.013089 -288.603481)
			(xy 424.96487 -288.593637) (xy 424.918854 -288.576185) (xy 424.876233 -288.551578) (xy 424.838112 -288.520453)
			(xy 424.805477 -288.483616) (xy 424.779174 -288.44202) (xy 424.759883 -288.396744) (xy 424.748106 -288.34896)
			(xy 424.744146 -288.299906) (xy 310.20512 -288.299906) (xy 310.204625 -288.324513) (xy 310.19673 -288.37309)
			(xy 310.181146 -288.419771) (xy 310.158275 -288.463348) (xy 310.12871 -288.502692) (xy 310.093217 -288.536784)
			(xy 310.052714 -288.56474) (xy 310.008252 -288.585838) (xy 309.960981 -288.59953) (xy 309.912126 -288.605462)
			(xy 309.862951 -288.603481) (xy 309.814732 -288.593637) (xy 309.768716 -288.576185) (xy 309.726095 -288.551578)
			(xy 309.687974 -288.520453) (xy 309.655339 -288.483616) (xy 309.629036 -288.44202) (xy 309.609745 -288.396744)
			(xy 309.597968 -288.34896) (xy 309.594008 -288.299906) (xy 309.25516 -288.299906) (xy 309.254665 -288.324513)
			(xy 309.24677 -288.37309) (xy 309.231186 -288.419771) (xy 309.208315 -288.463348) (xy 309.17875 -288.502692)
			(xy 309.143257 -288.536784) (xy 309.102754 -288.56474) (xy 309.058292 -288.585838) (xy 309.011021 -288.59953)
			(xy 308.962166 -288.605462) (xy 308.912991 -288.603481) (xy 308.864772 -288.593637) (xy 308.818756 -288.576185)
			(xy 308.776135 -288.551578) (xy 308.738014 -288.520453) (xy 308.705379 -288.483616) (xy 308.679076 -288.44202)
			(xy 308.659785 -288.396744) (xy 308.648008 -288.34896) (xy 308.644048 -288.299906) (xy 194.105276 -288.299906)
			(xy 194.104781 -288.324513) (xy 194.096886 -288.37309) (xy 194.081302 -288.419771) (xy 194.058431 -288.463348)
			(xy 194.028866 -288.502692) (xy 193.993373 -288.536784) (xy 193.95287 -288.56474) (xy 193.908408 -288.585838)
			(xy 193.861137 -288.59953) (xy 193.812282 -288.605462) (xy 193.763107 -288.603481) (xy 193.714888 -288.593637)
			(xy 193.668872 -288.576185) (xy 193.626251 -288.551578) (xy 193.58813 -288.520453) (xy 193.555495 -288.483616)
			(xy 193.529192 -288.44202) (xy 193.509901 -288.396744) (xy 193.498124 -288.34896) (xy 193.494164 -288.299906)
			(xy 193.155316 -288.299906) (xy 193.154821 -288.324513) (xy 193.146926 -288.37309) (xy 193.131342 -288.419771)
			(xy 193.108471 -288.463348) (xy 193.078906 -288.502692) (xy 193.043413 -288.536784) (xy 193.00291 -288.56474)
			(xy 192.958448 -288.585838) (xy 192.911177 -288.59953) (xy 192.862322 -288.605462) (xy 192.813147 -288.603481)
			(xy 192.764928 -288.593637) (xy 192.718912 -288.576185) (xy 192.676291 -288.551578) (xy 192.63817 -288.520453)
			(xy 192.605535 -288.483616) (xy 192.579232 -288.44202) (xy 192.559941 -288.396744) (xy 192.548164 -288.34896)
			(xy 192.544204 -288.299906) (xy 78.005178 -288.299906) (xy 78.004683 -288.324513) (xy 77.996788 -288.37309)
			(xy 77.981204 -288.419771) (xy 77.958333 -288.463348) (xy 77.928768 -288.502692) (xy 77.893275 -288.536784)
			(xy 77.852772 -288.56474) (xy 77.80831 -288.585838) (xy 77.761039 -288.59953) (xy 77.712184 -288.605462)
			(xy 77.663009 -288.603481) (xy 77.61479 -288.593637) (xy 77.568774 -288.576185) (xy 77.526153 -288.551578)
			(xy 77.488032 -288.520453) (xy 77.455397 -288.483616) (xy 77.429094 -288.44202) (xy 77.409803 -288.396744)
			(xy 77.398026 -288.34896) (xy 77.394066 -288.299906) (xy 77.055218 -288.299906) (xy 77.054723 -288.324513)
			(xy 77.046828 -288.37309) (xy 77.031244 -288.419771) (xy 77.008373 -288.463348) (xy 76.978808 -288.502692)
			(xy 76.943315 -288.536784) (xy 76.902812 -288.56474) (xy 76.85835 -288.585838) (xy 76.811079 -288.59953)
			(xy 76.762224 -288.605462) (xy 76.713049 -288.603481) (xy 76.66483 -288.593637) (xy 76.618814 -288.576185)
			(xy 76.576193 -288.551578) (xy 76.538072 -288.520453) (xy 76.505437 -288.483616) (xy 76.479134 -288.44202)
			(xy 76.459843 -288.396744) (xy 76.448066 -288.34896) (xy 76.444106 -288.299906) (xy 0.508 -288.299906)
			(xy 0.508 -288.800413) (xy 36.0443 -288.800413) (xy 36.0443 -288.748387) (xy 36.052439 -288.697003)
			(xy 36.068516 -288.647524) (xy 36.092136 -288.60117) (xy 36.122718 -288.559082) (xy 36.159507 -288.522297)
			(xy 36.201598 -288.49172) (xy 36.247954 -288.468104) (xy 36.297434 -288.452031) (xy 36.348819 -288.443897)
			(xy 36.374832 -288.443416) (xy 37.324792 -288.443416) (xy 37.3508 -288.443943) (xy 37.402175 -288.452079)
			(xy 37.451646 -288.468151) (xy 37.497993 -288.491765) (xy 37.540075 -288.522339) (xy 37.576856 -288.559119)
			(xy 37.60743 -288.601201) (xy 37.631045 -288.647547) (xy 37.647119 -288.697017) (xy 37.655257 -288.748392)
			(xy 37.655257 -288.800408) (xy 37.655257 -288.800411) (xy 42.694299 -288.800411) (xy 42.694299 -288.748389)
			(xy 42.702438 -288.697007) (xy 42.718514 -288.64753) (xy 42.742132 -288.601178) (xy 42.77271 -288.559091)
			(xy 42.809496 -288.522306) (xy 42.851583 -288.491729) (xy 42.897936 -288.468111) (xy 42.947413 -288.452036)
			(xy 42.998795 -288.443899) (xy 43.024806 -288.443416) (xy 43.974766 -288.443416) (xy 44.000775 -288.443941)
			(xy 44.052154 -288.452074) (xy 44.101628 -288.468144) (xy 44.147978 -288.491757) (xy 44.190064 -288.52233)
			(xy 44.226848 -288.55911) (xy 44.257426 -288.601193) (xy 44.281043 -288.647541) (xy 44.297119 -288.697013)
			(xy 44.305257 -288.748391) (xy 44.305257 -288.800409) (xy 44.297119 -288.851787) (xy 44.281043 -288.901259)
			(xy 44.257426 -288.947607) (xy 44.226848 -288.98969) (xy 44.190064 -289.02647) (xy 44.147978 -289.057043)
			(xy 44.101628 -289.080656) (xy 44.052154 -289.096726) (xy 44.000775 -289.104859) (xy 43.974766 -289.10534)
			(xy 43.024806 -289.10534) (xy 42.998795 -289.104901) (xy 42.947413 -289.096764) (xy 42.897936 -289.080689)
			(xy 42.851583 -289.057071) (xy 42.809496 -289.026494) (xy 42.77271 -288.989709) (xy 42.742132 -288.947622)
			(xy 42.718514 -288.90127) (xy 42.702438 -288.851793) (xy 42.694299 -288.800411) (xy 37.655257 -288.800411)
			(xy 37.647119 -288.851783) (xy 37.631045 -288.901253) (xy 37.60743 -288.947599) (xy 37.576856 -288.989681)
			(xy 37.540075 -289.026461) (xy 37.497993 -289.057035) (xy 37.451646 -289.080649) (xy 37.402175 -289.096721)
			(xy 37.3508 -289.104857) (xy 37.324792 -289.10534) (xy 36.374832 -289.10534) (xy 36.348819 -289.104903)
			(xy 36.297434 -289.096769) (xy 36.247954 -289.080696) (xy 36.201598 -289.05708) (xy 36.159507 -289.026503)
			(xy 36.122718 -288.989718) (xy 36.092136 -288.94763) (xy 36.068516 -288.901276) (xy 36.052439 -288.851797)
			(xy 36.0443 -288.800413) (xy 0.508 -288.800413) (xy 0.508 -297.350788) (xy 36.044382 -297.350788)
			(xy 36.044382 -297.298812) (xy 36.052512 -297.247477) (xy 36.068572 -297.198045) (xy 36.092168 -297.151734)
			(xy 36.122717 -297.109685) (xy 36.159468 -297.072931) (xy 36.201516 -297.042379) (xy 36.247825 -297.018781)
			(xy 36.297255 -297.002717) (xy 36.34859 -296.994583) (xy 36.374578 -296.994072) (xy 37.324538 -296.994072)
			(xy 37.350522 -296.994624) (xy 37.401848 -297.002759) (xy 37.451271 -297.018822) (xy 37.497572 -297.042419)
			(xy 37.539613 -297.072968) (xy 37.576357 -297.109716) (xy 37.606901 -297.15176) (xy 37.630492 -297.198064)
			(xy 37.64655 -297.247489) (xy 37.654679 -297.298816) (xy 37.654679 -297.350784) (xy 37.654678 -297.350788)
			(xy 152.144482 -297.350788) (xy 152.144482 -297.298812) (xy 152.152612 -297.247477) (xy 152.168672 -297.198046)
			(xy 152.192268 -297.151735) (xy 152.222816 -297.109685) (xy 152.259567 -297.072932) (xy 152.301615 -297.04238)
			(xy 152.347923 -297.018782) (xy 152.397354 -297.002717) (xy 152.448688 -296.994583) (xy 152.474676 -296.994072)
			(xy 153.424636 -296.994072) (xy 153.45062 -296.994624) (xy 153.501947 -297.002759) (xy 153.55137 -297.018822)
			(xy 153.597671 -297.042418) (xy 153.639712 -297.072967) (xy 153.676457 -297.109715) (xy 153.707001 -297.151759)
			(xy 153.730592 -297.198064) (xy 153.74665 -297.247488) (xy 153.754779 -297.298816) (xy 153.754779 -297.350784)
			(xy 153.754778 -297.350792) (xy 268.244255 -297.350792) (xy 268.244255 -297.298808) (xy 268.252388 -297.247465)
			(xy 268.268452 -297.198025) (xy 268.292053 -297.151708) (xy 268.322609 -297.109653) (xy 268.359368 -297.072896)
			(xy 268.401425 -297.042342) (xy 268.447744 -297.018744) (xy 268.497184 -297.002683) (xy 268.548528 -296.994554)
			(xy 268.57452 -296.994072) (xy 269.52448 -296.994072) (xy 269.550469 -296.994594) (xy 269.601807 -297.002722)
			(xy 269.651241 -297.018781) (xy 269.697554 -297.042377) (xy 269.739606 -297.072927) (xy 269.77636 -297.109679)
			(xy 269.806913 -297.151729) (xy 269.830511 -297.198041) (xy 269.846573 -297.247474) (xy 269.854705 -297.298811)
			(xy 269.854705 -297.350789) (xy 269.854705 -297.350792) (xy 384.344355 -297.350792) (xy 384.344355 -297.298808)
			(xy 384.352488 -297.247465) (xy 384.368552 -297.198026) (xy 384.392153 -297.151709) (xy 384.422709 -297.109654)
			(xy 384.459467 -297.072897) (xy 384.501524 -297.042343) (xy 384.547842 -297.018745) (xy 384.597282 -297.002683)
			(xy 384.648626 -296.994554) (xy 384.674618 -296.994072) (xy 385.624578 -296.994072) (xy 385.650567 -296.994593)
			(xy 385.701905 -297.002721) (xy 385.751339 -297.018781) (xy 385.797653 -297.042376) (xy 385.839705 -297.072926)
			(xy 385.87646 -297.109678) (xy 385.907013 -297.151728) (xy 385.930611 -297.19804) (xy 385.946673 -297.247474)
			(xy 385.954805 -297.298811) (xy 385.954805 -297.350789) (xy 385.946673 -297.402126) (xy 385.930611 -297.45156)
			(xy 385.907013 -297.497872) (xy 385.87646 -297.539922) (xy 385.839705 -297.576674) (xy 385.797653 -297.607224)
			(xy 385.751339 -297.630819) (xy 385.701905 -297.646879) (xy 385.650567 -297.655007) (xy 385.624578 -297.655488)
			(xy 384.674618 -297.655488) (xy 384.648626 -297.655046) (xy 384.597282 -297.646917) (xy 384.547842 -297.630855)
			(xy 384.501524 -297.607257) (xy 384.459467 -297.576703) (xy 384.422709 -297.539946) (xy 384.392153 -297.497891)
			(xy 384.368552 -297.451574) (xy 384.352488 -297.402135) (xy 384.344355 -297.350792) (xy 269.854705 -297.350792)
			(xy 269.846573 -297.402126) (xy 269.830511 -297.451559) (xy 269.806913 -297.497871) (xy 269.77636 -297.539921)
			(xy 269.739606 -297.576673) (xy 269.697554 -297.607223) (xy 269.651241 -297.630819) (xy 269.601807 -297.646878)
			(xy 269.550469 -297.655006) (xy 269.52448 -297.655488) (xy 268.57452 -297.655488) (xy 268.548528 -297.655046)
			(xy 268.497184 -297.646917) (xy 268.447744 -297.630856) (xy 268.401425 -297.607258) (xy 268.359368 -297.576704)
			(xy 268.322609 -297.539947) (xy 268.292053 -297.497892) (xy 268.268452 -297.451575) (xy 268.252388 -297.402135)
			(xy 268.244255 -297.350792) (xy 153.754778 -297.350792) (xy 153.74665 -297.402112) (xy 153.730592 -297.451536)
			(xy 153.707001 -297.497841) (xy 153.676457 -297.539885) (xy 153.639712 -297.576633) (xy 153.597671 -297.607182)
			(xy 153.55137 -297.630778) (xy 153.501947 -297.646841) (xy 153.45062 -297.654976) (xy 153.424636 -297.655488)
			(xy 152.474676 -297.655488) (xy 152.448688 -297.655017) (xy 152.397354 -297.646883) (xy 152.347923 -297.630818)
			(xy 152.301615 -297.60722) (xy 152.259567 -297.576668) (xy 152.222816 -297.539915) (xy 152.192268 -297.497865)
			(xy 152.168672 -297.451554) (xy 152.152612 -297.402123) (xy 152.144482 -297.350788) (xy 37.654678 -297.350788)
			(xy 37.64655 -297.402111) (xy 37.630492 -297.451536) (xy 37.606901 -297.49784) (xy 37.576357 -297.539884)
			(xy 37.539613 -297.576632) (xy 37.497572 -297.607181) (xy 37.451271 -297.630778) (xy 37.401848 -297.646841)
			(xy 37.350522 -297.654976) (xy 37.324538 -297.655488) (xy 36.374578 -297.655488) (xy 36.34859 -297.655017)
			(xy 36.297255 -297.646883) (xy 36.247825 -297.630819) (xy 36.201516 -297.607221) (xy 36.159468 -297.576669)
			(xy 36.122717 -297.539915) (xy 36.092168 -297.497866) (xy 36.068572 -297.451555) (xy 36.052512 -297.402123)
			(xy 36.044382 -297.350788) (xy 0.508 -297.350788) (xy 0.508 -298.77569) (xy 39.369695 -298.77569)
			(xy 39.369695 -298.72371) (xy 39.377827 -298.67237) (xy 39.393891 -298.622935) (xy 39.417492 -298.576621)
			(xy 39.448047 -298.53457) (xy 39.484805 -298.497817) (xy 39.52686 -298.467268) (xy 39.573177 -298.443674)
			(xy 39.622615 -298.427617) (xy 39.673956 -298.419492) (xy 39.699946 -298.419012) (xy 40.649906 -298.419012)
			(xy 40.675894 -298.419482) (xy 40.727231 -298.427614) (xy 40.776664 -298.443676) (xy 40.822975 -298.467274)
			(xy 40.865025 -298.497826) (xy 40.901778 -298.534579) (xy 40.932329 -298.57663) (xy 40.955926 -298.622942)
			(xy 40.971988 -298.672375) (xy 40.980118 -298.723712) (xy 40.980118 -298.775685) (xy 387.669821 -298.775685)
			(xy 387.669821 -298.723715) (xy 387.677951 -298.672385) (xy 387.69401 -298.622959) (xy 387.717603 -298.576653)
			(xy 387.74815 -298.534608) (xy 387.784897 -298.497859) (xy 387.826941 -298.467311) (xy 387.873246 -298.443716)
			(xy 387.922671 -298.427654) (xy 387.974001 -298.419523) (xy 387.999986 -298.419012) (xy 388.949946 -298.419012)
			(xy 388.975932 -298.419485) (xy 389.027264 -298.427622) (xy 389.076692 -298.443688) (xy 389.122998 -298.467288)
			(xy 389.165042 -298.49784) (xy 389.20179 -298.534593) (xy 389.232337 -298.576642) (xy 389.25593 -298.622951)
			(xy 389.271989 -298.67238) (xy 389.280119 -298.723714) (xy 389.280119 -298.775686) (xy 389.271989 -298.82702)
			(xy 389.25593 -298.876449) (xy 389.232337 -298.922758) (xy 389.20179 -298.964807) (xy 389.165042 -299.00156)
			(xy 389.122998 -299.032112) (xy 389.076692 -299.055712) (xy 389.027264 -299.071778) (xy 388.975932 -299.079915)
			(xy 388.949946 -299.080428) (xy 387.999986 -299.080428) (xy 387.974001 -299.079877) (xy 387.922671 -299.071746)
			(xy 387.873246 -299.055684) (xy 387.826941 -299.032089) (xy 387.784897 -299.001541) (xy 387.74815 -298.964792)
			(xy 387.717603 -298.922747) (xy 387.69401 -298.876441) (xy 387.677951 -298.827015) (xy 387.669821 -298.775685)
			(xy 40.980118 -298.775685) (xy 40.980118 -298.775688) (xy 40.971988 -298.827025) (xy 40.955926 -298.876458)
			(xy 40.932329 -298.92277) (xy 40.901778 -298.964821) (xy 40.865025 -299.001574) (xy 40.822975 -299.032126)
			(xy 40.776664 -299.055724) (xy 40.727231 -299.071786) (xy 40.675894 -299.079918) (xy 40.649906 -299.080428)
			(xy 39.699946 -299.080428) (xy 39.673956 -299.079908) (xy 39.622615 -299.071783) (xy 39.573177 -299.055726)
			(xy 39.52686 -299.032132) (xy 39.484805 -299.001583) (xy 39.448047 -298.96483) (xy 39.417492 -298.922779)
			(xy 39.393891 -298.876465) (xy 39.377827 -298.82703) (xy 39.369695 -298.77569) (xy 0.508 -298.77569)
			(xy 0.508 -299.25101) (xy 36.044102 -299.25101) (xy 36.044102 -299.19899) (xy 36.052239 -299.147611)
			(xy 36.068313 -299.098138) (xy 36.091929 -299.051788) (xy 36.122504 -299.009703) (xy 36.159286 -298.972918)
			(xy 36.201369 -298.94234) (xy 36.247718 -298.918722) (xy 36.29719 -298.902644) (xy 36.348568 -298.894504)
			(xy 36.374578 -298.893992) (xy 37.324538 -298.893992) (xy 37.35054 -298.894597) (xy 37.401902 -298.902737)
			(xy 37.451358 -298.918812) (xy 37.497691 -298.942425) (xy 37.539761 -298.972994) (xy 37.576531 -299.009768)
			(xy 37.607095 -299.051841) (xy 37.630703 -299.098177) (xy 37.646771 -299.147635) (xy 37.654906 -299.198998)
			(xy 37.654906 -299.251002) (xy 37.654905 -299.25101) (xy 152.144202 -299.25101) (xy 152.144202 -299.19899)
			(xy 152.152339 -299.147612) (xy 152.168413 -299.098138) (xy 152.192028 -299.051788) (xy 152.222603 -299.009703)
			(xy 152.259385 -298.972919) (xy 152.301468 -298.942341) (xy 152.347816 -298.918722) (xy 152.397288 -298.902645)
			(xy 152.448666 -298.894504) (xy 152.474676 -298.893992) (xy 153.424636 -298.893992) (xy 153.450638 -298.894597)
			(xy 153.502 -298.902737) (xy 153.551457 -298.918811) (xy 153.59779 -298.942424) (xy 153.63986 -298.972993)
			(xy 153.67663 -299.009767) (xy 153.707195 -299.05184) (xy 153.730803 -299.098177) (xy 153.746871 -299.147635)
			(xy 153.755006 -299.198998) (xy 153.755006 -299.251002) (xy 153.755005 -299.251009) (xy 154.994602 -299.251009)
			(xy 154.994602 -299.198991) (xy 155.002739 -299.147613) (xy 155.018812 -299.098141) (xy 155.042426 -299.051792)
			(xy 155.073 -299.009707) (xy 155.10978 -298.972923) (xy 155.151861 -298.942345) (xy 155.198208 -298.918726)
			(xy 155.247678 -298.902647) (xy 155.299055 -298.894505) (xy 155.325064 -298.893992) (xy 156.275024 -298.893992)
			(xy 156.301026 -298.894596) (xy 156.35239 -298.902735) (xy 156.401848 -298.918808) (xy 156.448184 -298.94242)
			(xy 156.490255 -298.972989) (xy 156.527026 -299.009763) (xy 156.557593 -299.051837) (xy 156.581201 -299.098174)
			(xy 156.597271 -299.147633) (xy 156.605406 -299.198998) (xy 156.605406 -299.251002) (xy 156.605404 -299.251014)
			(xy 268.243976 -299.251014) (xy 268.243976 -299.198986) (xy 268.252115 -299.147599) (xy 268.268193 -299.098118)
			(xy 268.291814 -299.051761) (xy 268.322396 -299.009671) (xy 268.359186 -298.972883) (xy 268.401279 -298.942303)
			(xy 268.447637 -298.918685) (xy 268.497119 -298.90261) (xy 268.548506 -298.894474) (xy 268.57452 -298.893992)
			(xy 269.52448 -298.893992) (xy 269.550487 -298.894566) (xy 269.60186 -298.9027) (xy 269.651328 -298.91877)
			(xy 269.697673 -298.942382) (xy 269.739754 -298.972953) (xy 269.776534 -299.009731) (xy 269.807108 -299.05181)
			(xy 269.830722 -299.098153) (xy 269.846796 -299.147621) (xy 269.854933 -299.198993) (xy 269.854933 -299.251007)
			(xy 269.854932 -299.251013) (xy 271.094376 -299.251013) (xy 271.094376 -299.198987) (xy 271.102514 -299.147601)
			(xy 271.118592 -299.098121) (xy 271.142212 -299.051765) (xy 271.172792 -299.009675) (xy 271.209581 -298.972887)
			(xy 271.251672 -298.942307) (xy 271.298028 -298.918689) (xy 271.347509 -298.902613) (xy 271.398895 -298.894475)
			(xy 271.424908 -298.893992) (xy 272.374868 -298.893992) (xy 272.400875 -298.894565) (xy 272.45225 -298.902697)
			(xy 272.50172 -298.918767) (xy 272.548067 -298.942378) (xy 272.590149 -298.972949) (xy 272.626931 -299.009727)
			(xy 272.657506 -299.051806) (xy 272.681121 -299.09815) (xy 272.697195 -299.147619) (xy 272.705333 -299.198993)
			(xy 272.705333 -299.251007) (xy 272.705332 -299.251014) (xy 384.344076 -299.251014) (xy 384.344076 -299.198986)
			(xy 384.352215 -299.147599) (xy 384.368293 -299.098118) (xy 384.391913 -299.051762) (xy 384.422495 -299.009672)
			(xy 384.459285 -298.972884) (xy 384.501377 -298.942304) (xy 384.547735 -298.918686) (xy 384.597217 -298.902611)
			(xy 384.648604 -298.894474) (xy 384.674618 -298.893992) (xy 385.624578 -298.893992) (xy 385.650585 -298.894566)
			(xy 385.701958 -298.902699) (xy 385.751427 -298.91877) (xy 385.797772 -298.942381) (xy 385.839853 -298.972952)
			(xy 385.876634 -299.00973) (xy 385.907207 -299.051809) (xy 385.930822 -299.098153) (xy 385.946896 -299.14762)
			(xy 385.955033 -299.198993) (xy 385.955033 -299.251007) (xy 385.946896 -299.30238) (xy 385.930822 -299.351847)
			(xy 385.907207 -299.398191) (xy 385.876634 -299.44027) (xy 385.839853 -299.477048) (xy 385.797772 -299.507619)
			(xy 385.751427 -299.53123) (xy 385.701958 -299.547301) (xy 385.650585 -299.555434) (xy 385.624578 -299.555916)
			(xy 384.674618 -299.555916) (xy 384.648604 -299.555526) (xy 384.597217 -299.547389) (xy 384.547735 -299.531314)
			(xy 384.501377 -299.507696) (xy 384.459285 -299.477116) (xy 384.422495 -299.440328) (xy 384.391913 -299.398238)
			(xy 384.368293 -299.351882) (xy 384.352215 -299.302401) (xy 384.344076 -299.251014) (xy 272.705332 -299.251014)
			(xy 272.697195 -299.302381) (xy 272.681121 -299.35185) (xy 272.657506 -299.398194) (xy 272.626931 -299.440273)
			(xy 272.590149 -299.477051) (xy 272.548067 -299.507622) (xy 272.50172 -299.531233) (xy 272.45225 -299.547303)
			(xy 272.400875 -299.555435) (xy 272.374868 -299.555916) (xy 271.424908 -299.555916) (xy 271.398895 -299.555525)
			(xy 271.347509 -299.547387) (xy 271.298028 -299.531311) (xy 271.251672 -299.507693) (xy 271.209581 -299.477113)
			(xy 271.172792 -299.440325) (xy 271.142212 -299.398235) (xy 271.118592 -299.351879) (xy 271.102514 -299.302399)
			(xy 271.094376 -299.251013) (xy 269.854932 -299.251013) (xy 269.846796 -299.302379) (xy 269.830722 -299.351847)
			(xy 269.807108 -299.39819) (xy 269.776534 -299.440269) (xy 269.739754 -299.477047) (xy 269.697673 -299.507618)
			(xy 269.651328 -299.53123) (xy 269.60186 -299.5473) (xy 269.550487 -299.555434) (xy 269.52448 -299.555916)
			(xy 268.57452 -299.555916) (xy 268.548506 -299.555526) (xy 268.497119 -299.54739) (xy 268.447637 -299.531315)
			(xy 268.401279 -299.507697) (xy 268.359186 -299.477117) (xy 268.322396 -299.440329) (xy 268.291814 -299.398239)
			(xy 268.268193 -299.351882) (xy 268.252115 -299.302401) (xy 268.243976 -299.251014) (xy 156.605404 -299.251014)
			(xy 156.597271 -299.302367) (xy 156.581201 -299.351826) (xy 156.557593 -299.398163) (xy 156.527026 -299.440237)
			(xy 156.490255 -299.477011) (xy 156.448184 -299.50758) (xy 156.401848 -299.531192) (xy 156.35239 -299.547265)
			(xy 156.301026 -299.555404) (xy 156.275024 -299.555916) (xy 155.325064 -299.555916) (xy 155.299055 -299.555495)
			(xy 155.247678 -299.547353) (xy 155.198208 -299.531274) (xy 155.151861 -299.507655) (xy 155.10978 -299.477077)
			(xy 155.073 -299.440293) (xy 155.042426 -299.398208) (xy 155.018812 -299.351859) (xy 155.002739 -299.302387)
			(xy 154.994602 -299.251009) (xy 153.755005 -299.251009) (xy 153.746871 -299.302365) (xy 153.730803 -299.351823)
			(xy 153.707195 -299.39816) (xy 153.67663 -299.440233) (xy 153.63986 -299.477007) (xy 153.59779 -299.507576)
			(xy 153.551457 -299.531189) (xy 153.502 -299.547263) (xy 153.450638 -299.555403) (xy 153.424636 -299.555916)
			(xy 152.474676 -299.555916) (xy 152.448666 -299.555496) (xy 152.397288 -299.547355) (xy 152.347816 -299.531278)
			(xy 152.301468 -299.507659) (xy 152.259385 -299.477081) (xy 152.222603 -299.440297) (xy 152.192028 -299.398212)
			(xy 152.168413 -299.351862) (xy 152.152339 -299.302388) (xy 152.144202 -299.25101) (xy 37.654905 -299.25101)
			(xy 37.646771 -299.302365) (xy 37.630703 -299.351823) (xy 37.607095 -299.398159) (xy 37.576531 -299.440232)
			(xy 37.539761 -299.477006) (xy 37.497691 -299.507575) (xy 37.451358 -299.531188) (xy 37.401902 -299.547263)
			(xy 37.35054 -299.555403) (xy 37.324538 -299.555916) (xy 36.374578 -299.555916) (xy 36.348568 -299.555496)
			(xy 36.29719 -299.547356) (xy 36.247718 -299.531278) (xy 36.201369 -299.50766) (xy 36.159286 -299.477082)
			(xy 36.122504 -299.440297) (xy 36.091929 -299.398212) (xy 36.068313 -299.351862) (xy 36.052239 -299.302389)
			(xy 36.044102 -299.25101) (xy 0.508 -299.25101) (xy 0.508 -301.599854) (xy 154.54428 -301.599854)
			(xy 154.54824 -301.5508) (xy 154.560017 -301.503016) (xy 154.579308 -301.45774) (xy 154.605611 -301.416144)
			(xy 154.638246 -301.379307) (xy 154.676367 -301.348182) (xy 154.718988 -301.323575) (xy 154.765004 -301.306123)
			(xy 154.813223 -301.296279) (xy 154.862398 -301.294298) (xy 154.911253 -301.30023) (xy 154.958524 -301.313922)
			(xy 155.002986 -301.33502) (xy 155.043489 -301.362976) (xy 155.078982 -301.397068) (xy 155.108547 -301.436412)
			(xy 155.131418 -301.479989) (xy 155.147002 -301.52667) (xy 155.154897 -301.575247) (xy 155.155392 -301.599854)
			(xy 155.49424 -301.599854) (xy 155.4982 -301.5508) (xy 155.509977 -301.503016) (xy 155.529268 -301.45774)
			(xy 155.555571 -301.416144) (xy 155.588206 -301.379307) (xy 155.626327 -301.348182) (xy 155.668948 -301.323575)
			(xy 155.714964 -301.306123) (xy 155.763183 -301.296279) (xy 155.812358 -301.294298) (xy 155.861213 -301.30023)
			(xy 155.908484 -301.313922) (xy 155.952946 -301.33502) (xy 155.993449 -301.362976) (xy 156.028942 -301.397068)
			(xy 156.058507 -301.436412) (xy 156.081378 -301.479989) (xy 156.096962 -301.52667) (xy 156.104857 -301.575247)
			(xy 156.105352 -301.599854) (xy 157.39416 -301.599854) (xy 157.39812 -301.5508) (xy 157.409897 -301.503016)
			(xy 157.429188 -301.45774) (xy 157.455491 -301.416144) (xy 157.488126 -301.379307) (xy 157.526247 -301.348182)
			(xy 157.568868 -301.323575) (xy 157.614884 -301.306123) (xy 157.663103 -301.296279) (xy 157.712278 -301.294298)
			(xy 157.761133 -301.30023) (xy 157.808404 -301.313922) (xy 157.852866 -301.33502) (xy 157.893369 -301.362976)
			(xy 157.928862 -301.397068) (xy 157.958427 -301.436412) (xy 157.981298 -301.479989) (xy 157.996882 -301.52667)
			(xy 158.004777 -301.575247) (xy 158.005272 -301.599854) (xy 158.34412 -301.599854) (xy 158.34808 -301.5508)
			(xy 158.359857 -301.503016) (xy 158.379148 -301.45774) (xy 158.405451 -301.416144) (xy 158.438086 -301.379307)
			(xy 158.476207 -301.348182) (xy 158.518828 -301.323575) (xy 158.564844 -301.306123) (xy 158.613063 -301.296279)
			(xy 158.662238 -301.294298) (xy 158.711093 -301.30023) (xy 158.758364 -301.313922) (xy 158.802826 -301.33502)
			(xy 158.843329 -301.362976) (xy 158.878822 -301.397068) (xy 158.908387 -301.436412) (xy 158.931258 -301.479989)
			(xy 158.946842 -301.52667) (xy 158.954737 -301.575247) (xy 158.955232 -301.599854) (xy 386.744222 -301.599854)
			(xy 386.748182 -301.5508) (xy 386.759959 -301.503016) (xy 386.77925 -301.45774) (xy 386.805553 -301.416144)
			(xy 386.838188 -301.379307) (xy 386.876309 -301.348182) (xy 386.91893 -301.323575) (xy 386.964946 -301.306123)
			(xy 387.013165 -301.296279) (xy 387.06234 -301.294298) (xy 387.111195 -301.30023) (xy 387.158466 -301.313922)
			(xy 387.202928 -301.33502) (xy 387.243431 -301.362976) (xy 387.278924 -301.397068) (xy 387.308489 -301.436412)
			(xy 387.33136 -301.479989) (xy 387.346944 -301.52667) (xy 387.354839 -301.575247) (xy 387.355334 -301.599854)
			(xy 387.694182 -301.599854) (xy 387.698142 -301.5508) (xy 387.709919 -301.503016) (xy 387.72921 -301.45774)
			(xy 387.755513 -301.416144) (xy 387.788148 -301.379307) (xy 387.826269 -301.348182) (xy 387.86889 -301.323575)
			(xy 387.914906 -301.306123) (xy 387.963125 -301.296279) (xy 388.0123 -301.294298) (xy 388.061155 -301.30023)
			(xy 388.108426 -301.313922) (xy 388.152888 -301.33502) (xy 388.193391 -301.362976) (xy 388.228884 -301.397068)
			(xy 388.258449 -301.436412) (xy 388.28132 -301.479989) (xy 388.296904 -301.52667) (xy 388.304799 -301.575247)
			(xy 388.305294 -301.599854) (xy 389.594102 -301.599854) (xy 389.598062 -301.5508) (xy 389.609839 -301.503016)
			(xy 389.62913 -301.45774) (xy 389.655433 -301.416144) (xy 389.688068 -301.379307) (xy 389.726189 -301.348182)
			(xy 389.76881 -301.323575) (xy 389.814826 -301.306123) (xy 389.863045 -301.296279) (xy 389.91222 -301.294298)
			(xy 389.961075 -301.30023) (xy 390.008346 -301.313922) (xy 390.052808 -301.33502) (xy 390.093311 -301.362976)
			(xy 390.128804 -301.397068) (xy 390.158369 -301.436412) (xy 390.18124 -301.479989) (xy 390.196824 -301.52667)
			(xy 390.204719 -301.575247) (xy 390.205214 -301.599854) (xy 390.544062 -301.599854) (xy 390.548022 -301.5508)
			(xy 390.559799 -301.503016) (xy 390.57909 -301.45774) (xy 390.605393 -301.416144) (xy 390.638028 -301.379307)
			(xy 390.676149 -301.348182) (xy 390.71877 -301.323575) (xy 390.764786 -301.306123) (xy 390.813005 -301.296279)
			(xy 390.86218 -301.294298) (xy 390.911035 -301.30023) (xy 390.958306 -301.313922) (xy 391.002768 -301.33502)
			(xy 391.043271 -301.362976) (xy 391.078764 -301.397068) (xy 391.108329 -301.436412) (xy 391.1312 -301.479989)
			(xy 391.146784 -301.52667) (xy 391.154679 -301.575247) (xy 391.155174 -301.599854) (xy 391.154679 -301.624461)
			(xy 391.146784 -301.673038) (xy 391.1312 -301.719719) (xy 391.108329 -301.763296) (xy 391.078764 -301.80264)
			(xy 391.043271 -301.836732) (xy 391.002768 -301.864688) (xy 390.958306 -301.885786) (xy 390.911035 -301.899478)
			(xy 390.86218 -301.90541) (xy 390.813005 -301.903429) (xy 390.764786 -301.893585) (xy 390.71877 -301.876133)
			(xy 390.676149 -301.851526) (xy 390.638028 -301.820401) (xy 390.605393 -301.783564) (xy 390.57909 -301.741968)
			(xy 390.559799 -301.696692) (xy 390.548022 -301.648908) (xy 390.544062 -301.599854) (xy 390.205214 -301.599854)
			(xy 390.204719 -301.624461) (xy 390.196824 -301.673038) (xy 390.18124 -301.719719) (xy 390.158369 -301.763296)
			(xy 390.128804 -301.80264) (xy 390.093311 -301.836732) (xy 390.052808 -301.864688) (xy 390.008346 -301.885786)
			(xy 389.961075 -301.899478) (xy 389.91222 -301.90541) (xy 389.863045 -301.903429) (xy 389.814826 -301.893585)
			(xy 389.76881 -301.876133) (xy 389.726189 -301.851526) (xy 389.688068 -301.820401) (xy 389.655433 -301.783564)
			(xy 389.62913 -301.741968) (xy 389.609839 -301.696692) (xy 389.598062 -301.648908) (xy 389.594102 -301.599854)
			(xy 388.305294 -301.599854) (xy 388.304799 -301.624461) (xy 388.296904 -301.673038) (xy 388.28132 -301.719719)
			(xy 388.258449 -301.763296) (xy 388.228884 -301.80264) (xy 388.193391 -301.836732) (xy 388.152888 -301.864688)
			(xy 388.108426 -301.885786) (xy 388.061155 -301.899478) (xy 388.0123 -301.90541) (xy 387.963125 -301.903429)
			(xy 387.914906 -301.893585) (xy 387.86889 -301.876133) (xy 387.826269 -301.851526) (xy 387.788148 -301.820401)
			(xy 387.755513 -301.783564) (xy 387.72921 -301.741968) (xy 387.709919 -301.696692) (xy 387.698142 -301.648908)
			(xy 387.694182 -301.599854) (xy 387.355334 -301.599854) (xy 387.354839 -301.624461) (xy 387.346944 -301.673038)
			(xy 387.33136 -301.719719) (xy 387.308489 -301.763296) (xy 387.278924 -301.80264) (xy 387.243431 -301.836732)
			(xy 387.202928 -301.864688) (xy 387.158466 -301.885786) (xy 387.111195 -301.899478) (xy 387.06234 -301.90541)
			(xy 387.013165 -301.903429) (xy 386.964946 -301.893585) (xy 386.91893 -301.876133) (xy 386.876309 -301.851526)
			(xy 386.838188 -301.820401) (xy 386.805553 -301.783564) (xy 386.77925 -301.741968) (xy 386.759959 -301.696692)
			(xy 386.748182 -301.648908) (xy 386.744222 -301.599854) (xy 158.955232 -301.599854) (xy 158.954737 -301.624461)
			(xy 158.946842 -301.673038) (xy 158.931258 -301.719719) (xy 158.908387 -301.763296) (xy 158.878822 -301.80264)
			(xy 158.843329 -301.836732) (xy 158.802826 -301.864688) (xy 158.758364 -301.885786) (xy 158.711093 -301.899478)
			(xy 158.662238 -301.90541) (xy 158.613063 -301.903429) (xy 158.564844 -301.893585) (xy 158.518828 -301.876133)
			(xy 158.476207 -301.851526) (xy 158.438086 -301.820401) (xy 158.405451 -301.783564) (xy 158.379148 -301.741968)
			(xy 158.359857 -301.696692) (xy 158.34808 -301.648908) (xy 158.34412 -301.599854) (xy 158.005272 -301.599854)
			(xy 158.004777 -301.624461) (xy 157.996882 -301.673038) (xy 157.981298 -301.719719) (xy 157.958427 -301.763296)
			(xy 157.928862 -301.80264) (xy 157.893369 -301.836732) (xy 157.852866 -301.864688) (xy 157.808404 -301.885786)
			(xy 157.761133 -301.899478) (xy 157.712278 -301.90541) (xy 157.663103 -301.903429) (xy 157.614884 -301.893585)
			(xy 157.568868 -301.876133) (xy 157.526247 -301.851526) (xy 157.488126 -301.820401) (xy 157.455491 -301.783564)
			(xy 157.429188 -301.741968) (xy 157.409897 -301.696692) (xy 157.39812 -301.648908) (xy 157.39416 -301.599854)
			(xy 156.105352 -301.599854) (xy 156.104857 -301.624461) (xy 156.096962 -301.673038) (xy 156.081378 -301.719719)
			(xy 156.058507 -301.763296) (xy 156.028942 -301.80264) (xy 155.993449 -301.836732) (xy 155.952946 -301.864688)
			(xy 155.908484 -301.885786) (xy 155.861213 -301.899478) (xy 155.812358 -301.90541) (xy 155.763183 -301.903429)
			(xy 155.714964 -301.893585) (xy 155.668948 -301.876133) (xy 155.626327 -301.851526) (xy 155.588206 -301.820401)
			(xy 155.555571 -301.783564) (xy 155.529268 -301.741968) (xy 155.509977 -301.696692) (xy 155.4982 -301.648908)
			(xy 155.49424 -301.599854) (xy 155.155392 -301.599854) (xy 155.154897 -301.624461) (xy 155.147002 -301.673038)
			(xy 155.131418 -301.719719) (xy 155.108547 -301.763296) (xy 155.078982 -301.80264) (xy 155.043489 -301.836732)
			(xy 155.002986 -301.864688) (xy 154.958524 -301.885786) (xy 154.911253 -301.899478) (xy 154.862398 -301.90541)
			(xy 154.813223 -301.903429) (xy 154.765004 -301.893585) (xy 154.718988 -301.876133) (xy 154.676367 -301.851526)
			(xy 154.638246 -301.820401) (xy 154.605611 -301.783564) (xy 154.579308 -301.741968) (xy 154.560017 -301.696692)
			(xy 154.54824 -301.648908) (xy 154.54428 -301.599854) (xy 0.508 -301.599854) (xy 0.508 -302.549814)
			(xy 152.644106 -302.549814) (xy 152.648066 -302.50076) (xy 152.659843 -302.452976) (xy 152.679134 -302.4077)
			(xy 152.705437 -302.366104) (xy 152.738072 -302.329267) (xy 152.776193 -302.298142) (xy 152.818814 -302.273535)
			(xy 152.86483 -302.256083) (xy 152.913049 -302.246239) (xy 152.962224 -302.244258) (xy 153.011079 -302.25019)
			(xy 153.05835 -302.263882) (xy 153.102812 -302.28498) (xy 153.143315 -302.312936) (xy 153.178808 -302.347028)
			(xy 153.208373 -302.386372) (xy 153.231244 -302.429949) (xy 153.246828 -302.47663) (xy 153.254723 -302.525207)
			(xy 153.255218 -302.549814) (xy 153.594066 -302.549814) (xy 153.598026 -302.50076) (xy 153.609803 -302.452976)
			(xy 153.629094 -302.4077) (xy 153.655397 -302.366104) (xy 153.688032 -302.329267) (xy 153.726153 -302.298142)
			(xy 153.768774 -302.273535) (xy 153.81479 -302.256083) (xy 153.863009 -302.246239) (xy 153.912184 -302.244258)
			(xy 153.961039 -302.25019) (xy 154.00831 -302.263882) (xy 154.052772 -302.28498) (xy 154.093275 -302.312936)
			(xy 154.128768 -302.347028) (xy 154.158333 -302.386372) (xy 154.181204 -302.429949) (xy 154.196788 -302.47663)
			(xy 154.204683 -302.525207) (xy 154.205178 -302.549814) (xy 159.29408 -302.549814) (xy 159.29804 -302.50076)
			(xy 159.309817 -302.452976) (xy 159.329108 -302.4077) (xy 159.355411 -302.366104) (xy 159.388046 -302.329267)
			(xy 159.426167 -302.298142) (xy 159.468788 -302.273535) (xy 159.514804 -302.256083) (xy 159.563023 -302.246239)
			(xy 159.612198 -302.244258) (xy 159.661053 -302.25019) (xy 159.708324 -302.263882) (xy 159.752786 -302.28498)
			(xy 159.793289 -302.312936) (xy 159.828782 -302.347028) (xy 159.858347 -302.386372) (xy 159.881218 -302.429949)
			(xy 159.896802 -302.47663) (xy 159.904697 -302.525207) (xy 159.905192 -302.549814) (xy 160.24404 -302.549814)
			(xy 160.248 -302.50076) (xy 160.259777 -302.452976) (xy 160.279068 -302.4077) (xy 160.305371 -302.366104)
			(xy 160.338006 -302.329267) (xy 160.376127 -302.298142) (xy 160.418748 -302.273535) (xy 160.464764 -302.256083)
			(xy 160.512983 -302.246239) (xy 160.562158 -302.244258) (xy 160.611013 -302.25019) (xy 160.658284 -302.263882)
			(xy 160.702746 -302.28498) (xy 160.743249 -302.312936) (xy 160.778742 -302.347028) (xy 160.808307 -302.386372)
			(xy 160.831178 -302.429949) (xy 160.846762 -302.47663) (xy 160.854657 -302.525207) (xy 160.855152 -302.549814)
			(xy 384.844048 -302.549814) (xy 384.848008 -302.50076) (xy 384.859785 -302.452976) (xy 384.879076 -302.4077)
			(xy 384.905379 -302.366104) (xy 384.938014 -302.329267) (xy 384.976135 -302.298142) (xy 385.018756 -302.273535)
			(xy 385.064772 -302.256083) (xy 385.112991 -302.246239) (xy 385.162166 -302.244258) (xy 385.211021 -302.25019)
			(xy 385.258292 -302.263882) (xy 385.302754 -302.28498) (xy 385.343257 -302.312936) (xy 385.37875 -302.347028)
			(xy 385.408315 -302.386372) (xy 385.431186 -302.429949) (xy 385.44677 -302.47663) (xy 385.454665 -302.525207)
			(xy 385.45516 -302.549814) (xy 385.794008 -302.549814) (xy 385.797968 -302.50076) (xy 385.809745 -302.452976)
			(xy 385.829036 -302.4077) (xy 385.855339 -302.366104) (xy 385.887974 -302.329267) (xy 385.926095 -302.298142)
			(xy 385.968716 -302.273535) (xy 386.014732 -302.256083) (xy 386.062951 -302.246239) (xy 386.112126 -302.244258)
			(xy 386.160981 -302.25019) (xy 386.208252 -302.263882) (xy 386.252714 -302.28498) (xy 386.293217 -302.312936)
			(xy 386.32871 -302.347028) (xy 386.358275 -302.386372) (xy 386.381146 -302.429949) (xy 386.39673 -302.47663)
			(xy 386.404625 -302.525207) (xy 386.40512 -302.549814) (xy 391.494022 -302.549814) (xy 391.497982 -302.50076)
			(xy 391.509759 -302.452976) (xy 391.52905 -302.4077) (xy 391.555353 -302.366104) (xy 391.587988 -302.329267)
			(xy 391.626109 -302.298142) (xy 391.66873 -302.273535) (xy 391.714746 -302.256083) (xy 391.762965 -302.246239)
			(xy 391.81214 -302.244258) (xy 391.860995 -302.25019) (xy 391.908266 -302.263882) (xy 391.952728 -302.28498)
			(xy 391.993231 -302.312936) (xy 392.028724 -302.347028) (xy 392.058289 -302.386372) (xy 392.08116 -302.429949)
			(xy 392.096744 -302.47663) (xy 392.104639 -302.525207) (xy 392.105134 -302.549814) (xy 392.443982 -302.549814)
			(xy 392.447942 -302.50076) (xy 392.459719 -302.452976) (xy 392.47901 -302.4077) (xy 392.505313 -302.366104)
			(xy 392.537948 -302.329267) (xy 392.576069 -302.298142) (xy 392.61869 -302.273535) (xy 392.664706 -302.256083)
			(xy 392.712925 -302.246239) (xy 392.7621 -302.244258) (xy 392.810955 -302.25019) (xy 392.858226 -302.263882)
			(xy 392.902688 -302.28498) (xy 392.943191 -302.312936) (xy 392.978684 -302.347028) (xy 393.008249 -302.386372)
			(xy 393.03112 -302.429949) (xy 393.046704 -302.47663) (xy 393.054599 -302.525207) (xy 393.055094 -302.549814)
			(xy 393.054599 -302.574421) (xy 393.046704 -302.622998) (xy 393.03112 -302.669679) (xy 393.008249 -302.713256)
			(xy 392.978684 -302.7526) (xy 392.943191 -302.786692) (xy 392.902688 -302.814648) (xy 392.858226 -302.835746)
			(xy 392.810955 -302.849438) (xy 392.7621 -302.85537) (xy 392.712925 -302.853389) (xy 392.664706 -302.843545)
			(xy 392.61869 -302.826093) (xy 392.576069 -302.801486) (xy 392.537948 -302.770361) (xy 392.505313 -302.733524)
			(xy 392.47901 -302.691928) (xy 392.459719 -302.646652) (xy 392.447942 -302.598868) (xy 392.443982 -302.549814)
			(xy 392.105134 -302.549814) (xy 392.104639 -302.574421) (xy 392.096744 -302.622998) (xy 392.08116 -302.669679)
			(xy 392.058289 -302.713256) (xy 392.028724 -302.7526) (xy 391.993231 -302.786692) (xy 391.952728 -302.814648)
			(xy 391.908266 -302.835746) (xy 391.860995 -302.849438) (xy 391.81214 -302.85537) (xy 391.762965 -302.853389)
			(xy 391.714746 -302.843545) (xy 391.66873 -302.826093) (xy 391.626109 -302.801486) (xy 391.587988 -302.770361)
			(xy 391.555353 -302.733524) (xy 391.52905 -302.691928) (xy 391.509759 -302.646652) (xy 391.497982 -302.598868)
			(xy 391.494022 -302.549814) (xy 386.40512 -302.549814) (xy 386.404625 -302.574421) (xy 386.39673 -302.622998)
			(xy 386.381146 -302.669679) (xy 386.358275 -302.713256) (xy 386.32871 -302.7526) (xy 386.293217 -302.786692)
			(xy 386.252714 -302.814648) (xy 386.208252 -302.835746) (xy 386.160981 -302.849438) (xy 386.112126 -302.85537)
			(xy 386.062951 -302.853389) (xy 386.014732 -302.843545) (xy 385.968716 -302.826093) (xy 385.926095 -302.801486)
			(xy 385.887974 -302.770361) (xy 385.855339 -302.733524) (xy 385.829036 -302.691928) (xy 385.809745 -302.646652)
			(xy 385.797968 -302.598868) (xy 385.794008 -302.549814) (xy 385.45516 -302.549814) (xy 385.454665 -302.574421)
			(xy 385.44677 -302.622998) (xy 385.431186 -302.669679) (xy 385.408315 -302.713256) (xy 385.37875 -302.7526)
			(xy 385.343257 -302.786692) (xy 385.302754 -302.814648) (xy 385.258292 -302.835746) (xy 385.211021 -302.849438)
			(xy 385.162166 -302.85537) (xy 385.112991 -302.853389) (xy 385.064772 -302.843545) (xy 385.018756 -302.826093)
			(xy 384.976135 -302.801486) (xy 384.938014 -302.770361) (xy 384.905379 -302.733524) (xy 384.879076 -302.691928)
			(xy 384.859785 -302.646652) (xy 384.848008 -302.598868) (xy 384.844048 -302.549814) (xy 160.855152 -302.549814)
			(xy 160.854657 -302.574421) (xy 160.846762 -302.622998) (xy 160.831178 -302.669679) (xy 160.808307 -302.713256)
			(xy 160.778742 -302.7526) (xy 160.743249 -302.786692) (xy 160.702746 -302.814648) (xy 160.658284 -302.835746)
			(xy 160.611013 -302.849438) (xy 160.562158 -302.85537) (xy 160.512983 -302.853389) (xy 160.464764 -302.843545)
			(xy 160.418748 -302.826093) (xy 160.376127 -302.801486) (xy 160.338006 -302.770361) (xy 160.305371 -302.733524)
			(xy 160.279068 -302.691928) (xy 160.259777 -302.646652) (xy 160.248 -302.598868) (xy 160.24404 -302.549814)
			(xy 159.905192 -302.549814) (xy 159.904697 -302.574421) (xy 159.896802 -302.622998) (xy 159.881218 -302.669679)
			(xy 159.858347 -302.713256) (xy 159.828782 -302.7526) (xy 159.793289 -302.786692) (xy 159.752786 -302.814648)
			(xy 159.708324 -302.835746) (xy 159.661053 -302.849438) (xy 159.612198 -302.85537) (xy 159.563023 -302.853389)
			(xy 159.514804 -302.843545) (xy 159.468788 -302.826093) (xy 159.426167 -302.801486) (xy 159.388046 -302.770361)
			(xy 159.355411 -302.733524) (xy 159.329108 -302.691928) (xy 159.309817 -302.646652) (xy 159.29804 -302.598868)
			(xy 159.29408 -302.549814) (xy 154.205178 -302.549814) (xy 154.204683 -302.574421) (xy 154.196788 -302.622998)
			(xy 154.181204 -302.669679) (xy 154.158333 -302.713256) (xy 154.128768 -302.7526) (xy 154.093275 -302.786692)
			(xy 154.052772 -302.814648) (xy 154.00831 -302.835746) (xy 153.961039 -302.849438) (xy 153.912184 -302.85537)
			(xy 153.863009 -302.853389) (xy 153.81479 -302.843545) (xy 153.768774 -302.826093) (xy 153.726153 -302.801486)
			(xy 153.688032 -302.770361) (xy 153.655397 -302.733524) (xy 153.629094 -302.691928) (xy 153.609803 -302.646652)
			(xy 153.598026 -302.598868) (xy 153.594066 -302.549814) (xy 153.255218 -302.549814) (xy 153.254723 -302.574421)
			(xy 153.246828 -302.622998) (xy 153.231244 -302.669679) (xy 153.208373 -302.713256) (xy 153.178808 -302.7526)
			(xy 153.143315 -302.786692) (xy 153.102812 -302.814648) (xy 153.05835 -302.835746) (xy 153.011079 -302.849438)
			(xy 152.962224 -302.85537) (xy 152.913049 -302.853389) (xy 152.86483 -302.843545) (xy 152.818814 -302.826093)
			(xy 152.776193 -302.801486) (xy 152.738072 -302.770361) (xy 152.705437 -302.733524) (xy 152.679134 -302.691928)
			(xy 152.659843 -302.646652) (xy 152.648066 -302.598868) (xy 152.644106 -302.549814) (xy 0.508 -302.549814)
			(xy 0.508 -303.499774) (xy 154.54428 -303.499774) (xy 154.54824 -303.45072) (xy 154.560017 -303.402936)
			(xy 154.579308 -303.35766) (xy 154.605611 -303.316064) (xy 154.638246 -303.279227) (xy 154.676367 -303.248102)
			(xy 154.718988 -303.223495) (xy 154.765004 -303.206043) (xy 154.813223 -303.196199) (xy 154.862398 -303.194218)
			(xy 154.911253 -303.20015) (xy 154.958524 -303.213842) (xy 155.002986 -303.23494) (xy 155.043489 -303.262896)
			(xy 155.078982 -303.296988) (xy 155.108547 -303.336332) (xy 155.131418 -303.379909) (xy 155.147002 -303.42659)
			(xy 155.154897 -303.475167) (xy 155.155392 -303.499774) (xy 155.49424 -303.499774) (xy 155.4982 -303.45072)
			(xy 155.509977 -303.402936) (xy 155.529268 -303.35766) (xy 155.555571 -303.316064) (xy 155.588206 -303.279227)
			(xy 155.626327 -303.248102) (xy 155.668948 -303.223495) (xy 155.714964 -303.206043) (xy 155.763183 -303.196199)
			(xy 155.812358 -303.194218) (xy 155.861213 -303.20015) (xy 155.908484 -303.213842) (xy 155.952946 -303.23494)
			(xy 155.993449 -303.262896) (xy 156.028942 -303.296988) (xy 156.058507 -303.336332) (xy 156.081378 -303.379909)
			(xy 156.096962 -303.42659) (xy 156.104857 -303.475167) (xy 156.105352 -303.499774) (xy 157.39416 -303.499774)
			(xy 157.39812 -303.45072) (xy 157.409897 -303.402936) (xy 157.429188 -303.35766) (xy 157.455491 -303.316064)
			(xy 157.488126 -303.279227) (xy 157.526247 -303.248102) (xy 157.568868 -303.223495) (xy 157.614884 -303.206043)
			(xy 157.663103 -303.196199) (xy 157.712278 -303.194218) (xy 157.761133 -303.20015) (xy 157.808404 -303.213842)
			(xy 157.852866 -303.23494) (xy 157.893369 -303.262896) (xy 157.928862 -303.296988) (xy 157.958427 -303.336332)
			(xy 157.981298 -303.379909) (xy 157.996882 -303.42659) (xy 158.004777 -303.475167) (xy 158.005272 -303.499774)
			(xy 158.34412 -303.499774) (xy 158.34808 -303.45072) (xy 158.359857 -303.402936) (xy 158.379148 -303.35766)
			(xy 158.405451 -303.316064) (xy 158.438086 -303.279227) (xy 158.476207 -303.248102) (xy 158.518828 -303.223495)
			(xy 158.564844 -303.206043) (xy 158.613063 -303.196199) (xy 158.662238 -303.194218) (xy 158.711093 -303.20015)
			(xy 158.758364 -303.213842) (xy 158.802826 -303.23494) (xy 158.843329 -303.262896) (xy 158.878822 -303.296988)
			(xy 158.908387 -303.336332) (xy 158.931258 -303.379909) (xy 158.946842 -303.42659) (xy 158.954737 -303.475167)
			(xy 158.955232 -303.499774) (xy 386.744222 -303.499774) (xy 386.748182 -303.45072) (xy 386.759959 -303.402936)
			(xy 386.77925 -303.35766) (xy 386.805553 -303.316064) (xy 386.838188 -303.279227) (xy 386.876309 -303.248102)
			(xy 386.91893 -303.223495) (xy 386.964946 -303.206043) (xy 387.013165 -303.196199) (xy 387.06234 -303.194218)
			(xy 387.111195 -303.20015) (xy 387.158466 -303.213842) (xy 387.202928 -303.23494) (xy 387.243431 -303.262896)
			(xy 387.278924 -303.296988) (xy 387.308489 -303.336332) (xy 387.33136 -303.379909) (xy 387.346944 -303.42659)
			(xy 387.354839 -303.475167) (xy 387.355334 -303.499774) (xy 387.694182 -303.499774) (xy 387.698142 -303.45072)
			(xy 387.709919 -303.402936) (xy 387.72921 -303.35766) (xy 387.755513 -303.316064) (xy 387.788148 -303.279227)
			(xy 387.826269 -303.248102) (xy 387.86889 -303.223495) (xy 387.914906 -303.206043) (xy 387.963125 -303.196199)
			(xy 388.0123 -303.194218) (xy 388.061155 -303.20015) (xy 388.108426 -303.213842) (xy 388.152888 -303.23494)
			(xy 388.193391 -303.262896) (xy 388.228884 -303.296988) (xy 388.258449 -303.336332) (xy 388.28132 -303.379909)
			(xy 388.296904 -303.42659) (xy 388.304799 -303.475167) (xy 388.305294 -303.499774) (xy 389.594102 -303.499774)
			(xy 389.598062 -303.45072) (xy 389.609839 -303.402936) (xy 389.62913 -303.35766) (xy 389.655433 -303.316064)
			(xy 389.688068 -303.279227) (xy 389.726189 -303.248102) (xy 389.76881 -303.223495) (xy 389.814826 -303.206043)
			(xy 389.863045 -303.196199) (xy 389.91222 -303.194218) (xy 389.961075 -303.20015) (xy 390.008346 -303.213842)
			(xy 390.052808 -303.23494) (xy 390.093311 -303.262896) (xy 390.128804 -303.296988) (xy 390.158369 -303.336332)
			(xy 390.18124 -303.379909) (xy 390.196824 -303.42659) (xy 390.204719 -303.475167) (xy 390.205214 -303.499774)
			(xy 390.544062 -303.499774) (xy 390.548022 -303.45072) (xy 390.559799 -303.402936) (xy 390.57909 -303.35766)
			(xy 390.605393 -303.316064) (xy 390.638028 -303.279227) (xy 390.676149 -303.248102) (xy 390.71877 -303.223495)
			(xy 390.764786 -303.206043) (xy 390.813005 -303.196199) (xy 390.86218 -303.194218) (xy 390.911035 -303.20015)
			(xy 390.958306 -303.213842) (xy 391.002768 -303.23494) (xy 391.043271 -303.262896) (xy 391.078764 -303.296988)
			(xy 391.108329 -303.336332) (xy 391.1312 -303.379909) (xy 391.146784 -303.42659) (xy 391.154679 -303.475167)
			(xy 391.155174 -303.499774) (xy 391.154679 -303.524381) (xy 391.146784 -303.572958) (xy 391.1312 -303.619639)
			(xy 391.108329 -303.663216) (xy 391.078764 -303.70256) (xy 391.043271 -303.736652) (xy 391.002768 -303.764608)
			(xy 390.958306 -303.785706) (xy 390.911035 -303.799398) (xy 390.86218 -303.80533) (xy 390.813005 -303.803349)
			(xy 390.764786 -303.793505) (xy 390.71877 -303.776053) (xy 390.676149 -303.751446) (xy 390.638028 -303.720321)
			(xy 390.605393 -303.683484) (xy 390.57909 -303.641888) (xy 390.559799 -303.596612) (xy 390.548022 -303.548828)
			(xy 390.544062 -303.499774) (xy 390.205214 -303.499774) (xy 390.204719 -303.524381) (xy 390.196824 -303.572958)
			(xy 390.18124 -303.619639) (xy 390.158369 -303.663216) (xy 390.128804 -303.70256) (xy 390.093311 -303.736652)
			(xy 390.052808 -303.764608) (xy 390.008346 -303.785706) (xy 389.961075 -303.799398) (xy 389.91222 -303.80533)
			(xy 389.863045 -303.803349) (xy 389.814826 -303.793505) (xy 389.76881 -303.776053) (xy 389.726189 -303.751446)
			(xy 389.688068 -303.720321) (xy 389.655433 -303.683484) (xy 389.62913 -303.641888) (xy 389.609839 -303.596612)
			(xy 389.598062 -303.548828) (xy 389.594102 -303.499774) (xy 388.305294 -303.499774) (xy 388.304799 -303.524381)
			(xy 388.296904 -303.572958) (xy 388.28132 -303.619639) (xy 388.258449 -303.663216) (xy 388.228884 -303.70256)
			(xy 388.193391 -303.736652) (xy 388.152888 -303.764608) (xy 388.108426 -303.785706) (xy 388.061155 -303.799398)
			(xy 388.0123 -303.80533) (xy 387.963125 -303.803349) (xy 387.914906 -303.793505) (xy 387.86889 -303.776053)
			(xy 387.826269 -303.751446) (xy 387.788148 -303.720321) (xy 387.755513 -303.683484) (xy 387.72921 -303.641888)
			(xy 387.709919 -303.596612) (xy 387.698142 -303.548828) (xy 387.694182 -303.499774) (xy 387.355334 -303.499774)
			(xy 387.354839 -303.524381) (xy 387.346944 -303.572958) (xy 387.33136 -303.619639) (xy 387.308489 -303.663216)
			(xy 387.278924 -303.70256) (xy 387.243431 -303.736652) (xy 387.202928 -303.764608) (xy 387.158466 -303.785706)
			(xy 387.111195 -303.799398) (xy 387.06234 -303.80533) (xy 387.013165 -303.803349) (xy 386.964946 -303.793505)
			(xy 386.91893 -303.776053) (xy 386.876309 -303.751446) (xy 386.838188 -303.720321) (xy 386.805553 -303.683484)
			(xy 386.77925 -303.641888) (xy 386.759959 -303.596612) (xy 386.748182 -303.548828) (xy 386.744222 -303.499774)
			(xy 158.955232 -303.499774) (xy 158.954737 -303.524381) (xy 158.946842 -303.572958) (xy 158.931258 -303.619639)
			(xy 158.908387 -303.663216) (xy 158.878822 -303.70256) (xy 158.843329 -303.736652) (xy 158.802826 -303.764608)
			(xy 158.758364 -303.785706) (xy 158.711093 -303.799398) (xy 158.662238 -303.80533) (xy 158.613063 -303.803349)
			(xy 158.564844 -303.793505) (xy 158.518828 -303.776053) (xy 158.476207 -303.751446) (xy 158.438086 -303.720321)
			(xy 158.405451 -303.683484) (xy 158.379148 -303.641888) (xy 158.359857 -303.596612) (xy 158.34808 -303.548828)
			(xy 158.34412 -303.499774) (xy 158.005272 -303.499774) (xy 158.004777 -303.524381) (xy 157.996882 -303.572958)
			(xy 157.981298 -303.619639) (xy 157.958427 -303.663216) (xy 157.928862 -303.70256) (xy 157.893369 -303.736652)
			(xy 157.852866 -303.764608) (xy 157.808404 -303.785706) (xy 157.761133 -303.799398) (xy 157.712278 -303.80533)
			(xy 157.663103 -303.803349) (xy 157.614884 -303.793505) (xy 157.568868 -303.776053) (xy 157.526247 -303.751446)
			(xy 157.488126 -303.720321) (xy 157.455491 -303.683484) (xy 157.429188 -303.641888) (xy 157.409897 -303.596612)
			(xy 157.39812 -303.548828) (xy 157.39416 -303.499774) (xy 156.105352 -303.499774) (xy 156.104857 -303.524381)
			(xy 156.096962 -303.572958) (xy 156.081378 -303.619639) (xy 156.058507 -303.663216) (xy 156.028942 -303.70256)
			(xy 155.993449 -303.736652) (xy 155.952946 -303.764608) (xy 155.908484 -303.785706) (xy 155.861213 -303.799398)
			(xy 155.812358 -303.80533) (xy 155.763183 -303.803349) (xy 155.714964 -303.793505) (xy 155.668948 -303.776053)
			(xy 155.626327 -303.751446) (xy 155.588206 -303.720321) (xy 155.555571 -303.683484) (xy 155.529268 -303.641888)
			(xy 155.509977 -303.596612) (xy 155.4982 -303.548828) (xy 155.49424 -303.499774) (xy 155.155392 -303.499774)
			(xy 155.154897 -303.524381) (xy 155.147002 -303.572958) (xy 155.131418 -303.619639) (xy 155.108547 -303.663216)
			(xy 155.078982 -303.70256) (xy 155.043489 -303.736652) (xy 155.002986 -303.764608) (xy 154.958524 -303.785706)
			(xy 154.911253 -303.799398) (xy 154.862398 -303.80533) (xy 154.813223 -303.803349) (xy 154.765004 -303.793505)
			(xy 154.718988 -303.776053) (xy 154.676367 -303.751446) (xy 154.638246 -303.720321) (xy 154.605611 -303.683484)
			(xy 154.579308 -303.641888) (xy 154.560017 -303.596612) (xy 154.54824 -303.548828) (xy 154.54428 -303.499774)
			(xy 0.508 -303.499774) (xy 0.508 -304.449734) (xy 74.544186 -304.449734) (xy 74.548146 -304.40068)
			(xy 74.559923 -304.352896) (xy 74.579214 -304.30762) (xy 74.605517 -304.266024) (xy 74.638152 -304.229187)
			(xy 74.676273 -304.198062) (xy 74.718894 -304.173455) (xy 74.76491 -304.156003) (xy 74.813129 -304.146159)
			(xy 74.862304 -304.144178) (xy 74.911159 -304.15011) (xy 74.95843 -304.163802) (xy 75.002892 -304.1849)
			(xy 75.043395 -304.212856) (xy 75.078888 -304.246948) (xy 75.108453 -304.286292) (xy 75.131324 -304.329869)
			(xy 75.146908 -304.37655) (xy 75.154803 -304.425127) (xy 75.155298 -304.449734) (xy 75.494146 -304.449734)
			(xy 75.498106 -304.40068) (xy 75.509883 -304.352896) (xy 75.529174 -304.30762) (xy 75.555477 -304.266024)
			(xy 75.588112 -304.229187) (xy 75.626233 -304.198062) (xy 75.668854 -304.173455) (xy 75.71487 -304.156003)
			(xy 75.763089 -304.146159) (xy 75.812264 -304.144178) (xy 75.861119 -304.15011) (xy 75.90839 -304.163802)
			(xy 75.952852 -304.1849) (xy 75.993355 -304.212856) (xy 76.028848 -304.246948) (xy 76.058413 -304.286292)
			(xy 76.081284 -304.329869) (xy 76.096868 -304.37655) (xy 76.104763 -304.425127) (xy 76.105258 -304.449734)
			(xy 81.19416 -304.449734) (xy 81.19812 -304.40068) (xy 81.209897 -304.352896) (xy 81.229188 -304.30762)
			(xy 81.255491 -304.266024) (xy 81.288126 -304.229187) (xy 81.326247 -304.198062) (xy 81.368868 -304.173455)
			(xy 81.414884 -304.156003) (xy 81.463103 -304.146159) (xy 81.512278 -304.144178) (xy 81.561133 -304.15011)
			(xy 81.608404 -304.163802) (xy 81.652866 -304.1849) (xy 81.693369 -304.212856) (xy 81.728862 -304.246948)
			(xy 81.758427 -304.286292) (xy 81.781298 -304.329869) (xy 81.796882 -304.37655) (xy 81.804777 -304.425127)
			(xy 81.805272 -304.449734) (xy 82.14412 -304.449734) (xy 82.14808 -304.40068) (xy 82.159857 -304.352896)
			(xy 82.179148 -304.30762) (xy 82.205451 -304.266024) (xy 82.238086 -304.229187) (xy 82.276207 -304.198062)
			(xy 82.318828 -304.173455) (xy 82.364844 -304.156003) (xy 82.413063 -304.146159) (xy 82.462238 -304.144178)
			(xy 82.511093 -304.15011) (xy 82.558364 -304.163802) (xy 82.602826 -304.1849) (xy 82.643329 -304.212856)
			(xy 82.678822 -304.246948) (xy 82.708387 -304.286292) (xy 82.731258 -304.329869) (xy 82.746842 -304.37655)
			(xy 82.754737 -304.425127) (xy 82.755232 -304.449734) (xy 152.644106 -304.449734) (xy 152.648066 -304.40068)
			(xy 152.659843 -304.352896) (xy 152.679134 -304.30762) (xy 152.705437 -304.266024) (xy 152.738072 -304.229187)
			(xy 152.776193 -304.198062) (xy 152.818814 -304.173455) (xy 152.86483 -304.156003) (xy 152.913049 -304.146159)
			(xy 152.962224 -304.144178) (xy 153.011079 -304.15011) (xy 153.05835 -304.163802) (xy 153.102812 -304.1849)
			(xy 153.143315 -304.212856) (xy 153.178808 -304.246948) (xy 153.208373 -304.286292) (xy 153.231244 -304.329869)
			(xy 153.246828 -304.37655) (xy 153.254723 -304.425127) (xy 153.255218 -304.449734) (xy 153.594066 -304.449734)
			(xy 153.598026 -304.40068) (xy 153.609803 -304.352896) (xy 153.629094 -304.30762) (xy 153.655397 -304.266024)
			(xy 153.688032 -304.229187) (xy 153.726153 -304.198062) (xy 153.768774 -304.173455) (xy 153.81479 -304.156003)
			(xy 153.863009 -304.146159) (xy 153.912184 -304.144178) (xy 153.961039 -304.15011) (xy 154.00831 -304.163802)
			(xy 154.052772 -304.1849) (xy 154.093275 -304.212856) (xy 154.128768 -304.246948) (xy 154.158333 -304.286292)
			(xy 154.181204 -304.329869) (xy 154.196788 -304.37655) (xy 154.204683 -304.425127) (xy 154.205178 -304.449734)
			(xy 159.29408 -304.449734) (xy 159.29804 -304.40068) (xy 159.309817 -304.352896) (xy 159.329108 -304.30762)
			(xy 159.355411 -304.266024) (xy 159.388046 -304.229187) (xy 159.426167 -304.198062) (xy 159.468788 -304.173455)
			(xy 159.514804 -304.156003) (xy 159.563023 -304.146159) (xy 159.612198 -304.144178) (xy 159.661053 -304.15011)
			(xy 159.708324 -304.163802) (xy 159.752786 -304.1849) (xy 159.793289 -304.212856) (xy 159.828782 -304.246948)
			(xy 159.858347 -304.286292) (xy 159.881218 -304.329869) (xy 159.896802 -304.37655) (xy 159.904697 -304.425127)
			(xy 159.905192 -304.449734) (xy 160.24404 -304.449734) (xy 160.248 -304.40068) (xy 160.259777 -304.352896)
			(xy 160.279068 -304.30762) (xy 160.305371 -304.266024) (xy 160.338006 -304.229187) (xy 160.376127 -304.198062)
			(xy 160.418748 -304.173455) (xy 160.464764 -304.156003) (xy 160.512983 -304.146159) (xy 160.562158 -304.144178)
			(xy 160.611013 -304.15011) (xy 160.658284 -304.163802) (xy 160.702746 -304.1849) (xy 160.743249 -304.212856)
			(xy 160.778742 -304.246948) (xy 160.808307 -304.286292) (xy 160.831178 -304.329869) (xy 160.846762 -304.37655)
			(xy 160.854657 -304.425127) (xy 160.855152 -304.449734) (xy 306.744128 -304.449734) (xy 306.748088 -304.40068)
			(xy 306.759865 -304.352896) (xy 306.779156 -304.30762) (xy 306.805459 -304.266024) (xy 306.838094 -304.229187)
			(xy 306.876215 -304.198062) (xy 306.918836 -304.173455) (xy 306.964852 -304.156003) (xy 307.013071 -304.146159)
			(xy 307.062246 -304.144178) (xy 307.111101 -304.15011) (xy 307.158372 -304.163802) (xy 307.202834 -304.1849)
			(xy 307.243337 -304.212856) (xy 307.27883 -304.246948) (xy 307.308395 -304.286292) (xy 307.331266 -304.329869)
			(xy 307.34685 -304.37655) (xy 307.354745 -304.425127) (xy 307.35524 -304.449734) (xy 307.694088 -304.449734)
			(xy 307.698048 -304.40068) (xy 307.709825 -304.352896) (xy 307.729116 -304.30762) (xy 307.755419 -304.266024)
			(xy 307.788054 -304.229187) (xy 307.826175 -304.198062) (xy 307.868796 -304.173455) (xy 307.914812 -304.156003)
			(xy 307.963031 -304.146159) (xy 308.012206 -304.144178) (xy 308.061061 -304.15011) (xy 308.108332 -304.163802)
			(xy 308.152794 -304.1849) (xy 308.193297 -304.212856) (xy 308.22879 -304.246948) (xy 308.258355 -304.286292)
			(xy 308.281226 -304.329869) (xy 308.29681 -304.37655) (xy 308.304705 -304.425127) (xy 308.3052 -304.449734)
			(xy 313.394102 -304.449734) (xy 313.398062 -304.40068) (xy 313.409839 -304.352896) (xy 313.42913 -304.30762)
			(xy 313.455433 -304.266024) (xy 313.488068 -304.229187) (xy 313.526189 -304.198062) (xy 313.56881 -304.173455)
			(xy 313.614826 -304.156003) (xy 313.663045 -304.146159) (xy 313.71222 -304.144178) (xy 313.761075 -304.15011)
			(xy 313.808346 -304.163802) (xy 313.852808 -304.1849) (xy 313.893311 -304.212856) (xy 313.928804 -304.246948)
			(xy 313.958369 -304.286292) (xy 313.98124 -304.329869) (xy 313.996824 -304.37655) (xy 314.004719 -304.425127)
			(xy 314.005214 -304.449734) (xy 314.344062 -304.449734) (xy 314.348022 -304.40068) (xy 314.359799 -304.352896)
			(xy 314.37909 -304.30762) (xy 314.405393 -304.266024) (xy 314.438028 -304.229187) (xy 314.476149 -304.198062)
			(xy 314.51877 -304.173455) (xy 314.564786 -304.156003) (xy 314.613005 -304.146159) (xy 314.66218 -304.144178)
			(xy 314.711035 -304.15011) (xy 314.758306 -304.163802) (xy 314.802768 -304.1849) (xy 314.843271 -304.212856)
			(xy 314.878764 -304.246948) (xy 314.908329 -304.286292) (xy 314.9312 -304.329869) (xy 314.946784 -304.37655)
			(xy 314.954679 -304.425127) (xy 314.955174 -304.449734) (xy 384.844048 -304.449734) (xy 384.848008 -304.40068)
			(xy 384.859785 -304.352896) (xy 384.879076 -304.30762) (xy 384.905379 -304.266024) (xy 384.938014 -304.229187)
			(xy 384.976135 -304.198062) (xy 385.018756 -304.173455) (xy 385.064772 -304.156003) (xy 385.112991 -304.146159)
			(xy 385.162166 -304.144178) (xy 385.211021 -304.15011) (xy 385.258292 -304.163802) (xy 385.302754 -304.1849)
			(xy 385.343257 -304.212856) (xy 385.37875 -304.246948) (xy 385.408315 -304.286292) (xy 385.431186 -304.329869)
			(xy 385.44677 -304.37655) (xy 385.454665 -304.425127) (xy 385.45516 -304.449734) (xy 385.794008 -304.449734)
			(xy 385.797968 -304.40068) (xy 385.809745 -304.352896) (xy 385.829036 -304.30762) (xy 385.855339 -304.266024)
			(xy 385.887974 -304.229187) (xy 385.926095 -304.198062) (xy 385.968716 -304.173455) (xy 386.014732 -304.156003)
			(xy 386.062951 -304.146159) (xy 386.112126 -304.144178) (xy 386.160981 -304.15011) (xy 386.208252 -304.163802)
			(xy 386.252714 -304.1849) (xy 386.293217 -304.212856) (xy 386.32871 -304.246948) (xy 386.358275 -304.286292)
			(xy 386.381146 -304.329869) (xy 386.39673 -304.37655) (xy 386.404625 -304.425127) (xy 386.40512 -304.449734)
			(xy 391.494022 -304.449734) (xy 391.497982 -304.40068) (xy 391.509759 -304.352896) (xy 391.52905 -304.30762)
			(xy 391.555353 -304.266024) (xy 391.587988 -304.229187) (xy 391.626109 -304.198062) (xy 391.66873 -304.173455)
			(xy 391.714746 -304.156003) (xy 391.762965 -304.146159) (xy 391.81214 -304.144178) (xy 391.860995 -304.15011)
			(xy 391.908266 -304.163802) (xy 391.952728 -304.1849) (xy 391.993231 -304.212856) (xy 392.028724 -304.246948)
			(xy 392.058289 -304.286292) (xy 392.08116 -304.329869) (xy 392.096744 -304.37655) (xy 392.104639 -304.425127)
			(xy 392.105134 -304.449734) (xy 392.443982 -304.449734) (xy 392.447942 -304.40068) (xy 392.459719 -304.352896)
			(xy 392.47901 -304.30762) (xy 392.505313 -304.266024) (xy 392.537948 -304.229187) (xy 392.576069 -304.198062)
			(xy 392.61869 -304.173455) (xy 392.664706 -304.156003) (xy 392.712925 -304.146159) (xy 392.7621 -304.144178)
			(xy 392.810955 -304.15011) (xy 392.858226 -304.163802) (xy 392.902688 -304.1849) (xy 392.943191 -304.212856)
			(xy 392.978684 -304.246948) (xy 393.008249 -304.286292) (xy 393.03112 -304.329869) (xy 393.046704 -304.37655)
			(xy 393.054599 -304.425127) (xy 393.055094 -304.449734) (xy 393.054599 -304.474341) (xy 393.046704 -304.522918)
			(xy 393.03112 -304.569599) (xy 393.008249 -304.613176) (xy 392.978684 -304.65252) (xy 392.943191 -304.686612)
			(xy 392.902688 -304.714568) (xy 392.858226 -304.735666) (xy 392.810955 -304.749358) (xy 392.7621 -304.75529)
			(xy 392.712925 -304.753309) (xy 392.664706 -304.743465) (xy 392.61869 -304.726013) (xy 392.576069 -304.701406)
			(xy 392.537948 -304.670281) (xy 392.505313 -304.633444) (xy 392.47901 -304.591848) (xy 392.459719 -304.546572)
			(xy 392.447942 -304.498788) (xy 392.443982 -304.449734) (xy 392.105134 -304.449734) (xy 392.104639 -304.474341)
			(xy 392.096744 -304.522918) (xy 392.08116 -304.569599) (xy 392.058289 -304.613176) (xy 392.028724 -304.65252)
			(xy 391.993231 -304.686612) (xy 391.952728 -304.714568) (xy 391.908266 -304.735666) (xy 391.860995 -304.749358)
			(xy 391.81214 -304.75529) (xy 391.762965 -304.753309) (xy 391.714746 -304.743465) (xy 391.66873 -304.726013)
			(xy 391.626109 -304.701406) (xy 391.587988 -304.670281) (xy 391.555353 -304.633444) (xy 391.52905 -304.591848)
			(xy 391.509759 -304.546572) (xy 391.497982 -304.498788) (xy 391.494022 -304.449734) (xy 386.40512 -304.449734)
			(xy 386.404625 -304.474341) (xy 386.39673 -304.522918) (xy 386.381146 -304.569599) (xy 386.358275 -304.613176)
			(xy 386.32871 -304.65252) (xy 386.293217 -304.686612) (xy 386.252714 -304.714568) (xy 386.208252 -304.735666)
			(xy 386.160981 -304.749358) (xy 386.112126 -304.75529) (xy 386.062951 -304.753309) (xy 386.014732 -304.743465)
			(xy 385.968716 -304.726013) (xy 385.926095 -304.701406) (xy 385.887974 -304.670281) (xy 385.855339 -304.633444)
			(xy 385.829036 -304.591848) (xy 385.809745 -304.546572) (xy 385.797968 -304.498788) (xy 385.794008 -304.449734)
			(xy 385.45516 -304.449734) (xy 385.454665 -304.474341) (xy 385.44677 -304.522918) (xy 385.431186 -304.569599)
			(xy 385.408315 -304.613176) (xy 385.37875 -304.65252) (xy 385.343257 -304.686612) (xy 385.302754 -304.714568)
			(xy 385.258292 -304.735666) (xy 385.211021 -304.749358) (xy 385.162166 -304.75529) (xy 385.112991 -304.753309)
			(xy 385.064772 -304.743465) (xy 385.018756 -304.726013) (xy 384.976135 -304.701406) (xy 384.938014 -304.670281)
			(xy 384.905379 -304.633444) (xy 384.879076 -304.591848) (xy 384.859785 -304.546572) (xy 384.848008 -304.498788)
			(xy 384.844048 -304.449734) (xy 314.955174 -304.449734) (xy 314.954679 -304.474341) (xy 314.946784 -304.522918)
			(xy 314.9312 -304.569599) (xy 314.908329 -304.613176) (xy 314.878764 -304.65252) (xy 314.843271 -304.686612)
			(xy 314.802768 -304.714568) (xy 314.758306 -304.735666) (xy 314.711035 -304.749358) (xy 314.66218 -304.75529)
			(xy 314.613005 -304.753309) (xy 314.564786 -304.743465) (xy 314.51877 -304.726013) (xy 314.476149 -304.701406)
			(xy 314.438028 -304.670281) (xy 314.405393 -304.633444) (xy 314.37909 -304.591848) (xy 314.359799 -304.546572)
			(xy 314.348022 -304.498788) (xy 314.344062 -304.449734) (xy 314.005214 -304.449734) (xy 314.004719 -304.474341)
			(xy 313.996824 -304.522918) (xy 313.98124 -304.569599) (xy 313.958369 -304.613176) (xy 313.928804 -304.65252)
			(xy 313.893311 -304.686612) (xy 313.852808 -304.714568) (xy 313.808346 -304.735666) (xy 313.761075 -304.749358)
			(xy 313.71222 -304.75529) (xy 313.663045 -304.753309) (xy 313.614826 -304.743465) (xy 313.56881 -304.726013)
			(xy 313.526189 -304.701406) (xy 313.488068 -304.670281) (xy 313.455433 -304.633444) (xy 313.42913 -304.591848)
			(xy 313.409839 -304.546572) (xy 313.398062 -304.498788) (xy 313.394102 -304.449734) (xy 308.3052 -304.449734)
			(xy 308.304705 -304.474341) (xy 308.29681 -304.522918) (xy 308.281226 -304.569599) (xy 308.258355 -304.613176)
			(xy 308.22879 -304.65252) (xy 308.193297 -304.686612) (xy 308.152794 -304.714568) (xy 308.108332 -304.735666)
			(xy 308.061061 -304.749358) (xy 308.012206 -304.75529) (xy 307.963031 -304.753309) (xy 307.914812 -304.743465)
			(xy 307.868796 -304.726013) (xy 307.826175 -304.701406) (xy 307.788054 -304.670281) (xy 307.755419 -304.633444)
			(xy 307.729116 -304.591848) (xy 307.709825 -304.546572) (xy 307.698048 -304.498788) (xy 307.694088 -304.449734)
			(xy 307.35524 -304.449734) (xy 307.354745 -304.474341) (xy 307.34685 -304.522918) (xy 307.331266 -304.569599)
			(xy 307.308395 -304.613176) (xy 307.27883 -304.65252) (xy 307.243337 -304.686612) (xy 307.202834 -304.714568)
			(xy 307.158372 -304.735666) (xy 307.111101 -304.749358) (xy 307.062246 -304.75529) (xy 307.013071 -304.753309)
			(xy 306.964852 -304.743465) (xy 306.918836 -304.726013) (xy 306.876215 -304.701406) (xy 306.838094 -304.670281)
			(xy 306.805459 -304.633444) (xy 306.779156 -304.591848) (xy 306.759865 -304.546572) (xy 306.748088 -304.498788)
			(xy 306.744128 -304.449734) (xy 160.855152 -304.449734) (xy 160.854657 -304.474341) (xy 160.846762 -304.522918)
			(xy 160.831178 -304.569599) (xy 160.808307 -304.613176) (xy 160.778742 -304.65252) (xy 160.743249 -304.686612)
			(xy 160.702746 -304.714568) (xy 160.658284 -304.735666) (xy 160.611013 -304.749358) (xy 160.562158 -304.75529)
			(xy 160.512983 -304.753309) (xy 160.464764 -304.743465) (xy 160.418748 -304.726013) (xy 160.376127 -304.701406)
			(xy 160.338006 -304.670281) (xy 160.305371 -304.633444) (xy 160.279068 -304.591848) (xy 160.259777 -304.546572)
			(xy 160.248 -304.498788) (xy 160.24404 -304.449734) (xy 159.905192 -304.449734) (xy 159.904697 -304.474341)
			(xy 159.896802 -304.522918) (xy 159.881218 -304.569599) (xy 159.858347 -304.613176) (xy 159.828782 -304.65252)
			(xy 159.793289 -304.686612) (xy 159.752786 -304.714568) (xy 159.708324 -304.735666) (xy 159.661053 -304.749358)
			(xy 159.612198 -304.75529) (xy 159.563023 -304.753309) (xy 159.514804 -304.743465) (xy 159.468788 -304.726013)
			(xy 159.426167 -304.701406) (xy 159.388046 -304.670281) (xy 159.355411 -304.633444) (xy 159.329108 -304.591848)
			(xy 159.309817 -304.546572) (xy 159.29804 -304.498788) (xy 159.29408 -304.449734) (xy 154.205178 -304.449734)
			(xy 154.204683 -304.474341) (xy 154.196788 -304.522918) (xy 154.181204 -304.569599) (xy 154.158333 -304.613176)
			(xy 154.128768 -304.65252) (xy 154.093275 -304.686612) (xy 154.052772 -304.714568) (xy 154.00831 -304.735666)
			(xy 153.961039 -304.749358) (xy 153.912184 -304.75529) (xy 153.863009 -304.753309) (xy 153.81479 -304.743465)
			(xy 153.768774 -304.726013) (xy 153.726153 -304.701406) (xy 153.688032 -304.670281) (xy 153.655397 -304.633444)
			(xy 153.629094 -304.591848) (xy 153.609803 -304.546572) (xy 153.598026 -304.498788) (xy 153.594066 -304.449734)
			(xy 153.255218 -304.449734) (xy 153.254723 -304.474341) (xy 153.246828 -304.522918) (xy 153.231244 -304.569599)
			(xy 153.208373 -304.613176) (xy 153.178808 -304.65252) (xy 153.143315 -304.686612) (xy 153.102812 -304.714568)
			(xy 153.05835 -304.735666) (xy 153.011079 -304.749358) (xy 152.962224 -304.75529) (xy 152.913049 -304.753309)
			(xy 152.86483 -304.743465) (xy 152.818814 -304.726013) (xy 152.776193 -304.701406) (xy 152.738072 -304.670281)
			(xy 152.705437 -304.633444) (xy 152.679134 -304.591848) (xy 152.659843 -304.546572) (xy 152.648066 -304.498788)
			(xy 152.644106 -304.449734) (xy 82.755232 -304.449734) (xy 82.754737 -304.474341) (xy 82.746842 -304.522918)
			(xy 82.731258 -304.569599) (xy 82.708387 -304.613176) (xy 82.678822 -304.65252) (xy 82.643329 -304.686612)
			(xy 82.602826 -304.714568) (xy 82.558364 -304.735666) (xy 82.511093 -304.749358) (xy 82.462238 -304.75529)
			(xy 82.413063 -304.753309) (xy 82.364844 -304.743465) (xy 82.318828 -304.726013) (xy 82.276207 -304.701406)
			(xy 82.238086 -304.670281) (xy 82.205451 -304.633444) (xy 82.179148 -304.591848) (xy 82.159857 -304.546572)
			(xy 82.14808 -304.498788) (xy 82.14412 -304.449734) (xy 81.805272 -304.449734) (xy 81.804777 -304.474341)
			(xy 81.796882 -304.522918) (xy 81.781298 -304.569599) (xy 81.758427 -304.613176) (xy 81.728862 -304.65252)
			(xy 81.693369 -304.686612) (xy 81.652866 -304.714568) (xy 81.608404 -304.735666) (xy 81.561133 -304.749358)
			(xy 81.512278 -304.75529) (xy 81.463103 -304.753309) (xy 81.414884 -304.743465) (xy 81.368868 -304.726013)
			(xy 81.326247 -304.701406) (xy 81.288126 -304.670281) (xy 81.255491 -304.633444) (xy 81.229188 -304.591848)
			(xy 81.209897 -304.546572) (xy 81.19812 -304.498788) (xy 81.19416 -304.449734) (xy 76.105258 -304.449734)
			(xy 76.104763 -304.474341) (xy 76.096868 -304.522918) (xy 76.081284 -304.569599) (xy 76.058413 -304.613176)
			(xy 76.028848 -304.65252) (xy 75.993355 -304.686612) (xy 75.952852 -304.714568) (xy 75.90839 -304.735666)
			(xy 75.861119 -304.749358) (xy 75.812264 -304.75529) (xy 75.763089 -304.753309) (xy 75.71487 -304.743465)
			(xy 75.668854 -304.726013) (xy 75.626233 -304.701406) (xy 75.588112 -304.670281) (xy 75.555477 -304.633444)
			(xy 75.529174 -304.591848) (xy 75.509883 -304.546572) (xy 75.498106 -304.498788) (xy 75.494146 -304.449734)
			(xy 75.155298 -304.449734) (xy 75.154803 -304.474341) (xy 75.146908 -304.522918) (xy 75.131324 -304.569599)
			(xy 75.108453 -304.613176) (xy 75.078888 -304.65252) (xy 75.043395 -304.686612) (xy 75.002892 -304.714568)
			(xy 74.95843 -304.735666) (xy 74.911159 -304.749358) (xy 74.862304 -304.75529) (xy 74.813129 -304.753309)
			(xy 74.76491 -304.743465) (xy 74.718894 -304.726013) (xy 74.676273 -304.701406) (xy 74.638152 -304.670281)
			(xy 74.605517 -304.633444) (xy 74.579214 -304.591848) (xy 74.559923 -304.546572) (xy 74.548146 -304.498788)
			(xy 74.544186 -304.449734) (xy 0.508 -304.449734) (xy 0.508 -305.19751) (xy 17.638266 -305.19751)
			(xy 17.642339 -305.141851) (xy 17.654474 -305.087378) (xy 17.67441 -305.035252) (xy 17.701724 -304.986584)
			(xy 17.735832 -304.942412) (xy 17.776009 -304.903677) (xy 17.821397 -304.871205) (xy 17.871029 -304.845687)
			(xy 17.923849 -304.827668) (xy 17.978728 -304.817531) (xy 18.034499 -304.815493) (xy 18.089973 -304.821596)
			(xy 18.143966 -304.835712) (xy 18.195329 -304.857539) (xy 18.242967 -304.886612) (xy 18.285863 -304.922311)
			(xy 18.323105 -304.963875) (xy 18.353899 -305.010419) (xy 18.377587 -305.06095) (xy 18.393665 -305.114392)
			(xy 18.401791 -305.169606) (xy 18.4023 -305.19751) (xy 18.401791 -305.225414) (xy 18.393665 -305.280628)
			(xy 18.377587 -305.33407) (xy 18.353899 -305.384601) (xy 18.343745 -305.399948) (xy 76.444106 -305.399948)
			(xy 76.448066 -305.350894) (xy 76.459843 -305.30311) (xy 76.479134 -305.257834) (xy 76.505437 -305.216238)
			(xy 76.538072 -305.179401) (xy 76.576193 -305.148276) (xy 76.618814 -305.123669) (xy 76.66483 -305.106217)
			(xy 76.713049 -305.096373) (xy 76.762224 -305.094392) (xy 76.811079 -305.100324) (xy 76.85835 -305.114016)
			(xy 76.902812 -305.135114) (xy 76.943315 -305.16307) (xy 76.978808 -305.197162) (xy 77.008373 -305.236506)
			(xy 77.031244 -305.280083) (xy 77.046828 -305.326764) (xy 77.054723 -305.375341) (xy 77.055218 -305.399948)
			(xy 77.394066 -305.399948) (xy 77.398026 -305.350894) (xy 77.409803 -305.30311) (xy 77.429094 -305.257834)
			(xy 77.455397 -305.216238) (xy 77.488032 -305.179401) (xy 77.526153 -305.148276) (xy 77.568774 -305.123669)
			(xy 77.61479 -305.106217) (xy 77.663009 -305.096373) (xy 77.712184 -305.094392) (xy 77.761039 -305.100324)
			(xy 77.80831 -305.114016) (xy 77.852772 -305.135114) (xy 77.893275 -305.16307) (xy 77.928768 -305.197162)
			(xy 77.958333 -305.236506) (xy 77.981204 -305.280083) (xy 77.996788 -305.326764) (xy 78.004683 -305.375341)
			(xy 78.005178 -305.399948) (xy 79.293986 -305.399948) (xy 79.297946 -305.350894) (xy 79.309723 -305.30311)
			(xy 79.329014 -305.257834) (xy 79.355317 -305.216238) (xy 79.387952 -305.179401) (xy 79.426073 -305.148276)
			(xy 79.468694 -305.123669) (xy 79.51471 -305.106217) (xy 79.562929 -305.096373) (xy 79.612104 -305.094392)
			(xy 79.660959 -305.100324) (xy 79.70823 -305.114016) (xy 79.752692 -305.135114) (xy 79.793195 -305.16307)
			(xy 79.828688 -305.197162) (xy 79.858253 -305.236506) (xy 79.881124 -305.280083) (xy 79.896708 -305.326764)
			(xy 79.904603 -305.375341) (xy 79.905098 -305.399948) (xy 80.243946 -305.399948) (xy 80.247906 -305.350894)
			(xy 80.259683 -305.30311) (xy 80.278974 -305.257834) (xy 80.305277 -305.216238) (xy 80.337912 -305.179401)
			(xy 80.376033 -305.148276) (xy 80.418654 -305.123669) (xy 80.46467 -305.106217) (xy 80.512889 -305.096373)
			(xy 80.562064 -305.094392) (xy 80.610919 -305.100324) (xy 80.65819 -305.114016) (xy 80.702652 -305.135114)
			(xy 80.743155 -305.16307) (xy 80.778648 -305.197162) (xy 80.808213 -305.236506) (xy 80.831084 -305.280083)
			(xy 80.846668 -305.326764) (xy 80.854563 -305.375341) (xy 80.855058 -305.399948) (xy 154.54428 -305.399948)
			(xy 154.54824 -305.350894) (xy 154.560017 -305.30311) (xy 154.579308 -305.257834) (xy 154.605611 -305.216238)
			(xy 154.638246 -305.179401) (xy 154.676367 -305.148276) (xy 154.718988 -305.123669) (xy 154.765004 -305.106217)
			(xy 154.813223 -305.096373) (xy 154.862398 -305.094392) (xy 154.911253 -305.100324) (xy 154.958524 -305.114016)
			(xy 155.002986 -305.135114) (xy 155.043489 -305.16307) (xy 155.078982 -305.197162) (xy 155.108547 -305.236506)
			(xy 155.131418 -305.280083) (xy 155.147002 -305.326764) (xy 155.154897 -305.375341) (xy 155.155392 -305.399948)
			(xy 155.49424 -305.399948) (xy 155.4982 -305.350894) (xy 155.509977 -305.30311) (xy 155.529268 -305.257834)
			(xy 155.555571 -305.216238) (xy 155.588206 -305.179401) (xy 155.626327 -305.148276) (xy 155.668948 -305.123669)
			(xy 155.714964 -305.106217) (xy 155.763183 -305.096373) (xy 155.812358 -305.094392) (xy 155.861213 -305.100324)
			(xy 155.908484 -305.114016) (xy 155.952946 -305.135114) (xy 155.993449 -305.16307) (xy 156.028942 -305.197162)
			(xy 156.058507 -305.236506) (xy 156.081378 -305.280083) (xy 156.096962 -305.326764) (xy 156.104857 -305.375341)
			(xy 156.105352 -305.399948) (xy 157.39416 -305.399948) (xy 157.39812 -305.350894) (xy 157.409897 -305.30311)
			(xy 157.429188 -305.257834) (xy 157.455491 -305.216238) (xy 157.488126 -305.179401) (xy 157.526247 -305.148276)
			(xy 157.568868 -305.123669) (xy 157.614884 -305.106217) (xy 157.663103 -305.096373) (xy 157.712278 -305.094392)
			(xy 157.761133 -305.100324) (xy 157.808404 -305.114016) (xy 157.852866 -305.135114) (xy 157.893369 -305.16307)
			(xy 157.928862 -305.197162) (xy 157.958427 -305.236506) (xy 157.981298 -305.280083) (xy 157.996882 -305.326764)
			(xy 158.004777 -305.375341) (xy 158.005272 -305.399948) (xy 158.34412 -305.399948) (xy 158.34808 -305.350894)
			(xy 158.359857 -305.30311) (xy 158.379148 -305.257834) (xy 158.405451 -305.216238) (xy 158.438086 -305.179401)
			(xy 158.476207 -305.148276) (xy 158.518828 -305.123669) (xy 158.564844 -305.106217) (xy 158.613063 -305.096373)
			(xy 158.662238 -305.094392) (xy 158.711093 -305.100324) (xy 158.758364 -305.114016) (xy 158.802826 -305.135114)
			(xy 158.843329 -305.16307) (xy 158.878822 -305.197162) (xy 158.908387 -305.236506) (xy 158.931258 -305.280083)
			(xy 158.946842 -305.326764) (xy 158.954737 -305.375341) (xy 158.955232 -305.399948) (xy 308.644048 -305.399948)
			(xy 308.648008 -305.350894) (xy 308.659785 -305.30311) (xy 308.679076 -305.257834) (xy 308.705379 -305.216238)
			(xy 308.738014 -305.179401) (xy 308.776135 -305.148276) (xy 308.818756 -305.123669) (xy 308.864772 -305.106217)
			(xy 308.912991 -305.096373) (xy 308.962166 -305.094392) (xy 309.011021 -305.100324) (xy 309.058292 -305.114016)
			(xy 309.102754 -305.135114) (xy 309.143257 -305.16307) (xy 309.17875 -305.197162) (xy 309.208315 -305.236506)
			(xy 309.231186 -305.280083) (xy 309.24677 -305.326764) (xy 309.254665 -305.375341) (xy 309.25516 -305.399948)
			(xy 309.594008 -305.399948) (xy 309.597968 -305.350894) (xy 309.609745 -305.30311) (xy 309.629036 -305.257834)
			(xy 309.655339 -305.216238) (xy 309.687974 -305.179401) (xy 309.726095 -305.148276) (xy 309.768716 -305.123669)
			(xy 309.814732 -305.106217) (xy 309.862951 -305.096373) (xy 309.912126 -305.094392) (xy 309.960981 -305.100324)
			(xy 310.008252 -305.114016) (xy 310.052714 -305.135114) (xy 310.093217 -305.16307) (xy 310.12871 -305.197162)
			(xy 310.158275 -305.236506) (xy 310.181146 -305.280083) (xy 310.19673 -305.326764) (xy 310.204625 -305.375341)
			(xy 310.20512 -305.399948) (xy 311.493928 -305.399948) (xy 311.497888 -305.350894) (xy 311.509665 -305.30311)
			(xy 311.528956 -305.257834) (xy 311.555259 -305.216238) (xy 311.587894 -305.179401) (xy 311.626015 -305.148276)
			(xy 311.668636 -305.123669) (xy 311.714652 -305.106217) (xy 311.762871 -305.096373) (xy 311.812046 -305.094392)
			(xy 311.860901 -305.100324) (xy 311.908172 -305.114016) (xy 311.952634 -305.135114) (xy 311.993137 -305.16307)
			(xy 312.02863 -305.197162) (xy 312.058195 -305.236506) (xy 312.081066 -305.280083) (xy 312.09665 -305.326764)
			(xy 312.104545 -305.375341) (xy 312.10504 -305.399948) (xy 312.443888 -305.399948) (xy 312.447848 -305.350894)
			(xy 312.459625 -305.30311) (xy 312.478916 -305.257834) (xy 312.505219 -305.216238) (xy 312.537854 -305.179401)
			(xy 312.575975 -305.148276) (xy 312.618596 -305.123669) (xy 312.664612 -305.106217) (xy 312.712831 -305.096373)
			(xy 312.762006 -305.094392) (xy 312.810861 -305.100324) (xy 312.858132 -305.114016) (xy 312.902594 -305.135114)
			(xy 312.943097 -305.16307) (xy 312.97859 -305.197162) (xy 313.008155 -305.236506) (xy 313.031026 -305.280083)
			(xy 313.04661 -305.326764) (xy 313.054505 -305.375341) (xy 313.055 -305.399948) (xy 386.744222 -305.399948)
			(xy 386.748182 -305.350894) (xy 386.759959 -305.30311) (xy 386.77925 -305.257834) (xy 386.805553 -305.216238)
			(xy 386.838188 -305.179401) (xy 386.876309 -305.148276) (xy 386.91893 -305.123669) (xy 386.964946 -305.106217)
			(xy 387.013165 -305.096373) (xy 387.06234 -305.094392) (xy 387.111195 -305.100324) (xy 387.158466 -305.114016)
			(xy 387.202928 -305.135114) (xy 387.243431 -305.16307) (xy 387.278924 -305.197162) (xy 387.308489 -305.236506)
			(xy 387.33136 -305.280083) (xy 387.346944 -305.326764) (xy 387.354839 -305.375341) (xy 387.355334 -305.399948)
			(xy 387.694182 -305.399948) (xy 387.698142 -305.350894) (xy 387.709919 -305.30311) (xy 387.72921 -305.257834)
			(xy 387.755513 -305.216238) (xy 387.788148 -305.179401) (xy 387.826269 -305.148276) (xy 387.86889 -305.123669)
			(xy 387.914906 -305.106217) (xy 387.963125 -305.096373) (xy 388.0123 -305.094392) (xy 388.061155 -305.100324)
			(xy 388.108426 -305.114016) (xy 388.152888 -305.135114) (xy 388.193391 -305.16307) (xy 388.228884 -305.197162)
			(xy 388.258449 -305.236506) (xy 388.28132 -305.280083) (xy 388.296904 -305.326764) (xy 388.304799 -305.375341)
			(xy 388.305294 -305.399948) (xy 389.594102 -305.399948) (xy 389.598062 -305.350894) (xy 389.609839 -305.30311)
			(xy 389.62913 -305.257834) (xy 389.655433 -305.216238) (xy 389.688068 -305.179401) (xy 389.726189 -305.148276)
			(xy 389.76881 -305.123669) (xy 389.814826 -305.106217) (xy 389.863045 -305.096373) (xy 389.91222 -305.094392)
			(xy 389.961075 -305.100324) (xy 390.008346 -305.114016) (xy 390.052808 -305.135114) (xy 390.093311 -305.16307)
			(xy 390.128804 -305.197162) (xy 390.158369 -305.236506) (xy 390.18124 -305.280083) (xy 390.196824 -305.326764)
			(xy 390.204719 -305.375341) (xy 390.205214 -305.399948) (xy 390.544062 -305.399948) (xy 390.548022 -305.350894)
			(xy 390.559799 -305.30311) (xy 390.57909 -305.257834) (xy 390.605393 -305.216238) (xy 390.638028 -305.179401)
			(xy 390.676149 -305.148276) (xy 390.71877 -305.123669) (xy 390.764786 -305.106217) (xy 390.813005 -305.096373)
			(xy 390.86218 -305.094392) (xy 390.911035 -305.100324) (xy 390.958306 -305.114016) (xy 391.002768 -305.135114)
			(xy 391.043271 -305.16307) (xy 391.078764 -305.197162) (xy 391.108329 -305.236506) (xy 391.1312 -305.280083)
			(xy 391.146784 -305.326764) (xy 391.154679 -305.375341) (xy 391.155174 -305.399948) (xy 391.154679 -305.424555)
			(xy 391.146784 -305.473132) (xy 391.1312 -305.519813) (xy 391.108329 -305.56339) (xy 391.078764 -305.602734)
			(xy 391.043271 -305.636826) (xy 391.002768 -305.664782) (xy 390.958306 -305.68588) (xy 390.911035 -305.699572)
			(xy 390.86218 -305.705504) (xy 390.813005 -305.703523) (xy 390.764786 -305.693679) (xy 390.71877 -305.676227)
			(xy 390.676149 -305.65162) (xy 390.638028 -305.620495) (xy 390.605393 -305.583658) (xy 390.57909 -305.542062)
			(xy 390.559799 -305.496786) (xy 390.548022 -305.449002) (xy 390.544062 -305.399948) (xy 390.205214 -305.399948)
			(xy 390.204719 -305.424555) (xy 390.196824 -305.473132) (xy 390.18124 -305.519813) (xy 390.158369 -305.56339)
			(xy 390.128804 -305.602734) (xy 390.093311 -305.636826) (xy 390.052808 -305.664782) (xy 390.008346 -305.68588)
			(xy 389.961075 -305.699572) (xy 389.91222 -305.705504) (xy 389.863045 -305.703523) (xy 389.814826 -305.693679)
			(xy 389.76881 -305.676227) (xy 389.726189 -305.65162) (xy 389.688068 -305.620495) (xy 389.655433 -305.583658)
			(xy 389.62913 -305.542062) (xy 389.609839 -305.496786) (xy 389.598062 -305.449002) (xy 389.594102 -305.399948)
			(xy 388.305294 -305.399948) (xy 388.304799 -305.424555) (xy 388.296904 -305.473132) (xy 388.28132 -305.519813)
			(xy 388.258449 -305.56339) (xy 388.228884 -305.602734) (xy 388.193391 -305.636826) (xy 388.152888 -305.664782)
			(xy 388.108426 -305.68588) (xy 388.061155 -305.699572) (xy 388.0123 -305.705504) (xy 387.963125 -305.703523)
			(xy 387.914906 -305.693679) (xy 387.86889 -305.676227) (xy 387.826269 -305.65162) (xy 387.788148 -305.620495)
			(xy 387.755513 -305.583658) (xy 387.72921 -305.542062) (xy 387.709919 -305.496786) (xy 387.698142 -305.449002)
			(xy 387.694182 -305.399948) (xy 387.355334 -305.399948) (xy 387.354839 -305.424555) (xy 387.346944 -305.473132)
			(xy 387.33136 -305.519813) (xy 387.308489 -305.56339) (xy 387.278924 -305.602734) (xy 387.243431 -305.636826)
			(xy 387.202928 -305.664782) (xy 387.158466 -305.68588) (xy 387.111195 -305.699572) (xy 387.06234 -305.705504)
			(xy 387.013165 -305.703523) (xy 386.964946 -305.693679) (xy 386.91893 -305.676227) (xy 386.876309 -305.65162)
			(xy 386.838188 -305.620495) (xy 386.805553 -305.583658) (xy 386.77925 -305.542062) (xy 386.759959 -305.496786)
			(xy 386.748182 -305.449002) (xy 386.744222 -305.399948) (xy 313.055 -305.399948) (xy 313.054505 -305.424555)
			(xy 313.04661 -305.473132) (xy 313.031026 -305.519813) (xy 313.008155 -305.56339) (xy 312.97859 -305.602734)
			(xy 312.943097 -305.636826) (xy 312.902594 -305.664782) (xy 312.858132 -305.68588) (xy 312.810861 -305.699572)
			(xy 312.762006 -305.705504) (xy 312.712831 -305.703523) (xy 312.664612 -305.693679) (xy 312.618596 -305.676227)
			(xy 312.575975 -305.65162) (xy 312.537854 -305.620495) (xy 312.505219 -305.583658) (xy 312.478916 -305.542062)
			(xy 312.459625 -305.496786) (xy 312.447848 -305.449002) (xy 312.443888 -305.399948) (xy 312.10504 -305.399948)
			(xy 312.104545 -305.424555) (xy 312.09665 -305.473132) (xy 312.081066 -305.519813) (xy 312.058195 -305.56339)
			(xy 312.02863 -305.602734) (xy 311.993137 -305.636826) (xy 311.952634 -305.664782) (xy 311.908172 -305.68588)
			(xy 311.860901 -305.699572) (xy 311.812046 -305.705504) (xy 311.762871 -305.703523) (xy 311.714652 -305.693679)
			(xy 311.668636 -305.676227) (xy 311.626015 -305.65162) (xy 311.587894 -305.620495) (xy 311.555259 -305.583658)
			(xy 311.528956 -305.542062) (xy 311.509665 -305.496786) (xy 311.497888 -305.449002) (xy 311.493928 -305.399948)
			(xy 310.20512 -305.399948) (xy 310.204625 -305.424555) (xy 310.19673 -305.473132) (xy 310.181146 -305.519813)
			(xy 310.158275 -305.56339) (xy 310.12871 -305.602734) (xy 310.093217 -305.636826) (xy 310.052714 -305.664782)
			(xy 310.008252 -305.68588) (xy 309.960981 -305.699572) (xy 309.912126 -305.705504) (xy 309.862951 -305.703523)
			(xy 309.814732 -305.693679) (xy 309.768716 -305.676227) (xy 309.726095 -305.65162) (xy 309.687974 -305.620495)
			(xy 309.655339 -305.583658) (xy 309.629036 -305.542062) (xy 309.609745 -305.496786) (xy 309.597968 -305.449002)
			(xy 309.594008 -305.399948) (xy 309.25516 -305.399948) (xy 309.254665 -305.424555) (xy 309.24677 -305.473132)
			(xy 309.231186 -305.519813) (xy 309.208315 -305.56339) (xy 309.17875 -305.602734) (xy 309.143257 -305.636826)
			(xy 309.102754 -305.664782) (xy 309.058292 -305.68588) (xy 309.011021 -305.699572) (xy 308.962166 -305.705504)
			(xy 308.912991 -305.703523) (xy 308.864772 -305.693679) (xy 308.818756 -305.676227) (xy 308.776135 -305.65162)
			(xy 308.738014 -305.620495) (xy 308.705379 -305.583658) (xy 308.679076 -305.542062) (xy 308.659785 -305.496786)
			(xy 308.648008 -305.449002) (xy 308.644048 -305.399948) (xy 158.955232 -305.399948) (xy 158.954737 -305.424555)
			(xy 158.946842 -305.473132) (xy 158.931258 -305.519813) (xy 158.908387 -305.56339) (xy 158.878822 -305.602734)
			(xy 158.843329 -305.636826) (xy 158.802826 -305.664782) (xy 158.758364 -305.68588) (xy 158.711093 -305.699572)
			(xy 158.662238 -305.705504) (xy 158.613063 -305.703523) (xy 158.564844 -305.693679) (xy 158.518828 -305.676227)
			(xy 158.476207 -305.65162) (xy 158.438086 -305.620495) (xy 158.405451 -305.583658) (xy 158.379148 -305.542062)
			(xy 158.359857 -305.496786) (xy 158.34808 -305.449002) (xy 158.34412 -305.399948) (xy 158.005272 -305.399948)
			(xy 158.004777 -305.424555) (xy 157.996882 -305.473132) (xy 157.981298 -305.519813) (xy 157.958427 -305.56339)
			(xy 157.928862 -305.602734) (xy 157.893369 -305.636826) (xy 157.852866 -305.664782) (xy 157.808404 -305.68588)
			(xy 157.761133 -305.699572) (xy 157.712278 -305.705504) (xy 157.663103 -305.703523) (xy 157.614884 -305.693679)
			(xy 157.568868 -305.676227) (xy 157.526247 -305.65162) (xy 157.488126 -305.620495) (xy 157.455491 -305.583658)
			(xy 157.429188 -305.542062) (xy 157.409897 -305.496786) (xy 157.39812 -305.449002) (xy 157.39416 -305.399948)
			(xy 156.105352 -305.399948) (xy 156.104857 -305.424555) (xy 156.096962 -305.473132) (xy 156.081378 -305.519813)
			(xy 156.058507 -305.56339) (xy 156.028942 -305.602734) (xy 155.993449 -305.636826) (xy 155.952946 -305.664782)
			(xy 155.908484 -305.68588) (xy 155.861213 -305.699572) (xy 155.812358 -305.705504) (xy 155.763183 -305.703523)
			(xy 155.714964 -305.693679) (xy 155.668948 -305.676227) (xy 155.626327 -305.65162) (xy 155.588206 -305.620495)
			(xy 155.555571 -305.583658) (xy 155.529268 -305.542062) (xy 155.509977 -305.496786) (xy 155.4982 -305.449002)
			(xy 155.49424 -305.399948) (xy 155.155392 -305.399948) (xy 155.154897 -305.424555) (xy 155.147002 -305.473132)
			(xy 155.131418 -305.519813) (xy 155.108547 -305.56339) (xy 155.078982 -305.602734) (xy 155.043489 -305.636826)
			(xy 155.002986 -305.664782) (xy 154.958524 -305.68588) (xy 154.911253 -305.699572) (xy 154.862398 -305.705504)
			(xy 154.813223 -305.703523) (xy 154.765004 -305.693679) (xy 154.718988 -305.676227) (xy 154.676367 -305.65162)
			(xy 154.638246 -305.620495) (xy 154.605611 -305.583658) (xy 154.579308 -305.542062) (xy 154.560017 -305.496786)
			(xy 154.54824 -305.449002) (xy 154.54428 -305.399948) (xy 80.855058 -305.399948) (xy 80.854563 -305.424555)
			(xy 80.846668 -305.473132) (xy 80.831084 -305.519813) (xy 80.808213 -305.56339) (xy 80.778648 -305.602734)
			(xy 80.743155 -305.636826) (xy 80.702652 -305.664782) (xy 80.65819 -305.68588) (xy 80.610919 -305.699572)
			(xy 80.562064 -305.705504) (xy 80.512889 -305.703523) (xy 80.46467 -305.693679) (xy 80.418654 -305.676227)
			(xy 80.376033 -305.65162) (xy 80.337912 -305.620495) (xy 80.305277 -305.583658) (xy 80.278974 -305.542062)
			(xy 80.259683 -305.496786) (xy 80.247906 -305.449002) (xy 80.243946 -305.399948) (xy 79.905098 -305.399948)
			(xy 79.904603 -305.424555) (xy 79.896708 -305.473132) (xy 79.881124 -305.519813) (xy 79.858253 -305.56339)
			(xy 79.828688 -305.602734) (xy 79.793195 -305.636826) (xy 79.752692 -305.664782) (xy 79.70823 -305.68588)
			(xy 79.660959 -305.699572) (xy 79.612104 -305.705504) (xy 79.562929 -305.703523) (xy 79.51471 -305.693679)
			(xy 79.468694 -305.676227) (xy 79.426073 -305.65162) (xy 79.387952 -305.620495) (xy 79.355317 -305.583658)
			(xy 79.329014 -305.542062) (xy 79.309723 -305.496786) (xy 79.297946 -305.449002) (xy 79.293986 -305.399948)
			(xy 78.005178 -305.399948) (xy 78.004683 -305.424555) (xy 77.996788 -305.473132) (xy 77.981204 -305.519813)
			(xy 77.958333 -305.56339) (xy 77.928768 -305.602734) (xy 77.893275 -305.636826) (xy 77.852772 -305.664782)
			(xy 77.80831 -305.68588) (xy 77.761039 -305.699572) (xy 77.712184 -305.705504) (xy 77.663009 -305.703523)
			(xy 77.61479 -305.693679) (xy 77.568774 -305.676227) (xy 77.526153 -305.65162) (xy 77.488032 -305.620495)
			(xy 77.455397 -305.583658) (xy 77.429094 -305.542062) (xy 77.409803 -305.496786) (xy 77.398026 -305.449002)
			(xy 77.394066 -305.399948) (xy 77.055218 -305.399948) (xy 77.054723 -305.424555) (xy 77.046828 -305.473132)
			(xy 77.031244 -305.519813) (xy 77.008373 -305.56339) (xy 76.978808 -305.602734) (xy 76.943315 -305.636826)
			(xy 76.902812 -305.664782) (xy 76.85835 -305.68588) (xy 76.811079 -305.699572) (xy 76.762224 -305.705504)
			(xy 76.713049 -305.703523) (xy 76.66483 -305.693679) (xy 76.618814 -305.676227) (xy 76.576193 -305.65162)
			(xy 76.538072 -305.620495) (xy 76.505437 -305.583658) (xy 76.479134 -305.542062) (xy 76.459843 -305.496786)
			(xy 76.448066 -305.449002) (xy 76.444106 -305.399948) (xy 18.343745 -305.399948) (xy 18.323105 -305.431145)
			(xy 18.285863 -305.472709) (xy 18.242967 -305.508408) (xy 18.195329 -305.537481) (xy 18.143966 -305.559308)
			(xy 18.089973 -305.573424) (xy 18.034499 -305.579527) (xy 17.978728 -305.577489) (xy 17.923849 -305.567352)
			(xy 17.871029 -305.549333) (xy 17.821397 -305.523815) (xy 17.776009 -305.491343) (xy 17.735832 -305.452608)
			(xy 17.701724 -305.408436) (xy 17.67441 -305.359768) (xy 17.654474 -305.307642) (xy 17.642339 -305.253169)
			(xy 17.638266 -305.19751) (xy 0.508 -305.19751) (xy 0.508 -306.28209) (xy 17.638266 -306.28209) (xy 17.642339 -306.226431)
			(xy 17.654474 -306.171958) (xy 17.67441 -306.119832) (xy 17.701724 -306.071164) (xy 17.735832 -306.026992)
			(xy 17.776009 -305.988257) (xy 17.821397 -305.955785) (xy 17.871029 -305.930267) (xy 17.923849 -305.912248)
			(xy 17.978728 -305.902111) (xy 18.034499 -305.900073) (xy 18.089973 -305.906176) (xy 18.143966 -305.920292)
			(xy 18.195329 -305.942119) (xy 18.242967 -305.971192) (xy 18.285863 -306.006891) (xy 18.323105 -306.048455)
			(xy 18.353899 -306.094999) (xy 18.377587 -306.14553) (xy 18.393665 -306.198972) (xy 18.401791 -306.254186)
			(xy 18.4023 -306.28209) (xy 18.401791 -306.309994) (xy 18.395917 -306.349908) (xy 74.544186 -306.349908)
			(xy 74.548146 -306.300854) (xy 74.559923 -306.25307) (xy 74.579214 -306.207794) (xy 74.605517 -306.166198)
			(xy 74.638152 -306.129361) (xy 74.676273 -306.098236) (xy 74.718894 -306.073629) (xy 74.76491 -306.056177)
			(xy 74.813129 -306.046333) (xy 74.862304 -306.044352) (xy 74.911159 -306.050284) (xy 74.95843 -306.063976)
			(xy 75.002892 -306.085074) (xy 75.043395 -306.11303) (xy 75.078888 -306.147122) (xy 75.108453 -306.186466)
			(xy 75.131324 -306.230043) (xy 75.146908 -306.276724) (xy 75.154803 -306.325301) (xy 75.155298 -306.349908)
			(xy 75.494146 -306.349908) (xy 75.498106 -306.300854) (xy 75.509883 -306.25307) (xy 75.529174 -306.207794)
			(xy 75.555477 -306.166198) (xy 75.588112 -306.129361) (xy 75.626233 -306.098236) (xy 75.668854 -306.073629)
			(xy 75.71487 -306.056177) (xy 75.763089 -306.046333) (xy 75.812264 -306.044352) (xy 75.861119 -306.050284)
			(xy 75.90839 -306.063976) (xy 75.952852 -306.085074) (xy 75.993355 -306.11303) (xy 76.028848 -306.147122)
			(xy 76.058413 -306.186466) (xy 76.081284 -306.230043) (xy 76.096868 -306.276724) (xy 76.104763 -306.325301)
			(xy 76.105258 -306.349908) (xy 81.19416 -306.349908) (xy 81.19812 -306.300854) (xy 81.209897 -306.25307)
			(xy 81.229188 -306.207794) (xy 81.255491 -306.166198) (xy 81.288126 -306.129361) (xy 81.326247 -306.098236)
			(xy 81.368868 -306.073629) (xy 81.414884 -306.056177) (xy 81.463103 -306.046333) (xy 81.512278 -306.044352)
			(xy 81.561133 -306.050284) (xy 81.608404 -306.063976) (xy 81.652866 -306.085074) (xy 81.693369 -306.11303)
			(xy 81.728862 -306.147122) (xy 81.758427 -306.186466) (xy 81.781298 -306.230043) (xy 81.796882 -306.276724)
			(xy 81.804777 -306.325301) (xy 81.805272 -306.349908) (xy 82.14412 -306.349908) (xy 82.14808 -306.300854)
			(xy 82.159857 -306.25307) (xy 82.179148 -306.207794) (xy 82.205451 -306.166198) (xy 82.238086 -306.129361)
			(xy 82.276207 -306.098236) (xy 82.318828 -306.073629) (xy 82.364844 -306.056177) (xy 82.413063 -306.046333)
			(xy 82.462238 -306.044352) (xy 82.511093 -306.050284) (xy 82.558364 -306.063976) (xy 82.602826 -306.085074)
			(xy 82.643329 -306.11303) (xy 82.678822 -306.147122) (xy 82.708387 -306.186466) (xy 82.731258 -306.230043)
			(xy 82.746842 -306.276724) (xy 82.754737 -306.325301) (xy 82.755232 -306.349908) (xy 152.644106 -306.349908)
			(xy 152.648066 -306.300854) (xy 152.659843 -306.25307) (xy 152.679134 -306.207794) (xy 152.705437 -306.166198)
			(xy 152.738072 -306.129361) (xy 152.776193 -306.098236) (xy 152.818814 -306.073629) (xy 152.86483 -306.056177)
			(xy 152.913049 -306.046333) (xy 152.962224 -306.044352) (xy 153.011079 -306.050284) (xy 153.05835 -306.063976)
			(xy 153.102812 -306.085074) (xy 153.143315 -306.11303) (xy 153.178808 -306.147122) (xy 153.208373 -306.186466)
			(xy 153.231244 -306.230043) (xy 153.246828 -306.276724) (xy 153.254723 -306.325301) (xy 153.255218 -306.349908)
			(xy 153.594066 -306.349908) (xy 153.598026 -306.300854) (xy 153.609803 -306.25307) (xy 153.629094 -306.207794)
			(xy 153.655397 -306.166198) (xy 153.688032 -306.129361) (xy 153.726153 -306.098236) (xy 153.768774 -306.073629)
			(xy 153.81479 -306.056177) (xy 153.863009 -306.046333) (xy 153.912184 -306.044352) (xy 153.961039 -306.050284)
			(xy 154.00831 -306.063976) (xy 154.052772 -306.085074) (xy 154.093275 -306.11303) (xy 154.128768 -306.147122)
			(xy 154.158333 -306.186466) (xy 154.181204 -306.230043) (xy 154.196788 -306.276724) (xy 154.204683 -306.325301)
			(xy 154.205178 -306.349908) (xy 159.29408 -306.349908) (xy 159.29804 -306.300854) (xy 159.309817 -306.25307)
			(xy 159.329108 -306.207794) (xy 159.355411 -306.166198) (xy 159.388046 -306.129361) (xy 159.426167 -306.098236)
			(xy 159.468788 -306.073629) (xy 159.514804 -306.056177) (xy 159.563023 -306.046333) (xy 159.612198 -306.044352)
			(xy 159.661053 -306.050284) (xy 159.708324 -306.063976) (xy 159.752786 -306.085074) (xy 159.793289 -306.11303)
			(xy 159.828782 -306.147122) (xy 159.858347 -306.186466) (xy 159.881218 -306.230043) (xy 159.896802 -306.276724)
			(xy 159.904697 -306.325301) (xy 159.905192 -306.349908) (xy 160.24404 -306.349908) (xy 160.248 -306.300854)
			(xy 160.259777 -306.25307) (xy 160.279068 -306.207794) (xy 160.305371 -306.166198) (xy 160.338006 -306.129361)
			(xy 160.376127 -306.098236) (xy 160.418748 -306.073629) (xy 160.464764 -306.056177) (xy 160.512983 -306.046333)
			(xy 160.562158 -306.044352) (xy 160.611013 -306.050284) (xy 160.658284 -306.063976) (xy 160.702746 -306.085074)
			(xy 160.743249 -306.11303) (xy 160.778742 -306.147122) (xy 160.808307 -306.186466) (xy 160.831178 -306.230043)
			(xy 160.846762 -306.276724) (xy 160.854657 -306.325301) (xy 160.855152 -306.349908) (xy 306.744128 -306.349908)
			(xy 306.748088 -306.300854) (xy 306.759865 -306.25307) (xy 306.779156 -306.207794) (xy 306.805459 -306.166198)
			(xy 306.838094 -306.129361) (xy 306.876215 -306.098236) (xy 306.918836 -306.073629) (xy 306.964852 -306.056177)
			(xy 307.013071 -306.046333) (xy 307.062246 -306.044352) (xy 307.111101 -306.050284) (xy 307.158372 -306.063976)
			(xy 307.202834 -306.085074) (xy 307.243337 -306.11303) (xy 307.27883 -306.147122) (xy 307.308395 -306.186466)
			(xy 307.331266 -306.230043) (xy 307.34685 -306.276724) (xy 307.354745 -306.325301) (xy 307.35524 -306.349908)
			(xy 307.694088 -306.349908) (xy 307.698048 -306.300854) (xy 307.709825 -306.25307) (xy 307.729116 -306.207794)
			(xy 307.755419 -306.166198) (xy 307.788054 -306.129361) (xy 307.826175 -306.098236) (xy 307.868796 -306.073629)
			(xy 307.914812 -306.056177) (xy 307.963031 -306.046333) (xy 308.012206 -306.044352) (xy 308.061061 -306.050284)
			(xy 308.108332 -306.063976) (xy 308.152794 -306.085074) (xy 308.193297 -306.11303) (xy 308.22879 -306.147122)
			(xy 308.258355 -306.186466) (xy 308.281226 -306.230043) (xy 308.29681 -306.276724) (xy 308.304705 -306.325301)
			(xy 308.3052 -306.349908) (xy 313.394102 -306.349908) (xy 313.398062 -306.300854) (xy 313.409839 -306.25307)
			(xy 313.42913 -306.207794) (xy 313.455433 -306.166198) (xy 313.488068 -306.129361) (xy 313.526189 -306.098236)
			(xy 313.56881 -306.073629) (xy 313.614826 -306.056177) (xy 313.663045 -306.046333) (xy 313.71222 -306.044352)
			(xy 313.761075 -306.050284) (xy 313.808346 -306.063976) (xy 313.852808 -306.085074) (xy 313.893311 -306.11303)
			(xy 313.928804 -306.147122) (xy 313.958369 -306.186466) (xy 313.98124 -306.230043) (xy 313.996824 -306.276724)
			(xy 314.004719 -306.325301) (xy 314.005214 -306.349908) (xy 314.344062 -306.349908) (xy 314.348022 -306.300854)
			(xy 314.359799 -306.25307) (xy 314.37909 -306.207794) (xy 314.405393 -306.166198) (xy 314.438028 -306.129361)
			(xy 314.476149 -306.098236) (xy 314.51877 -306.073629) (xy 314.564786 -306.056177) (xy 314.613005 -306.046333)
			(xy 314.66218 -306.044352) (xy 314.711035 -306.050284) (xy 314.758306 -306.063976) (xy 314.802768 -306.085074)
			(xy 314.843271 -306.11303) (xy 314.878764 -306.147122) (xy 314.908329 -306.186466) (xy 314.9312 -306.230043)
			(xy 314.946784 -306.276724) (xy 314.954679 -306.325301) (xy 314.955174 -306.349908) (xy 384.844048 -306.349908)
			(xy 384.848008 -306.300854) (xy 384.859785 -306.25307) (xy 384.879076 -306.207794) (xy 384.905379 -306.166198)
			(xy 384.938014 -306.129361) (xy 384.976135 -306.098236) (xy 385.018756 -306.073629) (xy 385.064772 -306.056177)
			(xy 385.112991 -306.046333) (xy 385.162166 -306.044352) (xy 385.211021 -306.050284) (xy 385.258292 -306.063976)
			(xy 385.302754 -306.085074) (xy 385.343257 -306.11303) (xy 385.37875 -306.147122) (xy 385.408315 -306.186466)
			(xy 385.431186 -306.230043) (xy 385.44677 -306.276724) (xy 385.454665 -306.325301) (xy 385.45516 -306.349908)
			(xy 385.794008 -306.349908) (xy 385.797968 -306.300854) (xy 385.809745 -306.25307) (xy 385.829036 -306.207794)
			(xy 385.855339 -306.166198) (xy 385.887974 -306.129361) (xy 385.926095 -306.098236) (xy 385.968716 -306.073629)
			(xy 386.014732 -306.056177) (xy 386.062951 -306.046333) (xy 386.112126 -306.044352) (xy 386.160981 -306.050284)
			(xy 386.208252 -306.063976) (xy 386.252714 -306.085074) (xy 386.293217 -306.11303) (xy 386.32871 -306.147122)
			(xy 386.358275 -306.186466) (xy 386.381146 -306.230043) (xy 386.39673 -306.276724) (xy 386.404625 -306.325301)
			(xy 386.40512 -306.349908) (xy 391.494022 -306.349908) (xy 391.497982 -306.300854) (xy 391.509759 -306.25307)
			(xy 391.52905 -306.207794) (xy 391.555353 -306.166198) (xy 391.587988 -306.129361) (xy 391.626109 -306.098236)
			(xy 391.66873 -306.073629) (xy 391.714746 -306.056177) (xy 391.762965 -306.046333) (xy 391.81214 -306.044352)
			(xy 391.860995 -306.050284) (xy 391.908266 -306.063976) (xy 391.952728 -306.085074) (xy 391.993231 -306.11303)
			(xy 392.028724 -306.147122) (xy 392.058289 -306.186466) (xy 392.08116 -306.230043) (xy 392.096744 -306.276724)
			(xy 392.104639 -306.325301) (xy 392.105134 -306.349908) (xy 392.443982 -306.349908) (xy 392.447942 -306.300854)
			(xy 392.459719 -306.25307) (xy 392.47901 -306.207794) (xy 392.505313 -306.166198) (xy 392.537948 -306.129361)
			(xy 392.576069 -306.098236) (xy 392.61869 -306.073629) (xy 392.664706 -306.056177) (xy 392.712925 -306.046333)
			(xy 392.7621 -306.044352) (xy 392.810955 -306.050284) (xy 392.858226 -306.063976) (xy 392.902688 -306.085074)
			(xy 392.943191 -306.11303) (xy 392.978684 -306.147122) (xy 393.008249 -306.186466) (xy 393.03112 -306.230043)
			(xy 393.046704 -306.276724) (xy 393.054599 -306.325301) (xy 393.055094 -306.349908) (xy 393.054599 -306.374515)
			(xy 393.046704 -306.423092) (xy 393.03112 -306.469773) (xy 393.008249 -306.51335) (xy 392.978684 -306.552694)
			(xy 392.943191 -306.586786) (xy 392.902688 -306.614742) (xy 392.858226 -306.63584) (xy 392.810955 -306.649532)
			(xy 392.7621 -306.655464) (xy 392.712925 -306.653483) (xy 392.664706 -306.643639) (xy 392.61869 -306.626187)
			(xy 392.576069 -306.60158) (xy 392.537948 -306.570455) (xy 392.505313 -306.533618) (xy 392.47901 -306.492022)
			(xy 392.459719 -306.446746) (xy 392.447942 -306.398962) (xy 392.443982 -306.349908) (xy 392.105134 -306.349908)
			(xy 392.104639 -306.374515) (xy 392.096744 -306.423092) (xy 392.08116 -306.469773) (xy 392.058289 -306.51335)
			(xy 392.028724 -306.552694) (xy 391.993231 -306.586786) (xy 391.952728 -306.614742) (xy 391.908266 -306.63584)
			(xy 391.860995 -306.649532) (xy 391.81214 -306.655464) (xy 391.762965 -306.653483) (xy 391.714746 -306.643639)
			(xy 391.66873 -306.626187) (xy 391.626109 -306.60158) (xy 391.587988 -306.570455) (xy 391.555353 -306.533618)
			(xy 391.52905 -306.492022) (xy 391.509759 -306.446746) (xy 391.497982 -306.398962) (xy 391.494022 -306.349908)
			(xy 386.40512 -306.349908) (xy 386.404625 -306.374515) (xy 386.39673 -306.423092) (xy 386.381146 -306.469773)
			(xy 386.358275 -306.51335) (xy 386.32871 -306.552694) (xy 386.293217 -306.586786) (xy 386.252714 -306.614742)
			(xy 386.208252 -306.63584) (xy 386.160981 -306.649532) (xy 386.112126 -306.655464) (xy 386.062951 -306.653483)
			(xy 386.014732 -306.643639) (xy 385.968716 -306.626187) (xy 385.926095 -306.60158) (xy 385.887974 -306.570455)
			(xy 385.855339 -306.533618) (xy 385.829036 -306.492022) (xy 385.809745 -306.446746) (xy 385.797968 -306.398962)
			(xy 385.794008 -306.349908) (xy 385.45516 -306.349908) (xy 385.454665 -306.374515) (xy 385.44677 -306.423092)
			(xy 385.431186 -306.469773) (xy 385.408315 -306.51335) (xy 385.37875 -306.552694) (xy 385.343257 -306.586786)
			(xy 385.302754 -306.614742) (xy 385.258292 -306.63584) (xy 385.211021 -306.649532) (xy 385.162166 -306.655464)
			(xy 385.112991 -306.653483) (xy 385.064772 -306.643639) (xy 385.018756 -306.626187) (xy 384.976135 -306.60158)
			(xy 384.938014 -306.570455) (xy 384.905379 -306.533618) (xy 384.879076 -306.492022) (xy 384.859785 -306.446746)
			(xy 384.848008 -306.398962) (xy 384.844048 -306.349908) (xy 314.955174 -306.349908) (xy 314.954679 -306.374515)
			(xy 314.946784 -306.423092) (xy 314.9312 -306.469773) (xy 314.908329 -306.51335) (xy 314.878764 -306.552694)
			(xy 314.843271 -306.586786) (xy 314.802768 -306.614742) (xy 314.758306 -306.63584) (xy 314.711035 -306.649532)
			(xy 314.66218 -306.655464) (xy 314.613005 -306.653483) (xy 314.564786 -306.643639) (xy 314.51877 -306.626187)
			(xy 314.476149 -306.60158) (xy 314.438028 -306.570455) (xy 314.405393 -306.533618) (xy 314.37909 -306.492022)
			(xy 314.359799 -306.446746) (xy 314.348022 -306.398962) (xy 314.344062 -306.349908) (xy 314.005214 -306.349908)
			(xy 314.004719 -306.374515) (xy 313.996824 -306.423092) (xy 313.98124 -306.469773) (xy 313.958369 -306.51335)
			(xy 313.928804 -306.552694) (xy 313.893311 -306.586786) (xy 313.852808 -306.614742) (xy 313.808346 -306.63584)
			(xy 313.761075 -306.649532) (xy 313.71222 -306.655464) (xy 313.663045 -306.653483) (xy 313.614826 -306.643639)
			(xy 313.56881 -306.626187) (xy 313.526189 -306.60158) (xy 313.488068 -306.570455) (xy 313.455433 -306.533618)
			(xy 313.42913 -306.492022) (xy 313.409839 -306.446746) (xy 313.398062 -306.398962) (xy 313.394102 -306.349908)
			(xy 308.3052 -306.349908) (xy 308.304705 -306.374515) (xy 308.29681 -306.423092) (xy 308.281226 -306.469773)
			(xy 308.258355 -306.51335) (xy 308.22879 -306.552694) (xy 308.193297 -306.586786) (xy 308.152794 -306.614742)
			(xy 308.108332 -306.63584) (xy 308.061061 -306.649532) (xy 308.012206 -306.655464) (xy 307.963031 -306.653483)
			(xy 307.914812 -306.643639) (xy 307.868796 -306.626187) (xy 307.826175 -306.60158) (xy 307.788054 -306.570455)
			(xy 307.755419 -306.533618) (xy 307.729116 -306.492022) (xy 307.709825 -306.446746) (xy 307.698048 -306.398962)
			(xy 307.694088 -306.349908) (xy 307.35524 -306.349908) (xy 307.354745 -306.374515) (xy 307.34685 -306.423092)
			(xy 307.331266 -306.469773) (xy 307.308395 -306.51335) (xy 307.27883 -306.552694) (xy 307.243337 -306.586786)
			(xy 307.202834 -306.614742) (xy 307.158372 -306.63584) (xy 307.111101 -306.649532) (xy 307.062246 -306.655464)
			(xy 307.013071 -306.653483) (xy 306.964852 -306.643639) (xy 306.918836 -306.626187) (xy 306.876215 -306.60158)
			(xy 306.838094 -306.570455) (xy 306.805459 -306.533618) (xy 306.779156 -306.492022) (xy 306.759865 -306.446746)
			(xy 306.748088 -306.398962) (xy 306.744128 -306.349908) (xy 160.855152 -306.349908) (xy 160.854657 -306.374515)
			(xy 160.846762 -306.423092) (xy 160.831178 -306.469773) (xy 160.808307 -306.51335) (xy 160.778742 -306.552694)
			(xy 160.743249 -306.586786) (xy 160.702746 -306.614742) (xy 160.658284 -306.63584) (xy 160.611013 -306.649532)
			(xy 160.562158 -306.655464) (xy 160.512983 -306.653483) (xy 160.464764 -306.643639) (xy 160.418748 -306.626187)
			(xy 160.376127 -306.60158) (xy 160.338006 -306.570455) (xy 160.305371 -306.533618) (xy 160.279068 -306.492022)
			(xy 160.259777 -306.446746) (xy 160.248 -306.398962) (xy 160.24404 -306.349908) (xy 159.905192 -306.349908)
			(xy 159.904697 -306.374515) (xy 159.896802 -306.423092) (xy 159.881218 -306.469773) (xy 159.858347 -306.51335)
			(xy 159.828782 -306.552694) (xy 159.793289 -306.586786) (xy 159.752786 -306.614742) (xy 159.708324 -306.63584)
			(xy 159.661053 -306.649532) (xy 159.612198 -306.655464) (xy 159.563023 -306.653483) (xy 159.514804 -306.643639)
			(xy 159.468788 -306.626187) (xy 159.426167 -306.60158) (xy 159.388046 -306.570455) (xy 159.355411 -306.533618)
			(xy 159.329108 -306.492022) (xy 159.309817 -306.446746) (xy 159.29804 -306.398962) (xy 159.29408 -306.349908)
			(xy 154.205178 -306.349908) (xy 154.204683 -306.374515) (xy 154.196788 -306.423092) (xy 154.181204 -306.469773)
			(xy 154.158333 -306.51335) (xy 154.128768 -306.552694) (xy 154.093275 -306.586786) (xy 154.052772 -306.614742)
			(xy 154.00831 -306.63584) (xy 153.961039 -306.649532) (xy 153.912184 -306.655464) (xy 153.863009 -306.653483)
			(xy 153.81479 -306.643639) (xy 153.768774 -306.626187) (xy 153.726153 -306.60158) (xy 153.688032 -306.570455)
			(xy 153.655397 -306.533618) (xy 153.629094 -306.492022) (xy 153.609803 -306.446746) (xy 153.598026 -306.398962)
			(xy 153.594066 -306.349908) (xy 153.255218 -306.349908) (xy 153.254723 -306.374515) (xy 153.246828 -306.423092)
			(xy 153.231244 -306.469773) (xy 153.208373 -306.51335) (xy 153.178808 -306.552694) (xy 153.143315 -306.586786)
			(xy 153.102812 -306.614742) (xy 153.05835 -306.63584) (xy 153.011079 -306.649532) (xy 152.962224 -306.655464)
			(xy 152.913049 -306.653483) (xy 152.86483 -306.643639) (xy 152.818814 -306.626187) (xy 152.776193 -306.60158)
			(xy 152.738072 -306.570455) (xy 152.705437 -306.533618) (xy 152.679134 -306.492022) (xy 152.659843 -306.446746)
			(xy 152.648066 -306.398962) (xy 152.644106 -306.349908) (xy 82.755232 -306.349908) (xy 82.754737 -306.374515)
			(xy 82.746842 -306.423092) (xy 82.731258 -306.469773) (xy 82.708387 -306.51335) (xy 82.678822 -306.552694)
			(xy 82.643329 -306.586786) (xy 82.602826 -306.614742) (xy 82.558364 -306.63584) (xy 82.511093 -306.649532)
			(xy 82.462238 -306.655464) (xy 82.413063 -306.653483) (xy 82.364844 -306.643639) (xy 82.318828 -306.626187)
			(xy 82.276207 -306.60158) (xy 82.238086 -306.570455) (xy 82.205451 -306.533618) (xy 82.179148 -306.492022)
			(xy 82.159857 -306.446746) (xy 82.14808 -306.398962) (xy 82.14412 -306.349908) (xy 81.805272 -306.349908)
			(xy 81.804777 -306.374515) (xy 81.796882 -306.423092) (xy 81.781298 -306.469773) (xy 81.758427 -306.51335)
			(xy 81.728862 -306.552694) (xy 81.693369 -306.586786) (xy 81.652866 -306.614742) (xy 81.608404 -306.63584)
			(xy 81.561133 -306.649532) (xy 81.512278 -306.655464) (xy 81.463103 -306.653483) (xy 81.414884 -306.643639)
			(xy 81.368868 -306.626187) (xy 81.326247 -306.60158) (xy 81.288126 -306.570455) (xy 81.255491 -306.533618)
			(xy 81.229188 -306.492022) (xy 81.209897 -306.446746) (xy 81.19812 -306.398962) (xy 81.19416 -306.349908)
			(xy 76.105258 -306.349908) (xy 76.104763 -306.374515) (xy 76.096868 -306.423092) (xy 76.081284 -306.469773)
			(xy 76.058413 -306.51335) (xy 76.028848 -306.552694) (xy 75.993355 -306.586786) (xy 75.952852 -306.614742)
			(xy 75.90839 -306.63584) (xy 75.861119 -306.649532) (xy 75.812264 -306.655464) (xy 75.763089 -306.653483)
			(xy 75.71487 -306.643639) (xy 75.668854 -306.626187) (xy 75.626233 -306.60158) (xy 75.588112 -306.570455)
			(xy 75.555477 -306.533618) (xy 75.529174 -306.492022) (xy 75.509883 -306.446746) (xy 75.498106 -306.398962)
			(xy 75.494146 -306.349908) (xy 75.155298 -306.349908) (xy 75.154803 -306.374515) (xy 75.146908 -306.423092)
			(xy 75.131324 -306.469773) (xy 75.108453 -306.51335) (xy 75.078888 -306.552694) (xy 75.043395 -306.586786)
			(xy 75.002892 -306.614742) (xy 74.95843 -306.63584) (xy 74.911159 -306.649532) (xy 74.862304 -306.655464)
			(xy 74.813129 -306.653483) (xy 74.76491 -306.643639) (xy 74.718894 -306.626187) (xy 74.676273 -306.60158)
			(xy 74.638152 -306.570455) (xy 74.605517 -306.533618) (xy 74.579214 -306.492022) (xy 74.559923 -306.446746)
			(xy 74.548146 -306.398962) (xy 74.544186 -306.349908) (xy 18.395917 -306.349908) (xy 18.393665 -306.365208)
			(xy 18.377587 -306.41865) (xy 18.353899 -306.469181) (xy 18.323105 -306.515725) (xy 18.285863 -306.557289)
			(xy 18.242967 -306.592988) (xy 18.195329 -306.622061) (xy 18.143966 -306.643888) (xy 18.089973 -306.658004)
			(xy 18.034499 -306.664107) (xy 17.978728 -306.662069) (xy 17.923849 -306.651932) (xy 17.871029 -306.633913)
			(xy 17.821397 -306.608395) (xy 17.776009 -306.575923) (xy 17.735832 -306.537188) (xy 17.701724 -306.493016)
			(xy 17.67441 -306.444348) (xy 17.654474 -306.392222) (xy 17.642339 -306.337749) (xy 17.638266 -306.28209)
			(xy 0.508 -306.28209) (xy 0.508 -307.299868) (xy 76.444106 -307.299868) (xy 76.448066 -307.250814)
			(xy 76.459843 -307.20303) (xy 76.479134 -307.157754) (xy 76.505437 -307.116158) (xy 76.538072 -307.079321)
			(xy 76.576193 -307.048196) (xy 76.618814 -307.023589) (xy 76.66483 -307.006137) (xy 76.713049 -306.996293)
			(xy 76.762224 -306.994312) (xy 76.811079 -307.000244) (xy 76.85835 -307.013936) (xy 76.902812 -307.035034)
			(xy 76.943315 -307.06299) (xy 76.978808 -307.097082) (xy 77.008373 -307.136426) (xy 77.031244 -307.180003)
			(xy 77.046828 -307.226684) (xy 77.054723 -307.275261) (xy 77.055218 -307.299868) (xy 77.394066 -307.299868)
			(xy 77.398026 -307.250814) (xy 77.409803 -307.20303) (xy 77.429094 -307.157754) (xy 77.455397 -307.116158)
			(xy 77.488032 -307.079321) (xy 77.526153 -307.048196) (xy 77.568774 -307.023589) (xy 77.61479 -307.006137)
			(xy 77.663009 -306.996293) (xy 77.712184 -306.994312) (xy 77.761039 -307.000244) (xy 77.80831 -307.013936)
			(xy 77.852772 -307.035034) (xy 77.893275 -307.06299) (xy 77.928768 -307.097082) (xy 77.958333 -307.136426)
			(xy 77.981204 -307.180003) (xy 77.996788 -307.226684) (xy 78.004683 -307.275261) (xy 78.005178 -307.299868)
			(xy 79.293986 -307.299868) (xy 79.297946 -307.250814) (xy 79.309723 -307.20303) (xy 79.329014 -307.157754)
			(xy 79.355317 -307.116158) (xy 79.387952 -307.079321) (xy 79.426073 -307.048196) (xy 79.468694 -307.023589)
			(xy 79.51471 -307.006137) (xy 79.562929 -306.996293) (xy 79.612104 -306.994312) (xy 79.660959 -307.000244)
			(xy 79.70823 -307.013936) (xy 79.752692 -307.035034) (xy 79.793195 -307.06299) (xy 79.828688 -307.097082)
			(xy 79.858253 -307.136426) (xy 79.881124 -307.180003) (xy 79.896708 -307.226684) (xy 79.904603 -307.275261)
			(xy 79.905098 -307.299868) (xy 80.243946 -307.299868) (xy 80.247906 -307.250814) (xy 80.259683 -307.20303)
			(xy 80.278974 -307.157754) (xy 80.305277 -307.116158) (xy 80.337912 -307.079321) (xy 80.376033 -307.048196)
			(xy 80.418654 -307.023589) (xy 80.46467 -307.006137) (xy 80.512889 -306.996293) (xy 80.562064 -306.994312)
			(xy 80.610919 -307.000244) (xy 80.65819 -307.013936) (xy 80.702652 -307.035034) (xy 80.743155 -307.06299)
			(xy 80.778648 -307.097082) (xy 80.808213 -307.136426) (xy 80.831084 -307.180003) (xy 80.846668 -307.226684)
			(xy 80.854563 -307.275261) (xy 80.855058 -307.299868) (xy 154.54428 -307.299868) (xy 154.54824 -307.250814)
			(xy 154.560017 -307.20303) (xy 154.579308 -307.157754) (xy 154.605611 -307.116158) (xy 154.638246 -307.079321)
			(xy 154.676367 -307.048196) (xy 154.718988 -307.023589) (xy 154.765004 -307.006137) (xy 154.813223 -306.996293)
			(xy 154.862398 -306.994312) (xy 154.911253 -307.000244) (xy 154.958524 -307.013936) (xy 155.002986 -307.035034)
			(xy 155.043489 -307.06299) (xy 155.078982 -307.097082) (xy 155.108547 -307.136426) (xy 155.131418 -307.180003)
			(xy 155.147002 -307.226684) (xy 155.154897 -307.275261) (xy 155.155392 -307.299868) (xy 155.49424 -307.299868)
			(xy 155.4982 -307.250814) (xy 155.509977 -307.20303) (xy 155.529268 -307.157754) (xy 155.555571 -307.116158)
			(xy 155.588206 -307.079321) (xy 155.626327 -307.048196) (xy 155.668948 -307.023589) (xy 155.714964 -307.006137)
			(xy 155.763183 -306.996293) (xy 155.812358 -306.994312) (xy 155.861213 -307.000244) (xy 155.908484 -307.013936)
			(xy 155.952946 -307.035034) (xy 155.993449 -307.06299) (xy 156.028942 -307.097082) (xy 156.058507 -307.136426)
			(xy 156.081378 -307.180003) (xy 156.096962 -307.226684) (xy 156.104857 -307.275261) (xy 156.105352 -307.299868)
			(xy 157.39416 -307.299868) (xy 157.39812 -307.250814) (xy 157.409897 -307.20303) (xy 157.429188 -307.157754)
			(xy 157.455491 -307.116158) (xy 157.488126 -307.079321) (xy 157.526247 -307.048196) (xy 157.568868 -307.023589)
			(xy 157.614884 -307.006137) (xy 157.663103 -306.996293) (xy 157.712278 -306.994312) (xy 157.761133 -307.000244)
			(xy 157.808404 -307.013936) (xy 157.852866 -307.035034) (xy 157.893369 -307.06299) (xy 157.928862 -307.097082)
			(xy 157.958427 -307.136426) (xy 157.981298 -307.180003) (xy 157.996882 -307.226684) (xy 158.004777 -307.275261)
			(xy 158.005272 -307.299868) (xy 158.34412 -307.299868) (xy 158.34808 -307.250814) (xy 158.359857 -307.20303)
			(xy 158.379148 -307.157754) (xy 158.405451 -307.116158) (xy 158.438086 -307.079321) (xy 158.476207 -307.048196)
			(xy 158.518828 -307.023589) (xy 158.564844 -307.006137) (xy 158.613063 -306.996293) (xy 158.662238 -306.994312)
			(xy 158.711093 -307.000244) (xy 158.758364 -307.013936) (xy 158.802826 -307.035034) (xy 158.843329 -307.06299)
			(xy 158.878822 -307.097082) (xy 158.908387 -307.136426) (xy 158.931258 -307.180003) (xy 158.946842 -307.226684)
			(xy 158.954737 -307.275261) (xy 158.955232 -307.299868) (xy 158.954737 -307.324475) (xy 158.946842 -307.373052)
			(xy 158.931258 -307.419733) (xy 158.908387 -307.46331) (xy 158.892635 -307.484272) (xy 231.935526 -307.484272)
			(xy 231.939599 -307.428613) (xy 231.951734 -307.37414) (xy 231.97167 -307.322014) (xy 231.998984 -307.273346)
			(xy 232.033092 -307.229174) (xy 232.073269 -307.190439) (xy 232.118657 -307.157967) (xy 232.168289 -307.132449)
			(xy 232.221109 -307.11443) (xy 232.275988 -307.104293) (xy 232.331759 -307.102255) (xy 232.387233 -307.108358)
			(xy 232.441226 -307.122474) (xy 232.492589 -307.144301) (xy 232.540227 -307.173374) (xy 232.583123 -307.209073)
			(xy 232.620365 -307.250637) (xy 232.651159 -307.297181) (xy 232.674847 -307.347712) (xy 232.690925 -307.401154)
			(xy 232.699051 -307.456368) (xy 232.69956 -307.484272) (xy 248.185684 -307.484272) (xy 248.189757 -307.428613)
			(xy 248.201892 -307.37414) (xy 248.221828 -307.322014) (xy 248.249142 -307.273346) (xy 248.28325 -307.229174)
			(xy 248.323427 -307.190439) (xy 248.368815 -307.157967) (xy 248.418447 -307.132449) (xy 248.471267 -307.11443)
			(xy 248.526146 -307.104293) (xy 248.581917 -307.102255) (xy 248.637391 -307.108358) (xy 248.691384 -307.122474)
			(xy 248.742747 -307.144301) (xy 248.790385 -307.173374) (xy 248.833281 -307.209073) (xy 248.870523 -307.250637)
			(xy 248.901317 -307.297181) (xy 248.902577 -307.299868) (xy 308.644048 -307.299868) (xy 308.648008 -307.250814)
			(xy 308.659785 -307.20303) (xy 308.679076 -307.157754) (xy 308.705379 -307.116158) (xy 308.738014 -307.079321)
			(xy 308.776135 -307.048196) (xy 308.818756 -307.023589) (xy 308.864772 -307.006137) (xy 308.912991 -306.996293)
			(xy 308.962166 -306.994312) (xy 309.011021 -307.000244) (xy 309.058292 -307.013936) (xy 309.102754 -307.035034)
			(xy 309.143257 -307.06299) (xy 309.17875 -307.097082) (xy 309.208315 -307.136426) (xy 309.231186 -307.180003)
			(xy 309.24677 -307.226684) (xy 309.254665 -307.275261) (xy 309.25516 -307.299868) (xy 309.594008 -307.299868)
			(xy 309.597968 -307.250814) (xy 309.609745 -307.20303) (xy 309.629036 -307.157754) (xy 309.655339 -307.116158)
			(xy 309.687974 -307.079321) (xy 309.726095 -307.048196) (xy 309.768716 -307.023589) (xy 309.814732 -307.006137)
			(xy 309.862951 -306.996293) (xy 309.912126 -306.994312) (xy 309.960981 -307.000244) (xy 310.008252 -307.013936)
			(xy 310.052714 -307.035034) (xy 310.093217 -307.06299) (xy 310.12871 -307.097082) (xy 310.158275 -307.136426)
			(xy 310.181146 -307.180003) (xy 310.19673 -307.226684) (xy 310.204625 -307.275261) (xy 310.20512 -307.299868)
			(xy 311.493928 -307.299868) (xy 311.497888 -307.250814) (xy 311.509665 -307.20303) (xy 311.528956 -307.157754)
			(xy 311.555259 -307.116158) (xy 311.587894 -307.079321) (xy 311.626015 -307.048196) (xy 311.668636 -307.023589)
			(xy 311.714652 -307.006137) (xy 311.762871 -306.996293) (xy 311.812046 -306.994312) (xy 311.860901 -307.000244)
			(xy 311.908172 -307.013936) (xy 311.952634 -307.035034) (xy 311.993137 -307.06299) (xy 312.02863 -307.097082)
			(xy 312.058195 -307.136426) (xy 312.081066 -307.180003) (xy 312.09665 -307.226684) (xy 312.104545 -307.275261)
			(xy 312.10504 -307.299868) (xy 312.443888 -307.299868) (xy 312.447848 -307.250814) (xy 312.459625 -307.20303)
			(xy 312.478916 -307.157754) (xy 312.505219 -307.116158) (xy 312.537854 -307.079321) (xy 312.575975 -307.048196)
			(xy 312.618596 -307.023589) (xy 312.664612 -307.006137) (xy 312.712831 -306.996293) (xy 312.762006 -306.994312)
			(xy 312.810861 -307.000244) (xy 312.858132 -307.013936) (xy 312.902594 -307.035034) (xy 312.943097 -307.06299)
			(xy 312.97859 -307.097082) (xy 313.008155 -307.136426) (xy 313.031026 -307.180003) (xy 313.04661 -307.226684)
			(xy 313.054505 -307.275261) (xy 313.055 -307.299868) (xy 386.744222 -307.299868) (xy 386.748182 -307.250814)
			(xy 386.759959 -307.20303) (xy 386.77925 -307.157754) (xy 386.805553 -307.116158) (xy 386.838188 -307.079321)
			(xy 386.876309 -307.048196) (xy 386.91893 -307.023589) (xy 386.964946 -307.006137) (xy 387.013165 -306.996293)
			(xy 387.06234 -306.994312) (xy 387.111195 -307.000244) (xy 387.158466 -307.013936) (xy 387.202928 -307.035034)
			(xy 387.243431 -307.06299) (xy 387.278924 -307.097082) (xy 387.308489 -307.136426) (xy 387.33136 -307.180003)
			(xy 387.346944 -307.226684) (xy 387.354839 -307.275261) (xy 387.355334 -307.299868) (xy 387.694182 -307.299868)
			(xy 387.698142 -307.250814) (xy 387.709919 -307.20303) (xy 387.72921 -307.157754) (xy 387.755513 -307.116158)
			(xy 387.788148 -307.079321) (xy 387.826269 -307.048196) (xy 387.86889 -307.023589) (xy 387.914906 -307.006137)
			(xy 387.963125 -306.996293) (xy 388.0123 -306.994312) (xy 388.061155 -307.000244) (xy 388.108426 -307.013936)
			(xy 388.152888 -307.035034) (xy 388.193391 -307.06299) (xy 388.228884 -307.097082) (xy 388.258449 -307.136426)
			(xy 388.28132 -307.180003) (xy 388.296904 -307.226684) (xy 388.304799 -307.275261) (xy 388.305294 -307.299868)
			(xy 389.594102 -307.299868) (xy 389.598062 -307.250814) (xy 389.609839 -307.20303) (xy 389.62913 -307.157754)
			(xy 389.655433 -307.116158) (xy 389.688068 -307.079321) (xy 389.726189 -307.048196) (xy 389.76881 -307.023589)
			(xy 389.814826 -307.006137) (xy 389.863045 -306.996293) (xy 389.91222 -306.994312) (xy 389.961075 -307.000244)
			(xy 390.008346 -307.013936) (xy 390.052808 -307.035034) (xy 390.093311 -307.06299) (xy 390.128804 -307.097082)
			(xy 390.158369 -307.136426) (xy 390.18124 -307.180003) (xy 390.196824 -307.226684) (xy 390.204719 -307.275261)
			(xy 390.205214 -307.299868) (xy 390.544062 -307.299868) (xy 390.548022 -307.250814) (xy 390.559799 -307.20303)
			(xy 390.57909 -307.157754) (xy 390.605393 -307.116158) (xy 390.638028 -307.079321) (xy 390.676149 -307.048196)
			(xy 390.71877 -307.023589) (xy 390.764786 -307.006137) (xy 390.813005 -306.996293) (xy 390.86218 -306.994312)
			(xy 390.911035 -307.000244) (xy 390.958306 -307.013936) (xy 391.002768 -307.035034) (xy 391.043271 -307.06299)
			(xy 391.078764 -307.097082) (xy 391.108329 -307.136426) (xy 391.1312 -307.180003) (xy 391.146784 -307.226684)
			(xy 391.154679 -307.275261) (xy 391.155174 -307.299868) (xy 391.154679 -307.324475) (xy 391.146784 -307.373052)
			(xy 391.1312 -307.419733) (xy 391.108329 -307.46331) (xy 391.078764 -307.502654) (xy 391.043271 -307.536746)
			(xy 391.002768 -307.564702) (xy 390.958306 -307.5858) (xy 390.911035 -307.599492) (xy 390.86218 -307.605424)
			(xy 390.813005 -307.603443) (xy 390.764786 -307.593599) (xy 390.71877 -307.576147) (xy 390.676149 -307.55154)
			(xy 390.638028 -307.520415) (xy 390.605393 -307.483578) (xy 390.57909 -307.441982) (xy 390.559799 -307.396706)
			(xy 390.548022 -307.348922) (xy 390.544062 -307.299868) (xy 390.205214 -307.299868) (xy 390.204719 -307.324475)
			(xy 390.196824 -307.373052) (xy 390.18124 -307.419733) (xy 390.158369 -307.46331) (xy 390.128804 -307.502654)
			(xy 390.093311 -307.536746) (xy 390.052808 -307.564702) (xy 390.008346 -307.5858) (xy 389.961075 -307.599492)
			(xy 389.91222 -307.605424) (xy 389.863045 -307.603443) (xy 389.814826 -307.593599) (xy 389.76881 -307.576147)
			(xy 389.726189 -307.55154) (xy 389.688068 -307.520415) (xy 389.655433 -307.483578) (xy 389.62913 -307.441982)
			(xy 389.609839 -307.396706) (xy 389.598062 -307.348922) (xy 389.594102 -307.299868) (xy 388.305294 -307.299868)
			(xy 388.304799 -307.324475) (xy 388.296904 -307.373052) (xy 388.28132 -307.419733) (xy 388.258449 -307.46331)
			(xy 388.228884 -307.502654) (xy 388.193391 -307.536746) (xy 388.152888 -307.564702) (xy 388.108426 -307.5858)
			(xy 388.061155 -307.599492) (xy 388.0123 -307.605424) (xy 387.963125 -307.603443) (xy 387.914906 -307.593599)
			(xy 387.86889 -307.576147) (xy 387.826269 -307.55154) (xy 387.788148 -307.520415) (xy 387.755513 -307.483578)
			(xy 387.72921 -307.441982) (xy 387.709919 -307.396706) (xy 387.698142 -307.348922) (xy 387.694182 -307.299868)
			(xy 387.355334 -307.299868) (xy 387.354839 -307.324475) (xy 387.346944 -307.373052) (xy 387.33136 -307.419733)
			(xy 387.308489 -307.46331) (xy 387.278924 -307.502654) (xy 387.243431 -307.536746) (xy 387.202928 -307.564702)
			(xy 387.158466 -307.5858) (xy 387.111195 -307.599492) (xy 387.06234 -307.605424) (xy 387.013165 -307.603443)
			(xy 386.964946 -307.593599) (xy 386.91893 -307.576147) (xy 386.876309 -307.55154) (xy 386.838188 -307.520415)
			(xy 386.805553 -307.483578) (xy 386.77925 -307.441982) (xy 386.759959 -307.396706) (xy 386.748182 -307.348922)
			(xy 386.744222 -307.299868) (xy 313.055 -307.299868) (xy 313.054505 -307.324475) (xy 313.04661 -307.373052)
			(xy 313.031026 -307.419733) (xy 313.008155 -307.46331) (xy 312.97859 -307.502654) (xy 312.943097 -307.536746)
			(xy 312.902594 -307.564702) (xy 312.858132 -307.5858) (xy 312.810861 -307.599492) (xy 312.762006 -307.605424)
			(xy 312.712831 -307.603443) (xy 312.664612 -307.593599) (xy 312.618596 -307.576147) (xy 312.575975 -307.55154)
			(xy 312.537854 -307.520415) (xy 312.505219 -307.483578) (xy 312.478916 -307.441982) (xy 312.459625 -307.396706)
			(xy 312.447848 -307.348922) (xy 312.443888 -307.299868) (xy 312.10504 -307.299868) (xy 312.104545 -307.324475)
			(xy 312.09665 -307.373052) (xy 312.081066 -307.419733) (xy 312.058195 -307.46331) (xy 312.02863 -307.502654)
			(xy 311.993137 -307.536746) (xy 311.952634 -307.564702) (xy 311.908172 -307.5858) (xy 311.860901 -307.599492)
			(xy 311.812046 -307.605424) (xy 311.762871 -307.603443) (xy 311.714652 -307.593599) (xy 311.668636 -307.576147)
			(xy 311.626015 -307.55154) (xy 311.587894 -307.520415) (xy 311.555259 -307.483578) (xy 311.528956 -307.441982)
			(xy 311.509665 -307.396706) (xy 311.497888 -307.348922) (xy 311.493928 -307.299868) (xy 310.20512 -307.299868)
			(xy 310.204625 -307.324475) (xy 310.19673 -307.373052) (xy 310.181146 -307.419733) (xy 310.158275 -307.46331)
			(xy 310.12871 -307.502654) (xy 310.093217 -307.536746) (xy 310.052714 -307.564702) (xy 310.008252 -307.5858)
			(xy 309.960981 -307.599492) (xy 309.912126 -307.605424) (xy 309.862951 -307.603443) (xy 309.814732 -307.593599)
			(xy 309.768716 -307.576147) (xy 309.726095 -307.55154) (xy 309.687974 -307.520415) (xy 309.655339 -307.483578)
			(xy 309.629036 -307.441982) (xy 309.609745 -307.396706) (xy 309.597968 -307.348922) (xy 309.594008 -307.299868)
			(xy 309.25516 -307.299868) (xy 309.254665 -307.324475) (xy 309.24677 -307.373052) (xy 309.231186 -307.419733)
			(xy 309.208315 -307.46331) (xy 309.17875 -307.502654) (xy 309.143257 -307.536746) (xy 309.102754 -307.564702)
			(xy 309.058292 -307.5858) (xy 309.011021 -307.599492) (xy 308.962166 -307.605424) (xy 308.912991 -307.603443)
			(xy 308.864772 -307.593599) (xy 308.818756 -307.576147) (xy 308.776135 -307.55154) (xy 308.738014 -307.520415)
			(xy 308.705379 -307.483578) (xy 308.679076 -307.441982) (xy 308.659785 -307.396706) (xy 308.648008 -307.348922)
			(xy 308.644048 -307.299868) (xy 248.902577 -307.299868) (xy 248.925005 -307.347712) (xy 248.941083 -307.401154)
			(xy 248.949209 -307.456368) (xy 248.949718 -307.484272) (xy 248.949209 -307.512176) (xy 248.941083 -307.56739)
			(xy 248.928951 -307.607716) (xy 462.556604 -307.607716) (xy 462.560677 -307.552057) (xy 462.572812 -307.497584)
			(xy 462.592748 -307.445458) (xy 462.620062 -307.39679) (xy 462.65417 -307.352618) (xy 462.694347 -307.313883)
			(xy 462.739735 -307.281411) (xy 462.789367 -307.255893) (xy 462.842187 -307.237874) (xy 462.897066 -307.227737)
			(xy 462.952837 -307.225699) (xy 463.008311 -307.231802) (xy 463.062304 -307.245918) (xy 463.113667 -307.267745)
			(xy 463.161305 -307.296818) (xy 463.204201 -307.332517) (xy 463.241443 -307.374081) (xy 463.272237 -307.420625)
			(xy 463.295925 -307.471156) (xy 463.312003 -307.524598) (xy 463.320129 -307.579812) (xy 463.320638 -307.607716)
			(xy 463.320129 -307.63562) (xy 463.312003 -307.690834) (xy 463.295925 -307.744276) (xy 463.272237 -307.794807)
			(xy 463.241443 -307.841351) (xy 463.204201 -307.882915) (xy 463.161305 -307.918614) (xy 463.113667 -307.947687)
			(xy 463.062304 -307.969514) (xy 463.008311 -307.98363) (xy 462.952837 -307.989733) (xy 462.897066 -307.987695)
			(xy 462.842187 -307.977558) (xy 462.789367 -307.959539) (xy 462.739735 -307.934021) (xy 462.694347 -307.901549)
			(xy 462.65417 -307.862814) (xy 462.620062 -307.818642) (xy 462.592748 -307.769974) (xy 462.572812 -307.717848)
			(xy 462.560677 -307.663375) (xy 462.556604 -307.607716) (xy 248.928951 -307.607716) (xy 248.925005 -307.620832)
			(xy 248.901317 -307.671363) (xy 248.870523 -307.717907) (xy 248.833281 -307.759471) (xy 248.790385 -307.79517)
			(xy 248.742747 -307.824243) (xy 248.691384 -307.84607) (xy 248.637391 -307.860186) (xy 248.581917 -307.866289)
			(xy 248.526146 -307.864251) (xy 248.471267 -307.854114) (xy 248.418447 -307.836095) (xy 248.368815 -307.810577)
			(xy 248.323427 -307.778105) (xy 248.28325 -307.73937) (xy 248.249142 -307.695198) (xy 248.221828 -307.64653)
			(xy 248.201892 -307.594404) (xy 248.189757 -307.539931) (xy 248.185684 -307.484272) (xy 232.69956 -307.484272)
			(xy 232.699051 -307.512176) (xy 232.690925 -307.56739) (xy 232.674847 -307.620832) (xy 232.651159 -307.671363)
			(xy 232.620365 -307.717907) (xy 232.583123 -307.759471) (xy 232.540227 -307.79517) (xy 232.492589 -307.824243)
			(xy 232.441226 -307.84607) (xy 232.387233 -307.860186) (xy 232.331759 -307.866289) (xy 232.275988 -307.864251)
			(xy 232.221109 -307.854114) (xy 232.168289 -307.836095) (xy 232.118657 -307.810577) (xy 232.073269 -307.778105)
			(xy 232.033092 -307.73937) (xy 231.998984 -307.695198) (xy 231.97167 -307.64653) (xy 231.951734 -307.594404)
			(xy 231.939599 -307.539931) (xy 231.935526 -307.484272) (xy 158.892635 -307.484272) (xy 158.878822 -307.502654)
			(xy 158.843329 -307.536746) (xy 158.802826 -307.564702) (xy 158.758364 -307.5858) (xy 158.711093 -307.599492)
			(xy 158.662238 -307.605424) (xy 158.613063 -307.603443) (xy 158.564844 -307.593599) (xy 158.518828 -307.576147)
			(xy 158.476207 -307.55154) (xy 158.438086 -307.520415) (xy 158.405451 -307.483578) (xy 158.379148 -307.441982)
			(xy 158.359857 -307.396706) (xy 158.34808 -307.348922) (xy 158.34412 -307.299868) (xy 158.005272 -307.299868)
			(xy 158.004777 -307.324475) (xy 157.996882 -307.373052) (xy 157.981298 -307.419733) (xy 157.958427 -307.46331)
			(xy 157.928862 -307.502654) (xy 157.893369 -307.536746) (xy 157.852866 -307.564702) (xy 157.808404 -307.5858)
			(xy 157.761133 -307.599492) (xy 157.712278 -307.605424) (xy 157.663103 -307.603443) (xy 157.614884 -307.593599)
			(xy 157.568868 -307.576147) (xy 157.526247 -307.55154) (xy 157.488126 -307.520415) (xy 157.455491 -307.483578)
			(xy 157.429188 -307.441982) (xy 157.409897 -307.396706) (xy 157.39812 -307.348922) (xy 157.39416 -307.299868)
			(xy 156.105352 -307.299868) (xy 156.104857 -307.324475) (xy 156.096962 -307.373052) (xy 156.081378 -307.419733)
			(xy 156.058507 -307.46331) (xy 156.028942 -307.502654) (xy 155.993449 -307.536746) (xy 155.952946 -307.564702)
			(xy 155.908484 -307.5858) (xy 155.861213 -307.599492) (xy 155.812358 -307.605424) (xy 155.763183 -307.603443)
			(xy 155.714964 -307.593599) (xy 155.668948 -307.576147) (xy 155.626327 -307.55154) (xy 155.588206 -307.520415)
			(xy 155.555571 -307.483578) (xy 155.529268 -307.441982) (xy 155.509977 -307.396706) (xy 155.4982 -307.348922)
			(xy 155.49424 -307.299868) (xy 155.155392 -307.299868) (xy 155.154897 -307.324475) (xy 155.147002 -307.373052)
			(xy 155.131418 -307.419733) (xy 155.108547 -307.46331) (xy 155.078982 -307.502654) (xy 155.043489 -307.536746)
			(xy 155.002986 -307.564702) (xy 154.958524 -307.5858) (xy 154.911253 -307.599492) (xy 154.862398 -307.605424)
			(xy 154.813223 -307.603443) (xy 154.765004 -307.593599) (xy 154.718988 -307.576147) (xy 154.676367 -307.55154)
			(xy 154.638246 -307.520415) (xy 154.605611 -307.483578) (xy 154.579308 -307.441982) (xy 154.560017 -307.396706)
			(xy 154.54824 -307.348922) (xy 154.54428 -307.299868) (xy 80.855058 -307.299868) (xy 80.854563 -307.324475)
			(xy 80.846668 -307.373052) (xy 80.831084 -307.419733) (xy 80.808213 -307.46331) (xy 80.778648 -307.502654)
			(xy 80.743155 -307.536746) (xy 80.702652 -307.564702) (xy 80.65819 -307.5858) (xy 80.610919 -307.599492)
			(xy 80.562064 -307.605424) (xy 80.512889 -307.603443) (xy 80.46467 -307.593599) (xy 80.418654 -307.576147)
			(xy 80.376033 -307.55154) (xy 80.337912 -307.520415) (xy 80.305277 -307.483578) (xy 80.278974 -307.441982)
			(xy 80.259683 -307.396706) (xy 80.247906 -307.348922) (xy 80.243946 -307.299868) (xy 79.905098 -307.299868)
			(xy 79.904603 -307.324475) (xy 79.896708 -307.373052) (xy 79.881124 -307.419733) (xy 79.858253 -307.46331)
			(xy 79.828688 -307.502654) (xy 79.793195 -307.536746) (xy 79.752692 -307.564702) (xy 79.70823 -307.5858)
			(xy 79.660959 -307.599492) (xy 79.612104 -307.605424) (xy 79.562929 -307.603443) (xy 79.51471 -307.593599)
			(xy 79.468694 -307.576147) (xy 79.426073 -307.55154) (xy 79.387952 -307.520415) (xy 79.355317 -307.483578)
			(xy 79.329014 -307.441982) (xy 79.309723 -307.396706) (xy 79.297946 -307.348922) (xy 79.293986 -307.299868)
			(xy 78.005178 -307.299868) (xy 78.004683 -307.324475) (xy 77.996788 -307.373052) (xy 77.981204 -307.419733)
			(xy 77.958333 -307.46331) (xy 77.928768 -307.502654) (xy 77.893275 -307.536746) (xy 77.852772 -307.564702)
			(xy 77.80831 -307.5858) (xy 77.761039 -307.599492) (xy 77.712184 -307.605424) (xy 77.663009 -307.603443)
			(xy 77.61479 -307.593599) (xy 77.568774 -307.576147) (xy 77.526153 -307.55154) (xy 77.488032 -307.520415)
			(xy 77.455397 -307.483578) (xy 77.429094 -307.441982) (xy 77.409803 -307.396706) (xy 77.398026 -307.348922)
			(xy 77.394066 -307.299868) (xy 77.055218 -307.299868) (xy 77.054723 -307.324475) (xy 77.046828 -307.373052)
			(xy 77.031244 -307.419733) (xy 77.008373 -307.46331) (xy 76.978808 -307.502654) (xy 76.943315 -307.536746)
			(xy 76.902812 -307.564702) (xy 76.85835 -307.5858) (xy 76.811079 -307.599492) (xy 76.762224 -307.605424)
			(xy 76.713049 -307.603443) (xy 76.66483 -307.593599) (xy 76.618814 -307.576147) (xy 76.576193 -307.55154)
			(xy 76.538072 -307.520415) (xy 76.505437 -307.483578) (xy 76.479134 -307.441982) (xy 76.459843 -307.396706)
			(xy 76.448066 -307.348922) (xy 76.444106 -307.299868) (xy 0.508 -307.299868) (xy 0.508 -308.249828)
			(xy 74.544186 -308.249828) (xy 74.548146 -308.200774) (xy 74.559923 -308.15299) (xy 74.579214 -308.107714)
			(xy 74.605517 -308.066118) (xy 74.638152 -308.029281) (xy 74.676273 -307.998156) (xy 74.718894 -307.973549)
			(xy 74.76491 -307.956097) (xy 74.813129 -307.946253) (xy 74.862304 -307.944272) (xy 74.911159 -307.950204)
			(xy 74.95843 -307.963896) (xy 75.002892 -307.984994) (xy 75.043395 -308.01295) (xy 75.078888 -308.047042)
			(xy 75.108453 -308.086386) (xy 75.131324 -308.129963) (xy 75.146908 -308.176644) (xy 75.154803 -308.225221)
			(xy 75.155298 -308.249828) (xy 75.494146 -308.249828) (xy 75.498106 -308.200774) (xy 75.509883 -308.15299)
			(xy 75.529174 -308.107714) (xy 75.555477 -308.066118) (xy 75.588112 -308.029281) (xy 75.626233 -307.998156)
			(xy 75.668854 -307.973549) (xy 75.71487 -307.956097) (xy 75.763089 -307.946253) (xy 75.812264 -307.944272)
			(xy 75.861119 -307.950204) (xy 75.90839 -307.963896) (xy 75.952852 -307.984994) (xy 75.993355 -308.01295)
			(xy 76.028848 -308.047042) (xy 76.058413 -308.086386) (xy 76.081284 -308.129963) (xy 76.096868 -308.176644)
			(xy 76.104763 -308.225221) (xy 76.105258 -308.249828) (xy 81.19416 -308.249828) (xy 81.19812 -308.200774)
			(xy 81.209897 -308.15299) (xy 81.229188 -308.107714) (xy 81.255491 -308.066118) (xy 81.288126 -308.029281)
			(xy 81.326247 -307.998156) (xy 81.368868 -307.973549) (xy 81.414884 -307.956097) (xy 81.463103 -307.946253)
			(xy 81.512278 -307.944272) (xy 81.561133 -307.950204) (xy 81.608404 -307.963896) (xy 81.652866 -307.984994)
			(xy 81.693369 -308.01295) (xy 81.728862 -308.047042) (xy 81.758427 -308.086386) (xy 81.781298 -308.129963)
			(xy 81.796882 -308.176644) (xy 81.804777 -308.225221) (xy 81.805272 -308.249828) (xy 82.14412 -308.249828)
			(xy 82.14808 -308.200774) (xy 82.159857 -308.15299) (xy 82.179148 -308.107714) (xy 82.205451 -308.066118)
			(xy 82.238086 -308.029281) (xy 82.276207 -307.998156) (xy 82.318828 -307.973549) (xy 82.364844 -307.956097)
			(xy 82.413063 -307.946253) (xy 82.462238 -307.944272) (xy 82.511093 -307.950204) (xy 82.558364 -307.963896)
			(xy 82.602826 -307.984994) (xy 82.643329 -308.01295) (xy 82.678822 -308.047042) (xy 82.708387 -308.086386)
			(xy 82.731258 -308.129963) (xy 82.746842 -308.176644) (xy 82.754737 -308.225221) (xy 82.755232 -308.249828)
			(xy 152.644106 -308.249828) (xy 152.648066 -308.200774) (xy 152.659843 -308.15299) (xy 152.679134 -308.107714)
			(xy 152.705437 -308.066118) (xy 152.738072 -308.029281) (xy 152.776193 -307.998156) (xy 152.818814 -307.973549)
			(xy 152.86483 -307.956097) (xy 152.913049 -307.946253) (xy 152.962224 -307.944272) (xy 153.011079 -307.950204)
			(xy 153.05835 -307.963896) (xy 153.102812 -307.984994) (xy 153.143315 -308.01295) (xy 153.178808 -308.047042)
			(xy 153.208373 -308.086386) (xy 153.231244 -308.129963) (xy 153.246828 -308.176644) (xy 153.254723 -308.225221)
			(xy 153.255218 -308.249828) (xy 153.594066 -308.249828) (xy 153.598026 -308.200774) (xy 153.609803 -308.15299)
			(xy 153.629094 -308.107714) (xy 153.655397 -308.066118) (xy 153.688032 -308.029281) (xy 153.726153 -307.998156)
			(xy 153.768774 -307.973549) (xy 153.81479 -307.956097) (xy 153.863009 -307.946253) (xy 153.912184 -307.944272)
			(xy 153.961039 -307.950204) (xy 154.00831 -307.963896) (xy 154.052772 -307.984994) (xy 154.093275 -308.01295)
			(xy 154.128768 -308.047042) (xy 154.158333 -308.086386) (xy 154.181204 -308.129963) (xy 154.196788 -308.176644)
			(xy 154.204683 -308.225221) (xy 154.205178 -308.249828) (xy 159.29408 -308.249828) (xy 159.29804 -308.200774)
			(xy 159.309817 -308.15299) (xy 159.329108 -308.107714) (xy 159.355411 -308.066118) (xy 159.388046 -308.029281)
			(xy 159.426167 -307.998156) (xy 159.468788 -307.973549) (xy 159.514804 -307.956097) (xy 159.563023 -307.946253)
			(xy 159.612198 -307.944272) (xy 159.661053 -307.950204) (xy 159.708324 -307.963896) (xy 159.752786 -307.984994)
			(xy 159.793289 -308.01295) (xy 159.828782 -308.047042) (xy 159.858347 -308.086386) (xy 159.881218 -308.129963)
			(xy 159.896802 -308.176644) (xy 159.904697 -308.225221) (xy 159.905192 -308.249828) (xy 160.24404 -308.249828)
			(xy 160.248 -308.200774) (xy 160.259777 -308.15299) (xy 160.279068 -308.107714) (xy 160.305371 -308.066118)
			(xy 160.338006 -308.029281) (xy 160.376127 -307.998156) (xy 160.418748 -307.973549) (xy 160.464764 -307.956097)
			(xy 160.512983 -307.946253) (xy 160.562158 -307.944272) (xy 160.611013 -307.950204) (xy 160.658284 -307.963896)
			(xy 160.702746 -307.984994) (xy 160.743249 -308.01295) (xy 160.778742 -308.047042) (xy 160.808307 -308.086386)
			(xy 160.831178 -308.129963) (xy 160.846762 -308.176644) (xy 160.854657 -308.225221) (xy 160.855152 -308.249828)
			(xy 160.854657 -308.274435) (xy 160.846762 -308.323012) (xy 160.831178 -308.369693) (xy 160.808307 -308.41327)
			(xy 160.778742 -308.452614) (xy 160.743249 -308.486706) (xy 160.702746 -308.514662) (xy 160.658284 -308.53576)
			(xy 160.611013 -308.549452) (xy 160.562158 -308.555384) (xy 160.512983 -308.553403) (xy 160.464764 -308.543559)
			(xy 160.418748 -308.526107) (xy 160.376127 -308.5015) (xy 160.338006 -308.470375) (xy 160.305371 -308.433538)
			(xy 160.279068 -308.391942) (xy 160.259777 -308.346666) (xy 160.248 -308.298882) (xy 160.24404 -308.249828)
			(xy 159.905192 -308.249828) (xy 159.904697 -308.274435) (xy 159.896802 -308.323012) (xy 159.881218 -308.369693)
			(xy 159.858347 -308.41327) (xy 159.828782 -308.452614) (xy 159.793289 -308.486706) (xy 159.752786 -308.514662)
			(xy 159.708324 -308.53576) (xy 159.661053 -308.549452) (xy 159.612198 -308.555384) (xy 159.563023 -308.553403)
			(xy 159.514804 -308.543559) (xy 159.468788 -308.526107) (xy 159.426167 -308.5015) (xy 159.388046 -308.470375)
			(xy 159.355411 -308.433538) (xy 159.329108 -308.391942) (xy 159.309817 -308.346666) (xy 159.29804 -308.298882)
			(xy 159.29408 -308.249828) (xy 154.205178 -308.249828) (xy 154.204683 -308.274435) (xy 154.196788 -308.323012)
			(xy 154.181204 -308.369693) (xy 154.158333 -308.41327) (xy 154.128768 -308.452614) (xy 154.093275 -308.486706)
			(xy 154.052772 -308.514662) (xy 154.00831 -308.53576) (xy 153.961039 -308.549452) (xy 153.912184 -308.555384)
			(xy 153.863009 -308.553403) (xy 153.81479 -308.543559) (xy 153.768774 -308.526107) (xy 153.726153 -308.5015)
			(xy 153.688032 -308.470375) (xy 153.655397 -308.433538) (xy 153.629094 -308.391942) (xy 153.609803 -308.346666)
			(xy 153.598026 -308.298882) (xy 153.594066 -308.249828) (xy 153.255218 -308.249828) (xy 153.254723 -308.274435)
			(xy 153.246828 -308.323012) (xy 153.231244 -308.369693) (xy 153.208373 -308.41327) (xy 153.178808 -308.452614)
			(xy 153.143315 -308.486706) (xy 153.102812 -308.514662) (xy 153.05835 -308.53576) (xy 153.011079 -308.549452)
			(xy 152.962224 -308.555384) (xy 152.913049 -308.553403) (xy 152.86483 -308.543559) (xy 152.818814 -308.526107)
			(xy 152.776193 -308.5015) (xy 152.738072 -308.470375) (xy 152.705437 -308.433538) (xy 152.679134 -308.391942)
			(xy 152.659843 -308.346666) (xy 152.648066 -308.298882) (xy 152.644106 -308.249828) (xy 82.755232 -308.249828)
			(xy 82.754737 -308.274435) (xy 82.746842 -308.323012) (xy 82.731258 -308.369693) (xy 82.708387 -308.41327)
			(xy 82.678822 -308.452614) (xy 82.643329 -308.486706) (xy 82.602826 -308.514662) (xy 82.558364 -308.53576)
			(xy 82.511093 -308.549452) (xy 82.462238 -308.555384) (xy 82.413063 -308.553403) (xy 82.364844 -308.543559)
			(xy 82.318828 -308.526107) (xy 82.276207 -308.5015) (xy 82.238086 -308.470375) (xy 82.205451 -308.433538)
			(xy 82.179148 -308.391942) (xy 82.159857 -308.346666) (xy 82.14808 -308.298882) (xy 82.14412 -308.249828)
			(xy 81.805272 -308.249828) (xy 81.804777 -308.274435) (xy 81.796882 -308.323012) (xy 81.781298 -308.369693)
			(xy 81.758427 -308.41327) (xy 81.728862 -308.452614) (xy 81.693369 -308.486706) (xy 81.652866 -308.514662)
			(xy 81.608404 -308.53576) (xy 81.561133 -308.549452) (xy 81.512278 -308.555384) (xy 81.463103 -308.553403)
			(xy 81.414884 -308.543559) (xy 81.368868 -308.526107) (xy 81.326247 -308.5015) (xy 81.288126 -308.470375)
			(xy 81.255491 -308.433538) (xy 81.229188 -308.391942) (xy 81.209897 -308.346666) (xy 81.19812 -308.298882)
			(xy 81.19416 -308.249828) (xy 76.105258 -308.249828) (xy 76.104763 -308.274435) (xy 76.096868 -308.323012)
			(xy 76.081284 -308.369693) (xy 76.058413 -308.41327) (xy 76.028848 -308.452614) (xy 75.993355 -308.486706)
			(xy 75.952852 -308.514662) (xy 75.90839 -308.53576) (xy 75.861119 -308.549452) (xy 75.812264 -308.555384)
			(xy 75.763089 -308.553403) (xy 75.71487 -308.543559) (xy 75.668854 -308.526107) (xy 75.626233 -308.5015)
			(xy 75.588112 -308.470375) (xy 75.555477 -308.433538) (xy 75.529174 -308.391942) (xy 75.509883 -308.346666)
			(xy 75.498106 -308.298882) (xy 75.494146 -308.249828) (xy 75.155298 -308.249828) (xy 75.154803 -308.274435)
			(xy 75.146908 -308.323012) (xy 75.131324 -308.369693) (xy 75.108453 -308.41327) (xy 75.078888 -308.452614)
			(xy 75.043395 -308.486706) (xy 75.002892 -308.514662) (xy 74.95843 -308.53576) (xy 74.911159 -308.549452)
			(xy 74.862304 -308.555384) (xy 74.813129 -308.553403) (xy 74.76491 -308.543559) (xy 74.718894 -308.526107)
			(xy 74.676273 -308.5015) (xy 74.638152 -308.470375) (xy 74.605517 -308.433538) (xy 74.579214 -308.391942)
			(xy 74.559923 -308.346666) (xy 74.548146 -308.298882) (xy 74.544186 -308.249828) (xy 0.508 -308.249828)
			(xy 0.508 -308.568852) (xy 231.935526 -308.568852) (xy 231.939599 -308.513193) (xy 231.951734 -308.45872)
			(xy 231.97167 -308.406594) (xy 231.998984 -308.357926) (xy 232.033092 -308.313754) (xy 232.073269 -308.275019)
			(xy 232.118657 -308.242547) (xy 232.168289 -308.217029) (xy 232.221109 -308.19901) (xy 232.275988 -308.188873)
			(xy 232.331759 -308.186835) (xy 232.387233 -308.192938) (xy 232.441226 -308.207054) (xy 232.492589 -308.228881)
			(xy 232.540227 -308.257954) (xy 232.583123 -308.293653) (xy 232.620365 -308.335217) (xy 232.651159 -308.381761)
			(xy 232.674847 -308.432292) (xy 232.690925 -308.485734) (xy 232.699051 -308.540948) (xy 232.69956 -308.568852)
			(xy 248.185684 -308.568852) (xy 248.189757 -308.513193) (xy 248.201892 -308.45872) (xy 248.221828 -308.406594)
			(xy 248.249142 -308.357926) (xy 248.28325 -308.313754) (xy 248.323427 -308.275019) (xy 248.368815 -308.242547)
			(xy 248.418447 -308.217029) (xy 248.471267 -308.19901) (xy 248.526146 -308.188873) (xy 248.581917 -308.186835)
			(xy 248.637391 -308.192938) (xy 248.691384 -308.207054) (xy 248.742747 -308.228881) (xy 248.77707 -308.249828)
			(xy 306.744128 -308.249828) (xy 306.748088 -308.200774) (xy 306.759865 -308.15299) (xy 306.779156 -308.107714)
			(xy 306.805459 -308.066118) (xy 306.838094 -308.029281) (xy 306.876215 -307.998156) (xy 306.918836 -307.973549)
			(xy 306.964852 -307.956097) (xy 307.013071 -307.946253) (xy 307.062246 -307.944272) (xy 307.111101 -307.950204)
			(xy 307.158372 -307.963896) (xy 307.202834 -307.984994) (xy 307.243337 -308.01295) (xy 307.27883 -308.047042)
			(xy 307.308395 -308.086386) (xy 307.331266 -308.129963) (xy 307.34685 -308.176644) (xy 307.354745 -308.225221)
			(xy 307.35524 -308.249828) (xy 307.694088 -308.249828) (xy 307.698048 -308.200774) (xy 307.709825 -308.15299)
			(xy 307.729116 -308.107714) (xy 307.755419 -308.066118) (xy 307.788054 -308.029281) (xy 307.826175 -307.998156)
			(xy 307.868796 -307.973549) (xy 307.914812 -307.956097) (xy 307.963031 -307.946253) (xy 308.012206 -307.944272)
			(xy 308.061061 -307.950204) (xy 308.108332 -307.963896) (xy 308.152794 -307.984994) (xy 308.193297 -308.01295)
			(xy 308.22879 -308.047042) (xy 308.258355 -308.086386) (xy 308.281226 -308.129963) (xy 308.29681 -308.176644)
			(xy 308.304705 -308.225221) (xy 308.3052 -308.249828) (xy 313.394102 -308.249828) (xy 313.398062 -308.200774)
			(xy 313.409839 -308.15299) (xy 313.42913 -308.107714) (xy 313.455433 -308.066118) (xy 313.488068 -308.029281)
			(xy 313.526189 -307.998156) (xy 313.56881 -307.973549) (xy 313.614826 -307.956097) (xy 313.663045 -307.946253)
			(xy 313.71222 -307.944272) (xy 313.761075 -307.950204) (xy 313.808346 -307.963896) (xy 313.852808 -307.984994)
			(xy 313.893311 -308.01295) (xy 313.928804 -308.047042) (xy 313.958369 -308.086386) (xy 313.98124 -308.129963)
			(xy 313.996824 -308.176644) (xy 314.004719 -308.225221) (xy 314.005214 -308.249828) (xy 314.344062 -308.249828)
			(xy 314.348022 -308.200774) (xy 314.359799 -308.15299) (xy 314.37909 -308.107714) (xy 314.405393 -308.066118)
			(xy 314.438028 -308.029281) (xy 314.476149 -307.998156) (xy 314.51877 -307.973549) (xy 314.564786 -307.956097)
			(xy 314.613005 -307.946253) (xy 314.66218 -307.944272) (xy 314.711035 -307.950204) (xy 314.758306 -307.963896)
			(xy 314.802768 -307.984994) (xy 314.843271 -308.01295) (xy 314.878764 -308.047042) (xy 314.908329 -308.086386)
			(xy 314.9312 -308.129963) (xy 314.946784 -308.176644) (xy 314.954679 -308.225221) (xy 314.955174 -308.249828)
			(xy 384.844048 -308.249828) (xy 384.848008 -308.200774) (xy 384.859785 -308.15299) (xy 384.879076 -308.107714)
			(xy 384.905379 -308.066118) (xy 384.938014 -308.029281) (xy 384.976135 -307.998156) (xy 385.018756 -307.973549)
			(xy 385.064772 -307.956097) (xy 385.112991 -307.946253) (xy 385.162166 -307.944272) (xy 385.211021 -307.950204)
			(xy 385.258292 -307.963896) (xy 385.302754 -307.984994) (xy 385.343257 -308.01295) (xy 385.37875 -308.047042)
			(xy 385.408315 -308.086386) (xy 385.431186 -308.129963) (xy 385.44677 -308.176644) (xy 385.454665 -308.225221)
			(xy 385.45516 -308.249828) (xy 385.794008 -308.249828) (xy 385.797968 -308.200774) (xy 385.809745 -308.15299)
			(xy 385.829036 -308.107714) (xy 385.855339 -308.066118) (xy 385.887974 -308.029281) (xy 385.926095 -307.998156)
			(xy 385.968716 -307.973549) (xy 386.014732 -307.956097) (xy 386.062951 -307.946253) (xy 386.112126 -307.944272)
			(xy 386.160981 -307.950204) (xy 386.208252 -307.963896) (xy 386.252714 -307.984994) (xy 386.293217 -308.01295)
			(xy 386.32871 -308.047042) (xy 386.358275 -308.086386) (xy 386.381146 -308.129963) (xy 386.39673 -308.176644)
			(xy 386.404625 -308.225221) (xy 386.40512 -308.249828) (xy 391.494022 -308.249828) (xy 391.497982 -308.200774)
			(xy 391.509759 -308.15299) (xy 391.52905 -308.107714) (xy 391.555353 -308.066118) (xy 391.587988 -308.029281)
			(xy 391.626109 -307.998156) (xy 391.66873 -307.973549) (xy 391.714746 -307.956097) (xy 391.762965 -307.946253)
			(xy 391.81214 -307.944272) (xy 391.860995 -307.950204) (xy 391.908266 -307.963896) (xy 391.952728 -307.984994)
			(xy 391.993231 -308.01295) (xy 392.028724 -308.047042) (xy 392.058289 -308.086386) (xy 392.08116 -308.129963)
			(xy 392.096744 -308.176644) (xy 392.104639 -308.225221) (xy 392.105134 -308.249828) (xy 392.443982 -308.249828)
			(xy 392.447942 -308.200774) (xy 392.459719 -308.15299) (xy 392.47901 -308.107714) (xy 392.505313 -308.066118)
			(xy 392.537948 -308.029281) (xy 392.576069 -307.998156) (xy 392.61869 -307.973549) (xy 392.664706 -307.956097)
			(xy 392.712925 -307.946253) (xy 392.7621 -307.944272) (xy 392.810955 -307.950204) (xy 392.858226 -307.963896)
			(xy 392.902688 -307.984994) (xy 392.943191 -308.01295) (xy 392.978684 -308.047042) (xy 393.008249 -308.086386)
			(xy 393.03112 -308.129963) (xy 393.046704 -308.176644) (xy 393.054599 -308.225221) (xy 393.055094 -308.249828)
			(xy 393.054599 -308.274435) (xy 393.046704 -308.323012) (xy 393.03112 -308.369693) (xy 393.008249 -308.41327)
			(xy 392.978684 -308.452614) (xy 392.943191 -308.486706) (xy 392.902688 -308.514662) (xy 392.858226 -308.53576)
			(xy 392.810955 -308.549452) (xy 392.7621 -308.555384) (xy 392.712925 -308.553403) (xy 392.664706 -308.543559)
			(xy 392.61869 -308.526107) (xy 392.576069 -308.5015) (xy 392.537948 -308.470375) (xy 392.505313 -308.433538)
			(xy 392.47901 -308.391942) (xy 392.459719 -308.346666) (xy 392.447942 -308.298882) (xy 392.443982 -308.249828)
			(xy 392.105134 -308.249828) (xy 392.104639 -308.274435) (xy 392.096744 -308.323012) (xy 392.08116 -308.369693)
			(xy 392.058289 -308.41327) (xy 392.028724 -308.452614) (xy 391.993231 -308.486706) (xy 391.952728 -308.514662)
			(xy 391.908266 -308.53576) (xy 391.860995 -308.549452) (xy 391.81214 -308.555384) (xy 391.762965 -308.553403)
			(xy 391.714746 -308.543559) (xy 391.66873 -308.526107) (xy 391.626109 -308.5015) (xy 391.587988 -308.470375)
			(xy 391.555353 -308.433538) (xy 391.52905 -308.391942) (xy 391.509759 -308.346666) (xy 391.497982 -308.298882)
			(xy 391.494022 -308.249828) (xy 386.40512 -308.249828) (xy 386.404625 -308.274435) (xy 386.39673 -308.323012)
			(xy 386.381146 -308.369693) (xy 386.358275 -308.41327) (xy 386.32871 -308.452614) (xy 386.293217 -308.486706)
			(xy 386.252714 -308.514662) (xy 386.208252 -308.53576) (xy 386.160981 -308.549452) (xy 386.112126 -308.555384)
			(xy 386.062951 -308.553403) (xy 386.014732 -308.543559) (xy 385.968716 -308.526107) (xy 385.926095 -308.5015)
			(xy 385.887974 -308.470375) (xy 385.855339 -308.433538) (xy 385.829036 -308.391942) (xy 385.809745 -308.346666)
			(xy 385.797968 -308.298882) (xy 385.794008 -308.249828) (xy 385.45516 -308.249828) (xy 385.454665 -308.274435)
			(xy 385.44677 -308.323012) (xy 385.431186 -308.369693) (xy 385.408315 -308.41327) (xy 385.37875 -308.452614)
			(xy 385.343257 -308.486706) (xy 385.302754 -308.514662) (xy 385.258292 -308.53576) (xy 385.211021 -308.549452)
			(xy 385.162166 -308.555384) (xy 385.112991 -308.553403) (xy 385.064772 -308.543559) (xy 385.018756 -308.526107)
			(xy 384.976135 -308.5015) (xy 384.938014 -308.470375) (xy 384.905379 -308.433538) (xy 384.879076 -308.391942)
			(xy 384.859785 -308.346666) (xy 384.848008 -308.298882) (xy 384.844048 -308.249828) (xy 314.955174 -308.249828)
			(xy 314.954679 -308.274435) (xy 314.946784 -308.323012) (xy 314.9312 -308.369693) (xy 314.908329 -308.41327)
			(xy 314.878764 -308.452614) (xy 314.843271 -308.486706) (xy 314.802768 -308.514662) (xy 314.758306 -308.53576)
			(xy 314.711035 -308.549452) (xy 314.66218 -308.555384) (xy 314.613005 -308.553403) (xy 314.564786 -308.543559)
			(xy 314.51877 -308.526107) (xy 314.476149 -308.5015) (xy 314.438028 -308.470375) (xy 314.405393 -308.433538)
			(xy 314.37909 -308.391942) (xy 314.359799 -308.346666) (xy 314.348022 -308.298882) (xy 314.344062 -308.249828)
			(xy 314.005214 -308.249828) (xy 314.004719 -308.274435) (xy 313.996824 -308.323012) (xy 313.98124 -308.369693)
			(xy 313.958369 -308.41327) (xy 313.928804 -308.452614) (xy 313.893311 -308.486706) (xy 313.852808 -308.514662)
			(xy 313.808346 -308.53576) (xy 313.761075 -308.549452) (xy 313.71222 -308.555384) (xy 313.663045 -308.553403)
			(xy 313.614826 -308.543559) (xy 313.56881 -308.526107) (xy 313.526189 -308.5015) (xy 313.488068 -308.470375)
			(xy 313.455433 -308.433538) (xy 313.42913 -308.391942) (xy 313.409839 -308.346666) (xy 313.398062 -308.298882)
			(xy 313.394102 -308.249828) (xy 308.3052 -308.249828) (xy 308.304705 -308.274435) (xy 308.29681 -308.323012)
			(xy 308.281226 -308.369693) (xy 308.258355 -308.41327) (xy 308.22879 -308.452614) (xy 308.193297 -308.486706)
			(xy 308.152794 -308.514662) (xy 308.108332 -308.53576) (xy 308.061061 -308.549452) (xy 308.012206 -308.555384)
			(xy 307.963031 -308.553403) (xy 307.914812 -308.543559) (xy 307.868796 -308.526107) (xy 307.826175 -308.5015)
			(xy 307.788054 -308.470375) (xy 307.755419 -308.433538) (xy 307.729116 -308.391942) (xy 307.709825 -308.346666)
			(xy 307.698048 -308.298882) (xy 307.694088 -308.249828) (xy 307.35524 -308.249828) (xy 307.354745 -308.274435)
			(xy 307.34685 -308.323012) (xy 307.331266 -308.369693) (xy 307.308395 -308.41327) (xy 307.27883 -308.452614)
			(xy 307.243337 -308.486706) (xy 307.202834 -308.514662) (xy 307.158372 -308.53576) (xy 307.111101 -308.549452)
			(xy 307.062246 -308.555384) (xy 307.013071 -308.553403) (xy 306.964852 -308.543559) (xy 306.918836 -308.526107)
			(xy 306.876215 -308.5015) (xy 306.838094 -308.470375) (xy 306.805459 -308.433538) (xy 306.779156 -308.391942)
			(xy 306.759865 -308.346666) (xy 306.748088 -308.298882) (xy 306.744128 -308.249828) (xy 248.77707 -308.249828)
			(xy 248.790385 -308.257954) (xy 248.833281 -308.293653) (xy 248.870523 -308.335217) (xy 248.901317 -308.381761)
			(xy 248.925005 -308.432292) (xy 248.941083 -308.485734) (xy 248.949209 -308.540948) (xy 248.949718 -308.568852)
			(xy 248.949209 -308.596756) (xy 248.941083 -308.65197) (xy 248.928951 -308.692296) (xy 462.556604 -308.692296)
			(xy 462.560677 -308.636637) (xy 462.572812 -308.582164) (xy 462.592748 -308.530038) (xy 462.620062 -308.48137)
			(xy 462.65417 -308.437198) (xy 462.694347 -308.398463) (xy 462.739735 -308.365991) (xy 462.789367 -308.340473)
			(xy 462.842187 -308.322454) (xy 462.897066 -308.312317) (xy 462.952837 -308.310279) (xy 463.008311 -308.316382)
			(xy 463.062304 -308.330498) (xy 463.113667 -308.352325) (xy 463.161305 -308.381398) (xy 463.204201 -308.417097)
			(xy 463.241443 -308.458661) (xy 463.272237 -308.505205) (xy 463.295925 -308.555736) (xy 463.312003 -308.609178)
			(xy 463.320129 -308.664392) (xy 463.320638 -308.692296) (xy 463.320129 -308.7202) (xy 463.312003 -308.775414)
			(xy 463.295925 -308.828856) (xy 463.272237 -308.879387) (xy 463.241443 -308.925931) (xy 463.204201 -308.967495)
			(xy 463.161305 -309.003194) (xy 463.113667 -309.032267) (xy 463.062304 -309.054094) (xy 463.008311 -309.06821)
			(xy 462.952837 -309.074313) (xy 462.897066 -309.072275) (xy 462.842187 -309.062138) (xy 462.789367 -309.044119)
			(xy 462.739735 -309.018601) (xy 462.694347 -308.986129) (xy 462.65417 -308.947394) (xy 462.620062 -308.903222)
			(xy 462.592748 -308.854554) (xy 462.572812 -308.802428) (xy 462.560677 -308.747955) (xy 462.556604 -308.692296)
			(xy 248.928951 -308.692296) (xy 248.925005 -308.705412) (xy 248.901317 -308.755943) (xy 248.870523 -308.802487)
			(xy 248.833281 -308.844051) (xy 248.790385 -308.87975) (xy 248.742747 -308.908823) (xy 248.691384 -308.93065)
			(xy 248.637391 -308.944766) (xy 248.581917 -308.950869) (xy 248.526146 -308.948831) (xy 248.471267 -308.938694)
			(xy 248.418447 -308.920675) (xy 248.368815 -308.895157) (xy 248.323427 -308.862685) (xy 248.28325 -308.82395)
			(xy 248.249142 -308.779778) (xy 248.221828 -308.73111) (xy 248.201892 -308.678984) (xy 248.189757 -308.624511)
			(xy 248.185684 -308.568852) (xy 232.69956 -308.568852) (xy 232.699051 -308.596756) (xy 232.690925 -308.65197)
			(xy 232.674847 -308.705412) (xy 232.651159 -308.755943) (xy 232.620365 -308.802487) (xy 232.583123 -308.844051)
			(xy 232.540227 -308.87975) (xy 232.492589 -308.908823) (xy 232.441226 -308.93065) (xy 232.387233 -308.944766)
			(xy 232.331759 -308.950869) (xy 232.275988 -308.948831) (xy 232.221109 -308.938694) (xy 232.168289 -308.920675)
			(xy 232.118657 -308.895157) (xy 232.073269 -308.862685) (xy 232.033092 -308.82395) (xy 231.998984 -308.779778)
			(xy 231.97167 -308.73111) (xy 231.951734 -308.678984) (xy 231.939599 -308.624511) (xy 231.935526 -308.568852)
			(xy 0.508 -308.568852) (xy 0.508 -309.199788) (xy 76.444106 -309.199788) (xy 76.448066 -309.150734)
			(xy 76.459843 -309.10295) (xy 76.479134 -309.057674) (xy 76.505437 -309.016078) (xy 76.538072 -308.979241)
			(xy 76.576193 -308.948116) (xy 76.618814 -308.923509) (xy 76.66483 -308.906057) (xy 76.713049 -308.896213)
			(xy 76.762224 -308.894232) (xy 76.811079 -308.900164) (xy 76.85835 -308.913856) (xy 76.902812 -308.934954)
			(xy 76.943315 -308.96291) (xy 76.978808 -308.997002) (xy 77.008373 -309.036346) (xy 77.031244 -309.079923)
			(xy 77.046828 -309.126604) (xy 77.054723 -309.175181) (xy 77.055218 -309.199788) (xy 77.394066 -309.199788)
			(xy 77.398026 -309.150734) (xy 77.409803 -309.10295) (xy 77.429094 -309.057674) (xy 77.455397 -309.016078)
			(xy 77.488032 -308.979241) (xy 77.526153 -308.948116) (xy 77.568774 -308.923509) (xy 77.61479 -308.906057)
			(xy 77.663009 -308.896213) (xy 77.712184 -308.894232) (xy 77.761039 -308.900164) (xy 77.80831 -308.913856)
			(xy 77.852772 -308.934954) (xy 77.893275 -308.96291) (xy 77.928768 -308.997002) (xy 77.958333 -309.036346)
			(xy 77.981204 -309.079923) (xy 77.996788 -309.126604) (xy 78.004683 -309.175181) (xy 78.005178 -309.199788)
			(xy 79.293986 -309.199788) (xy 79.297946 -309.150734) (xy 79.309723 -309.10295) (xy 79.329014 -309.057674)
			(xy 79.355317 -309.016078) (xy 79.387952 -308.979241) (xy 79.426073 -308.948116) (xy 79.468694 -308.923509)
			(xy 79.51471 -308.906057) (xy 79.562929 -308.896213) (xy 79.612104 -308.894232) (xy 79.660959 -308.900164)
			(xy 79.70823 -308.913856) (xy 79.752692 -308.934954) (xy 79.793195 -308.96291) (xy 79.828688 -308.997002)
			(xy 79.858253 -309.036346) (xy 79.881124 -309.079923) (xy 79.896708 -309.126604) (xy 79.904603 -309.175181)
			(xy 79.905098 -309.199788) (xy 80.243946 -309.199788) (xy 80.247906 -309.150734) (xy 80.259683 -309.10295)
			(xy 80.278974 -309.057674) (xy 80.305277 -309.016078) (xy 80.337912 -308.979241) (xy 80.376033 -308.948116)
			(xy 80.418654 -308.923509) (xy 80.46467 -308.906057) (xy 80.512889 -308.896213) (xy 80.562064 -308.894232)
			(xy 80.610919 -308.900164) (xy 80.65819 -308.913856) (xy 80.702652 -308.934954) (xy 80.743155 -308.96291)
			(xy 80.778648 -308.997002) (xy 80.808213 -309.036346) (xy 80.831084 -309.079923) (xy 80.846668 -309.126604)
			(xy 80.854563 -309.175181) (xy 80.855058 -309.199788) (xy 154.54428 -309.199788) (xy 154.54824 -309.150734)
			(xy 154.560017 -309.10295) (xy 154.579308 -309.057674) (xy 154.605611 -309.016078) (xy 154.638246 -308.979241)
			(xy 154.676367 -308.948116) (xy 154.718988 -308.923509) (xy 154.765004 -308.906057) (xy 154.813223 -308.896213)
			(xy 154.862398 -308.894232) (xy 154.911253 -308.900164) (xy 154.958524 -308.913856) (xy 155.002986 -308.934954)
			(xy 155.043489 -308.96291) (xy 155.078982 -308.997002) (xy 155.108547 -309.036346) (xy 155.131418 -309.079923)
			(xy 155.147002 -309.126604) (xy 155.154897 -309.175181) (xy 155.155392 -309.199788) (xy 155.49424 -309.199788)
			(xy 155.4982 -309.150734) (xy 155.509977 -309.10295) (xy 155.529268 -309.057674) (xy 155.555571 -309.016078)
			(xy 155.588206 -308.979241) (xy 155.626327 -308.948116) (xy 155.668948 -308.923509) (xy 155.714964 -308.906057)
			(xy 155.763183 -308.896213) (xy 155.812358 -308.894232) (xy 155.861213 -308.900164) (xy 155.908484 -308.913856)
			(xy 155.952946 -308.934954) (xy 155.993449 -308.96291) (xy 156.028942 -308.997002) (xy 156.058507 -309.036346)
			(xy 156.081378 -309.079923) (xy 156.096962 -309.126604) (xy 156.104857 -309.175181) (xy 156.105352 -309.199788)
			(xy 157.39416 -309.199788) (xy 157.39812 -309.150734) (xy 157.409897 -309.10295) (xy 157.429188 -309.057674)
			(xy 157.455491 -309.016078) (xy 157.488126 -308.979241) (xy 157.526247 -308.948116) (xy 157.568868 -308.923509)
			(xy 157.614884 -308.906057) (xy 157.663103 -308.896213) (xy 157.712278 -308.894232) (xy 157.761133 -308.900164)
			(xy 157.808404 -308.913856) (xy 157.852866 -308.934954) (xy 157.893369 -308.96291) (xy 157.928862 -308.997002)
			(xy 157.958427 -309.036346) (xy 157.981298 -309.079923) (xy 157.996882 -309.126604) (xy 158.004777 -309.175181)
			(xy 158.005272 -309.199788) (xy 158.34412 -309.199788) (xy 158.34808 -309.150734) (xy 158.359857 -309.10295)
			(xy 158.379148 -309.057674) (xy 158.405451 -309.016078) (xy 158.438086 -308.979241) (xy 158.476207 -308.948116)
			(xy 158.518828 -308.923509) (xy 158.564844 -308.906057) (xy 158.613063 -308.896213) (xy 158.662238 -308.894232)
			(xy 158.711093 -308.900164) (xy 158.758364 -308.913856) (xy 158.802826 -308.934954) (xy 158.843329 -308.96291)
			(xy 158.878822 -308.997002) (xy 158.908387 -309.036346) (xy 158.931258 -309.079923) (xy 158.946842 -309.126604)
			(xy 158.954737 -309.175181) (xy 158.955232 -309.199788) (xy 308.644048 -309.199788) (xy 308.648008 -309.150734)
			(xy 308.659785 -309.10295) (xy 308.679076 -309.057674) (xy 308.705379 -309.016078) (xy 308.738014 -308.979241)
			(xy 308.776135 -308.948116) (xy 308.818756 -308.923509) (xy 308.864772 -308.906057) (xy 308.912991 -308.896213)
			(xy 308.962166 -308.894232) (xy 309.011021 -308.900164) (xy 309.058292 -308.913856) (xy 309.102754 -308.934954)
			(xy 309.143257 -308.96291) (xy 309.17875 -308.997002) (xy 309.208315 -309.036346) (xy 309.231186 -309.079923)
			(xy 309.24677 -309.126604) (xy 309.254665 -309.175181) (xy 309.25516 -309.199788) (xy 309.594008 -309.199788)
			(xy 309.597968 -309.150734) (xy 309.609745 -309.10295) (xy 309.629036 -309.057674) (xy 309.655339 -309.016078)
			(xy 309.687974 -308.979241) (xy 309.726095 -308.948116) (xy 309.768716 -308.923509) (xy 309.814732 -308.906057)
			(xy 309.862951 -308.896213) (xy 309.912126 -308.894232) (xy 309.960981 -308.900164) (xy 310.008252 -308.913856)
			(xy 310.052714 -308.934954) (xy 310.093217 -308.96291) (xy 310.12871 -308.997002) (xy 310.158275 -309.036346)
			(xy 310.181146 -309.079923) (xy 310.19673 -309.126604) (xy 310.204625 -309.175181) (xy 310.20512 -309.199788)
			(xy 311.493928 -309.199788) (xy 311.497888 -309.150734) (xy 311.509665 -309.10295) (xy 311.528956 -309.057674)
			(xy 311.555259 -309.016078) (xy 311.587894 -308.979241) (xy 311.626015 -308.948116) (xy 311.668636 -308.923509)
			(xy 311.714652 -308.906057) (xy 311.762871 -308.896213) (xy 311.812046 -308.894232) (xy 311.860901 -308.900164)
			(xy 311.908172 -308.913856) (xy 311.952634 -308.934954) (xy 311.993137 -308.96291) (xy 312.02863 -308.997002)
			(xy 312.058195 -309.036346) (xy 312.081066 -309.079923) (xy 312.09665 -309.126604) (xy 312.104545 -309.175181)
			(xy 312.10504 -309.199788) (xy 312.443888 -309.199788) (xy 312.447848 -309.150734) (xy 312.459625 -309.10295)
			(xy 312.478916 -309.057674) (xy 312.505219 -309.016078) (xy 312.537854 -308.979241) (xy 312.575975 -308.948116)
			(xy 312.618596 -308.923509) (xy 312.664612 -308.906057) (xy 312.712831 -308.896213) (xy 312.762006 -308.894232)
			(xy 312.810861 -308.900164) (xy 312.858132 -308.913856) (xy 312.902594 -308.934954) (xy 312.943097 -308.96291)
			(xy 312.97859 -308.997002) (xy 313.008155 -309.036346) (xy 313.031026 -309.079923) (xy 313.04661 -309.126604)
			(xy 313.054505 -309.175181) (xy 313.055 -309.199788) (xy 386.744222 -309.199788) (xy 386.748182 -309.150734)
			(xy 386.759959 -309.10295) (xy 386.77925 -309.057674) (xy 386.805553 -309.016078) (xy 386.838188 -308.979241)
			(xy 386.876309 -308.948116) (xy 386.91893 -308.923509) (xy 386.964946 -308.906057) (xy 387.013165 -308.896213)
			(xy 387.06234 -308.894232) (xy 387.111195 -308.900164) (xy 387.158466 -308.913856) (xy 387.202928 -308.934954)
			(xy 387.243431 -308.96291) (xy 387.278924 -308.997002) (xy 387.308489 -309.036346) (xy 387.33136 -309.079923)
			(xy 387.346944 -309.126604) (xy 387.354839 -309.175181) (xy 387.355334 -309.199788) (xy 387.694182 -309.199788)
			(xy 387.698142 -309.150734) (xy 387.709919 -309.10295) (xy 387.72921 -309.057674) (xy 387.755513 -309.016078)
			(xy 387.788148 -308.979241) (xy 387.826269 -308.948116) (xy 387.86889 -308.923509) (xy 387.914906 -308.906057)
			(xy 387.963125 -308.896213) (xy 388.0123 -308.894232) (xy 388.061155 -308.900164) (xy 388.108426 -308.913856)
			(xy 388.152888 -308.934954) (xy 388.193391 -308.96291) (xy 388.228884 -308.997002) (xy 388.258449 -309.036346)
			(xy 388.28132 -309.079923) (xy 388.296904 -309.126604) (xy 388.304799 -309.175181) (xy 388.305294 -309.199788)
			(xy 389.594102 -309.199788) (xy 389.598062 -309.150734) (xy 389.609839 -309.10295) (xy 389.62913 -309.057674)
			(xy 389.655433 -309.016078) (xy 389.688068 -308.979241) (xy 389.726189 -308.948116) (xy 389.76881 -308.923509)
			(xy 389.814826 -308.906057) (xy 389.863045 -308.896213) (xy 389.91222 -308.894232) (xy 389.961075 -308.900164)
			(xy 390.008346 -308.913856) (xy 390.052808 -308.934954) (xy 390.093311 -308.96291) (xy 390.128804 -308.997002)
			(xy 390.158369 -309.036346) (xy 390.18124 -309.079923) (xy 390.196824 -309.126604) (xy 390.204719 -309.175181)
			(xy 390.205214 -309.199788) (xy 390.544062 -309.199788) (xy 390.548022 -309.150734) (xy 390.559799 -309.10295)
			(xy 390.57909 -309.057674) (xy 390.605393 -309.016078) (xy 390.638028 -308.979241) (xy 390.676149 -308.948116)
			(xy 390.71877 -308.923509) (xy 390.764786 -308.906057) (xy 390.813005 -308.896213) (xy 390.86218 -308.894232)
			(xy 390.911035 -308.900164) (xy 390.958306 -308.913856) (xy 391.002768 -308.934954) (xy 391.043271 -308.96291)
			(xy 391.078764 -308.997002) (xy 391.108329 -309.036346) (xy 391.1312 -309.079923) (xy 391.146784 -309.126604)
			(xy 391.154679 -309.175181) (xy 391.155174 -309.199788) (xy 391.154679 -309.224395) (xy 391.146784 -309.272972)
			(xy 391.1312 -309.319653) (xy 391.108329 -309.36323) (xy 391.078764 -309.402574) (xy 391.043271 -309.436666)
			(xy 391.002768 -309.464622) (xy 390.958306 -309.48572) (xy 390.911035 -309.499412) (xy 390.86218 -309.505344)
			(xy 390.813005 -309.503363) (xy 390.764786 -309.493519) (xy 390.71877 -309.476067) (xy 390.676149 -309.45146)
			(xy 390.638028 -309.420335) (xy 390.605393 -309.383498) (xy 390.57909 -309.341902) (xy 390.559799 -309.296626)
			(xy 390.548022 -309.248842) (xy 390.544062 -309.199788) (xy 390.205214 -309.199788) (xy 390.204719 -309.224395)
			(xy 390.196824 -309.272972) (xy 390.18124 -309.319653) (xy 390.158369 -309.36323) (xy 390.128804 -309.402574)
			(xy 390.093311 -309.436666) (xy 390.052808 -309.464622) (xy 390.008346 -309.48572) (xy 389.961075 -309.499412)
			(xy 389.91222 -309.505344) (xy 389.863045 -309.503363) (xy 389.814826 -309.493519) (xy 389.76881 -309.476067)
			(xy 389.726189 -309.45146) (xy 389.688068 -309.420335) (xy 389.655433 -309.383498) (xy 389.62913 -309.341902)
			(xy 389.609839 -309.296626) (xy 389.598062 -309.248842) (xy 389.594102 -309.199788) (xy 388.305294 -309.199788)
			(xy 388.304799 -309.224395) (xy 388.296904 -309.272972) (xy 388.28132 -309.319653) (xy 388.258449 -309.36323)
			(xy 388.228884 -309.402574) (xy 388.193391 -309.436666) (xy 388.152888 -309.464622) (xy 388.108426 -309.48572)
			(xy 388.061155 -309.499412) (xy 388.0123 -309.505344) (xy 387.963125 -309.503363) (xy 387.914906 -309.493519)
			(xy 387.86889 -309.476067) (xy 387.826269 -309.45146) (xy 387.788148 -309.420335) (xy 387.755513 -309.383498)
			(xy 387.72921 -309.341902) (xy 387.709919 -309.296626) (xy 387.698142 -309.248842) (xy 387.694182 -309.199788)
			(xy 387.355334 -309.199788) (xy 387.354839 -309.224395) (xy 387.346944 -309.272972) (xy 387.33136 -309.319653)
			(xy 387.308489 -309.36323) (xy 387.278924 -309.402574) (xy 387.243431 -309.436666) (xy 387.202928 -309.464622)
			(xy 387.158466 -309.48572) (xy 387.111195 -309.499412) (xy 387.06234 -309.505344) (xy 387.013165 -309.503363)
			(xy 386.964946 -309.493519) (xy 386.91893 -309.476067) (xy 386.876309 -309.45146) (xy 386.838188 -309.420335)
			(xy 386.805553 -309.383498) (xy 386.77925 -309.341902) (xy 386.759959 -309.296626) (xy 386.748182 -309.248842)
			(xy 386.744222 -309.199788) (xy 313.055 -309.199788) (xy 313.054505 -309.224395) (xy 313.04661 -309.272972)
			(xy 313.031026 -309.319653) (xy 313.008155 -309.36323) (xy 312.97859 -309.402574) (xy 312.943097 -309.436666)
			(xy 312.902594 -309.464622) (xy 312.858132 -309.48572) (xy 312.810861 -309.499412) (xy 312.762006 -309.505344)
			(xy 312.712831 -309.503363) (xy 312.664612 -309.493519) (xy 312.618596 -309.476067) (xy 312.575975 -309.45146)
			(xy 312.537854 -309.420335) (xy 312.505219 -309.383498) (xy 312.478916 -309.341902) (xy 312.459625 -309.296626)
			(xy 312.447848 -309.248842) (xy 312.443888 -309.199788) (xy 312.10504 -309.199788) (xy 312.104545 -309.224395)
			(xy 312.09665 -309.272972) (xy 312.081066 -309.319653) (xy 312.058195 -309.36323) (xy 312.02863 -309.402574)
			(xy 311.993137 -309.436666) (xy 311.952634 -309.464622) (xy 311.908172 -309.48572) (xy 311.860901 -309.499412)
			(xy 311.812046 -309.505344) (xy 311.762871 -309.503363) (xy 311.714652 -309.493519) (xy 311.668636 -309.476067)
			(xy 311.626015 -309.45146) (xy 311.587894 -309.420335) (xy 311.555259 -309.383498) (xy 311.528956 -309.341902)
			(xy 311.509665 -309.296626) (xy 311.497888 -309.248842) (xy 311.493928 -309.199788) (xy 310.20512 -309.199788)
			(xy 310.204625 -309.224395) (xy 310.19673 -309.272972) (xy 310.181146 -309.319653) (xy 310.158275 -309.36323)
			(xy 310.12871 -309.402574) (xy 310.093217 -309.436666) (xy 310.052714 -309.464622) (xy 310.008252 -309.48572)
			(xy 309.960981 -309.499412) (xy 309.912126 -309.505344) (xy 309.862951 -309.503363) (xy 309.814732 -309.493519)
			(xy 309.768716 -309.476067) (xy 309.726095 -309.45146) (xy 309.687974 -309.420335) (xy 309.655339 -309.383498)
			(xy 309.629036 -309.341902) (xy 309.609745 -309.296626) (xy 309.597968 -309.248842) (xy 309.594008 -309.199788)
			(xy 309.25516 -309.199788) (xy 309.254665 -309.224395) (xy 309.24677 -309.272972) (xy 309.231186 -309.319653)
			(xy 309.208315 -309.36323) (xy 309.17875 -309.402574) (xy 309.143257 -309.436666) (xy 309.102754 -309.464622)
			(xy 309.058292 -309.48572) (xy 309.011021 -309.499412) (xy 308.962166 -309.505344) (xy 308.912991 -309.503363)
			(xy 308.864772 -309.493519) (xy 308.818756 -309.476067) (xy 308.776135 -309.45146) (xy 308.738014 -309.420335)
			(xy 308.705379 -309.383498) (xy 308.679076 -309.341902) (xy 308.659785 -309.296626) (xy 308.648008 -309.248842)
			(xy 308.644048 -309.199788) (xy 158.955232 -309.199788) (xy 158.954737 -309.224395) (xy 158.946842 -309.272972)
			(xy 158.931258 -309.319653) (xy 158.908387 -309.36323) (xy 158.878822 -309.402574) (xy 158.843329 -309.436666)
			(xy 158.802826 -309.464622) (xy 158.758364 -309.48572) (xy 158.711093 -309.499412) (xy 158.662238 -309.505344)
			(xy 158.613063 -309.503363) (xy 158.564844 -309.493519) (xy 158.518828 -309.476067) (xy 158.476207 -309.45146)
			(xy 158.438086 -309.420335) (xy 158.405451 -309.383498) (xy 158.379148 -309.341902) (xy 158.359857 -309.296626)
			(xy 158.34808 -309.248842) (xy 158.34412 -309.199788) (xy 158.005272 -309.199788) (xy 158.004777 -309.224395)
			(xy 157.996882 -309.272972) (xy 157.981298 -309.319653) (xy 157.958427 -309.36323) (xy 157.928862 -309.402574)
			(xy 157.893369 -309.436666) (xy 157.852866 -309.464622) (xy 157.808404 -309.48572) (xy 157.761133 -309.499412)
			(xy 157.712278 -309.505344) (xy 157.663103 -309.503363) (xy 157.614884 -309.493519) (xy 157.568868 -309.476067)
			(xy 157.526247 -309.45146) (xy 157.488126 -309.420335) (xy 157.455491 -309.383498) (xy 157.429188 -309.341902)
			(xy 157.409897 -309.296626) (xy 157.39812 -309.248842) (xy 157.39416 -309.199788) (xy 156.105352 -309.199788)
			(xy 156.104857 -309.224395) (xy 156.096962 -309.272972) (xy 156.081378 -309.319653) (xy 156.058507 -309.36323)
			(xy 156.028942 -309.402574) (xy 155.993449 -309.436666) (xy 155.952946 -309.464622) (xy 155.908484 -309.48572)
			(xy 155.861213 -309.499412) (xy 155.812358 -309.505344) (xy 155.763183 -309.503363) (xy 155.714964 -309.493519)
			(xy 155.668948 -309.476067) (xy 155.626327 -309.45146) (xy 155.588206 -309.420335) (xy 155.555571 -309.383498)
			(xy 155.529268 -309.341902) (xy 155.509977 -309.296626) (xy 155.4982 -309.248842) (xy 155.49424 -309.199788)
			(xy 155.155392 -309.199788) (xy 155.154897 -309.224395) (xy 155.147002 -309.272972) (xy 155.131418 -309.319653)
			(xy 155.108547 -309.36323) (xy 155.078982 -309.402574) (xy 155.043489 -309.436666) (xy 155.002986 -309.464622)
			(xy 154.958524 -309.48572) (xy 154.911253 -309.499412) (xy 154.862398 -309.505344) (xy 154.813223 -309.503363)
			(xy 154.765004 -309.493519) (xy 154.718988 -309.476067) (xy 154.676367 -309.45146) (xy 154.638246 -309.420335)
			(xy 154.605611 -309.383498) (xy 154.579308 -309.341902) (xy 154.560017 -309.296626) (xy 154.54824 -309.248842)
			(xy 154.54428 -309.199788) (xy 80.855058 -309.199788) (xy 80.854563 -309.224395) (xy 80.846668 -309.272972)
			(xy 80.831084 -309.319653) (xy 80.808213 -309.36323) (xy 80.778648 -309.402574) (xy 80.743155 -309.436666)
			(xy 80.702652 -309.464622) (xy 80.65819 -309.48572) (xy 80.610919 -309.499412) (xy 80.562064 -309.505344)
			(xy 80.512889 -309.503363) (xy 80.46467 -309.493519) (xy 80.418654 -309.476067) (xy 80.376033 -309.45146)
			(xy 80.337912 -309.420335) (xy 80.305277 -309.383498) (xy 80.278974 -309.341902) (xy 80.259683 -309.296626)
			(xy 80.247906 -309.248842) (xy 80.243946 -309.199788) (xy 79.905098 -309.199788) (xy 79.904603 -309.224395)
			(xy 79.896708 -309.272972) (xy 79.881124 -309.319653) (xy 79.858253 -309.36323) (xy 79.828688 -309.402574)
			(xy 79.793195 -309.436666) (xy 79.752692 -309.464622) (xy 79.70823 -309.48572) (xy 79.660959 -309.499412)
			(xy 79.612104 -309.505344) (xy 79.562929 -309.503363) (xy 79.51471 -309.493519) (xy 79.468694 -309.476067)
			(xy 79.426073 -309.45146) (xy 79.387952 -309.420335) (xy 79.355317 -309.383498) (xy 79.329014 -309.341902)
			(xy 79.309723 -309.296626) (xy 79.297946 -309.248842) (xy 79.293986 -309.199788) (xy 78.005178 -309.199788)
			(xy 78.004683 -309.224395) (xy 77.996788 -309.272972) (xy 77.981204 -309.319653) (xy 77.958333 -309.36323)
			(xy 77.928768 -309.402574) (xy 77.893275 -309.436666) (xy 77.852772 -309.464622) (xy 77.80831 -309.48572)
			(xy 77.761039 -309.499412) (xy 77.712184 -309.505344) (xy 77.663009 -309.503363) (xy 77.61479 -309.493519)
			(xy 77.568774 -309.476067) (xy 77.526153 -309.45146) (xy 77.488032 -309.420335) (xy 77.455397 -309.383498)
			(xy 77.429094 -309.341902) (xy 77.409803 -309.296626) (xy 77.398026 -309.248842) (xy 77.394066 -309.199788)
			(xy 77.055218 -309.199788) (xy 77.054723 -309.224395) (xy 77.046828 -309.272972) (xy 77.031244 -309.319653)
			(xy 77.008373 -309.36323) (xy 76.978808 -309.402574) (xy 76.943315 -309.436666) (xy 76.902812 -309.464622)
			(xy 76.85835 -309.48572) (xy 76.811079 -309.499412) (xy 76.762224 -309.505344) (xy 76.713049 -309.503363)
			(xy 76.66483 -309.493519) (xy 76.618814 -309.476067) (xy 76.576193 -309.45146) (xy 76.538072 -309.420335)
			(xy 76.505437 -309.383498) (xy 76.479134 -309.341902) (xy 76.459843 -309.296626) (xy 76.448066 -309.248842)
			(xy 76.444106 -309.199788) (xy 0.508 -309.199788) (xy 0.508 -310.149748) (xy 81.19416 -310.149748)
			(xy 81.19812 -310.100694) (xy 81.209897 -310.05291) (xy 81.229188 -310.007634) (xy 81.255491 -309.966038)
			(xy 81.288126 -309.929201) (xy 81.326247 -309.898076) (xy 81.368868 -309.873469) (xy 81.414884 -309.856017)
			(xy 81.463103 -309.846173) (xy 81.512278 -309.844192) (xy 81.561133 -309.850124) (xy 81.608404 -309.863816)
			(xy 81.652866 -309.884914) (xy 81.693369 -309.91287) (xy 81.728862 -309.946962) (xy 81.758427 -309.986306)
			(xy 81.781298 -310.029883) (xy 81.796882 -310.076564) (xy 81.804777 -310.125141) (xy 81.805272 -310.149748)
			(xy 82.14412 -310.149748) (xy 82.14808 -310.100694) (xy 82.159857 -310.05291) (xy 82.179148 -310.007634)
			(xy 82.205451 -309.966038) (xy 82.238086 -309.929201) (xy 82.276207 -309.898076) (xy 82.318828 -309.873469)
			(xy 82.364844 -309.856017) (xy 82.413063 -309.846173) (xy 82.462238 -309.844192) (xy 82.511093 -309.850124)
			(xy 82.558364 -309.863816) (xy 82.602826 -309.884914) (xy 82.643329 -309.91287) (xy 82.678822 -309.946962)
			(xy 82.708387 -309.986306) (xy 82.731258 -310.029883) (xy 82.746842 -310.076564) (xy 82.754737 -310.125141)
			(xy 82.755232 -310.149748) (xy 152.644106 -310.149748) (xy 152.648066 -310.100694) (xy 152.659843 -310.05291)
			(xy 152.679134 -310.007634) (xy 152.705437 -309.966038) (xy 152.738072 -309.929201) (xy 152.776193 -309.898076)
			(xy 152.818814 -309.873469) (xy 152.86483 -309.856017) (xy 152.913049 -309.846173) (xy 152.962224 -309.844192)
			(xy 153.011079 -309.850124) (xy 153.05835 -309.863816) (xy 153.102812 -309.884914) (xy 153.143315 -309.91287)
			(xy 153.178808 -309.946962) (xy 153.208373 -309.986306) (xy 153.231244 -310.029883) (xy 153.246828 -310.076564)
			(xy 153.254723 -310.125141) (xy 153.255218 -310.149748) (xy 153.594066 -310.149748) (xy 153.598026 -310.100694)
			(xy 153.609803 -310.05291) (xy 153.629094 -310.007634) (xy 153.655397 -309.966038) (xy 153.688032 -309.929201)
			(xy 153.726153 -309.898076) (xy 153.768774 -309.873469) (xy 153.81479 -309.856017) (xy 153.863009 -309.846173)
			(xy 153.912184 -309.844192) (xy 153.961039 -309.850124) (xy 154.00831 -309.863816) (xy 154.052772 -309.884914)
			(xy 154.093275 -309.91287) (xy 154.128768 -309.946962) (xy 154.158333 -309.986306) (xy 154.181204 -310.029883)
			(xy 154.196788 -310.076564) (xy 154.204683 -310.125141) (xy 154.205178 -310.149748) (xy 313.394102 -310.149748)
			(xy 313.398062 -310.100694) (xy 313.409839 -310.05291) (xy 313.42913 -310.007634) (xy 313.455433 -309.966038)
			(xy 313.488068 -309.929201) (xy 313.526189 -309.898076) (xy 313.56881 -309.873469) (xy 313.614826 -309.856017)
			(xy 313.663045 -309.846173) (xy 313.71222 -309.844192) (xy 313.761075 -309.850124) (xy 313.808346 -309.863816)
			(xy 313.852808 -309.884914) (xy 313.893311 -309.91287) (xy 313.928804 -309.946962) (xy 313.958369 -309.986306)
			(xy 313.98124 -310.029883) (xy 313.996824 -310.076564) (xy 314.004719 -310.125141) (xy 314.005214 -310.149748)
			(xy 314.344062 -310.149748) (xy 314.348022 -310.100694) (xy 314.359799 -310.05291) (xy 314.37909 -310.007634)
			(xy 314.405393 -309.966038) (xy 314.438028 -309.929201) (xy 314.476149 -309.898076) (xy 314.51877 -309.873469)
			(xy 314.564786 -309.856017) (xy 314.613005 -309.846173) (xy 314.66218 -309.844192) (xy 314.711035 -309.850124)
			(xy 314.758306 -309.863816) (xy 314.802768 -309.884914) (xy 314.843271 -309.91287) (xy 314.878764 -309.946962)
			(xy 314.908329 -309.986306) (xy 314.9312 -310.029883) (xy 314.946784 -310.076564) (xy 314.954679 -310.125141)
			(xy 314.955174 -310.149748) (xy 384.844048 -310.149748) (xy 384.848008 -310.100694) (xy 384.859785 -310.05291)
			(xy 384.879076 -310.007634) (xy 384.905379 -309.966038) (xy 384.938014 -309.929201) (xy 384.976135 -309.898076)
			(xy 385.018756 -309.873469) (xy 385.064772 -309.856017) (xy 385.112991 -309.846173) (xy 385.162166 -309.844192)
			(xy 385.211021 -309.850124) (xy 385.258292 -309.863816) (xy 385.302754 -309.884914) (xy 385.343257 -309.91287)
			(xy 385.37875 -309.946962) (xy 385.408315 -309.986306) (xy 385.431186 -310.029883) (xy 385.44677 -310.076564)
			(xy 385.454665 -310.125141) (xy 385.45516 -310.149748) (xy 385.794008 -310.149748) (xy 385.797968 -310.100694)
			(xy 385.809745 -310.05291) (xy 385.829036 -310.007634) (xy 385.855339 -309.966038) (xy 385.887974 -309.929201)
			(xy 385.926095 -309.898076) (xy 385.968716 -309.873469) (xy 386.014732 -309.856017) (xy 386.062951 -309.846173)
			(xy 386.112126 -309.844192) (xy 386.160981 -309.850124) (xy 386.208252 -309.863816) (xy 386.252714 -309.884914)
			(xy 386.293217 -309.91287) (xy 386.32871 -309.946962) (xy 386.358275 -309.986306) (xy 386.381146 -310.029883)
			(xy 386.39673 -310.076564) (xy 386.404625 -310.125141) (xy 386.40512 -310.149748) (xy 386.404625 -310.174355)
			(xy 386.39673 -310.222932) (xy 386.381146 -310.269613) (xy 386.358275 -310.31319) (xy 386.32871 -310.352534)
			(xy 386.293217 -310.386626) (xy 386.252714 -310.414582) (xy 386.208252 -310.43568) (xy 386.160981 -310.449372)
			(xy 386.112126 -310.455304) (xy 386.062951 -310.453323) (xy 386.014732 -310.443479) (xy 385.968716 -310.426027)
			(xy 385.926095 -310.40142) (xy 385.887974 -310.370295) (xy 385.855339 -310.333458) (xy 385.829036 -310.291862)
			(xy 385.809745 -310.246586) (xy 385.797968 -310.198802) (xy 385.794008 -310.149748) (xy 385.45516 -310.149748)
			(xy 385.454665 -310.174355) (xy 385.44677 -310.222932) (xy 385.431186 -310.269613) (xy 385.408315 -310.31319)
			(xy 385.37875 -310.352534) (xy 385.343257 -310.386626) (xy 385.302754 -310.414582) (xy 385.258292 -310.43568)
			(xy 385.211021 -310.449372) (xy 385.162166 -310.455304) (xy 385.112991 -310.453323) (xy 385.064772 -310.443479)
			(xy 385.018756 -310.426027) (xy 384.976135 -310.40142) (xy 384.938014 -310.370295) (xy 384.905379 -310.333458)
			(xy 384.879076 -310.291862) (xy 384.859785 -310.246586) (xy 384.848008 -310.198802) (xy 384.844048 -310.149748)
			(xy 314.955174 -310.149748) (xy 314.954679 -310.174355) (xy 314.946784 -310.222932) (xy 314.9312 -310.269613)
			(xy 314.908329 -310.31319) (xy 314.878764 -310.352534) (xy 314.843271 -310.386626) (xy 314.802768 -310.414582)
			(xy 314.758306 -310.43568) (xy 314.711035 -310.449372) (xy 314.66218 -310.455304) (xy 314.613005 -310.453323)
			(xy 314.564786 -310.443479) (xy 314.51877 -310.426027) (xy 314.476149 -310.40142) (xy 314.438028 -310.370295)
			(xy 314.405393 -310.333458) (xy 314.37909 -310.291862) (xy 314.359799 -310.246586) (xy 314.348022 -310.198802)
			(xy 314.344062 -310.149748) (xy 314.005214 -310.149748) (xy 314.004719 -310.174355) (xy 313.996824 -310.222932)
			(xy 313.98124 -310.269613) (xy 313.958369 -310.31319) (xy 313.928804 -310.352534) (xy 313.893311 -310.386626)
			(xy 313.852808 -310.414582) (xy 313.808346 -310.43568) (xy 313.761075 -310.449372) (xy 313.71222 -310.455304)
			(xy 313.663045 -310.453323) (xy 313.614826 -310.443479) (xy 313.56881 -310.426027) (xy 313.526189 -310.40142)
			(xy 313.488068 -310.370295) (xy 313.455433 -310.333458) (xy 313.42913 -310.291862) (xy 313.409839 -310.246586)
			(xy 313.398062 -310.198802) (xy 313.394102 -310.149748) (xy 154.205178 -310.149748) (xy 154.204683 -310.174355)
			(xy 154.196788 -310.222932) (xy 154.181204 -310.269613) (xy 154.158333 -310.31319) (xy 154.128768 -310.352534)
			(xy 154.093275 -310.386626) (xy 154.052772 -310.414582) (xy 154.00831 -310.43568) (xy 153.961039 -310.449372)
			(xy 153.912184 -310.455304) (xy 153.863009 -310.453323) (xy 153.81479 -310.443479) (xy 153.768774 -310.426027)
			(xy 153.726153 -310.40142) (xy 153.688032 -310.370295) (xy 153.655397 -310.333458) (xy 153.629094 -310.291862)
			(xy 153.609803 -310.246586) (xy 153.598026 -310.198802) (xy 153.594066 -310.149748) (xy 153.255218 -310.149748)
			(xy 153.254723 -310.174355) (xy 153.246828 -310.222932) (xy 153.231244 -310.269613) (xy 153.208373 -310.31319)
			(xy 153.178808 -310.352534) (xy 153.143315 -310.386626) (xy 153.102812 -310.414582) (xy 153.05835 -310.43568)
			(xy 153.011079 -310.449372) (xy 152.962224 -310.455304) (xy 152.913049 -310.453323) (xy 152.86483 -310.443479)
			(xy 152.818814 -310.426027) (xy 152.776193 -310.40142) (xy 152.738072 -310.370295) (xy 152.705437 -310.333458)
			(xy 152.679134 -310.291862) (xy 152.659843 -310.246586) (xy 152.648066 -310.198802) (xy 152.644106 -310.149748)
			(xy 82.755232 -310.149748) (xy 82.754737 -310.174355) (xy 82.746842 -310.222932) (xy 82.731258 -310.269613)
			(xy 82.708387 -310.31319) (xy 82.678822 -310.352534) (xy 82.643329 -310.386626) (xy 82.602826 -310.414582)
			(xy 82.558364 -310.43568) (xy 82.511093 -310.449372) (xy 82.462238 -310.455304) (xy 82.413063 -310.453323)
			(xy 82.364844 -310.443479) (xy 82.318828 -310.426027) (xy 82.276207 -310.40142) (xy 82.238086 -310.370295)
			(xy 82.205451 -310.333458) (xy 82.179148 -310.291862) (xy 82.159857 -310.246586) (xy 82.14808 -310.198802)
			(xy 82.14412 -310.149748) (xy 81.805272 -310.149748) (xy 81.804777 -310.174355) (xy 81.796882 -310.222932)
			(xy 81.781298 -310.269613) (xy 81.758427 -310.31319) (xy 81.728862 -310.352534) (xy 81.693369 -310.386626)
			(xy 81.652866 -310.414582) (xy 81.608404 -310.43568) (xy 81.561133 -310.449372) (xy 81.512278 -310.455304)
			(xy 81.463103 -310.453323) (xy 81.414884 -310.443479) (xy 81.368868 -310.426027) (xy 81.326247 -310.40142)
			(xy 81.288126 -310.370295) (xy 81.255491 -310.333458) (xy 81.229188 -310.291862) (xy 81.209897 -310.246586)
			(xy 81.19812 -310.198802) (xy 81.19416 -310.149748) (xy 0.508 -310.149748) (xy 0.508 -311.099962)
			(xy 43.193982 -311.099962) (xy 43.197942 -311.050908) (xy 43.209719 -311.003124) (xy 43.22901 -310.957848)
			(xy 43.255313 -310.916252) (xy 43.287948 -310.879415) (xy 43.326069 -310.84829) (xy 43.36869 -310.823683)
			(xy 43.414706 -310.806231) (xy 43.462925 -310.796387) (xy 43.5121 -310.794406) (xy 43.560955 -310.800338)
			(xy 43.608226 -310.81403) (xy 43.652688 -310.835128) (xy 43.693191 -310.863084) (xy 43.728684 -310.897176)
			(xy 43.758249 -310.93652) (xy 43.78112 -310.980097) (xy 43.796704 -311.026778) (xy 43.804599 -311.075355)
			(xy 43.805094 -311.099962) (xy 45.094156 -311.099962) (xy 45.098116 -311.050908) (xy 45.109893 -311.003124)
			(xy 45.129184 -310.957848) (xy 45.155487 -310.916252) (xy 45.188122 -310.879415) (xy 45.226243 -310.84829)
			(xy 45.268864 -310.823683) (xy 45.31488 -310.806231) (xy 45.363099 -310.796387) (xy 45.412274 -310.794406)
			(xy 45.461129 -310.800338) (xy 45.5084 -310.81403) (xy 45.552862 -310.835128) (xy 45.593365 -310.863084)
			(xy 45.628858 -310.897176) (xy 45.658423 -310.93652) (xy 45.681294 -310.980097) (xy 45.696878 -311.026778)
			(xy 45.704773 -311.075355) (xy 45.705268 -311.099962) (xy 46.994076 -311.099962) (xy 46.998036 -311.050908)
			(xy 47.009813 -311.003124) (xy 47.029104 -310.957848) (xy 47.055407 -310.916252) (xy 47.088042 -310.879415)
			(xy 47.126163 -310.84829) (xy 47.168784 -310.823683) (xy 47.2148 -310.806231) (xy 47.263019 -310.796387)
			(xy 47.312194 -310.794406) (xy 47.361049 -310.800338) (xy 47.40832 -310.81403) (xy 47.452782 -310.835128)
			(xy 47.493285 -310.863084) (xy 47.528778 -310.897176) (xy 47.558343 -310.93652) (xy 47.581214 -310.980097)
			(xy 47.596798 -311.026778) (xy 47.604693 -311.075355) (xy 47.605188 -311.099962) (xy 48.893996 -311.099962)
			(xy 48.897956 -311.050908) (xy 48.909733 -311.003124) (xy 48.929024 -310.957848) (xy 48.955327 -310.916252)
			(xy 48.987962 -310.879415) (xy 49.026083 -310.84829) (xy 49.068704 -310.823683) (xy 49.11472 -310.806231)
			(xy 49.162939 -310.796387) (xy 49.212114 -310.794406) (xy 49.260969 -310.800338) (xy 49.30824 -310.81403)
			(xy 49.352702 -310.835128) (xy 49.393205 -310.863084) (xy 49.428698 -310.897176) (xy 49.458263 -310.93652)
			(xy 49.481134 -310.980097) (xy 49.496718 -311.026778) (xy 49.504613 -311.075355) (xy 49.505108 -311.099962)
			(xy 50.79417 -311.099962) (xy 50.79813 -311.050908) (xy 50.809907 -311.003124) (xy 50.829198 -310.957848)
			(xy 50.855501 -310.916252) (xy 50.888136 -310.879415) (xy 50.926257 -310.84829) (xy 50.968878 -310.823683)
			(xy 51.014894 -310.806231) (xy 51.063113 -310.796387) (xy 51.112288 -310.794406) (xy 51.161143 -310.800338)
			(xy 51.208414 -310.81403) (xy 51.252876 -310.835128) (xy 51.293379 -310.863084) (xy 51.328872 -310.897176)
			(xy 51.358437 -310.93652) (xy 51.381308 -310.980097) (xy 51.396892 -311.026778) (xy 51.404787 -311.075355)
			(xy 51.405282 -311.099962) (xy 52.69409 -311.099962) (xy 52.69805 -311.050908) (xy 52.709827 -311.003124)
			(xy 52.729118 -310.957848) (xy 52.755421 -310.916252) (xy 52.788056 -310.879415) (xy 52.826177 -310.84829)
			(xy 52.868798 -310.823683) (xy 52.914814 -310.806231) (xy 52.963033 -310.796387) (xy 53.012208 -310.794406)
			(xy 53.061063 -310.800338) (xy 53.108334 -310.81403) (xy 53.152796 -310.835128) (xy 53.193299 -310.863084)
			(xy 53.228792 -310.897176) (xy 53.258357 -310.93652) (xy 53.281228 -310.980097) (xy 53.296812 -311.026778)
			(xy 53.304707 -311.075355) (xy 53.305202 -311.099962) (xy 54.59401 -311.099962) (xy 54.59797 -311.050908)
			(xy 54.609747 -311.003124) (xy 54.629038 -310.957848) (xy 54.655341 -310.916252) (xy 54.687976 -310.879415)
			(xy 54.726097 -310.84829) (xy 54.768718 -310.823683) (xy 54.814734 -310.806231) (xy 54.862953 -310.796387)
			(xy 54.912128 -310.794406) (xy 54.960983 -310.800338) (xy 55.008254 -310.81403) (xy 55.052716 -310.835128)
			(xy 55.093219 -310.863084) (xy 55.128712 -310.897176) (xy 55.158277 -310.93652) (xy 55.181148 -310.980097)
			(xy 55.196732 -311.026778) (xy 55.204627 -311.075355) (xy 55.205122 -311.099962) (xy 56.494184 -311.099962)
			(xy 56.498144 -311.050908) (xy 56.509921 -311.003124) (xy 56.529212 -310.957848) (xy 56.555515 -310.916252)
			(xy 56.58815 -310.879415) (xy 56.626271 -310.84829) (xy 56.668892 -310.823683) (xy 56.714908 -310.806231)
			(xy 56.763127 -310.796387) (xy 56.812302 -310.794406) (xy 56.861157 -310.800338) (xy 56.908428 -310.81403)
			(xy 56.95289 -310.835128) (xy 56.993393 -310.863084) (xy 57.028886 -310.897176) (xy 57.058451 -310.93652)
			(xy 57.081322 -310.980097) (xy 57.096906 -311.026778) (xy 57.104801 -311.075355) (xy 57.105296 -311.099962)
			(xy 73.593972 -311.099962) (xy 73.597932 -311.050908) (xy 73.609709 -311.003124) (xy 73.629 -310.957848)
			(xy 73.655303 -310.916252) (xy 73.687938 -310.879415) (xy 73.726059 -310.84829) (xy 73.76868 -310.823683)
			(xy 73.814696 -310.806231) (xy 73.862915 -310.796387) (xy 73.91209 -310.794406) (xy 73.960945 -310.800338)
			(xy 74.008216 -310.81403) (xy 74.052678 -310.835128) (xy 74.093181 -310.863084) (xy 74.128674 -310.897176)
			(xy 74.158239 -310.93652) (xy 74.18111 -310.980097) (xy 74.196694 -311.026778) (xy 74.204589 -311.075355)
			(xy 74.205084 -311.099962) (xy 75.494146 -311.099962) (xy 75.498106 -311.050908) (xy 75.509883 -311.003124)
			(xy 75.529174 -310.957848) (xy 75.555477 -310.916252) (xy 75.588112 -310.879415) (xy 75.626233 -310.84829)
			(xy 75.668854 -310.823683) (xy 75.71487 -310.806231) (xy 75.763089 -310.796387) (xy 75.812264 -310.794406)
			(xy 75.861119 -310.800338) (xy 75.90839 -310.81403) (xy 75.952852 -310.835128) (xy 75.993355 -310.863084)
			(xy 76.028848 -310.897176) (xy 76.058413 -310.93652) (xy 76.081284 -310.980097) (xy 76.096868 -311.026778)
			(xy 76.104763 -311.075355) (xy 76.105258 -311.099962) (xy 77.394066 -311.099962) (xy 77.398026 -311.050908)
			(xy 77.409803 -311.003124) (xy 77.429094 -310.957848) (xy 77.455397 -310.916252) (xy 77.488032 -310.879415)
			(xy 77.526153 -310.84829) (xy 77.568774 -310.823683) (xy 77.61479 -310.806231) (xy 77.663009 -310.796387)
			(xy 77.712184 -310.794406) (xy 77.761039 -310.800338) (xy 77.80831 -310.81403) (xy 77.852772 -310.835128)
			(xy 77.893275 -310.863084) (xy 77.928768 -310.897176) (xy 77.958333 -310.93652) (xy 77.981204 -310.980097)
			(xy 77.996788 -311.026778) (xy 78.004683 -311.075355) (xy 78.005178 -311.099962) (xy 79.293986 -311.099962)
			(xy 79.297946 -311.050908) (xy 79.309723 -311.003124) (xy 79.329014 -310.957848) (xy 79.355317 -310.916252)
			(xy 79.387952 -310.879415) (xy 79.426073 -310.84829) (xy 79.468694 -310.823683) (xy 79.51471 -310.806231)
			(xy 79.562929 -310.796387) (xy 79.612104 -310.794406) (xy 79.660959 -310.800338) (xy 79.70823 -310.81403)
			(xy 79.752692 -310.835128) (xy 79.793195 -310.863084) (xy 79.828688 -310.897176) (xy 79.858253 -310.93652)
			(xy 79.881124 -310.980097) (xy 79.896708 -311.026778) (xy 79.904603 -311.075355) (xy 79.905098 -311.099962)
			(xy 155.49424 -311.099962) (xy 155.4982 -311.050908) (xy 155.509977 -311.003124) (xy 155.529268 -310.957848)
			(xy 155.555571 -310.916252) (xy 155.588206 -310.879415) (xy 155.626327 -310.84829) (xy 155.668948 -310.823683)
			(xy 155.714964 -310.806231) (xy 155.763183 -310.796387) (xy 155.812358 -310.794406) (xy 155.861213 -310.800338)
			(xy 155.908484 -310.81403) (xy 155.952946 -310.835128) (xy 155.993449 -310.863084) (xy 156.028942 -310.897176)
			(xy 156.058507 -310.93652) (xy 156.081378 -310.980097) (xy 156.096962 -311.026778) (xy 156.104857 -311.075355)
			(xy 156.105352 -311.099962) (xy 157.39416 -311.099962) (xy 157.39812 -311.050908) (xy 157.409897 -311.003124)
			(xy 157.429188 -310.957848) (xy 157.455491 -310.916252) (xy 157.488126 -310.879415) (xy 157.526247 -310.84829)
			(xy 157.568868 -310.823683) (xy 157.614884 -310.806231) (xy 157.663103 -310.796387) (xy 157.712278 -310.794406)
			(xy 157.761133 -310.800338) (xy 157.808404 -310.81403) (xy 157.852866 -310.835128) (xy 157.893369 -310.863084)
			(xy 157.928862 -310.897176) (xy 157.958427 -310.93652) (xy 157.981298 -310.980097) (xy 157.996882 -311.026778)
			(xy 158.004777 -311.075355) (xy 158.005272 -311.099962) (xy 159.29408 -311.099962) (xy 159.29804 -311.050908)
			(xy 159.309817 -311.003124) (xy 159.329108 -310.957848) (xy 159.355411 -310.916252) (xy 159.388046 -310.879415)
			(xy 159.426167 -310.84829) (xy 159.468788 -310.823683) (xy 159.514804 -310.806231) (xy 159.563023 -310.796387)
			(xy 159.612198 -310.794406) (xy 159.661053 -310.800338) (xy 159.708324 -310.81403) (xy 159.752786 -310.835128)
			(xy 159.793289 -310.863084) (xy 159.828782 -310.897176) (xy 159.858347 -310.93652) (xy 159.881218 -310.980097)
			(xy 159.896802 -311.026778) (xy 159.904697 -311.075355) (xy 159.905192 -311.099962) (xy 161.194254 -311.099962)
			(xy 161.198214 -311.050908) (xy 161.209991 -311.003124) (xy 161.229282 -310.957848) (xy 161.255585 -310.916252)
			(xy 161.28822 -310.879415) (xy 161.326341 -310.84829) (xy 161.368962 -310.823683) (xy 161.414978 -310.806231)
			(xy 161.463197 -310.796387) (xy 161.512372 -310.794406) (xy 161.561227 -310.800338) (xy 161.608498 -310.81403)
			(xy 161.65296 -310.835128) (xy 161.693463 -310.863084) (xy 161.728956 -310.897176) (xy 161.758521 -310.93652)
			(xy 161.781392 -310.980097) (xy 161.796976 -311.026778) (xy 161.804871 -311.075355) (xy 161.805366 -311.099962)
			(xy 163.094174 -311.099962) (xy 163.098134 -311.050908) (xy 163.109911 -311.003124) (xy 163.129202 -310.957848)
			(xy 163.155505 -310.916252) (xy 163.18814 -310.879415) (xy 163.226261 -310.84829) (xy 163.268882 -310.823683)
			(xy 163.314898 -310.806231) (xy 163.363117 -310.796387) (xy 163.412292 -310.794406) (xy 163.461147 -310.800338)
			(xy 163.508418 -310.81403) (xy 163.55288 -310.835128) (xy 163.593383 -310.863084) (xy 163.628876 -310.897176)
			(xy 163.658441 -310.93652) (xy 163.681312 -310.980097) (xy 163.696896 -311.026778) (xy 163.704791 -311.075355)
			(xy 163.705286 -311.099962) (xy 164.994094 -311.099962) (xy 164.998054 -311.050908) (xy 165.009831 -311.003124)
			(xy 165.029122 -310.957848) (xy 165.055425 -310.916252) (xy 165.08806 -310.879415) (xy 165.126181 -310.84829)
			(xy 165.168802 -310.823683) (xy 165.214818 -310.806231) (xy 165.263037 -310.796387) (xy 165.312212 -310.794406)
			(xy 165.361067 -310.800338) (xy 165.408338 -310.81403) (xy 165.4528 -310.835128) (xy 165.493303 -310.863084)
			(xy 165.528796 -310.897176) (xy 165.558361 -310.93652) (xy 165.581232 -310.980097) (xy 165.596816 -311.026778)
			(xy 165.604711 -311.075355) (xy 165.605206 -311.099962) (xy 182.094136 -311.099962) (xy 182.098096 -311.050908)
			(xy 182.109873 -311.003124) (xy 182.129164 -310.957848) (xy 182.155467 -310.916252) (xy 182.188102 -310.879415)
			(xy 182.226223 -310.84829) (xy 182.268844 -310.823683) (xy 182.31486 -310.806231) (xy 182.363079 -310.796387)
			(xy 182.412254 -310.794406) (xy 182.461109 -310.800338) (xy 182.50838 -310.81403) (xy 182.552842 -310.835128)
			(xy 182.593345 -310.863084) (xy 182.628838 -310.897176) (xy 182.658403 -310.93652) (xy 182.681274 -310.980097)
			(xy 182.696858 -311.026778) (xy 182.704753 -311.075355) (xy 182.705248 -311.099962) (xy 183.994056 -311.099962)
			(xy 183.998016 -311.050908) (xy 184.009793 -311.003124) (xy 184.029084 -310.957848) (xy 184.055387 -310.916252)
			(xy 184.088022 -310.879415) (xy 184.126143 -310.84829) (xy 184.168764 -310.823683) (xy 184.21478 -310.806231)
			(xy 184.262999 -310.796387) (xy 184.312174 -310.794406) (xy 184.361029 -310.800338) (xy 184.4083 -310.81403)
			(xy 184.452762 -310.835128) (xy 184.493265 -310.863084) (xy 184.528758 -310.897176) (xy 184.558323 -310.93652)
			(xy 184.581194 -310.980097) (xy 184.596778 -311.026778) (xy 184.604673 -311.075355) (xy 184.605168 -311.099962)
			(xy 185.89423 -311.099962) (xy 185.89819 -311.050908) (xy 185.909967 -311.003124) (xy 185.929258 -310.957848)
			(xy 185.955561 -310.916252) (xy 185.988196 -310.879415) (xy 186.026317 -310.84829) (xy 186.068938 -310.823683)
			(xy 186.114954 -310.806231) (xy 186.163173 -310.796387) (xy 186.212348 -310.794406) (xy 186.261203 -310.800338)
			(xy 186.308474 -310.81403) (xy 186.352936 -310.835128) (xy 186.393439 -310.863084) (xy 186.428932 -310.897176)
			(xy 186.458497 -310.93652) (xy 186.481368 -310.980097) (xy 186.496952 -311.026778) (xy 186.504847 -311.075355)
			(xy 186.505342 -311.099962) (xy 187.79415 -311.099962) (xy 187.79811 -311.050908) (xy 187.809887 -311.003124)
			(xy 187.829178 -310.957848) (xy 187.855481 -310.916252) (xy 187.888116 -310.879415) (xy 187.926237 -310.84829)
			(xy 187.968858 -310.823683) (xy 188.014874 -310.806231) (xy 188.063093 -310.796387) (xy 188.112268 -310.794406)
			(xy 188.161123 -310.800338) (xy 188.208394 -310.81403) (xy 188.252856 -310.835128) (xy 188.293359 -310.863084)
			(xy 188.328852 -310.897176) (xy 188.358417 -310.93652) (xy 188.381288 -310.980097) (xy 188.396872 -311.026778)
			(xy 188.404767 -311.075355) (xy 188.405262 -311.099962) (xy 275.393924 -311.099962) (xy 275.397884 -311.050908)
			(xy 275.409661 -311.003124) (xy 275.428952 -310.957848) (xy 275.455255 -310.916252) (xy 275.48789 -310.879415)
			(xy 275.526011 -310.84829) (xy 275.568632 -310.823683) (xy 275.614648 -310.806231) (xy 275.662867 -310.796387)
			(xy 275.712042 -310.794406) (xy 275.760897 -310.800338) (xy 275.808168 -310.81403) (xy 275.85263 -310.835128)
			(xy 275.893133 -310.863084) (xy 275.928626 -310.897176) (xy 275.958191 -310.93652) (xy 275.981062 -310.980097)
			(xy 275.996646 -311.026778) (xy 276.004541 -311.075355) (xy 276.005036 -311.099962) (xy 277.294098 -311.099962)
			(xy 277.298058 -311.050908) (xy 277.309835 -311.003124) (xy 277.329126 -310.957848) (xy 277.355429 -310.916252)
			(xy 277.388064 -310.879415) (xy 277.426185 -310.84829) (xy 277.468806 -310.823683) (xy 277.514822 -310.806231)
			(xy 277.563041 -310.796387) (xy 277.612216 -310.794406) (xy 277.661071 -310.800338) (xy 277.708342 -310.81403)
			(xy 277.752804 -310.835128) (xy 277.793307 -310.863084) (xy 277.8288 -310.897176) (xy 277.858365 -310.93652)
			(xy 277.881236 -310.980097) (xy 277.89682 -311.026778) (xy 277.904715 -311.075355) (xy 277.90521 -311.099962)
			(xy 279.194018 -311.099962) (xy 279.197978 -311.050908) (xy 279.209755 -311.003124) (xy 279.229046 -310.957848)
			(xy 279.255349 -310.916252) (xy 279.287984 -310.879415) (xy 279.326105 -310.84829) (xy 279.368726 -310.823683)
			(xy 279.414742 -310.806231) (xy 279.462961 -310.796387) (xy 279.512136 -310.794406) (xy 279.560991 -310.800338)
			(xy 279.608262 -310.81403) (xy 279.652724 -310.835128) (xy 279.693227 -310.863084) (xy 279.72872 -310.897176)
			(xy 279.758285 -310.93652) (xy 279.781156 -310.980097) (xy 279.79674 -311.026778) (xy 279.804635 -311.075355)
			(xy 279.80513 -311.099962) (xy 281.093938 -311.099962) (xy 281.097898 -311.050908) (xy 281.109675 -311.003124)
			(xy 281.128966 -310.957848) (xy 281.155269 -310.916252) (xy 281.187904 -310.879415) (xy 281.226025 -310.84829)
			(xy 281.268646 -310.823683) (xy 281.314662 -310.806231) (xy 281.362881 -310.796387) (xy 281.412056 -310.794406)
			(xy 281.460911 -310.800338) (xy 281.508182 -310.81403) (xy 281.552644 -310.835128) (xy 281.593147 -310.863084)
			(xy 281.62864 -310.897176) (xy 281.658205 -310.93652) (xy 281.681076 -310.980097) (xy 281.69666 -311.026778)
			(xy 281.704555 -311.075355) (xy 281.70505 -311.099962) (xy 282.994112 -311.099962) (xy 282.998072 -311.050908)
			(xy 283.009849 -311.003124) (xy 283.02914 -310.957848) (xy 283.055443 -310.916252) (xy 283.088078 -310.879415)
			(xy 283.126199 -310.84829) (xy 283.16882 -310.823683) (xy 283.214836 -310.806231) (xy 283.263055 -310.796387)
			(xy 283.31223 -310.794406) (xy 283.361085 -310.800338) (xy 283.408356 -310.81403) (xy 283.452818 -310.835128)
			(xy 283.493321 -310.863084) (xy 283.528814 -310.897176) (xy 283.558379 -310.93652) (xy 283.58125 -310.980097)
			(xy 283.596834 -311.026778) (xy 283.604729 -311.075355) (xy 283.605224 -311.099962) (xy 284.894032 -311.099962)
			(xy 284.897992 -311.050908) (xy 284.909769 -311.003124) (xy 284.92906 -310.957848) (xy 284.955363 -310.916252)
			(xy 284.987998 -310.879415) (xy 285.026119 -310.84829) (xy 285.06874 -310.823683) (xy 285.114756 -310.806231)
			(xy 285.162975 -310.796387) (xy 285.21215 -310.794406) (xy 285.261005 -310.800338) (xy 285.308276 -310.81403)
			(xy 285.352738 -310.835128) (xy 285.393241 -310.863084) (xy 285.428734 -310.897176) (xy 285.458299 -310.93652)
			(xy 285.48117 -310.980097) (xy 285.496754 -311.026778) (xy 285.504649 -311.075355) (xy 285.505144 -311.099962)
			(xy 286.793952 -311.099962) (xy 286.797912 -311.050908) (xy 286.809689 -311.003124) (xy 286.82898 -310.957848)
			(xy 286.855283 -310.916252) (xy 286.887918 -310.879415) (xy 286.926039 -310.84829) (xy 286.96866 -310.823683)
			(xy 287.014676 -310.806231) (xy 287.062895 -310.796387) (xy 287.11207 -310.794406) (xy 287.160925 -310.800338)
			(xy 287.208196 -310.81403) (xy 287.252658 -310.835128) (xy 287.293161 -310.863084) (xy 287.328654 -310.897176)
			(xy 287.358219 -310.93652) (xy 287.38109 -310.980097) (xy 287.396674 -311.026778) (xy 287.404569 -311.075355)
			(xy 287.405064 -311.099962) (xy 288.694126 -311.099962) (xy 288.698086 -311.050908) (xy 288.709863 -311.003124)
			(xy 288.729154 -310.957848) (xy 288.755457 -310.916252) (xy 288.788092 -310.879415) (xy 288.826213 -310.84829)
			(xy 288.868834 -310.823683) (xy 288.91485 -310.806231) (xy 288.963069 -310.796387) (xy 289.012244 -310.794406)
			(xy 289.061099 -310.800338) (xy 289.10837 -310.81403) (xy 289.152832 -310.835128) (xy 289.193335 -310.863084)
			(xy 289.228828 -310.897176) (xy 289.258393 -310.93652) (xy 289.281264 -310.980097) (xy 289.296848 -311.026778)
			(xy 289.304743 -311.075355) (xy 289.305238 -311.099962) (xy 305.793914 -311.099962) (xy 305.797874 -311.050908)
			(xy 305.809651 -311.003124) (xy 305.828942 -310.957848) (xy 305.855245 -310.916252) (xy 305.88788 -310.879415)
			(xy 305.926001 -310.84829) (xy 305.968622 -310.823683) (xy 306.014638 -310.806231) (xy 306.062857 -310.796387)
			(xy 306.112032 -310.794406) (xy 306.160887 -310.800338) (xy 306.208158 -310.81403) (xy 306.25262 -310.835128)
			(xy 306.293123 -310.863084) (xy 306.328616 -310.897176) (xy 306.358181 -310.93652) (xy 306.381052 -310.980097)
			(xy 306.396636 -311.026778) (xy 306.404531 -311.075355) (xy 306.405026 -311.099962) (xy 307.694088 -311.099962)
			(xy 307.698048 -311.050908) (xy 307.709825 -311.003124) (xy 307.729116 -310.957848) (xy 307.755419 -310.916252)
			(xy 307.788054 -310.879415) (xy 307.826175 -310.84829) (xy 307.868796 -310.823683) (xy 307.914812 -310.806231)
			(xy 307.963031 -310.796387) (xy 308.012206 -310.794406) (xy 308.061061 -310.800338) (xy 308.108332 -310.81403)
			(xy 308.152794 -310.835128) (xy 308.193297 -310.863084) (xy 308.22879 -310.897176) (xy 308.258355 -310.93652)
			(xy 308.281226 -310.980097) (xy 308.29681 -311.026778) (xy 308.304705 -311.075355) (xy 308.3052 -311.099962)
			(xy 309.594008 -311.099962) (xy 309.597968 -311.050908) (xy 309.609745 -311.003124) (xy 309.629036 -310.957848)
			(xy 309.655339 -310.916252) (xy 309.687974 -310.879415) (xy 309.726095 -310.84829) (xy 309.768716 -310.823683)
			(xy 309.814732 -310.806231) (xy 309.862951 -310.796387) (xy 309.912126 -310.794406) (xy 309.960981 -310.800338)
			(xy 310.008252 -310.81403) (xy 310.052714 -310.835128) (xy 310.093217 -310.863084) (xy 310.12871 -310.897176)
			(xy 310.158275 -310.93652) (xy 310.181146 -310.980097) (xy 310.19673 -311.026778) (xy 310.204625 -311.075355)
			(xy 310.20512 -311.099962) (xy 311.493928 -311.099962) (xy 311.497888 -311.050908) (xy 311.509665 -311.003124)
			(xy 311.528956 -310.957848) (xy 311.555259 -310.916252) (xy 311.587894 -310.879415) (xy 311.626015 -310.84829)
			(xy 311.668636 -310.823683) (xy 311.714652 -310.806231) (xy 311.762871 -310.796387) (xy 311.812046 -310.794406)
			(xy 311.860901 -310.800338) (xy 311.908172 -310.81403) (xy 311.952634 -310.835128) (xy 311.993137 -310.863084)
			(xy 312.02863 -310.897176) (xy 312.058195 -310.93652) (xy 312.081066 -310.980097) (xy 312.09665 -311.026778)
			(xy 312.104545 -311.075355) (xy 312.10504 -311.099962) (xy 387.694182 -311.099962) (xy 387.698142 -311.050908)
			(xy 387.709919 -311.003124) (xy 387.72921 -310.957848) (xy 387.755513 -310.916252) (xy 387.788148 -310.879415)
			(xy 387.826269 -310.84829) (xy 387.86889 -310.823683) (xy 387.914906 -310.806231) (xy 387.963125 -310.796387)
			(xy 388.0123 -310.794406) (xy 388.061155 -310.800338) (xy 388.108426 -310.81403) (xy 388.152888 -310.835128)
			(xy 388.193391 -310.863084) (xy 388.228884 -310.897176) (xy 388.258449 -310.93652) (xy 388.28132 -310.980097)
			(xy 388.296904 -311.026778) (xy 388.304799 -311.075355) (xy 388.305294 -311.099962) (xy 389.594102 -311.099962)
			(xy 389.598062 -311.050908) (xy 389.609839 -311.003124) (xy 389.62913 -310.957848) (xy 389.655433 -310.916252)
			(xy 389.688068 -310.879415) (xy 389.726189 -310.84829) (xy 389.76881 -310.823683) (xy 389.814826 -310.806231)
			(xy 389.863045 -310.796387) (xy 389.91222 -310.794406) (xy 389.961075 -310.800338) (xy 390.008346 -310.81403)
			(xy 390.052808 -310.835128) (xy 390.093311 -310.863084) (xy 390.128804 -310.897176) (xy 390.158369 -310.93652)
			(xy 390.18124 -310.980097) (xy 390.196824 -311.026778) (xy 390.204719 -311.075355) (xy 390.205214 -311.099962)
			(xy 391.494022 -311.099962) (xy 391.497982 -311.050908) (xy 391.509759 -311.003124) (xy 391.52905 -310.957848)
			(xy 391.555353 -310.916252) (xy 391.587988 -310.879415) (xy 391.626109 -310.84829) (xy 391.66873 -310.823683)
			(xy 391.714746 -310.806231) (xy 391.762965 -310.796387) (xy 391.81214 -310.794406) (xy 391.860995 -310.800338)
			(xy 391.908266 -310.81403) (xy 391.952728 -310.835128) (xy 391.993231 -310.863084) (xy 392.028724 -310.897176)
			(xy 392.058289 -310.93652) (xy 392.08116 -310.980097) (xy 392.096744 -311.026778) (xy 392.104639 -311.075355)
			(xy 392.105134 -311.099962) (xy 393.394196 -311.099962) (xy 393.398156 -311.050908) (xy 393.409933 -311.003124)
			(xy 393.429224 -310.957848) (xy 393.455527 -310.916252) (xy 393.488162 -310.879415) (xy 393.526283 -310.84829)
			(xy 393.568904 -310.823683) (xy 393.61492 -310.806231) (xy 393.663139 -310.796387) (xy 393.712314 -310.794406)
			(xy 393.761169 -310.800338) (xy 393.80844 -310.81403) (xy 393.852902 -310.835128) (xy 393.893405 -310.863084)
			(xy 393.928898 -310.897176) (xy 393.958463 -310.93652) (xy 393.981334 -310.980097) (xy 393.996918 -311.026778)
			(xy 394.004813 -311.075355) (xy 394.005308 -311.099962) (xy 395.294116 -311.099962) (xy 395.298076 -311.050908)
			(xy 395.309853 -311.003124) (xy 395.329144 -310.957848) (xy 395.355447 -310.916252) (xy 395.388082 -310.879415)
			(xy 395.426203 -310.84829) (xy 395.468824 -310.823683) (xy 395.51484 -310.806231) (xy 395.563059 -310.796387)
			(xy 395.612234 -310.794406) (xy 395.661089 -310.800338) (xy 395.70836 -310.81403) (xy 395.752822 -310.835128)
			(xy 395.793325 -310.863084) (xy 395.828818 -310.897176) (xy 395.858383 -310.93652) (xy 395.881254 -310.980097)
			(xy 395.896838 -311.026778) (xy 395.904733 -311.075355) (xy 395.905228 -311.099962) (xy 397.194036 -311.099962)
			(xy 397.197996 -311.050908) (xy 397.209773 -311.003124) (xy 397.229064 -310.957848) (xy 397.255367 -310.916252)
			(xy 397.288002 -310.879415) (xy 397.326123 -310.84829) (xy 397.368744 -310.823683) (xy 397.41476 -310.806231)
			(xy 397.462979 -310.796387) (xy 397.512154 -310.794406) (xy 397.561009 -310.800338) (xy 397.60828 -310.81403)
			(xy 397.652742 -310.835128) (xy 397.693245 -310.863084) (xy 397.728738 -310.897176) (xy 397.758303 -310.93652)
			(xy 397.781174 -310.980097) (xy 397.796758 -311.026778) (xy 397.804653 -311.075355) (xy 397.805148 -311.099962)
			(xy 414.294078 -311.099962) (xy 414.298038 -311.050908) (xy 414.309815 -311.003124) (xy 414.329106 -310.957848)
			(xy 414.355409 -310.916252) (xy 414.388044 -310.879415) (xy 414.426165 -310.84829) (xy 414.468786 -310.823683)
			(xy 414.514802 -310.806231) (xy 414.563021 -310.796387) (xy 414.612196 -310.794406) (xy 414.661051 -310.800338)
			(xy 414.708322 -310.81403) (xy 414.752784 -310.835128) (xy 414.793287 -310.863084) (xy 414.82878 -310.897176)
			(xy 414.858345 -310.93652) (xy 414.881216 -310.980097) (xy 414.8968 -311.026778) (xy 414.904695 -311.075355)
			(xy 414.90519 -311.099962) (xy 416.193998 -311.099962) (xy 416.197958 -311.050908) (xy 416.209735 -311.003124)
			(xy 416.229026 -310.957848) (xy 416.255329 -310.916252) (xy 416.287964 -310.879415) (xy 416.326085 -310.84829)
			(xy 416.368706 -310.823683) (xy 416.414722 -310.806231) (xy 416.462941 -310.796387) (xy 416.512116 -310.794406)
			(xy 416.560971 -310.800338) (xy 416.608242 -310.81403) (xy 416.652704 -310.835128) (xy 416.693207 -310.863084)
			(xy 416.7287 -310.897176) (xy 416.758265 -310.93652) (xy 416.781136 -310.980097) (xy 416.79672 -311.026778)
			(xy 416.804615 -311.075355) (xy 416.80511 -311.099962) (xy 418.094172 -311.099962) (xy 418.098132 -311.050908)
			(xy 418.109909 -311.003124) (xy 418.1292 -310.957848) (xy 418.155503 -310.916252) (xy 418.188138 -310.879415)
			(xy 418.226259 -310.84829) (xy 418.26888 -310.823683) (xy 418.314896 -310.806231) (xy 418.363115 -310.796387)
			(xy 418.41229 -310.794406) (xy 418.461145 -310.800338) (xy 418.508416 -310.81403) (xy 418.552878 -310.835128)
			(xy 418.593381 -310.863084) (xy 418.628874 -310.897176) (xy 418.658439 -310.93652) (xy 418.68131 -310.980097)
			(xy 418.696894 -311.026778) (xy 418.704789 -311.075355) (xy 418.705284 -311.099962) (xy 419.994092 -311.099962)
			(xy 419.998052 -311.050908) (xy 420.009829 -311.003124) (xy 420.02912 -310.957848) (xy 420.055423 -310.916252)
			(xy 420.088058 -310.879415) (xy 420.126179 -310.84829) (xy 420.1688 -310.823683) (xy 420.214816 -310.806231)
			(xy 420.263035 -310.796387) (xy 420.31221 -310.794406) (xy 420.361065 -310.800338) (xy 420.408336 -310.81403)
			(xy 420.452798 -310.835128) (xy 420.493301 -310.863084) (xy 420.528794 -310.897176) (xy 420.558359 -310.93652)
			(xy 420.58123 -310.980097) (xy 420.596814 -311.026778) (xy 420.604709 -311.075355) (xy 420.605204 -311.099962)
			(xy 420.604709 -311.124569) (xy 420.596814 -311.173146) (xy 420.58123 -311.219827) (xy 420.558359 -311.263404)
			(xy 420.528794 -311.302748) (xy 420.493301 -311.33684) (xy 420.452798 -311.364796) (xy 420.408336 -311.385894)
			(xy 420.361065 -311.399586) (xy 420.31221 -311.405518) (xy 420.263035 -311.403537) (xy 420.214816 -311.393693)
			(xy 420.1688 -311.376241) (xy 420.126179 -311.351634) (xy 420.088058 -311.320509) (xy 420.055423 -311.283672)
			(xy 420.02912 -311.242076) (xy 420.009829 -311.1968) (xy 419.998052 -311.149016) (xy 419.994092 -311.099962)
			(xy 418.705284 -311.099962) (xy 418.704789 -311.124569) (xy 418.696894 -311.173146) (xy 418.68131 -311.219827)
			(xy 418.658439 -311.263404) (xy 418.628874 -311.302748) (xy 418.593381 -311.33684) (xy 418.552878 -311.364796)
			(xy 418.508416 -311.385894) (xy 418.461145 -311.399586) (xy 418.41229 -311.405518) (xy 418.363115 -311.403537)
			(xy 418.314896 -311.393693) (xy 418.26888 -311.376241) (xy 418.226259 -311.351634) (xy 418.188138 -311.320509)
			(xy 418.155503 -311.283672) (xy 418.1292 -311.242076) (xy 418.109909 -311.1968) (xy 418.098132 -311.149016)
			(xy 418.094172 -311.099962) (xy 416.80511 -311.099962) (xy 416.804615 -311.124569) (xy 416.79672 -311.173146)
			(xy 416.781136 -311.219827) (xy 416.758265 -311.263404) (xy 416.7287 -311.302748) (xy 416.693207 -311.33684)
			(xy 416.652704 -311.364796) (xy 416.608242 -311.385894) (xy 416.560971 -311.399586) (xy 416.512116 -311.405518)
			(xy 416.462941 -311.403537) (xy 416.414722 -311.393693) (xy 416.368706 -311.376241) (xy 416.326085 -311.351634)
			(xy 416.287964 -311.320509) (xy 416.255329 -311.283672) (xy 416.229026 -311.242076) (xy 416.209735 -311.1968)
			(xy 416.197958 -311.149016) (xy 416.193998 -311.099962) (xy 414.90519 -311.099962) (xy 414.904695 -311.124569)
			(xy 414.8968 -311.173146) (xy 414.881216 -311.219827) (xy 414.858345 -311.263404) (xy 414.82878 -311.302748)
			(xy 414.793287 -311.33684) (xy 414.752784 -311.364796) (xy 414.708322 -311.385894) (xy 414.661051 -311.399586)
			(xy 414.612196 -311.405518) (xy 414.563021 -311.403537) (xy 414.514802 -311.393693) (xy 414.468786 -311.376241)
			(xy 414.426165 -311.351634) (xy 414.388044 -311.320509) (xy 414.355409 -311.283672) (xy 414.329106 -311.242076)
			(xy 414.309815 -311.1968) (xy 414.298038 -311.149016) (xy 414.294078 -311.099962) (xy 397.805148 -311.099962)
			(xy 397.804653 -311.124569) (xy 397.796758 -311.173146) (xy 397.781174 -311.219827) (xy 397.758303 -311.263404)
			(xy 397.728738 -311.302748) (xy 397.693245 -311.33684) (xy 397.652742 -311.364796) (xy 397.60828 -311.385894)
			(xy 397.561009 -311.399586) (xy 397.512154 -311.405518) (xy 397.462979 -311.403537) (xy 397.41476 -311.393693)
			(xy 397.368744 -311.376241) (xy 397.326123 -311.351634) (xy 397.288002 -311.320509) (xy 397.255367 -311.283672)
			(xy 397.229064 -311.242076) (xy 397.209773 -311.1968) (xy 397.197996 -311.149016) (xy 397.194036 -311.099962)
			(xy 395.905228 -311.099962) (xy 395.904733 -311.124569) (xy 395.896838 -311.173146) (xy 395.881254 -311.219827)
			(xy 395.858383 -311.263404) (xy 395.828818 -311.302748) (xy 395.793325 -311.33684) (xy 395.752822 -311.364796)
			(xy 395.70836 -311.385894) (xy 395.661089 -311.399586) (xy 395.612234 -311.405518) (xy 395.563059 -311.403537)
			(xy 395.51484 -311.393693) (xy 395.468824 -311.376241) (xy 395.426203 -311.351634) (xy 395.388082 -311.320509)
			(xy 395.355447 -311.283672) (xy 395.329144 -311.242076) (xy 395.309853 -311.1968) (xy 395.298076 -311.149016)
			(xy 395.294116 -311.099962) (xy 394.005308 -311.099962) (xy 394.004813 -311.124569) (xy 393.996918 -311.173146)
			(xy 393.981334 -311.219827) (xy 393.958463 -311.263404) (xy 393.928898 -311.302748) (xy 393.893405 -311.33684)
			(xy 393.852902 -311.364796) (xy 393.80844 -311.385894) (xy 393.761169 -311.399586) (xy 393.712314 -311.405518)
			(xy 393.663139 -311.403537) (xy 393.61492 -311.393693) (xy 393.568904 -311.376241) (xy 393.526283 -311.351634)
			(xy 393.488162 -311.320509) (xy 393.455527 -311.283672) (xy 393.429224 -311.242076) (xy 393.409933 -311.1968)
			(xy 393.398156 -311.149016) (xy 393.394196 -311.099962) (xy 392.105134 -311.099962) (xy 392.104639 -311.124569)
			(xy 392.096744 -311.173146) (xy 392.08116 -311.219827) (xy 392.058289 -311.263404) (xy 392.028724 -311.302748)
			(xy 391.993231 -311.33684) (xy 391.952728 -311.364796) (xy 391.908266 -311.385894) (xy 391.860995 -311.399586)
			(xy 391.81214 -311.405518) (xy 391.762965 -311.403537) (xy 391.714746 -311.393693) (xy 391.66873 -311.376241)
			(xy 391.626109 -311.351634) (xy 391.587988 -311.320509) (xy 391.555353 -311.283672) (xy 391.52905 -311.242076)
			(xy 391.509759 -311.1968) (xy 391.497982 -311.149016) (xy 391.494022 -311.099962) (xy 390.205214 -311.099962)
			(xy 390.204719 -311.124569) (xy 390.196824 -311.173146) (xy 390.18124 -311.219827) (xy 390.158369 -311.263404)
			(xy 390.128804 -311.302748) (xy 390.093311 -311.33684) (xy 390.052808 -311.364796) (xy 390.008346 -311.385894)
			(xy 389.961075 -311.399586) (xy 389.91222 -311.405518) (xy 389.863045 -311.403537) (xy 389.814826 -311.393693)
			(xy 389.76881 -311.376241) (xy 389.726189 -311.351634) (xy 389.688068 -311.320509) (xy 389.655433 -311.283672)
			(xy 389.62913 -311.242076) (xy 389.609839 -311.1968) (xy 389.598062 -311.149016) (xy 389.594102 -311.099962)
			(xy 388.305294 -311.099962) (xy 388.304799 -311.124569) (xy 388.296904 -311.173146) (xy 388.28132 -311.219827)
			(xy 388.258449 -311.263404) (xy 388.228884 -311.302748) (xy 388.193391 -311.33684) (xy 388.152888 -311.364796)
			(xy 388.108426 -311.385894) (xy 388.061155 -311.399586) (xy 388.0123 -311.405518) (xy 387.963125 -311.403537)
			(xy 387.914906 -311.393693) (xy 387.86889 -311.376241) (xy 387.826269 -311.351634) (xy 387.788148 -311.320509)
			(xy 387.755513 -311.283672) (xy 387.72921 -311.242076) (xy 387.709919 -311.1968) (xy 387.698142 -311.149016)
			(xy 387.694182 -311.099962) (xy 312.10504 -311.099962) (xy 312.104545 -311.124569) (xy 312.09665 -311.173146)
			(xy 312.081066 -311.219827) (xy 312.058195 -311.263404) (xy 312.02863 -311.302748) (xy 311.993137 -311.33684)
			(xy 311.952634 -311.364796) (xy 311.908172 -311.385894) (xy 311.860901 -311.399586) (xy 311.812046 -311.405518)
			(xy 311.762871 -311.403537) (xy 311.714652 -311.393693) (xy 311.668636 -311.376241) (xy 311.626015 -311.351634)
			(xy 311.587894 -311.320509) (xy 311.555259 -311.283672) (xy 311.528956 -311.242076) (xy 311.509665 -311.1968)
			(xy 311.497888 -311.149016) (xy 311.493928 -311.099962) (xy 310.20512 -311.099962) (xy 310.204625 -311.124569)
			(xy 310.19673 -311.173146) (xy 310.181146 -311.219827) (xy 310.158275 -311.263404) (xy 310.12871 -311.302748)
			(xy 310.093217 -311.33684) (xy 310.052714 -311.364796) (xy 310.008252 -311.385894) (xy 309.960981 -311.399586)
			(xy 309.912126 -311.405518) (xy 309.862951 -311.403537) (xy 309.814732 -311.393693) (xy 309.768716 -311.376241)
			(xy 309.726095 -311.351634) (xy 309.687974 -311.320509) (xy 309.655339 -311.283672) (xy 309.629036 -311.242076)
			(xy 309.609745 -311.1968) (xy 309.597968 -311.149016) (xy 309.594008 -311.099962) (xy 308.3052 -311.099962)
			(xy 308.304705 -311.124569) (xy 308.29681 -311.173146) (xy 308.281226 -311.219827) (xy 308.258355 -311.263404)
			(xy 308.22879 -311.302748) (xy 308.193297 -311.33684) (xy 308.152794 -311.364796) (xy 308.108332 -311.385894)
			(xy 308.061061 -311.399586) (xy 308.012206 -311.405518) (xy 307.963031 -311.403537) (xy 307.914812 -311.393693)
			(xy 307.868796 -311.376241) (xy 307.826175 -311.351634) (xy 307.788054 -311.320509) (xy 307.755419 -311.283672)
			(xy 307.729116 -311.242076) (xy 307.709825 -311.1968) (xy 307.698048 -311.149016) (xy 307.694088 -311.099962)
			(xy 306.405026 -311.099962) (xy 306.404531 -311.124569) (xy 306.396636 -311.173146) (xy 306.381052 -311.219827)
			(xy 306.358181 -311.263404) (xy 306.328616 -311.302748) (xy 306.293123 -311.33684) (xy 306.25262 -311.364796)
			(xy 306.208158 -311.385894) (xy 306.160887 -311.399586) (xy 306.112032 -311.405518) (xy 306.062857 -311.403537)
			(xy 306.014638 -311.393693) (xy 305.968622 -311.376241) (xy 305.926001 -311.351634) (xy 305.88788 -311.320509)
			(xy 305.855245 -311.283672) (xy 305.828942 -311.242076) (xy 305.809651 -311.1968) (xy 305.797874 -311.149016)
			(xy 305.793914 -311.099962) (xy 289.305238 -311.099962) (xy 289.304743 -311.124569) (xy 289.296848 -311.173146)
			(xy 289.281264 -311.219827) (xy 289.258393 -311.263404) (xy 289.228828 -311.302748) (xy 289.193335 -311.33684)
			(xy 289.152832 -311.364796) (xy 289.10837 -311.385894) (xy 289.061099 -311.399586) (xy 289.012244 -311.405518)
			(xy 288.963069 -311.403537) (xy 288.91485 -311.393693) (xy 288.868834 -311.376241) (xy 288.826213 -311.351634)
			(xy 288.788092 -311.320509) (xy 288.755457 -311.283672) (xy 288.729154 -311.242076) (xy 288.709863 -311.1968)
			(xy 288.698086 -311.149016) (xy 288.694126 -311.099962) (xy 287.405064 -311.099962) (xy 287.404569 -311.124569)
			(xy 287.396674 -311.173146) (xy 287.38109 -311.219827) (xy 287.358219 -311.263404) (xy 287.328654 -311.302748)
			(xy 287.293161 -311.33684) (xy 287.252658 -311.364796) (xy 287.208196 -311.385894) (xy 287.160925 -311.399586)
			(xy 287.11207 -311.405518) (xy 287.062895 -311.403537) (xy 287.014676 -311.393693) (xy 286.96866 -311.376241)
			(xy 286.926039 -311.351634) (xy 286.887918 -311.320509) (xy 286.855283 -311.283672) (xy 286.82898 -311.242076)
			(xy 286.809689 -311.1968) (xy 286.797912 -311.149016) (xy 286.793952 -311.099962) (xy 285.505144 -311.099962)
			(xy 285.504649 -311.124569) (xy 285.496754 -311.173146) (xy 285.48117 -311.219827) (xy 285.458299 -311.263404)
			(xy 285.428734 -311.302748) (xy 285.393241 -311.33684) (xy 285.352738 -311.364796) (xy 285.308276 -311.385894)
			(xy 285.261005 -311.399586) (xy 285.21215 -311.405518) (xy 285.162975 -311.403537) (xy 285.114756 -311.393693)
			(xy 285.06874 -311.376241) (xy 285.026119 -311.351634) (xy 284.987998 -311.320509) (xy 284.955363 -311.283672)
			(xy 284.92906 -311.242076) (xy 284.909769 -311.1968) (xy 284.897992 -311.149016) (xy 284.894032 -311.099962)
			(xy 283.605224 -311.099962) (xy 283.604729 -311.124569) (xy 283.596834 -311.173146) (xy 283.58125 -311.219827)
			(xy 283.558379 -311.263404) (xy 283.528814 -311.302748) (xy 283.493321 -311.33684) (xy 283.452818 -311.364796)
			(xy 283.408356 -311.385894) (xy 283.361085 -311.399586) (xy 283.31223 -311.405518) (xy 283.263055 -311.403537)
			(xy 283.214836 -311.393693) (xy 283.16882 -311.376241) (xy 283.126199 -311.351634) (xy 283.088078 -311.320509)
			(xy 283.055443 -311.283672) (xy 283.02914 -311.242076) (xy 283.009849 -311.1968) (xy 282.998072 -311.149016)
			(xy 282.994112 -311.099962) (xy 281.70505 -311.099962) (xy 281.704555 -311.124569) (xy 281.69666 -311.173146)
			(xy 281.681076 -311.219827) (xy 281.658205 -311.263404) (xy 281.62864 -311.302748) (xy 281.593147 -311.33684)
			(xy 281.552644 -311.364796) (xy 281.508182 -311.385894) (xy 281.460911 -311.399586) (xy 281.412056 -311.405518)
			(xy 281.362881 -311.403537) (xy 281.314662 -311.393693) (xy 281.268646 -311.376241) (xy 281.226025 -311.351634)
			(xy 281.187904 -311.320509) (xy 281.155269 -311.283672) (xy 281.128966 -311.242076) (xy 281.109675 -311.1968)
			(xy 281.097898 -311.149016) (xy 281.093938 -311.099962) (xy 279.80513 -311.099962) (xy 279.804635 -311.124569)
			(xy 279.79674 -311.173146) (xy 279.781156 -311.219827) (xy 279.758285 -311.263404) (xy 279.72872 -311.302748)
			(xy 279.693227 -311.33684) (xy 279.652724 -311.364796) (xy 279.608262 -311.385894) (xy 279.560991 -311.399586)
			(xy 279.512136 -311.405518) (xy 279.462961 -311.403537) (xy 279.414742 -311.393693) (xy 279.368726 -311.376241)
			(xy 279.326105 -311.351634) (xy 279.287984 -311.320509) (xy 279.255349 -311.283672) (xy 279.229046 -311.242076)
			(xy 279.209755 -311.1968) (xy 279.197978 -311.149016) (xy 279.194018 -311.099962) (xy 277.90521 -311.099962)
			(xy 277.904715 -311.124569) (xy 277.89682 -311.173146) (xy 277.881236 -311.219827) (xy 277.858365 -311.263404)
			(xy 277.8288 -311.302748) (xy 277.793307 -311.33684) (xy 277.752804 -311.364796) (xy 277.708342 -311.385894)
			(xy 277.661071 -311.399586) (xy 277.612216 -311.405518) (xy 277.563041 -311.403537) (xy 277.514822 -311.393693)
			(xy 277.468806 -311.376241) (xy 277.426185 -311.351634) (xy 277.388064 -311.320509) (xy 277.355429 -311.283672)
			(xy 277.329126 -311.242076) (xy 277.309835 -311.1968) (xy 277.298058 -311.149016) (xy 277.294098 -311.099962)
			(xy 276.005036 -311.099962) (xy 276.004541 -311.124569) (xy 275.996646 -311.173146) (xy 275.981062 -311.219827)
			(xy 275.958191 -311.263404) (xy 275.928626 -311.302748) (xy 275.893133 -311.33684) (xy 275.85263 -311.364796)
			(xy 275.808168 -311.385894) (xy 275.760897 -311.399586) (xy 275.712042 -311.405518) (xy 275.662867 -311.403537)
			(xy 275.614648 -311.393693) (xy 275.568632 -311.376241) (xy 275.526011 -311.351634) (xy 275.48789 -311.320509)
			(xy 275.455255 -311.283672) (xy 275.428952 -311.242076) (xy 275.409661 -311.1968) (xy 275.397884 -311.149016)
			(xy 275.393924 -311.099962) (xy 188.405262 -311.099962) (xy 188.404767 -311.124569) (xy 188.396872 -311.173146)
			(xy 188.381288 -311.219827) (xy 188.358417 -311.263404) (xy 188.328852 -311.302748) (xy 188.293359 -311.33684)
			(xy 188.252856 -311.364796) (xy 188.208394 -311.385894) (xy 188.161123 -311.399586) (xy 188.112268 -311.405518)
			(xy 188.063093 -311.403537) (xy 188.014874 -311.393693) (xy 187.968858 -311.376241) (xy 187.926237 -311.351634)
			(xy 187.888116 -311.320509) (xy 187.855481 -311.283672) (xy 187.829178 -311.242076) (xy 187.809887 -311.1968)
			(xy 187.79811 -311.149016) (xy 187.79415 -311.099962) (xy 186.505342 -311.099962) (xy 186.504847 -311.124569)
			(xy 186.496952 -311.173146) (xy 186.481368 -311.219827) (xy 186.458497 -311.263404) (xy 186.428932 -311.302748)
			(xy 186.393439 -311.33684) (xy 186.352936 -311.364796) (xy 186.308474 -311.385894) (xy 186.261203 -311.399586)
			(xy 186.212348 -311.405518) (xy 186.163173 -311.403537) (xy 186.114954 -311.393693) (xy 186.068938 -311.376241)
			(xy 186.026317 -311.351634) (xy 185.988196 -311.320509) (xy 185.955561 -311.283672) (xy 185.929258 -311.242076)
			(xy 185.909967 -311.1968) (xy 185.89819 -311.149016) (xy 185.89423 -311.099962) (xy 184.605168 -311.099962)
			(xy 184.604673 -311.124569) (xy 184.596778 -311.173146) (xy 184.581194 -311.219827) (xy 184.558323 -311.263404)
			(xy 184.528758 -311.302748) (xy 184.493265 -311.33684) (xy 184.452762 -311.364796) (xy 184.4083 -311.385894)
			(xy 184.361029 -311.399586) (xy 184.312174 -311.405518) (xy 184.262999 -311.403537) (xy 184.21478 -311.393693)
			(xy 184.168764 -311.376241) (xy 184.126143 -311.351634) (xy 184.088022 -311.320509) (xy 184.055387 -311.283672)
			(xy 184.029084 -311.242076) (xy 184.009793 -311.1968) (xy 183.998016 -311.149016) (xy 183.994056 -311.099962)
			(xy 182.705248 -311.099962) (xy 182.704753 -311.124569) (xy 182.696858 -311.173146) (xy 182.681274 -311.219827)
			(xy 182.658403 -311.263404) (xy 182.628838 -311.302748) (xy 182.593345 -311.33684) (xy 182.552842 -311.364796)
			(xy 182.50838 -311.385894) (xy 182.461109 -311.399586) (xy 182.412254 -311.405518) (xy 182.363079 -311.403537)
			(xy 182.31486 -311.393693) (xy 182.268844 -311.376241) (xy 182.226223 -311.351634) (xy 182.188102 -311.320509)
			(xy 182.155467 -311.283672) (xy 182.129164 -311.242076) (xy 182.109873 -311.1968) (xy 182.098096 -311.149016)
			(xy 182.094136 -311.099962) (xy 165.605206 -311.099962) (xy 165.604711 -311.124569) (xy 165.596816 -311.173146)
			(xy 165.581232 -311.219827) (xy 165.558361 -311.263404) (xy 165.528796 -311.302748) (xy 165.493303 -311.33684)
			(xy 165.4528 -311.364796) (xy 165.408338 -311.385894) (xy 165.361067 -311.399586) (xy 165.312212 -311.405518)
			(xy 165.263037 -311.403537) (xy 165.214818 -311.393693) (xy 165.168802 -311.376241) (xy 165.126181 -311.351634)
			(xy 165.08806 -311.320509) (xy 165.055425 -311.283672) (xy 165.029122 -311.242076) (xy 165.009831 -311.1968)
			(xy 164.998054 -311.149016) (xy 164.994094 -311.099962) (xy 163.705286 -311.099962) (xy 163.704791 -311.124569)
			(xy 163.696896 -311.173146) (xy 163.681312 -311.219827) (xy 163.658441 -311.263404) (xy 163.628876 -311.302748)
			(xy 163.593383 -311.33684) (xy 163.55288 -311.364796) (xy 163.508418 -311.385894) (xy 163.461147 -311.399586)
			(xy 163.412292 -311.405518) (xy 163.363117 -311.403537) (xy 163.314898 -311.393693) (xy 163.268882 -311.376241)
			(xy 163.226261 -311.351634) (xy 163.18814 -311.320509) (xy 163.155505 -311.283672) (xy 163.129202 -311.242076)
			(xy 163.109911 -311.1968) (xy 163.098134 -311.149016) (xy 163.094174 -311.099962) (xy 161.805366 -311.099962)
			(xy 161.804871 -311.124569) (xy 161.796976 -311.173146) (xy 161.781392 -311.219827) (xy 161.758521 -311.263404)
			(xy 161.728956 -311.302748) (xy 161.693463 -311.33684) (xy 161.65296 -311.364796) (xy 161.608498 -311.385894)
			(xy 161.561227 -311.399586) (xy 161.512372 -311.405518) (xy 161.463197 -311.403537) (xy 161.414978 -311.393693)
			(xy 161.368962 -311.376241) (xy 161.326341 -311.351634) (xy 161.28822 -311.320509) (xy 161.255585 -311.283672)
			(xy 161.229282 -311.242076) (xy 161.209991 -311.1968) (xy 161.198214 -311.149016) (xy 161.194254 -311.099962)
			(xy 159.905192 -311.099962) (xy 159.904697 -311.124569) (xy 159.896802 -311.173146) (xy 159.881218 -311.219827)
			(xy 159.858347 -311.263404) (xy 159.828782 -311.302748) (xy 159.793289 -311.33684) (xy 159.752786 -311.364796)
			(xy 159.708324 -311.385894) (xy 159.661053 -311.399586) (xy 159.612198 -311.405518) (xy 159.563023 -311.403537)
			(xy 159.514804 -311.393693) (xy 159.468788 -311.376241) (xy 159.426167 -311.351634) (xy 159.388046 -311.320509)
			(xy 159.355411 -311.283672) (xy 159.329108 -311.242076) (xy 159.309817 -311.1968) (xy 159.29804 -311.149016)
			(xy 159.29408 -311.099962) (xy 158.005272 -311.099962) (xy 158.004777 -311.124569) (xy 157.996882 -311.173146)
			(xy 157.981298 -311.219827) (xy 157.958427 -311.263404) (xy 157.928862 -311.302748) (xy 157.893369 -311.33684)
			(xy 157.852866 -311.364796) (xy 157.808404 -311.385894) (xy 157.761133 -311.399586) (xy 157.712278 -311.405518)
			(xy 157.663103 -311.403537) (xy 157.614884 -311.393693) (xy 157.568868 -311.376241) (xy 157.526247 -311.351634)
			(xy 157.488126 -311.320509) (xy 157.455491 -311.283672) (xy 157.429188 -311.242076) (xy 157.409897 -311.1968)
			(xy 157.39812 -311.149016) (xy 157.39416 -311.099962) (xy 156.105352 -311.099962) (xy 156.104857 -311.124569)
			(xy 156.096962 -311.173146) (xy 156.081378 -311.219827) (xy 156.058507 -311.263404) (xy 156.028942 -311.302748)
			(xy 155.993449 -311.33684) (xy 155.952946 -311.364796) (xy 155.908484 -311.385894) (xy 155.861213 -311.399586)
			(xy 155.812358 -311.405518) (xy 155.763183 -311.403537) (xy 155.714964 -311.393693) (xy 155.668948 -311.376241)
			(xy 155.626327 -311.351634) (xy 155.588206 -311.320509) (xy 155.555571 -311.283672) (xy 155.529268 -311.242076)
			(xy 155.509977 -311.1968) (xy 155.4982 -311.149016) (xy 155.49424 -311.099962) (xy 79.905098 -311.099962)
			(xy 79.904603 -311.124569) (xy 79.896708 -311.173146) (xy 79.881124 -311.219827) (xy 79.858253 -311.263404)
			(xy 79.828688 -311.302748) (xy 79.793195 -311.33684) (xy 79.752692 -311.364796) (xy 79.70823 -311.385894)
			(xy 79.660959 -311.399586) (xy 79.612104 -311.405518) (xy 79.562929 -311.403537) (xy 79.51471 -311.393693)
			(xy 79.468694 -311.376241) (xy 79.426073 -311.351634) (xy 79.387952 -311.320509) (xy 79.355317 -311.283672)
			(xy 79.329014 -311.242076) (xy 79.309723 -311.1968) (xy 79.297946 -311.149016) (xy 79.293986 -311.099962)
			(xy 78.005178 -311.099962) (xy 78.004683 -311.124569) (xy 77.996788 -311.173146) (xy 77.981204 -311.219827)
			(xy 77.958333 -311.263404) (xy 77.928768 -311.302748) (xy 77.893275 -311.33684) (xy 77.852772 -311.364796)
			(xy 77.80831 -311.385894) (xy 77.761039 -311.399586) (xy 77.712184 -311.405518) (xy 77.663009 -311.403537)
			(xy 77.61479 -311.393693) (xy 77.568774 -311.376241) (xy 77.526153 -311.351634) (xy 77.488032 -311.320509)
			(xy 77.455397 -311.283672) (xy 77.429094 -311.242076) (xy 77.409803 -311.1968) (xy 77.398026 -311.149016)
			(xy 77.394066 -311.099962) (xy 76.105258 -311.099962) (xy 76.104763 -311.124569) (xy 76.096868 -311.173146)
			(xy 76.081284 -311.219827) (xy 76.058413 -311.263404) (xy 76.028848 -311.302748) (xy 75.993355 -311.33684)
			(xy 75.952852 -311.364796) (xy 75.90839 -311.385894) (xy 75.861119 -311.399586) (xy 75.812264 -311.405518)
			(xy 75.763089 -311.403537) (xy 75.71487 -311.393693) (xy 75.668854 -311.376241) (xy 75.626233 -311.351634)
			(xy 75.588112 -311.320509) (xy 75.555477 -311.283672) (xy 75.529174 -311.242076) (xy 75.509883 -311.1968)
			(xy 75.498106 -311.149016) (xy 75.494146 -311.099962) (xy 74.205084 -311.099962) (xy 74.204589 -311.124569)
			(xy 74.196694 -311.173146) (xy 74.18111 -311.219827) (xy 74.158239 -311.263404) (xy 74.128674 -311.302748)
			(xy 74.093181 -311.33684) (xy 74.052678 -311.364796) (xy 74.008216 -311.385894) (xy 73.960945 -311.399586)
			(xy 73.91209 -311.405518) (xy 73.862915 -311.403537) (xy 73.814696 -311.393693) (xy 73.76868 -311.376241)
			(xy 73.726059 -311.351634) (xy 73.687938 -311.320509) (xy 73.655303 -311.283672) (xy 73.629 -311.242076)
			(xy 73.609709 -311.1968) (xy 73.597932 -311.149016) (xy 73.593972 -311.099962) (xy 57.105296 -311.099962)
			(xy 57.104801 -311.124569) (xy 57.096906 -311.173146) (xy 57.081322 -311.219827) (xy 57.058451 -311.263404)
			(xy 57.028886 -311.302748) (xy 56.993393 -311.33684) (xy 56.95289 -311.364796) (xy 56.908428 -311.385894)
			(xy 56.861157 -311.399586) (xy 56.812302 -311.405518) (xy 56.763127 -311.403537) (xy 56.714908 -311.393693)
			(xy 56.668892 -311.376241) (xy 56.626271 -311.351634) (xy 56.58815 -311.320509) (xy 56.555515 -311.283672)
			(xy 56.529212 -311.242076) (xy 56.509921 -311.1968) (xy 56.498144 -311.149016) (xy 56.494184 -311.099962)
			(xy 55.205122 -311.099962) (xy 55.204627 -311.124569) (xy 55.196732 -311.173146) (xy 55.181148 -311.219827)
			(xy 55.158277 -311.263404) (xy 55.128712 -311.302748) (xy 55.093219 -311.33684) (xy 55.052716 -311.364796)
			(xy 55.008254 -311.385894) (xy 54.960983 -311.399586) (xy 54.912128 -311.405518) (xy 54.862953 -311.403537)
			(xy 54.814734 -311.393693) (xy 54.768718 -311.376241) (xy 54.726097 -311.351634) (xy 54.687976 -311.320509)
			(xy 54.655341 -311.283672) (xy 54.629038 -311.242076) (xy 54.609747 -311.1968) (xy 54.59797 -311.149016)
			(xy 54.59401 -311.099962) (xy 53.305202 -311.099962) (xy 53.304707 -311.124569) (xy 53.296812 -311.173146)
			(xy 53.281228 -311.219827) (xy 53.258357 -311.263404) (xy 53.228792 -311.302748) (xy 53.193299 -311.33684)
			(xy 53.152796 -311.364796) (xy 53.108334 -311.385894) (xy 53.061063 -311.399586) (xy 53.012208 -311.405518)
			(xy 52.963033 -311.403537) (xy 52.914814 -311.393693) (xy 52.868798 -311.376241) (xy 52.826177 -311.351634)
			(xy 52.788056 -311.320509) (xy 52.755421 -311.283672) (xy 52.729118 -311.242076) (xy 52.709827 -311.1968)
			(xy 52.69805 -311.149016) (xy 52.69409 -311.099962) (xy 51.405282 -311.099962) (xy 51.404787 -311.124569)
			(xy 51.396892 -311.173146) (xy 51.381308 -311.219827) (xy 51.358437 -311.263404) (xy 51.328872 -311.302748)
			(xy 51.293379 -311.33684) (xy 51.252876 -311.364796) (xy 51.208414 -311.385894) (xy 51.161143 -311.399586)
			(xy 51.112288 -311.405518) (xy 51.063113 -311.403537) (xy 51.014894 -311.393693) (xy 50.968878 -311.376241)
			(xy 50.926257 -311.351634) (xy 50.888136 -311.320509) (xy 50.855501 -311.283672) (xy 50.829198 -311.242076)
			(xy 50.809907 -311.1968) (xy 50.79813 -311.149016) (xy 50.79417 -311.099962) (xy 49.505108 -311.099962)
			(xy 49.504613 -311.124569) (xy 49.496718 -311.173146) (xy 49.481134 -311.219827) (xy 49.458263 -311.263404)
			(xy 49.428698 -311.302748) (xy 49.393205 -311.33684) (xy 49.352702 -311.364796) (xy 49.30824 -311.385894)
			(xy 49.260969 -311.399586) (xy 49.212114 -311.405518) (xy 49.162939 -311.403537) (xy 49.11472 -311.393693)
			(xy 49.068704 -311.376241) (xy 49.026083 -311.351634) (xy 48.987962 -311.320509) (xy 48.955327 -311.283672)
			(xy 48.929024 -311.242076) (xy 48.909733 -311.1968) (xy 48.897956 -311.149016) (xy 48.893996 -311.099962)
			(xy 47.605188 -311.099962) (xy 47.604693 -311.124569) (xy 47.596798 -311.173146) (xy 47.581214 -311.219827)
			(xy 47.558343 -311.263404) (xy 47.528778 -311.302748) (xy 47.493285 -311.33684) (xy 47.452782 -311.364796)
			(xy 47.40832 -311.385894) (xy 47.361049 -311.399586) (xy 47.312194 -311.405518) (xy 47.263019 -311.403537)
			(xy 47.2148 -311.393693) (xy 47.168784 -311.376241) (xy 47.126163 -311.351634) (xy 47.088042 -311.320509)
			(xy 47.055407 -311.283672) (xy 47.029104 -311.242076) (xy 47.009813 -311.1968) (xy 46.998036 -311.149016)
			(xy 46.994076 -311.099962) (xy 45.705268 -311.099962) (xy 45.704773 -311.124569) (xy 45.696878 -311.173146)
			(xy 45.681294 -311.219827) (xy 45.658423 -311.263404) (xy 45.628858 -311.302748) (xy 45.593365 -311.33684)
			(xy 45.552862 -311.364796) (xy 45.5084 -311.385894) (xy 45.461129 -311.399586) (xy 45.412274 -311.405518)
			(xy 45.363099 -311.403537) (xy 45.31488 -311.393693) (xy 45.268864 -311.376241) (xy 45.226243 -311.351634)
			(xy 45.188122 -311.320509) (xy 45.155487 -311.283672) (xy 45.129184 -311.242076) (xy 45.109893 -311.1968)
			(xy 45.098116 -311.149016) (xy 45.094156 -311.099962) (xy 43.805094 -311.099962) (xy 43.804599 -311.124569)
			(xy 43.796704 -311.173146) (xy 43.78112 -311.219827) (xy 43.758249 -311.263404) (xy 43.728684 -311.302748)
			(xy 43.693191 -311.33684) (xy 43.652688 -311.364796) (xy 43.608226 -311.385894) (xy 43.560955 -311.399586)
			(xy 43.5121 -311.405518) (xy 43.462925 -311.403537) (xy 43.414706 -311.393693) (xy 43.36869 -311.376241)
			(xy 43.326069 -311.351634) (xy 43.287948 -311.320509) (xy 43.255313 -311.283672) (xy 43.22901 -311.242076)
			(xy 43.209719 -311.1968) (xy 43.197942 -311.149016) (xy 43.193982 -311.099962) (xy 0.508 -311.099962)
			(xy 0.508 -312.049922) (xy 43.193982 -312.049922) (xy 43.197942 -312.000868) (xy 43.209719 -311.953084)
			(xy 43.22901 -311.907808) (xy 43.255313 -311.866212) (xy 43.287948 -311.829375) (xy 43.326069 -311.79825)
			(xy 43.36869 -311.773643) (xy 43.414706 -311.756191) (xy 43.462925 -311.746347) (xy 43.5121 -311.744366)
			(xy 43.560955 -311.750298) (xy 43.608226 -311.76399) (xy 43.652688 -311.785088) (xy 43.693191 -311.813044)
			(xy 43.728684 -311.847136) (xy 43.758249 -311.88648) (xy 43.78112 -311.930057) (xy 43.796704 -311.976738)
			(xy 43.804599 -312.025315) (xy 43.805094 -312.049922) (xy 45.094156 -312.049922) (xy 45.098116 -312.000868)
			(xy 45.109893 -311.953084) (xy 45.129184 -311.907808) (xy 45.155487 -311.866212) (xy 45.188122 -311.829375)
			(xy 45.226243 -311.79825) (xy 45.268864 -311.773643) (xy 45.31488 -311.756191) (xy 45.363099 -311.746347)
			(xy 45.412274 -311.744366) (xy 45.461129 -311.750298) (xy 45.5084 -311.76399) (xy 45.552862 -311.785088)
			(xy 45.593365 -311.813044) (xy 45.628858 -311.847136) (xy 45.658423 -311.88648) (xy 45.681294 -311.930057)
			(xy 45.696878 -311.976738) (xy 45.704773 -312.025315) (xy 45.705268 -312.049922) (xy 46.994076 -312.049922)
			(xy 46.998036 -312.000868) (xy 47.009813 -311.953084) (xy 47.029104 -311.907808) (xy 47.055407 -311.866212)
			(xy 47.088042 -311.829375) (xy 47.126163 -311.79825) (xy 47.168784 -311.773643) (xy 47.2148 -311.756191)
			(xy 47.263019 -311.746347) (xy 47.312194 -311.744366) (xy 47.361049 -311.750298) (xy 47.40832 -311.76399)
			(xy 47.452782 -311.785088) (xy 47.493285 -311.813044) (xy 47.528778 -311.847136) (xy 47.558343 -311.88648)
			(xy 47.581214 -311.930057) (xy 47.596798 -311.976738) (xy 47.604693 -312.025315) (xy 47.605188 -312.049922)
			(xy 48.893996 -312.049922) (xy 48.897956 -312.000868) (xy 48.909733 -311.953084) (xy 48.929024 -311.907808)
			(xy 48.955327 -311.866212) (xy 48.987962 -311.829375) (xy 49.026083 -311.79825) (xy 49.068704 -311.773643)
			(xy 49.11472 -311.756191) (xy 49.162939 -311.746347) (xy 49.212114 -311.744366) (xy 49.260969 -311.750298)
			(xy 49.30824 -311.76399) (xy 49.352702 -311.785088) (xy 49.393205 -311.813044) (xy 49.428698 -311.847136)
			(xy 49.458263 -311.88648) (xy 49.481134 -311.930057) (xy 49.496718 -311.976738) (xy 49.504613 -312.025315)
			(xy 49.505108 -312.049922) (xy 50.79417 -312.049922) (xy 50.79813 -312.000868) (xy 50.809907 -311.953084)
			(xy 50.829198 -311.907808) (xy 50.855501 -311.866212) (xy 50.888136 -311.829375) (xy 50.926257 -311.79825)
			(xy 50.968878 -311.773643) (xy 51.014894 -311.756191) (xy 51.063113 -311.746347) (xy 51.112288 -311.744366)
			(xy 51.161143 -311.750298) (xy 51.208414 -311.76399) (xy 51.252876 -311.785088) (xy 51.293379 -311.813044)
			(xy 51.328872 -311.847136) (xy 51.358437 -311.88648) (xy 51.381308 -311.930057) (xy 51.396892 -311.976738)
			(xy 51.404787 -312.025315) (xy 51.405282 -312.049922) (xy 52.69409 -312.049922) (xy 52.69805 -312.000868)
			(xy 52.709827 -311.953084) (xy 52.729118 -311.907808) (xy 52.755421 -311.866212) (xy 52.788056 -311.829375)
			(xy 52.826177 -311.79825) (xy 52.868798 -311.773643) (xy 52.914814 -311.756191) (xy 52.963033 -311.746347)
			(xy 53.012208 -311.744366) (xy 53.061063 -311.750298) (xy 53.108334 -311.76399) (xy 53.152796 -311.785088)
			(xy 53.193299 -311.813044) (xy 53.228792 -311.847136) (xy 53.258357 -311.88648) (xy 53.281228 -311.930057)
			(xy 53.296812 -311.976738) (xy 53.304707 -312.025315) (xy 53.305202 -312.049922) (xy 54.59401 -312.049922)
			(xy 54.59797 -312.000868) (xy 54.609747 -311.953084) (xy 54.629038 -311.907808) (xy 54.655341 -311.866212)
			(xy 54.687976 -311.829375) (xy 54.726097 -311.79825) (xy 54.768718 -311.773643) (xy 54.814734 -311.756191)
			(xy 54.862953 -311.746347) (xy 54.912128 -311.744366) (xy 54.960983 -311.750298) (xy 55.008254 -311.76399)
			(xy 55.052716 -311.785088) (xy 55.093219 -311.813044) (xy 55.128712 -311.847136) (xy 55.158277 -311.88648)
			(xy 55.181148 -311.930057) (xy 55.196732 -311.976738) (xy 55.204627 -312.025315) (xy 55.205122 -312.049922)
			(xy 56.494184 -312.049922) (xy 56.498144 -312.000868) (xy 56.509921 -311.953084) (xy 56.529212 -311.907808)
			(xy 56.555515 -311.866212) (xy 56.58815 -311.829375) (xy 56.626271 -311.79825) (xy 56.668892 -311.773643)
			(xy 56.714908 -311.756191) (xy 56.763127 -311.746347) (xy 56.812302 -311.744366) (xy 56.861157 -311.750298)
			(xy 56.908428 -311.76399) (xy 56.95289 -311.785088) (xy 56.993393 -311.813044) (xy 57.028886 -311.847136)
			(xy 57.058451 -311.88648) (xy 57.081322 -311.930057) (xy 57.096906 -311.976738) (xy 57.104801 -312.025315)
			(xy 57.105296 -312.049922) (xy 73.593972 -312.049922) (xy 73.597932 -312.000868) (xy 73.609709 -311.953084)
			(xy 73.629 -311.907808) (xy 73.655303 -311.866212) (xy 73.687938 -311.829375) (xy 73.726059 -311.79825)
			(xy 73.76868 -311.773643) (xy 73.814696 -311.756191) (xy 73.862915 -311.746347) (xy 73.91209 -311.744366)
			(xy 73.960945 -311.750298) (xy 74.008216 -311.76399) (xy 74.052678 -311.785088) (xy 74.093181 -311.813044)
			(xy 74.128674 -311.847136) (xy 74.158239 -311.88648) (xy 74.18111 -311.930057) (xy 74.196694 -311.976738)
			(xy 74.204589 -312.025315) (xy 74.205084 -312.049922) (xy 75.494146 -312.049922) (xy 75.498106 -312.000868)
			(xy 75.509883 -311.953084) (xy 75.529174 -311.907808) (xy 75.555477 -311.866212) (xy 75.588112 -311.829375)
			(xy 75.626233 -311.79825) (xy 75.668854 -311.773643) (xy 75.71487 -311.756191) (xy 75.763089 -311.746347)
			(xy 75.812264 -311.744366) (xy 75.861119 -311.750298) (xy 75.90839 -311.76399) (xy 75.952852 -311.785088)
			(xy 75.993355 -311.813044) (xy 76.028848 -311.847136) (xy 76.058413 -311.88648) (xy 76.081284 -311.930057)
			(xy 76.096868 -311.976738) (xy 76.104763 -312.025315) (xy 76.105258 -312.049922) (xy 77.394066 -312.049922)
			(xy 77.398026 -312.000868) (xy 77.409803 -311.953084) (xy 77.429094 -311.907808) (xy 77.455397 -311.866212)
			(xy 77.488032 -311.829375) (xy 77.526153 -311.79825) (xy 77.568774 -311.773643) (xy 77.61479 -311.756191)
			(xy 77.663009 -311.746347) (xy 77.712184 -311.744366) (xy 77.761039 -311.750298) (xy 77.80831 -311.76399)
			(xy 77.852772 -311.785088) (xy 77.893275 -311.813044) (xy 77.928768 -311.847136) (xy 77.958333 -311.88648)
			(xy 77.981204 -311.930057) (xy 77.996788 -311.976738) (xy 78.004683 -312.025315) (xy 78.005178 -312.049922)
			(xy 79.293986 -312.049922) (xy 79.297946 -312.000868) (xy 79.309723 -311.953084) (xy 79.329014 -311.907808)
			(xy 79.355317 -311.866212) (xy 79.387952 -311.829375) (xy 79.426073 -311.79825) (xy 79.468694 -311.773643)
			(xy 79.51471 -311.756191) (xy 79.562929 -311.746347) (xy 79.612104 -311.744366) (xy 79.660959 -311.750298)
			(xy 79.70823 -311.76399) (xy 79.752692 -311.785088) (xy 79.793195 -311.813044) (xy 79.828688 -311.847136)
			(xy 79.858253 -311.88648) (xy 79.881124 -311.930057) (xy 79.896708 -311.976738) (xy 79.904603 -312.025315)
			(xy 79.905098 -312.049922) (xy 81.19416 -312.049922) (xy 81.19812 -312.000868) (xy 81.209897 -311.953084)
			(xy 81.229188 -311.907808) (xy 81.255491 -311.866212) (xy 81.288126 -311.829375) (xy 81.326247 -311.79825)
			(xy 81.368868 -311.773643) (xy 81.414884 -311.756191) (xy 81.463103 -311.746347) (xy 81.512278 -311.744366)
			(xy 81.561133 -311.750298) (xy 81.608404 -311.76399) (xy 81.652866 -311.785088) (xy 81.693369 -311.813044)
			(xy 81.728862 -311.847136) (xy 81.758427 -311.88648) (xy 81.781298 -311.930057) (xy 81.796882 -311.976738)
			(xy 81.804777 -312.025315) (xy 81.805272 -312.049922) (xy 82.14412 -312.049922) (xy 82.14808 -312.000868)
			(xy 82.159857 -311.953084) (xy 82.179148 -311.907808) (xy 82.205451 -311.866212) (xy 82.238086 -311.829375)
			(xy 82.276207 -311.79825) (xy 82.318828 -311.773643) (xy 82.364844 -311.756191) (xy 82.413063 -311.746347)
			(xy 82.462238 -311.744366) (xy 82.511093 -311.750298) (xy 82.558364 -311.76399) (xy 82.602826 -311.785088)
			(xy 82.643329 -311.813044) (xy 82.678822 -311.847136) (xy 82.708387 -311.88648) (xy 82.731258 -311.930057)
			(xy 82.746842 -311.976738) (xy 82.754737 -312.025315) (xy 82.755232 -312.049922) (xy 152.644106 -312.049922)
			(xy 152.648066 -312.000868) (xy 152.659843 -311.953084) (xy 152.679134 -311.907808) (xy 152.705437 -311.866212)
			(xy 152.738072 -311.829375) (xy 152.776193 -311.79825) (xy 152.818814 -311.773643) (xy 152.86483 -311.756191)
			(xy 152.913049 -311.746347) (xy 152.962224 -311.744366) (xy 153.011079 -311.750298) (xy 153.05835 -311.76399)
			(xy 153.102812 -311.785088) (xy 153.143315 -311.813044) (xy 153.178808 -311.847136) (xy 153.208373 -311.88648)
			(xy 153.231244 -311.930057) (xy 153.246828 -311.976738) (xy 153.254723 -312.025315) (xy 153.255218 -312.049922)
			(xy 153.594066 -312.049922) (xy 153.598026 -312.000868) (xy 153.609803 -311.953084) (xy 153.629094 -311.907808)
			(xy 153.655397 -311.866212) (xy 153.688032 -311.829375) (xy 153.726153 -311.79825) (xy 153.768774 -311.773643)
			(xy 153.81479 -311.756191) (xy 153.863009 -311.746347) (xy 153.912184 -311.744366) (xy 153.961039 -311.750298)
			(xy 154.00831 -311.76399) (xy 154.052772 -311.785088) (xy 154.093275 -311.813044) (xy 154.128768 -311.847136)
			(xy 154.158333 -311.88648) (xy 154.181204 -311.930057) (xy 154.196788 -311.976738) (xy 154.204683 -312.025315)
			(xy 154.205178 -312.049922) (xy 155.49424 -312.049922) (xy 155.4982 -312.000868) (xy 155.509977 -311.953084)
			(xy 155.529268 -311.907808) (xy 155.555571 -311.866212) (xy 155.588206 -311.829375) (xy 155.626327 -311.79825)
			(xy 155.668948 -311.773643) (xy 155.714964 -311.756191) (xy 155.763183 -311.746347) (xy 155.812358 -311.744366)
			(xy 155.861213 -311.750298) (xy 155.908484 -311.76399) (xy 155.952946 -311.785088) (xy 155.993449 -311.813044)
			(xy 156.028942 -311.847136) (xy 156.058507 -311.88648) (xy 156.081378 -311.930057) (xy 156.096962 -311.976738)
			(xy 156.104857 -312.025315) (xy 156.105352 -312.049922) (xy 157.39416 -312.049922) (xy 157.39812 -312.000868)
			(xy 157.409897 -311.953084) (xy 157.429188 -311.907808) (xy 157.455491 -311.866212) (xy 157.488126 -311.829375)
			(xy 157.526247 -311.79825) (xy 157.568868 -311.773643) (xy 157.614884 -311.756191) (xy 157.663103 -311.746347)
			(xy 157.712278 -311.744366) (xy 157.761133 -311.750298) (xy 157.808404 -311.76399) (xy 157.852866 -311.785088)
			(xy 157.893369 -311.813044) (xy 157.928862 -311.847136) (xy 157.958427 -311.88648) (xy 157.981298 -311.930057)
			(xy 157.996882 -311.976738) (xy 158.004777 -312.025315) (xy 158.005272 -312.049922) (xy 159.29408 -312.049922)
			(xy 159.29804 -312.000868) (xy 159.309817 -311.953084) (xy 159.329108 -311.907808) (xy 159.355411 -311.866212)
			(xy 159.388046 -311.829375) (xy 159.426167 -311.79825) (xy 159.468788 -311.773643) (xy 159.514804 -311.756191)
			(xy 159.563023 -311.746347) (xy 159.612198 -311.744366) (xy 159.661053 -311.750298) (xy 159.708324 -311.76399)
			(xy 159.752786 -311.785088) (xy 159.793289 -311.813044) (xy 159.828782 -311.847136) (xy 159.858347 -311.88648)
			(xy 159.881218 -311.930057) (xy 159.896802 -311.976738) (xy 159.904697 -312.025315) (xy 159.905192 -312.049922)
			(xy 161.194254 -312.049922) (xy 161.198214 -312.000868) (xy 161.209991 -311.953084) (xy 161.229282 -311.907808)
			(xy 161.255585 -311.866212) (xy 161.28822 -311.829375) (xy 161.326341 -311.79825) (xy 161.368962 -311.773643)
			(xy 161.414978 -311.756191) (xy 161.463197 -311.746347) (xy 161.512372 -311.744366) (xy 161.561227 -311.750298)
			(xy 161.608498 -311.76399) (xy 161.65296 -311.785088) (xy 161.693463 -311.813044) (xy 161.728956 -311.847136)
			(xy 161.758521 -311.88648) (xy 161.781392 -311.930057) (xy 161.796976 -311.976738) (xy 161.804871 -312.025315)
			(xy 161.805366 -312.049922) (xy 163.094174 -312.049922) (xy 163.098134 -312.000868) (xy 163.109911 -311.953084)
			(xy 163.129202 -311.907808) (xy 163.155505 -311.866212) (xy 163.18814 -311.829375) (xy 163.226261 -311.79825)
			(xy 163.268882 -311.773643) (xy 163.314898 -311.756191) (xy 163.363117 -311.746347) (xy 163.412292 -311.744366)
			(xy 163.461147 -311.750298) (xy 163.508418 -311.76399) (xy 163.55288 -311.785088) (xy 163.593383 -311.813044)
			(xy 163.628876 -311.847136) (xy 163.658441 -311.88648) (xy 163.681312 -311.930057) (xy 163.696896 -311.976738)
			(xy 163.704791 -312.025315) (xy 163.705286 -312.049922) (xy 164.994094 -312.049922) (xy 164.998054 -312.000868)
			(xy 165.009831 -311.953084) (xy 165.029122 -311.907808) (xy 165.055425 -311.866212) (xy 165.08806 -311.829375)
			(xy 165.126181 -311.79825) (xy 165.168802 -311.773643) (xy 165.214818 -311.756191) (xy 165.263037 -311.746347)
			(xy 165.312212 -311.744366) (xy 165.361067 -311.750298) (xy 165.408338 -311.76399) (xy 165.4528 -311.785088)
			(xy 165.493303 -311.813044) (xy 165.528796 -311.847136) (xy 165.558361 -311.88648) (xy 165.581232 -311.930057)
			(xy 165.596816 -311.976738) (xy 165.604711 -312.025315) (xy 165.605206 -312.049922) (xy 182.094136 -312.049922)
			(xy 182.098096 -312.000868) (xy 182.109873 -311.953084) (xy 182.129164 -311.907808) (xy 182.155467 -311.866212)
			(xy 182.188102 -311.829375) (xy 182.226223 -311.79825) (xy 182.268844 -311.773643) (xy 182.31486 -311.756191)
			(xy 182.363079 -311.746347) (xy 182.412254 -311.744366) (xy 182.461109 -311.750298) (xy 182.50838 -311.76399)
			(xy 182.552842 -311.785088) (xy 182.593345 -311.813044) (xy 182.628838 -311.847136) (xy 182.658403 -311.88648)
			(xy 182.681274 -311.930057) (xy 182.696858 -311.976738) (xy 182.704753 -312.025315) (xy 182.705248 -312.049922)
			(xy 183.994056 -312.049922) (xy 183.998016 -312.000868) (xy 184.009793 -311.953084) (xy 184.029084 -311.907808)
			(xy 184.055387 -311.866212) (xy 184.088022 -311.829375) (xy 184.126143 -311.79825) (xy 184.168764 -311.773643)
			(xy 184.21478 -311.756191) (xy 184.262999 -311.746347) (xy 184.312174 -311.744366) (xy 184.361029 -311.750298)
			(xy 184.4083 -311.76399) (xy 184.452762 -311.785088) (xy 184.493265 -311.813044) (xy 184.528758 -311.847136)
			(xy 184.558323 -311.88648) (xy 184.581194 -311.930057) (xy 184.596778 -311.976738) (xy 184.604673 -312.025315)
			(xy 184.605168 -312.049922) (xy 185.89423 -312.049922) (xy 185.89819 -312.000868) (xy 185.909967 -311.953084)
			(xy 185.929258 -311.907808) (xy 185.955561 -311.866212) (xy 185.988196 -311.829375) (xy 186.026317 -311.79825)
			(xy 186.068938 -311.773643) (xy 186.114954 -311.756191) (xy 186.163173 -311.746347) (xy 186.212348 -311.744366)
			(xy 186.261203 -311.750298) (xy 186.308474 -311.76399) (xy 186.352936 -311.785088) (xy 186.393439 -311.813044)
			(xy 186.428932 -311.847136) (xy 186.458497 -311.88648) (xy 186.481368 -311.930057) (xy 186.496952 -311.976738)
			(xy 186.504847 -312.025315) (xy 186.505342 -312.049922) (xy 187.79415 -312.049922) (xy 187.79811 -312.000868)
			(xy 187.809887 -311.953084) (xy 187.829178 -311.907808) (xy 187.855481 -311.866212) (xy 187.888116 -311.829375)
			(xy 187.926237 -311.79825) (xy 187.968858 -311.773643) (xy 188.014874 -311.756191) (xy 188.063093 -311.746347)
			(xy 188.112268 -311.744366) (xy 188.161123 -311.750298) (xy 188.208394 -311.76399) (xy 188.252856 -311.785088)
			(xy 188.293359 -311.813044) (xy 188.328852 -311.847136) (xy 188.358417 -311.88648) (xy 188.381288 -311.930057)
			(xy 188.396872 -311.976738) (xy 188.404767 -312.025315) (xy 188.405262 -312.049922) (xy 275.393924 -312.049922)
			(xy 275.397884 -312.000868) (xy 275.409661 -311.953084) (xy 275.428952 -311.907808) (xy 275.455255 -311.866212)
			(xy 275.48789 -311.829375) (xy 275.526011 -311.79825) (xy 275.568632 -311.773643) (xy 275.614648 -311.756191)
			(xy 275.662867 -311.746347) (xy 275.712042 -311.744366) (xy 275.760897 -311.750298) (xy 275.808168 -311.76399)
			(xy 275.85263 -311.785088) (xy 275.893133 -311.813044) (xy 275.928626 -311.847136) (xy 275.958191 -311.88648)
			(xy 275.981062 -311.930057) (xy 275.996646 -311.976738) (xy 276.004541 -312.025315) (xy 276.005036 -312.049922)
			(xy 277.294098 -312.049922) (xy 277.298058 -312.000868) (xy 277.309835 -311.953084) (xy 277.329126 -311.907808)
			(xy 277.355429 -311.866212) (xy 277.388064 -311.829375) (xy 277.426185 -311.79825) (xy 277.468806 -311.773643)
			(xy 277.514822 -311.756191) (xy 277.563041 -311.746347) (xy 277.612216 -311.744366) (xy 277.661071 -311.750298)
			(xy 277.708342 -311.76399) (xy 277.752804 -311.785088) (xy 277.793307 -311.813044) (xy 277.8288 -311.847136)
			(xy 277.858365 -311.88648) (xy 277.881236 -311.930057) (xy 277.89682 -311.976738) (xy 277.904715 -312.025315)
			(xy 277.90521 -312.049922) (xy 279.194018 -312.049922) (xy 279.197978 -312.000868) (xy 279.209755 -311.953084)
			(xy 279.229046 -311.907808) (xy 279.255349 -311.866212) (xy 279.287984 -311.829375) (xy 279.326105 -311.79825)
			(xy 279.368726 -311.773643) (xy 279.414742 -311.756191) (xy 279.462961 -311.746347) (xy 279.512136 -311.744366)
			(xy 279.560991 -311.750298) (xy 279.608262 -311.76399) (xy 279.652724 -311.785088) (xy 279.693227 -311.813044)
			(xy 279.72872 -311.847136) (xy 279.758285 -311.88648) (xy 279.781156 -311.930057) (xy 279.79674 -311.976738)
			(xy 279.804635 -312.025315) (xy 279.80513 -312.049922) (xy 281.093938 -312.049922) (xy 281.097898 -312.000868)
			(xy 281.109675 -311.953084) (xy 281.128966 -311.907808) (xy 281.155269 -311.866212) (xy 281.187904 -311.829375)
			(xy 281.226025 -311.79825) (xy 281.268646 -311.773643) (xy 281.314662 -311.756191) (xy 281.362881 -311.746347)
			(xy 281.412056 -311.744366) (xy 281.460911 -311.750298) (xy 281.508182 -311.76399) (xy 281.552644 -311.785088)
			(xy 281.593147 -311.813044) (xy 281.62864 -311.847136) (xy 281.658205 -311.88648) (xy 281.681076 -311.930057)
			(xy 281.69666 -311.976738) (xy 281.704555 -312.025315) (xy 281.70505 -312.049922) (xy 282.994112 -312.049922)
			(xy 282.998072 -312.000868) (xy 283.009849 -311.953084) (xy 283.02914 -311.907808) (xy 283.055443 -311.866212)
			(xy 283.088078 -311.829375) (xy 283.126199 -311.79825) (xy 283.16882 -311.773643) (xy 283.214836 -311.756191)
			(xy 283.263055 -311.746347) (xy 283.31223 -311.744366) (xy 283.361085 -311.750298) (xy 283.408356 -311.76399)
			(xy 283.452818 -311.785088) (xy 283.493321 -311.813044) (xy 283.528814 -311.847136) (xy 283.558379 -311.88648)
			(xy 283.58125 -311.930057) (xy 283.596834 -311.976738) (xy 283.604729 -312.025315) (xy 283.605224 -312.049922)
			(xy 284.894032 -312.049922) (xy 284.897992 -312.000868) (xy 284.909769 -311.953084) (xy 284.92906 -311.907808)
			(xy 284.955363 -311.866212) (xy 284.987998 -311.829375) (xy 285.026119 -311.79825) (xy 285.06874 -311.773643)
			(xy 285.114756 -311.756191) (xy 285.162975 -311.746347) (xy 285.21215 -311.744366) (xy 285.261005 -311.750298)
			(xy 285.308276 -311.76399) (xy 285.352738 -311.785088) (xy 285.393241 -311.813044) (xy 285.428734 -311.847136)
			(xy 285.458299 -311.88648) (xy 285.48117 -311.930057) (xy 285.496754 -311.976738) (xy 285.504649 -312.025315)
			(xy 285.505144 -312.049922) (xy 286.793952 -312.049922) (xy 286.797912 -312.000868) (xy 286.809689 -311.953084)
			(xy 286.82898 -311.907808) (xy 286.855283 -311.866212) (xy 286.887918 -311.829375) (xy 286.926039 -311.79825)
			(xy 286.96866 -311.773643) (xy 287.014676 -311.756191) (xy 287.062895 -311.746347) (xy 287.11207 -311.744366)
			(xy 287.160925 -311.750298) (xy 287.208196 -311.76399) (xy 287.252658 -311.785088) (xy 287.293161 -311.813044)
			(xy 287.328654 -311.847136) (xy 287.358219 -311.88648) (xy 287.38109 -311.930057) (xy 287.396674 -311.976738)
			(xy 287.404569 -312.025315) (xy 287.405064 -312.049922) (xy 288.694126 -312.049922) (xy 288.698086 -312.000868)
			(xy 288.709863 -311.953084) (xy 288.729154 -311.907808) (xy 288.755457 -311.866212) (xy 288.788092 -311.829375)
			(xy 288.826213 -311.79825) (xy 288.868834 -311.773643) (xy 288.91485 -311.756191) (xy 288.963069 -311.746347)
			(xy 289.012244 -311.744366) (xy 289.061099 -311.750298) (xy 289.10837 -311.76399) (xy 289.152832 -311.785088)
			(xy 289.193335 -311.813044) (xy 289.228828 -311.847136) (xy 289.258393 -311.88648) (xy 289.281264 -311.930057)
			(xy 289.296848 -311.976738) (xy 289.304743 -312.025315) (xy 289.305238 -312.049922) (xy 305.793914 -312.049922)
			(xy 305.797874 -312.000868) (xy 305.809651 -311.953084) (xy 305.828942 -311.907808) (xy 305.855245 -311.866212)
			(xy 305.88788 -311.829375) (xy 305.926001 -311.79825) (xy 305.968622 -311.773643) (xy 306.014638 -311.756191)
			(xy 306.062857 -311.746347) (xy 306.112032 -311.744366) (xy 306.160887 -311.750298) (xy 306.208158 -311.76399)
			(xy 306.25262 -311.785088) (xy 306.293123 -311.813044) (xy 306.328616 -311.847136) (xy 306.358181 -311.88648)
			(xy 306.381052 -311.930057) (xy 306.396636 -311.976738) (xy 306.404531 -312.025315) (xy 306.405026 -312.049922)
			(xy 307.694088 -312.049922) (xy 307.698048 -312.000868) (xy 307.709825 -311.953084) (xy 307.729116 -311.907808)
			(xy 307.755419 -311.866212) (xy 307.788054 -311.829375) (xy 307.826175 -311.79825) (xy 307.868796 -311.773643)
			(xy 307.914812 -311.756191) (xy 307.963031 -311.746347) (xy 308.012206 -311.744366) (xy 308.061061 -311.750298)
			(xy 308.108332 -311.76399) (xy 308.152794 -311.785088) (xy 308.193297 -311.813044) (xy 308.22879 -311.847136)
			(xy 308.258355 -311.88648) (xy 308.281226 -311.930057) (xy 308.29681 -311.976738) (xy 308.304705 -312.025315)
			(xy 308.3052 -312.049922) (xy 309.594008 -312.049922) (xy 309.597968 -312.000868) (xy 309.609745 -311.953084)
			(xy 309.629036 -311.907808) (xy 309.655339 -311.866212) (xy 309.687974 -311.829375) (xy 309.726095 -311.79825)
			(xy 309.768716 -311.773643) (xy 309.814732 -311.756191) (xy 309.862951 -311.746347) (xy 309.912126 -311.744366)
			(xy 309.960981 -311.750298) (xy 310.008252 -311.76399) (xy 310.052714 -311.785088) (xy 310.093217 -311.813044)
			(xy 310.12871 -311.847136) (xy 310.158275 -311.88648) (xy 310.181146 -311.930057) (xy 310.19673 -311.976738)
			(xy 310.204625 -312.025315) (xy 310.20512 -312.049922) (xy 311.493928 -312.049922) (xy 311.497888 -312.000868)
			(xy 311.509665 -311.953084) (xy 311.528956 -311.907808) (xy 311.555259 -311.866212) (xy 311.587894 -311.829375)
			(xy 311.626015 -311.79825) (xy 311.668636 -311.773643) (xy 311.714652 -311.756191) (xy 311.762871 -311.746347)
			(xy 311.812046 -311.744366) (xy 311.860901 -311.750298) (xy 311.908172 -311.76399) (xy 311.952634 -311.785088)
			(xy 311.993137 -311.813044) (xy 312.02863 -311.847136) (xy 312.058195 -311.88648) (xy 312.081066 -311.930057)
			(xy 312.09665 -311.976738) (xy 312.104545 -312.025315) (xy 312.10504 -312.049922) (xy 313.394102 -312.049922)
			(xy 313.398062 -312.000868) (xy 313.409839 -311.953084) (xy 313.42913 -311.907808) (xy 313.455433 -311.866212)
			(xy 313.488068 -311.829375) (xy 313.526189 -311.79825) (xy 313.56881 -311.773643) (xy 313.614826 -311.756191)
			(xy 313.663045 -311.746347) (xy 313.71222 -311.744366) (xy 313.761075 -311.750298) (xy 313.808346 -311.76399)
			(xy 313.852808 -311.785088) (xy 313.893311 -311.813044) (xy 313.928804 -311.847136) (xy 313.958369 -311.88648)
			(xy 313.98124 -311.930057) (xy 313.996824 -311.976738) (xy 314.004719 -312.025315) (xy 314.005214 -312.049922)
			(xy 314.344062 -312.049922) (xy 314.348022 -312.000868) (xy 314.359799 -311.953084) (xy 314.37909 -311.907808)
			(xy 314.405393 -311.866212) (xy 314.438028 -311.829375) (xy 314.476149 -311.79825) (xy 314.51877 -311.773643)
			(xy 314.564786 -311.756191) (xy 314.613005 -311.746347) (xy 314.66218 -311.744366) (xy 314.711035 -311.750298)
			(xy 314.758306 -311.76399) (xy 314.802768 -311.785088) (xy 314.843271 -311.813044) (xy 314.878764 -311.847136)
			(xy 314.908329 -311.88648) (xy 314.9312 -311.930057) (xy 314.946784 -311.976738) (xy 314.954679 -312.025315)
			(xy 314.955174 -312.049922) (xy 384.844048 -312.049922) (xy 384.848008 -312.000868) (xy 384.859785 -311.953084)
			(xy 384.879076 -311.907808) (xy 384.905379 -311.866212) (xy 384.938014 -311.829375) (xy 384.976135 -311.79825)
			(xy 385.018756 -311.773643) (xy 385.064772 -311.756191) (xy 385.112991 -311.746347) (xy 385.162166 -311.744366)
			(xy 385.211021 -311.750298) (xy 385.258292 -311.76399) (xy 385.302754 -311.785088) (xy 385.343257 -311.813044)
			(xy 385.37875 -311.847136) (xy 385.408315 -311.88648) (xy 385.431186 -311.930057) (xy 385.44677 -311.976738)
			(xy 385.454665 -312.025315) (xy 385.45516 -312.049922) (xy 385.794008 -312.049922) (xy 385.797968 -312.000868)
			(xy 385.809745 -311.953084) (xy 385.829036 -311.907808) (xy 385.855339 -311.866212) (xy 385.887974 -311.829375)
			(xy 385.926095 -311.79825) (xy 385.968716 -311.773643) (xy 386.014732 -311.756191) (xy 386.062951 -311.746347)
			(xy 386.112126 -311.744366) (xy 386.160981 -311.750298) (xy 386.208252 -311.76399) (xy 386.252714 -311.785088)
			(xy 386.293217 -311.813044) (xy 386.32871 -311.847136) (xy 386.358275 -311.88648) (xy 386.381146 -311.930057)
			(xy 386.39673 -311.976738) (xy 386.404625 -312.025315) (xy 386.40512 -312.049922) (xy 387.694182 -312.049922)
			(xy 387.698142 -312.000868) (xy 387.709919 -311.953084) (xy 387.72921 -311.907808) (xy 387.755513 -311.866212)
			(xy 387.788148 -311.829375) (xy 387.826269 -311.79825) (xy 387.86889 -311.773643) (xy 387.914906 -311.756191)
			(xy 387.963125 -311.746347) (xy 388.0123 -311.744366) (xy 388.061155 -311.750298) (xy 388.108426 -311.76399)
			(xy 388.152888 -311.785088) (xy 388.193391 -311.813044) (xy 388.228884 -311.847136) (xy 388.258449 -311.88648)
			(xy 388.28132 -311.930057) (xy 388.296904 -311.976738) (xy 388.304799 -312.025315) (xy 388.305294 -312.049922)
			(xy 389.594102 -312.049922) (xy 389.598062 -312.000868) (xy 389.609839 -311.953084) (xy 389.62913 -311.907808)
			(xy 389.655433 -311.866212) (xy 389.688068 -311.829375) (xy 389.726189 -311.79825) (xy 389.76881 -311.773643)
			(xy 389.814826 -311.756191) (xy 389.863045 -311.746347) (xy 389.91222 -311.744366) (xy 389.961075 -311.750298)
			(xy 390.008346 -311.76399) (xy 390.052808 -311.785088) (xy 390.093311 -311.813044) (xy 390.128804 -311.847136)
			(xy 390.158369 -311.88648) (xy 390.18124 -311.930057) (xy 390.196824 -311.976738) (xy 390.204719 -312.025315)
			(xy 390.205214 -312.049922) (xy 391.494022 -312.049922) (xy 391.497982 -312.000868) (xy 391.509759 -311.953084)
			(xy 391.52905 -311.907808) (xy 391.555353 -311.866212) (xy 391.587988 -311.829375) (xy 391.626109 -311.79825)
			(xy 391.66873 -311.773643) (xy 391.714746 -311.756191) (xy 391.762965 -311.746347) (xy 391.81214 -311.744366)
			(xy 391.860995 -311.750298) (xy 391.908266 -311.76399) (xy 391.952728 -311.785088) (xy 391.993231 -311.813044)
			(xy 392.028724 -311.847136) (xy 392.058289 -311.88648) (xy 392.08116 -311.930057) (xy 392.096744 -311.976738)
			(xy 392.104639 -312.025315) (xy 392.105134 -312.049922) (xy 393.394196 -312.049922) (xy 393.398156 -312.000868)
			(xy 393.409933 -311.953084) (xy 393.429224 -311.907808) (xy 393.455527 -311.866212) (xy 393.488162 -311.829375)
			(xy 393.526283 -311.79825) (xy 393.568904 -311.773643) (xy 393.61492 -311.756191) (xy 393.663139 -311.746347)
			(xy 393.712314 -311.744366) (xy 393.761169 -311.750298) (xy 393.80844 -311.76399) (xy 393.852902 -311.785088)
			(xy 393.893405 -311.813044) (xy 393.928898 -311.847136) (xy 393.958463 -311.88648) (xy 393.981334 -311.930057)
			(xy 393.996918 -311.976738) (xy 394.004813 -312.025315) (xy 394.005308 -312.049922) (xy 395.294116 -312.049922)
			(xy 395.298076 -312.000868) (xy 395.309853 -311.953084) (xy 395.329144 -311.907808) (xy 395.355447 -311.866212)
			(xy 395.388082 -311.829375) (xy 395.426203 -311.79825) (xy 395.468824 -311.773643) (xy 395.51484 -311.756191)
			(xy 395.563059 -311.746347) (xy 395.612234 -311.744366) (xy 395.661089 -311.750298) (xy 395.70836 -311.76399)
			(xy 395.752822 -311.785088) (xy 395.793325 -311.813044) (xy 395.828818 -311.847136) (xy 395.858383 -311.88648)
			(xy 395.881254 -311.930057) (xy 395.896838 -311.976738) (xy 395.904733 -312.025315) (xy 395.905228 -312.049922)
			(xy 397.194036 -312.049922) (xy 397.197996 -312.000868) (xy 397.209773 -311.953084) (xy 397.229064 -311.907808)
			(xy 397.255367 -311.866212) (xy 397.288002 -311.829375) (xy 397.326123 -311.79825) (xy 397.368744 -311.773643)
			(xy 397.41476 -311.756191) (xy 397.462979 -311.746347) (xy 397.512154 -311.744366) (xy 397.561009 -311.750298)
			(xy 397.60828 -311.76399) (xy 397.652742 -311.785088) (xy 397.693245 -311.813044) (xy 397.728738 -311.847136)
			(xy 397.758303 -311.88648) (xy 397.781174 -311.930057) (xy 397.796758 -311.976738) (xy 397.804653 -312.025315)
			(xy 397.805148 -312.049922) (xy 414.294078 -312.049922) (xy 414.298038 -312.000868) (xy 414.309815 -311.953084)
			(xy 414.329106 -311.907808) (xy 414.355409 -311.866212) (xy 414.388044 -311.829375) (xy 414.426165 -311.79825)
			(xy 414.468786 -311.773643) (xy 414.514802 -311.756191) (xy 414.563021 -311.746347) (xy 414.612196 -311.744366)
			(xy 414.661051 -311.750298) (xy 414.708322 -311.76399) (xy 414.752784 -311.785088) (xy 414.793287 -311.813044)
			(xy 414.82878 -311.847136) (xy 414.858345 -311.88648) (xy 414.881216 -311.930057) (xy 414.8968 -311.976738)
			(xy 414.904695 -312.025315) (xy 414.90519 -312.049922) (xy 416.193998 -312.049922) (xy 416.197958 -312.000868)
			(xy 416.209735 -311.953084) (xy 416.229026 -311.907808) (xy 416.255329 -311.866212) (xy 416.287964 -311.829375)
			(xy 416.326085 -311.79825) (xy 416.368706 -311.773643) (xy 416.414722 -311.756191) (xy 416.462941 -311.746347)
			(xy 416.512116 -311.744366) (xy 416.560971 -311.750298) (xy 416.608242 -311.76399) (xy 416.652704 -311.785088)
			(xy 416.693207 -311.813044) (xy 416.7287 -311.847136) (xy 416.758265 -311.88648) (xy 416.781136 -311.930057)
			(xy 416.79672 -311.976738) (xy 416.804615 -312.025315) (xy 416.80511 -312.049922) (xy 418.094172 -312.049922)
			(xy 418.098132 -312.000868) (xy 418.109909 -311.953084) (xy 418.1292 -311.907808) (xy 418.155503 -311.866212)
			(xy 418.188138 -311.829375) (xy 418.226259 -311.79825) (xy 418.26888 -311.773643) (xy 418.314896 -311.756191)
			(xy 418.363115 -311.746347) (xy 418.41229 -311.744366) (xy 418.461145 -311.750298) (xy 418.508416 -311.76399)
			(xy 418.552878 -311.785088) (xy 418.593381 -311.813044) (xy 418.628874 -311.847136) (xy 418.658439 -311.88648)
			(xy 418.68131 -311.930057) (xy 418.696894 -311.976738) (xy 418.704789 -312.025315) (xy 418.705284 -312.049922)
			(xy 419.994092 -312.049922) (xy 419.998052 -312.000868) (xy 420.009829 -311.953084) (xy 420.02912 -311.907808)
			(xy 420.055423 -311.866212) (xy 420.088058 -311.829375) (xy 420.126179 -311.79825) (xy 420.1688 -311.773643)
			(xy 420.214816 -311.756191) (xy 420.263035 -311.746347) (xy 420.31221 -311.744366) (xy 420.361065 -311.750298)
			(xy 420.408336 -311.76399) (xy 420.452798 -311.785088) (xy 420.493301 -311.813044) (xy 420.528794 -311.847136)
			(xy 420.558359 -311.88648) (xy 420.58123 -311.930057) (xy 420.596814 -311.976738) (xy 420.604709 -312.025315)
			(xy 420.605204 -312.049922) (xy 420.604709 -312.074529) (xy 420.596814 -312.123106) (xy 420.58123 -312.169787)
			(xy 420.558359 -312.213364) (xy 420.528794 -312.252708) (xy 420.493301 -312.2868) (xy 420.452798 -312.314756)
			(xy 420.408336 -312.335854) (xy 420.361065 -312.349546) (xy 420.31221 -312.355478) (xy 420.263035 -312.353497)
			(xy 420.214816 -312.343653) (xy 420.1688 -312.326201) (xy 420.126179 -312.301594) (xy 420.088058 -312.270469)
			(xy 420.055423 -312.233632) (xy 420.02912 -312.192036) (xy 420.009829 -312.14676) (xy 419.998052 -312.098976)
			(xy 419.994092 -312.049922) (xy 418.705284 -312.049922) (xy 418.704789 -312.074529) (xy 418.696894 -312.123106)
			(xy 418.68131 -312.169787) (xy 418.658439 -312.213364) (xy 418.628874 -312.252708) (xy 418.593381 -312.2868)
			(xy 418.552878 -312.314756) (xy 418.508416 -312.335854) (xy 418.461145 -312.349546) (xy 418.41229 -312.355478)
			(xy 418.363115 -312.353497) (xy 418.314896 -312.343653) (xy 418.26888 -312.326201) (xy 418.226259 -312.301594)
			(xy 418.188138 -312.270469) (xy 418.155503 -312.233632) (xy 418.1292 -312.192036) (xy 418.109909 -312.14676)
			(xy 418.098132 -312.098976) (xy 418.094172 -312.049922) (xy 416.80511 -312.049922) (xy 416.804615 -312.074529)
			(xy 416.79672 -312.123106) (xy 416.781136 -312.169787) (xy 416.758265 -312.213364) (xy 416.7287 -312.252708)
			(xy 416.693207 -312.2868) (xy 416.652704 -312.314756) (xy 416.608242 -312.335854) (xy 416.560971 -312.349546)
			(xy 416.512116 -312.355478) (xy 416.462941 -312.353497) (xy 416.414722 -312.343653) (xy 416.368706 -312.326201)
			(xy 416.326085 -312.301594) (xy 416.287964 -312.270469) (xy 416.255329 -312.233632) (xy 416.229026 -312.192036)
			(xy 416.209735 -312.14676) (xy 416.197958 -312.098976) (xy 416.193998 -312.049922) (xy 414.90519 -312.049922)
			(xy 414.904695 -312.074529) (xy 414.8968 -312.123106) (xy 414.881216 -312.169787) (xy 414.858345 -312.213364)
			(xy 414.82878 -312.252708) (xy 414.793287 -312.2868) (xy 414.752784 -312.314756) (xy 414.708322 -312.335854)
			(xy 414.661051 -312.349546) (xy 414.612196 -312.355478) (xy 414.563021 -312.353497) (xy 414.514802 -312.343653)
			(xy 414.468786 -312.326201) (xy 414.426165 -312.301594) (xy 414.388044 -312.270469) (xy 414.355409 -312.233632)
			(xy 414.329106 -312.192036) (xy 414.309815 -312.14676) (xy 414.298038 -312.098976) (xy 414.294078 -312.049922)
			(xy 397.805148 -312.049922) (xy 397.804653 -312.074529) (xy 397.796758 -312.123106) (xy 397.781174 -312.169787)
			(xy 397.758303 -312.213364) (xy 397.728738 -312.252708) (xy 397.693245 -312.2868) (xy 397.652742 -312.314756)
			(xy 397.60828 -312.335854) (xy 397.561009 -312.349546) (xy 397.512154 -312.355478) (xy 397.462979 -312.353497)
			(xy 397.41476 -312.343653) (xy 397.368744 -312.326201) (xy 397.326123 -312.301594) (xy 397.288002 -312.270469)
			(xy 397.255367 -312.233632) (xy 397.229064 -312.192036) (xy 397.209773 -312.14676) (xy 397.197996 -312.098976)
			(xy 397.194036 -312.049922) (xy 395.905228 -312.049922) (xy 395.904733 -312.074529) (xy 395.896838 -312.123106)
			(xy 395.881254 -312.169787) (xy 395.858383 -312.213364) (xy 395.828818 -312.252708) (xy 395.793325 -312.2868)
			(xy 395.752822 -312.314756) (xy 395.70836 -312.335854) (xy 395.661089 -312.349546) (xy 395.612234 -312.355478)
			(xy 395.563059 -312.353497) (xy 395.51484 -312.343653) (xy 395.468824 -312.326201) (xy 395.426203 -312.301594)
			(xy 395.388082 -312.270469) (xy 395.355447 -312.233632) (xy 395.329144 -312.192036) (xy 395.309853 -312.14676)
			(xy 395.298076 -312.098976) (xy 395.294116 -312.049922) (xy 394.005308 -312.049922) (xy 394.004813 -312.074529)
			(xy 393.996918 -312.123106) (xy 393.981334 -312.169787) (xy 393.958463 -312.213364) (xy 393.928898 -312.252708)
			(xy 393.893405 -312.2868) (xy 393.852902 -312.314756) (xy 393.80844 -312.335854) (xy 393.761169 -312.349546)
			(xy 393.712314 -312.355478) (xy 393.663139 -312.353497) (xy 393.61492 -312.343653) (xy 393.568904 -312.326201)
			(xy 393.526283 -312.301594) (xy 393.488162 -312.270469) (xy 393.455527 -312.233632) (xy 393.429224 -312.192036)
			(xy 393.409933 -312.14676) (xy 393.398156 -312.098976) (xy 393.394196 -312.049922) (xy 392.105134 -312.049922)
			(xy 392.104639 -312.074529) (xy 392.096744 -312.123106) (xy 392.08116 -312.169787) (xy 392.058289 -312.213364)
			(xy 392.028724 -312.252708) (xy 391.993231 -312.2868) (xy 391.952728 -312.314756) (xy 391.908266 -312.335854)
			(xy 391.860995 -312.349546) (xy 391.81214 -312.355478) (xy 391.762965 -312.353497) (xy 391.714746 -312.343653)
			(xy 391.66873 -312.326201) (xy 391.626109 -312.301594) (xy 391.587988 -312.270469) (xy 391.555353 -312.233632)
			(xy 391.52905 -312.192036) (xy 391.509759 -312.14676) (xy 391.497982 -312.098976) (xy 391.494022 -312.049922)
			(xy 390.205214 -312.049922) (xy 390.204719 -312.074529) (xy 390.196824 -312.123106) (xy 390.18124 -312.169787)
			(xy 390.158369 -312.213364) (xy 390.128804 -312.252708) (xy 390.093311 -312.2868) (xy 390.052808 -312.314756)
			(xy 390.008346 -312.335854) (xy 389.961075 -312.349546) (xy 389.91222 -312.355478) (xy 389.863045 -312.353497)
			(xy 389.814826 -312.343653) (xy 389.76881 -312.326201) (xy 389.726189 -312.301594) (xy 389.688068 -312.270469)
			(xy 389.655433 -312.233632) (xy 389.62913 -312.192036) (xy 389.609839 -312.14676) (xy 389.598062 -312.098976)
			(xy 389.594102 -312.049922) (xy 388.305294 -312.049922) (xy 388.304799 -312.074529) (xy 388.296904 -312.123106)
			(xy 388.28132 -312.169787) (xy 388.258449 -312.213364) (xy 388.228884 -312.252708) (xy 388.193391 -312.2868)
			(xy 388.152888 -312.314756) (xy 388.108426 -312.335854) (xy 388.061155 -312.349546) (xy 388.0123 -312.355478)
			(xy 387.963125 -312.353497) (xy 387.914906 -312.343653) (xy 387.86889 -312.326201) (xy 387.826269 -312.301594)
			(xy 387.788148 -312.270469) (xy 387.755513 -312.233632) (xy 387.72921 -312.192036) (xy 387.709919 -312.14676)
			(xy 387.698142 -312.098976) (xy 387.694182 -312.049922) (xy 386.40512 -312.049922) (xy 386.404625 -312.074529)
			(xy 386.39673 -312.123106) (xy 386.381146 -312.169787) (xy 386.358275 -312.213364) (xy 386.32871 -312.252708)
			(xy 386.293217 -312.2868) (xy 386.252714 -312.314756) (xy 386.208252 -312.335854) (xy 386.160981 -312.349546)
			(xy 386.112126 -312.355478) (xy 386.062951 -312.353497) (xy 386.014732 -312.343653) (xy 385.968716 -312.326201)
			(xy 385.926095 -312.301594) (xy 385.887974 -312.270469) (xy 385.855339 -312.233632) (xy 385.829036 -312.192036)
			(xy 385.809745 -312.14676) (xy 385.797968 -312.098976) (xy 385.794008 -312.049922) (xy 385.45516 -312.049922)
			(xy 385.454665 -312.074529) (xy 385.44677 -312.123106) (xy 385.431186 -312.169787) (xy 385.408315 -312.213364)
			(xy 385.37875 -312.252708) (xy 385.343257 -312.2868) (xy 385.302754 -312.314756) (xy 385.258292 -312.335854)
			(xy 385.211021 -312.349546) (xy 385.162166 -312.355478) (xy 385.112991 -312.353497) (xy 385.064772 -312.343653)
			(xy 385.018756 -312.326201) (xy 384.976135 -312.301594) (xy 384.938014 -312.270469) (xy 384.905379 -312.233632)
			(xy 384.879076 -312.192036) (xy 384.859785 -312.14676) (xy 384.848008 -312.098976) (xy 384.844048 -312.049922)
			(xy 314.955174 -312.049922) (xy 314.954679 -312.074529) (xy 314.946784 -312.123106) (xy 314.9312 -312.169787)
			(xy 314.908329 -312.213364) (xy 314.878764 -312.252708) (xy 314.843271 -312.2868) (xy 314.802768 -312.314756)
			(xy 314.758306 -312.335854) (xy 314.711035 -312.349546) (xy 314.66218 -312.355478) (xy 314.613005 -312.353497)
			(xy 314.564786 -312.343653) (xy 314.51877 -312.326201) (xy 314.476149 -312.301594) (xy 314.438028 -312.270469)
			(xy 314.405393 -312.233632) (xy 314.37909 -312.192036) (xy 314.359799 -312.14676) (xy 314.348022 -312.098976)
			(xy 314.344062 -312.049922) (xy 314.005214 -312.049922) (xy 314.004719 -312.074529) (xy 313.996824 -312.123106)
			(xy 313.98124 -312.169787) (xy 313.958369 -312.213364) (xy 313.928804 -312.252708) (xy 313.893311 -312.2868)
			(xy 313.852808 -312.314756) (xy 313.808346 -312.335854) (xy 313.761075 -312.349546) (xy 313.71222 -312.355478)
			(xy 313.663045 -312.353497) (xy 313.614826 -312.343653) (xy 313.56881 -312.326201) (xy 313.526189 -312.301594)
			(xy 313.488068 -312.270469) (xy 313.455433 -312.233632) (xy 313.42913 -312.192036) (xy 313.409839 -312.14676)
			(xy 313.398062 -312.098976) (xy 313.394102 -312.049922) (xy 312.10504 -312.049922) (xy 312.104545 -312.074529)
			(xy 312.09665 -312.123106) (xy 312.081066 -312.169787) (xy 312.058195 -312.213364) (xy 312.02863 -312.252708)
			(xy 311.993137 -312.2868) (xy 311.952634 -312.314756) (xy 311.908172 -312.335854) (xy 311.860901 -312.349546)
			(xy 311.812046 -312.355478) (xy 311.762871 -312.353497) (xy 311.714652 -312.343653) (xy 311.668636 -312.326201)
			(xy 311.626015 -312.301594) (xy 311.587894 -312.270469) (xy 311.555259 -312.233632) (xy 311.528956 -312.192036)
			(xy 311.509665 -312.14676) (xy 311.497888 -312.098976) (xy 311.493928 -312.049922) (xy 310.20512 -312.049922)
			(xy 310.204625 -312.074529) (xy 310.19673 -312.123106) (xy 310.181146 -312.169787) (xy 310.158275 -312.213364)
			(xy 310.12871 -312.252708) (xy 310.093217 -312.2868) (xy 310.052714 -312.314756) (xy 310.008252 -312.335854)
			(xy 309.960981 -312.349546) (xy 309.912126 -312.355478) (xy 309.862951 -312.353497) (xy 309.814732 -312.343653)
			(xy 309.768716 -312.326201) (xy 309.726095 -312.301594) (xy 309.687974 -312.270469) (xy 309.655339 -312.233632)
			(xy 309.629036 -312.192036) (xy 309.609745 -312.14676) (xy 309.597968 -312.098976) (xy 309.594008 -312.049922)
			(xy 308.3052 -312.049922) (xy 308.304705 -312.074529) (xy 308.29681 -312.123106) (xy 308.281226 -312.169787)
			(xy 308.258355 -312.213364) (xy 308.22879 -312.252708) (xy 308.193297 -312.2868) (xy 308.152794 -312.314756)
			(xy 308.108332 -312.335854) (xy 308.061061 -312.349546) (xy 308.012206 -312.355478) (xy 307.963031 -312.353497)
			(xy 307.914812 -312.343653) (xy 307.868796 -312.326201) (xy 307.826175 -312.301594) (xy 307.788054 -312.270469)
			(xy 307.755419 -312.233632) (xy 307.729116 -312.192036) (xy 307.709825 -312.14676) (xy 307.698048 -312.098976)
			(xy 307.694088 -312.049922) (xy 306.405026 -312.049922) (xy 306.404531 -312.074529) (xy 306.396636 -312.123106)
			(xy 306.381052 -312.169787) (xy 306.358181 -312.213364) (xy 306.328616 -312.252708) (xy 306.293123 -312.2868)
			(xy 306.25262 -312.314756) (xy 306.208158 -312.335854) (xy 306.160887 -312.349546) (xy 306.112032 -312.355478)
			(xy 306.062857 -312.353497) (xy 306.014638 -312.343653) (xy 305.968622 -312.326201) (xy 305.926001 -312.301594)
			(xy 305.88788 -312.270469) (xy 305.855245 -312.233632) (xy 305.828942 -312.192036) (xy 305.809651 -312.14676)
			(xy 305.797874 -312.098976) (xy 305.793914 -312.049922) (xy 289.305238 -312.049922) (xy 289.304743 -312.074529)
			(xy 289.296848 -312.123106) (xy 289.281264 -312.169787) (xy 289.258393 -312.213364) (xy 289.228828 -312.252708)
			(xy 289.193335 -312.2868) (xy 289.152832 -312.314756) (xy 289.10837 -312.335854) (xy 289.061099 -312.349546)
			(xy 289.012244 -312.355478) (xy 288.963069 -312.353497) (xy 288.91485 -312.343653) (xy 288.868834 -312.326201)
			(xy 288.826213 -312.301594) (xy 288.788092 -312.270469) (xy 288.755457 -312.233632) (xy 288.729154 -312.192036)
			(xy 288.709863 -312.14676) (xy 288.698086 -312.098976) (xy 288.694126 -312.049922) (xy 287.405064 -312.049922)
			(xy 287.404569 -312.074529) (xy 287.396674 -312.123106) (xy 287.38109 -312.169787) (xy 287.358219 -312.213364)
			(xy 287.328654 -312.252708) (xy 287.293161 -312.2868) (xy 287.252658 -312.314756) (xy 287.208196 -312.335854)
			(xy 287.160925 -312.349546) (xy 287.11207 -312.355478) (xy 287.062895 -312.353497) (xy 287.014676 -312.343653)
			(xy 286.96866 -312.326201) (xy 286.926039 -312.301594) (xy 286.887918 -312.270469) (xy 286.855283 -312.233632)
			(xy 286.82898 -312.192036) (xy 286.809689 -312.14676) (xy 286.797912 -312.098976) (xy 286.793952 -312.049922)
			(xy 285.505144 -312.049922) (xy 285.504649 -312.074529) (xy 285.496754 -312.123106) (xy 285.48117 -312.169787)
			(xy 285.458299 -312.213364) (xy 285.428734 -312.252708) (xy 285.393241 -312.2868) (xy 285.352738 -312.314756)
			(xy 285.308276 -312.335854) (xy 285.261005 -312.349546) (xy 285.21215 -312.355478) (xy 285.162975 -312.353497)
			(xy 285.114756 -312.343653) (xy 285.06874 -312.326201) (xy 285.026119 -312.301594) (xy 284.987998 -312.270469)
			(xy 284.955363 -312.233632) (xy 284.92906 -312.192036) (xy 284.909769 -312.14676) (xy 284.897992 -312.098976)
			(xy 284.894032 -312.049922) (xy 283.605224 -312.049922) (xy 283.604729 -312.074529) (xy 283.596834 -312.123106)
			(xy 283.58125 -312.169787) (xy 283.558379 -312.213364) (xy 283.528814 -312.252708) (xy 283.493321 -312.2868)
			(xy 283.452818 -312.314756) (xy 283.408356 -312.335854) (xy 283.361085 -312.349546) (xy 283.31223 -312.355478)
			(xy 283.263055 -312.353497) (xy 283.214836 -312.343653) (xy 283.16882 -312.326201) (xy 283.126199 -312.301594)
			(xy 283.088078 -312.270469) (xy 283.055443 -312.233632) (xy 283.02914 -312.192036) (xy 283.009849 -312.14676)
			(xy 282.998072 -312.098976) (xy 282.994112 -312.049922) (xy 281.70505 -312.049922) (xy 281.704555 -312.074529)
			(xy 281.69666 -312.123106) (xy 281.681076 -312.169787) (xy 281.658205 -312.213364) (xy 281.62864 -312.252708)
			(xy 281.593147 -312.2868) (xy 281.552644 -312.314756) (xy 281.508182 -312.335854) (xy 281.460911 -312.349546)
			(xy 281.412056 -312.355478) (xy 281.362881 -312.353497) (xy 281.314662 -312.343653) (xy 281.268646 -312.326201)
			(xy 281.226025 -312.301594) (xy 281.187904 -312.270469) (xy 281.155269 -312.233632) (xy 281.128966 -312.192036)
			(xy 281.109675 -312.14676) (xy 281.097898 -312.098976) (xy 281.093938 -312.049922) (xy 279.80513 -312.049922)
			(xy 279.804635 -312.074529) (xy 279.79674 -312.123106) (xy 279.781156 -312.169787) (xy 279.758285 -312.213364)
			(xy 279.72872 -312.252708) (xy 279.693227 -312.2868) (xy 279.652724 -312.314756) (xy 279.608262 -312.335854)
			(xy 279.560991 -312.349546) (xy 279.512136 -312.355478) (xy 279.462961 -312.353497) (xy 279.414742 -312.343653)
			(xy 279.368726 -312.326201) (xy 279.326105 -312.301594) (xy 279.287984 -312.270469) (xy 279.255349 -312.233632)
			(xy 279.229046 -312.192036) (xy 279.209755 -312.14676) (xy 279.197978 -312.098976) (xy 279.194018 -312.049922)
			(xy 277.90521 -312.049922) (xy 277.904715 -312.074529) (xy 277.89682 -312.123106) (xy 277.881236 -312.169787)
			(xy 277.858365 -312.213364) (xy 277.8288 -312.252708) (xy 277.793307 -312.2868) (xy 277.752804 -312.314756)
			(xy 277.708342 -312.335854) (xy 277.661071 -312.349546) (xy 277.612216 -312.355478) (xy 277.563041 -312.353497)
			(xy 277.514822 -312.343653) (xy 277.468806 -312.326201) (xy 277.426185 -312.301594) (xy 277.388064 -312.270469)
			(xy 277.355429 -312.233632) (xy 277.329126 -312.192036) (xy 277.309835 -312.14676) (xy 277.298058 -312.098976)
			(xy 277.294098 -312.049922) (xy 276.005036 -312.049922) (xy 276.004541 -312.074529) (xy 275.996646 -312.123106)
			(xy 275.981062 -312.169787) (xy 275.958191 -312.213364) (xy 275.928626 -312.252708) (xy 275.893133 -312.2868)
			(xy 275.85263 -312.314756) (xy 275.808168 -312.335854) (xy 275.760897 -312.349546) (xy 275.712042 -312.355478)
			(xy 275.662867 -312.353497) (xy 275.614648 -312.343653) (xy 275.568632 -312.326201) (xy 275.526011 -312.301594)
			(xy 275.48789 -312.270469) (xy 275.455255 -312.233632) (xy 275.428952 -312.192036) (xy 275.409661 -312.14676)
			(xy 275.397884 -312.098976) (xy 275.393924 -312.049922) (xy 188.405262 -312.049922) (xy 188.404767 -312.074529)
			(xy 188.396872 -312.123106) (xy 188.381288 -312.169787) (xy 188.358417 -312.213364) (xy 188.328852 -312.252708)
			(xy 188.293359 -312.2868) (xy 188.252856 -312.314756) (xy 188.208394 -312.335854) (xy 188.161123 -312.349546)
			(xy 188.112268 -312.355478) (xy 188.063093 -312.353497) (xy 188.014874 -312.343653) (xy 187.968858 -312.326201)
			(xy 187.926237 -312.301594) (xy 187.888116 -312.270469) (xy 187.855481 -312.233632) (xy 187.829178 -312.192036)
			(xy 187.809887 -312.14676) (xy 187.79811 -312.098976) (xy 187.79415 -312.049922) (xy 186.505342 -312.049922)
			(xy 186.504847 -312.074529) (xy 186.496952 -312.123106) (xy 186.481368 -312.169787) (xy 186.458497 -312.213364)
			(xy 186.428932 -312.252708) (xy 186.393439 -312.2868) (xy 186.352936 -312.314756) (xy 186.308474 -312.335854)
			(xy 186.261203 -312.349546) (xy 186.212348 -312.355478) (xy 186.163173 -312.353497) (xy 186.114954 -312.343653)
			(xy 186.068938 -312.326201) (xy 186.026317 -312.301594) (xy 185.988196 -312.270469) (xy 185.955561 -312.233632)
			(xy 185.929258 -312.192036) (xy 185.909967 -312.14676) (xy 185.89819 -312.098976) (xy 185.89423 -312.049922)
			(xy 184.605168 -312.049922) (xy 184.604673 -312.074529) (xy 184.596778 -312.123106) (xy 184.581194 -312.169787)
			(xy 184.558323 -312.213364) (xy 184.528758 -312.252708) (xy 184.493265 -312.2868) (xy 184.452762 -312.314756)
			(xy 184.4083 -312.335854) (xy 184.361029 -312.349546) (xy 184.312174 -312.355478) (xy 184.262999 -312.353497)
			(xy 184.21478 -312.343653) (xy 184.168764 -312.326201) (xy 184.126143 -312.301594) (xy 184.088022 -312.270469)
			(xy 184.055387 -312.233632) (xy 184.029084 -312.192036) (xy 184.009793 -312.14676) (xy 183.998016 -312.098976)
			(xy 183.994056 -312.049922) (xy 182.705248 -312.049922) (xy 182.704753 -312.074529) (xy 182.696858 -312.123106)
			(xy 182.681274 -312.169787) (xy 182.658403 -312.213364) (xy 182.628838 -312.252708) (xy 182.593345 -312.2868)
			(xy 182.552842 -312.314756) (xy 182.50838 -312.335854) (xy 182.461109 -312.349546) (xy 182.412254 -312.355478)
			(xy 182.363079 -312.353497) (xy 182.31486 -312.343653) (xy 182.268844 -312.326201) (xy 182.226223 -312.301594)
			(xy 182.188102 -312.270469) (xy 182.155467 -312.233632) (xy 182.129164 -312.192036) (xy 182.109873 -312.14676)
			(xy 182.098096 -312.098976) (xy 182.094136 -312.049922) (xy 165.605206 -312.049922) (xy 165.604711 -312.074529)
			(xy 165.596816 -312.123106) (xy 165.581232 -312.169787) (xy 165.558361 -312.213364) (xy 165.528796 -312.252708)
			(xy 165.493303 -312.2868) (xy 165.4528 -312.314756) (xy 165.408338 -312.335854) (xy 165.361067 -312.349546)
			(xy 165.312212 -312.355478) (xy 165.263037 -312.353497) (xy 165.214818 -312.343653) (xy 165.168802 -312.326201)
			(xy 165.126181 -312.301594) (xy 165.08806 -312.270469) (xy 165.055425 -312.233632) (xy 165.029122 -312.192036)
			(xy 165.009831 -312.14676) (xy 164.998054 -312.098976) (xy 164.994094 -312.049922) (xy 163.705286 -312.049922)
			(xy 163.704791 -312.074529) (xy 163.696896 -312.123106) (xy 163.681312 -312.169787) (xy 163.658441 -312.213364)
			(xy 163.628876 -312.252708) (xy 163.593383 -312.2868) (xy 163.55288 -312.314756) (xy 163.508418 -312.335854)
			(xy 163.461147 -312.349546) (xy 163.412292 -312.355478) (xy 163.363117 -312.353497) (xy 163.314898 -312.343653)
			(xy 163.268882 -312.326201) (xy 163.226261 -312.301594) (xy 163.18814 -312.270469) (xy 163.155505 -312.233632)
			(xy 163.129202 -312.192036) (xy 163.109911 -312.14676) (xy 163.098134 -312.098976) (xy 163.094174 -312.049922)
			(xy 161.805366 -312.049922) (xy 161.804871 -312.074529) (xy 161.796976 -312.123106) (xy 161.781392 -312.169787)
			(xy 161.758521 -312.213364) (xy 161.728956 -312.252708) (xy 161.693463 -312.2868) (xy 161.65296 -312.314756)
			(xy 161.608498 -312.335854) (xy 161.561227 -312.349546) (xy 161.512372 -312.355478) (xy 161.463197 -312.353497)
			(xy 161.414978 -312.343653) (xy 161.368962 -312.326201) (xy 161.326341 -312.301594) (xy 161.28822 -312.270469)
			(xy 161.255585 -312.233632) (xy 161.229282 -312.192036) (xy 161.209991 -312.14676) (xy 161.198214 -312.098976)
			(xy 161.194254 -312.049922) (xy 159.905192 -312.049922) (xy 159.904697 -312.074529) (xy 159.896802 -312.123106)
			(xy 159.881218 -312.169787) (xy 159.858347 -312.213364) (xy 159.828782 -312.252708) (xy 159.793289 -312.2868)
			(xy 159.752786 -312.314756) (xy 159.708324 -312.335854) (xy 159.661053 -312.349546) (xy 159.612198 -312.355478)
			(xy 159.563023 -312.353497) (xy 159.514804 -312.343653) (xy 159.468788 -312.326201) (xy 159.426167 -312.301594)
			(xy 159.388046 -312.270469) (xy 159.355411 -312.233632) (xy 159.329108 -312.192036) (xy 159.309817 -312.14676)
			(xy 159.29804 -312.098976) (xy 159.29408 -312.049922) (xy 158.005272 -312.049922) (xy 158.004777 -312.074529)
			(xy 157.996882 -312.123106) (xy 157.981298 -312.169787) (xy 157.958427 -312.213364) (xy 157.928862 -312.252708)
			(xy 157.893369 -312.2868) (xy 157.852866 -312.314756) (xy 157.808404 -312.335854) (xy 157.761133 -312.349546)
			(xy 157.712278 -312.355478) (xy 157.663103 -312.353497) (xy 157.614884 -312.343653) (xy 157.568868 -312.326201)
			(xy 157.526247 -312.301594) (xy 157.488126 -312.270469) (xy 157.455491 -312.233632) (xy 157.429188 -312.192036)
			(xy 157.409897 -312.14676) (xy 157.39812 -312.098976) (xy 157.39416 -312.049922) (xy 156.105352 -312.049922)
			(xy 156.104857 -312.074529) (xy 156.096962 -312.123106) (xy 156.081378 -312.169787) (xy 156.058507 -312.213364)
			(xy 156.028942 -312.252708) (xy 155.993449 -312.2868) (xy 155.952946 -312.314756) (xy 155.908484 -312.335854)
			(xy 155.861213 -312.349546) (xy 155.812358 -312.355478) (xy 155.763183 -312.353497) (xy 155.714964 -312.343653)
			(xy 155.668948 -312.326201) (xy 155.626327 -312.301594) (xy 155.588206 -312.270469) (xy 155.555571 -312.233632)
			(xy 155.529268 -312.192036) (xy 155.509977 -312.14676) (xy 155.4982 -312.098976) (xy 155.49424 -312.049922)
			(xy 154.205178 -312.049922) (xy 154.204683 -312.074529) (xy 154.196788 -312.123106) (xy 154.181204 -312.169787)
			(xy 154.158333 -312.213364) (xy 154.128768 -312.252708) (xy 154.093275 -312.2868) (xy 154.052772 -312.314756)
			(xy 154.00831 -312.335854) (xy 153.961039 -312.349546) (xy 153.912184 -312.355478) (xy 153.863009 -312.353497)
			(xy 153.81479 -312.343653) (xy 153.768774 -312.326201) (xy 153.726153 -312.301594) (xy 153.688032 -312.270469)
			(xy 153.655397 -312.233632) (xy 153.629094 -312.192036) (xy 153.609803 -312.14676) (xy 153.598026 -312.098976)
			(xy 153.594066 -312.049922) (xy 153.255218 -312.049922) (xy 153.254723 -312.074529) (xy 153.246828 -312.123106)
			(xy 153.231244 -312.169787) (xy 153.208373 -312.213364) (xy 153.178808 -312.252708) (xy 153.143315 -312.2868)
			(xy 153.102812 -312.314756) (xy 153.05835 -312.335854) (xy 153.011079 -312.349546) (xy 152.962224 -312.355478)
			(xy 152.913049 -312.353497) (xy 152.86483 -312.343653) (xy 152.818814 -312.326201) (xy 152.776193 -312.301594)
			(xy 152.738072 -312.270469) (xy 152.705437 -312.233632) (xy 152.679134 -312.192036) (xy 152.659843 -312.14676)
			(xy 152.648066 -312.098976) (xy 152.644106 -312.049922) (xy 82.755232 -312.049922) (xy 82.754737 -312.074529)
			(xy 82.746842 -312.123106) (xy 82.731258 -312.169787) (xy 82.708387 -312.213364) (xy 82.678822 -312.252708)
			(xy 82.643329 -312.2868) (xy 82.602826 -312.314756) (xy 82.558364 -312.335854) (xy 82.511093 -312.349546)
			(xy 82.462238 -312.355478) (xy 82.413063 -312.353497) (xy 82.364844 -312.343653) (xy 82.318828 -312.326201)
			(xy 82.276207 -312.301594) (xy 82.238086 -312.270469) (xy 82.205451 -312.233632) (xy 82.179148 -312.192036)
			(xy 82.159857 -312.14676) (xy 82.14808 -312.098976) (xy 82.14412 -312.049922) (xy 81.805272 -312.049922)
			(xy 81.804777 -312.074529) (xy 81.796882 -312.123106) (xy 81.781298 -312.169787) (xy 81.758427 -312.213364)
			(xy 81.728862 -312.252708) (xy 81.693369 -312.2868) (xy 81.652866 -312.314756) (xy 81.608404 -312.335854)
			(xy 81.561133 -312.349546) (xy 81.512278 -312.355478) (xy 81.463103 -312.353497) (xy 81.414884 -312.343653)
			(xy 81.368868 -312.326201) (xy 81.326247 -312.301594) (xy 81.288126 -312.270469) (xy 81.255491 -312.233632)
			(xy 81.229188 -312.192036) (xy 81.209897 -312.14676) (xy 81.19812 -312.098976) (xy 81.19416 -312.049922)
			(xy 79.905098 -312.049922) (xy 79.904603 -312.074529) (xy 79.896708 -312.123106) (xy 79.881124 -312.169787)
			(xy 79.858253 -312.213364) (xy 79.828688 -312.252708) (xy 79.793195 -312.2868) (xy 79.752692 -312.314756)
			(xy 79.70823 -312.335854) (xy 79.660959 -312.349546) (xy 79.612104 -312.355478) (xy 79.562929 -312.353497)
			(xy 79.51471 -312.343653) (xy 79.468694 -312.326201) (xy 79.426073 -312.301594) (xy 79.387952 -312.270469)
			(xy 79.355317 -312.233632) (xy 79.329014 -312.192036) (xy 79.309723 -312.14676) (xy 79.297946 -312.098976)
			(xy 79.293986 -312.049922) (xy 78.005178 -312.049922) (xy 78.004683 -312.074529) (xy 77.996788 -312.123106)
			(xy 77.981204 -312.169787) (xy 77.958333 -312.213364) (xy 77.928768 -312.252708) (xy 77.893275 -312.2868)
			(xy 77.852772 -312.314756) (xy 77.80831 -312.335854) (xy 77.761039 -312.349546) (xy 77.712184 -312.355478)
			(xy 77.663009 -312.353497) (xy 77.61479 -312.343653) (xy 77.568774 -312.326201) (xy 77.526153 -312.301594)
			(xy 77.488032 -312.270469) (xy 77.455397 -312.233632) (xy 77.429094 -312.192036) (xy 77.409803 -312.14676)
			(xy 77.398026 -312.098976) (xy 77.394066 -312.049922) (xy 76.105258 -312.049922) (xy 76.104763 -312.074529)
			(xy 76.096868 -312.123106) (xy 76.081284 -312.169787) (xy 76.058413 -312.213364) (xy 76.028848 -312.252708)
			(xy 75.993355 -312.2868) (xy 75.952852 -312.314756) (xy 75.90839 -312.335854) (xy 75.861119 -312.349546)
			(xy 75.812264 -312.355478) (xy 75.763089 -312.353497) (xy 75.71487 -312.343653) (xy 75.668854 -312.326201)
			(xy 75.626233 -312.301594) (xy 75.588112 -312.270469) (xy 75.555477 -312.233632) (xy 75.529174 -312.192036)
			(xy 75.509883 -312.14676) (xy 75.498106 -312.098976) (xy 75.494146 -312.049922) (xy 74.205084 -312.049922)
			(xy 74.204589 -312.074529) (xy 74.196694 -312.123106) (xy 74.18111 -312.169787) (xy 74.158239 -312.213364)
			(xy 74.128674 -312.252708) (xy 74.093181 -312.2868) (xy 74.052678 -312.314756) (xy 74.008216 -312.335854)
			(xy 73.960945 -312.349546) (xy 73.91209 -312.355478) (xy 73.862915 -312.353497) (xy 73.814696 -312.343653)
			(xy 73.76868 -312.326201) (xy 73.726059 -312.301594) (xy 73.687938 -312.270469) (xy 73.655303 -312.233632)
			(xy 73.629 -312.192036) (xy 73.609709 -312.14676) (xy 73.597932 -312.098976) (xy 73.593972 -312.049922)
			(xy 57.105296 -312.049922) (xy 57.104801 -312.074529) (xy 57.096906 -312.123106) (xy 57.081322 -312.169787)
			(xy 57.058451 -312.213364) (xy 57.028886 -312.252708) (xy 56.993393 -312.2868) (xy 56.95289 -312.314756)
			(xy 56.908428 -312.335854) (xy 56.861157 -312.349546) (xy 56.812302 -312.355478) (xy 56.763127 -312.353497)
			(xy 56.714908 -312.343653) (xy 56.668892 -312.326201) (xy 56.626271 -312.301594) (xy 56.58815 -312.270469)
			(xy 56.555515 -312.233632) (xy 56.529212 -312.192036) (xy 56.509921 -312.14676) (xy 56.498144 -312.098976)
			(xy 56.494184 -312.049922) (xy 55.205122 -312.049922) (xy 55.204627 -312.074529) (xy 55.196732 -312.123106)
			(xy 55.181148 -312.169787) (xy 55.158277 -312.213364) (xy 55.128712 -312.252708) (xy 55.093219 -312.2868)
			(xy 55.052716 -312.314756) (xy 55.008254 -312.335854) (xy 54.960983 -312.349546) (xy 54.912128 -312.355478)
			(xy 54.862953 -312.353497) (xy 54.814734 -312.343653) (xy 54.768718 -312.326201) (xy 54.726097 -312.301594)
			(xy 54.687976 -312.270469) (xy 54.655341 -312.233632) (xy 54.629038 -312.192036) (xy 54.609747 -312.14676)
			(xy 54.59797 -312.098976) (xy 54.59401 -312.049922) (xy 53.305202 -312.049922) (xy 53.304707 -312.074529)
			(xy 53.296812 -312.123106) (xy 53.281228 -312.169787) (xy 53.258357 -312.213364) (xy 53.228792 -312.252708)
			(xy 53.193299 -312.2868) (xy 53.152796 -312.314756) (xy 53.108334 -312.335854) (xy 53.061063 -312.349546)
			(xy 53.012208 -312.355478) (xy 52.963033 -312.353497) (xy 52.914814 -312.343653) (xy 52.868798 -312.326201)
			(xy 52.826177 -312.301594) (xy 52.788056 -312.270469) (xy 52.755421 -312.233632) (xy 52.729118 -312.192036)
			(xy 52.709827 -312.14676) (xy 52.69805 -312.098976) (xy 52.69409 -312.049922) (xy 51.405282 -312.049922)
			(xy 51.404787 -312.074529) (xy 51.396892 -312.123106) (xy 51.381308 -312.169787) (xy 51.358437 -312.213364)
			(xy 51.328872 -312.252708) (xy 51.293379 -312.2868) (xy 51.252876 -312.314756) (xy 51.208414 -312.335854)
			(xy 51.161143 -312.349546) (xy 51.112288 -312.355478) (xy 51.063113 -312.353497) (xy 51.014894 -312.343653)
			(xy 50.968878 -312.326201) (xy 50.926257 -312.301594) (xy 50.888136 -312.270469) (xy 50.855501 -312.233632)
			(xy 50.829198 -312.192036) (xy 50.809907 -312.14676) (xy 50.79813 -312.098976) (xy 50.79417 -312.049922)
			(xy 49.505108 -312.049922) (xy 49.504613 -312.074529) (xy 49.496718 -312.123106) (xy 49.481134 -312.169787)
			(xy 49.458263 -312.213364) (xy 49.428698 -312.252708) (xy 49.393205 -312.2868) (xy 49.352702 -312.314756)
			(xy 49.30824 -312.335854) (xy 49.260969 -312.349546) (xy 49.212114 -312.355478) (xy 49.162939 -312.353497)
			(xy 49.11472 -312.343653) (xy 49.068704 -312.326201) (xy 49.026083 -312.301594) (xy 48.987962 -312.270469)
			(xy 48.955327 -312.233632) (xy 48.929024 -312.192036) (xy 48.909733 -312.14676) (xy 48.897956 -312.098976)
			(xy 48.893996 -312.049922) (xy 47.605188 -312.049922) (xy 47.604693 -312.074529) (xy 47.596798 -312.123106)
			(xy 47.581214 -312.169787) (xy 47.558343 -312.213364) (xy 47.528778 -312.252708) (xy 47.493285 -312.2868)
			(xy 47.452782 -312.314756) (xy 47.40832 -312.335854) (xy 47.361049 -312.349546) (xy 47.312194 -312.355478)
			(xy 47.263019 -312.353497) (xy 47.2148 -312.343653) (xy 47.168784 -312.326201) (xy 47.126163 -312.301594)
			(xy 47.088042 -312.270469) (xy 47.055407 -312.233632) (xy 47.029104 -312.192036) (xy 47.009813 -312.14676)
			(xy 46.998036 -312.098976) (xy 46.994076 -312.049922) (xy 45.705268 -312.049922) (xy 45.704773 -312.074529)
			(xy 45.696878 -312.123106) (xy 45.681294 -312.169787) (xy 45.658423 -312.213364) (xy 45.628858 -312.252708)
			(xy 45.593365 -312.2868) (xy 45.552862 -312.314756) (xy 45.5084 -312.335854) (xy 45.461129 -312.349546)
			(xy 45.412274 -312.355478) (xy 45.363099 -312.353497) (xy 45.31488 -312.343653) (xy 45.268864 -312.326201)
			(xy 45.226243 -312.301594) (xy 45.188122 -312.270469) (xy 45.155487 -312.233632) (xy 45.129184 -312.192036)
			(xy 45.109893 -312.14676) (xy 45.098116 -312.098976) (xy 45.094156 -312.049922) (xy 43.805094 -312.049922)
			(xy 43.804599 -312.074529) (xy 43.796704 -312.123106) (xy 43.78112 -312.169787) (xy 43.758249 -312.213364)
			(xy 43.728684 -312.252708) (xy 43.693191 -312.2868) (xy 43.652688 -312.314756) (xy 43.608226 -312.335854)
			(xy 43.560955 -312.349546) (xy 43.5121 -312.355478) (xy 43.462925 -312.353497) (xy 43.414706 -312.343653)
			(xy 43.36869 -312.326201) (xy 43.326069 -312.301594) (xy 43.287948 -312.270469) (xy 43.255313 -312.233632)
			(xy 43.22901 -312.192036) (xy 43.209719 -312.14676) (xy 43.197942 -312.098976) (xy 43.193982 -312.049922)
			(xy 0.508 -312.049922) (xy 0.508 -312.999882) (xy 44.143942 -312.999882) (xy 44.147902 -312.950828)
			(xy 44.159679 -312.903044) (xy 44.17897 -312.857768) (xy 44.205273 -312.816172) (xy 44.237908 -312.779335)
			(xy 44.276029 -312.74821) (xy 44.31865 -312.723603) (xy 44.364666 -312.706151) (xy 44.412885 -312.696307)
			(xy 44.46206 -312.694326) (xy 44.510915 -312.700258) (xy 44.558186 -312.71395) (xy 44.602648 -312.735048)
			(xy 44.643151 -312.763004) (xy 44.678644 -312.797096) (xy 44.708209 -312.83644) (xy 44.73108 -312.880017)
			(xy 44.746664 -312.926698) (xy 44.754559 -312.975275) (xy 44.755054 -312.999882) (xy 46.044116 -312.999882)
			(xy 46.048076 -312.950828) (xy 46.059853 -312.903044) (xy 46.079144 -312.857768) (xy 46.105447 -312.816172)
			(xy 46.138082 -312.779335) (xy 46.176203 -312.74821) (xy 46.218824 -312.723603) (xy 46.26484 -312.706151)
			(xy 46.313059 -312.696307) (xy 46.362234 -312.694326) (xy 46.411089 -312.700258) (xy 46.45836 -312.71395)
			(xy 46.502822 -312.735048) (xy 46.543325 -312.763004) (xy 46.578818 -312.797096) (xy 46.608383 -312.83644)
			(xy 46.631254 -312.880017) (xy 46.646838 -312.926698) (xy 46.654733 -312.975275) (xy 46.655228 -312.999882)
			(xy 47.944036 -312.999882) (xy 47.947996 -312.950828) (xy 47.959773 -312.903044) (xy 47.979064 -312.857768)
			(xy 48.005367 -312.816172) (xy 48.038002 -312.779335) (xy 48.076123 -312.74821) (xy 48.118744 -312.723603)
			(xy 48.16476 -312.706151) (xy 48.212979 -312.696307) (xy 48.262154 -312.694326) (xy 48.311009 -312.700258)
			(xy 48.35828 -312.71395) (xy 48.402742 -312.735048) (xy 48.443245 -312.763004) (xy 48.478738 -312.797096)
			(xy 48.508303 -312.83644) (xy 48.531174 -312.880017) (xy 48.546758 -312.926698) (xy 48.554653 -312.975275)
			(xy 48.555148 -312.999882) (xy 49.843956 -312.999882) (xy 49.847916 -312.950828) (xy 49.859693 -312.903044)
			(xy 49.878984 -312.857768) (xy 49.905287 -312.816172) (xy 49.937922 -312.779335) (xy 49.976043 -312.74821)
			(xy 50.018664 -312.723603) (xy 50.06468 -312.706151) (xy 50.112899 -312.696307) (xy 50.162074 -312.694326)
			(xy 50.210929 -312.700258) (xy 50.2582 -312.71395) (xy 50.302662 -312.735048) (xy 50.343165 -312.763004)
			(xy 50.378658 -312.797096) (xy 50.408223 -312.83644) (xy 50.431094 -312.880017) (xy 50.446678 -312.926698)
			(xy 50.454573 -312.975275) (xy 50.455068 -312.999882) (xy 51.74413 -312.999882) (xy 51.74809 -312.950828)
			(xy 51.759867 -312.903044) (xy 51.779158 -312.857768) (xy 51.805461 -312.816172) (xy 51.838096 -312.779335)
			(xy 51.876217 -312.74821) (xy 51.918838 -312.723603) (xy 51.964854 -312.706151) (xy 52.013073 -312.696307)
			(xy 52.062248 -312.694326) (xy 52.111103 -312.700258) (xy 52.158374 -312.71395) (xy 52.202836 -312.735048)
			(xy 52.243339 -312.763004) (xy 52.278832 -312.797096) (xy 52.308397 -312.83644) (xy 52.331268 -312.880017)
			(xy 52.346852 -312.926698) (xy 52.354747 -312.975275) (xy 52.355242 -312.999882) (xy 53.64405 -312.999882)
			(xy 53.64801 -312.950828) (xy 53.659787 -312.903044) (xy 53.679078 -312.857768) (xy 53.705381 -312.816172)
			(xy 53.738016 -312.779335) (xy 53.776137 -312.74821) (xy 53.818758 -312.723603) (xy 53.864774 -312.706151)
			(xy 53.912993 -312.696307) (xy 53.962168 -312.694326) (xy 54.011023 -312.700258) (xy 54.058294 -312.71395)
			(xy 54.102756 -312.735048) (xy 54.143259 -312.763004) (xy 54.178752 -312.797096) (xy 54.208317 -312.83644)
			(xy 54.231188 -312.880017) (xy 54.246772 -312.926698) (xy 54.254667 -312.975275) (xy 54.255162 -312.999882)
			(xy 55.54397 -312.999882) (xy 55.54793 -312.950828) (xy 55.559707 -312.903044) (xy 55.578998 -312.857768)
			(xy 55.605301 -312.816172) (xy 55.637936 -312.779335) (xy 55.676057 -312.74821) (xy 55.718678 -312.723603)
			(xy 55.764694 -312.706151) (xy 55.812913 -312.696307) (xy 55.862088 -312.694326) (xy 55.910943 -312.700258)
			(xy 55.958214 -312.71395) (xy 56.002676 -312.735048) (xy 56.043179 -312.763004) (xy 56.078672 -312.797096)
			(xy 56.108237 -312.83644) (xy 56.131108 -312.880017) (xy 56.146692 -312.926698) (xy 56.154587 -312.975275)
			(xy 56.155082 -312.999882) (xy 57.444144 -312.999882) (xy 57.448104 -312.950828) (xy 57.459881 -312.903044)
			(xy 57.479172 -312.857768) (xy 57.505475 -312.816172) (xy 57.53811 -312.779335) (xy 57.576231 -312.74821)
			(xy 57.618852 -312.723603) (xy 57.664868 -312.706151) (xy 57.713087 -312.696307) (xy 57.762262 -312.694326)
			(xy 57.811117 -312.700258) (xy 57.858388 -312.71395) (xy 57.90285 -312.735048) (xy 57.943353 -312.763004)
			(xy 57.978846 -312.797096) (xy 58.008411 -312.83644) (xy 58.031282 -312.880017) (xy 58.046866 -312.926698)
			(xy 58.054761 -312.975275) (xy 58.055256 -312.999882) (xy 74.544186 -312.999882) (xy 74.548146 -312.950828)
			(xy 74.559923 -312.903044) (xy 74.579214 -312.857768) (xy 74.605517 -312.816172) (xy 74.638152 -312.779335)
			(xy 74.676273 -312.74821) (xy 74.718894 -312.723603) (xy 74.76491 -312.706151) (xy 74.813129 -312.696307)
			(xy 74.862304 -312.694326) (xy 74.911159 -312.700258) (xy 74.95843 -312.71395) (xy 75.002892 -312.735048)
			(xy 75.043395 -312.763004) (xy 75.078888 -312.797096) (xy 75.108453 -312.83644) (xy 75.131324 -312.880017)
			(xy 75.146908 -312.926698) (xy 75.154803 -312.975275) (xy 75.155298 -312.999882) (xy 76.444106 -312.999882)
			(xy 76.448066 -312.950828) (xy 76.459843 -312.903044) (xy 76.479134 -312.857768) (xy 76.505437 -312.816172)
			(xy 76.538072 -312.779335) (xy 76.576193 -312.74821) (xy 76.618814 -312.723603) (xy 76.66483 -312.706151)
			(xy 76.713049 -312.696307) (xy 76.762224 -312.694326) (xy 76.811079 -312.700258) (xy 76.85835 -312.71395)
			(xy 76.902812 -312.735048) (xy 76.943315 -312.763004) (xy 76.978808 -312.797096) (xy 77.008373 -312.83644)
			(xy 77.031244 -312.880017) (xy 77.046828 -312.926698) (xy 77.054723 -312.975275) (xy 77.055218 -312.999882)
			(xy 78.344026 -312.999882) (xy 78.347986 -312.950828) (xy 78.359763 -312.903044) (xy 78.379054 -312.857768)
			(xy 78.405357 -312.816172) (xy 78.437992 -312.779335) (xy 78.476113 -312.74821) (xy 78.518734 -312.723603)
			(xy 78.56475 -312.706151) (xy 78.612969 -312.696307) (xy 78.662144 -312.694326) (xy 78.710999 -312.700258)
			(xy 78.75827 -312.71395) (xy 78.802732 -312.735048) (xy 78.843235 -312.763004) (xy 78.878728 -312.797096)
			(xy 78.908293 -312.83644) (xy 78.931164 -312.880017) (xy 78.946748 -312.926698) (xy 78.954643 -312.975275)
			(xy 78.955138 -312.999882) (xy 80.243946 -312.999882) (xy 80.247906 -312.950828) (xy 80.259683 -312.903044)
			(xy 80.278974 -312.857768) (xy 80.305277 -312.816172) (xy 80.337912 -312.779335) (xy 80.376033 -312.74821)
			(xy 80.418654 -312.723603) (xy 80.46467 -312.706151) (xy 80.512889 -312.696307) (xy 80.562064 -312.694326)
			(xy 80.610919 -312.700258) (xy 80.65819 -312.71395) (xy 80.702652 -312.735048) (xy 80.743155 -312.763004)
			(xy 80.778648 -312.797096) (xy 80.808213 -312.83644) (xy 80.831084 -312.880017) (xy 80.846668 -312.926698)
			(xy 80.854563 -312.975275) (xy 80.855058 -312.999882) (xy 154.54428 -312.999882) (xy 154.54824 -312.950828)
			(xy 154.560017 -312.903044) (xy 154.579308 -312.857768) (xy 154.605611 -312.816172) (xy 154.638246 -312.779335)
			(xy 154.676367 -312.74821) (xy 154.718988 -312.723603) (xy 154.765004 -312.706151) (xy 154.813223 -312.696307)
			(xy 154.862398 -312.694326) (xy 154.911253 -312.700258) (xy 154.958524 -312.71395) (xy 155.002986 -312.735048)
			(xy 155.043489 -312.763004) (xy 155.078982 -312.797096) (xy 155.108547 -312.83644) (xy 155.131418 -312.880017)
			(xy 155.147002 -312.926698) (xy 155.154897 -312.975275) (xy 155.155392 -312.999882) (xy 156.4442 -312.999882)
			(xy 156.44816 -312.950828) (xy 156.459937 -312.903044) (xy 156.479228 -312.857768) (xy 156.505531 -312.816172)
			(xy 156.538166 -312.779335) (xy 156.576287 -312.74821) (xy 156.618908 -312.723603) (xy 156.664924 -312.706151)
			(xy 156.713143 -312.696307) (xy 156.762318 -312.694326) (xy 156.811173 -312.700258) (xy 156.858444 -312.71395)
			(xy 156.902906 -312.735048) (xy 156.943409 -312.763004) (xy 156.978902 -312.797096) (xy 157.008467 -312.83644)
			(xy 157.031338 -312.880017) (xy 157.046922 -312.926698) (xy 157.054817 -312.975275) (xy 157.055312 -312.999882)
			(xy 158.34412 -312.999882) (xy 158.34808 -312.950828) (xy 158.359857 -312.903044) (xy 158.379148 -312.857768)
			(xy 158.405451 -312.816172) (xy 158.438086 -312.779335) (xy 158.476207 -312.74821) (xy 158.518828 -312.723603)
			(xy 158.564844 -312.706151) (xy 158.613063 -312.696307) (xy 158.662238 -312.694326) (xy 158.711093 -312.700258)
			(xy 158.758364 -312.71395) (xy 158.802826 -312.735048) (xy 158.843329 -312.763004) (xy 158.878822 -312.797096)
			(xy 158.908387 -312.83644) (xy 158.931258 -312.880017) (xy 158.946842 -312.926698) (xy 158.954737 -312.975275)
			(xy 158.955232 -312.999882) (xy 160.24404 -312.999882) (xy 160.248 -312.950828) (xy 160.259777 -312.903044)
			(xy 160.279068 -312.857768) (xy 160.305371 -312.816172) (xy 160.338006 -312.779335) (xy 160.376127 -312.74821)
			(xy 160.418748 -312.723603) (xy 160.464764 -312.706151) (xy 160.512983 -312.696307) (xy 160.562158 -312.694326)
			(xy 160.611013 -312.700258) (xy 160.658284 -312.71395) (xy 160.702746 -312.735048) (xy 160.743249 -312.763004)
			(xy 160.778742 -312.797096) (xy 160.808307 -312.83644) (xy 160.831178 -312.880017) (xy 160.846762 -312.926698)
			(xy 160.854657 -312.975275) (xy 160.855152 -312.999882) (xy 162.144214 -312.999882) (xy 162.148174 -312.950828)
			(xy 162.159951 -312.903044) (xy 162.179242 -312.857768) (xy 162.205545 -312.816172) (xy 162.23818 -312.779335)
			(xy 162.276301 -312.74821) (xy 162.318922 -312.723603) (xy 162.364938 -312.706151) (xy 162.413157 -312.696307)
			(xy 162.462332 -312.694326) (xy 162.511187 -312.700258) (xy 162.558458 -312.71395) (xy 162.60292 -312.735048)
			(xy 162.643423 -312.763004) (xy 162.678916 -312.797096) (xy 162.708481 -312.83644) (xy 162.731352 -312.880017)
			(xy 162.746936 -312.926698) (xy 162.754831 -312.975275) (xy 162.755326 -312.999882) (xy 164.044134 -312.999882)
			(xy 164.048094 -312.950828) (xy 164.059871 -312.903044) (xy 164.079162 -312.857768) (xy 164.105465 -312.816172)
			(xy 164.1381 -312.779335) (xy 164.176221 -312.74821) (xy 164.218842 -312.723603) (xy 164.264858 -312.706151)
			(xy 164.313077 -312.696307) (xy 164.362252 -312.694326) (xy 164.411107 -312.700258) (xy 164.458378 -312.71395)
			(xy 164.50284 -312.735048) (xy 164.543343 -312.763004) (xy 164.578836 -312.797096) (xy 164.608401 -312.83644)
			(xy 164.631272 -312.880017) (xy 164.646856 -312.926698) (xy 164.654751 -312.975275) (xy 164.655246 -312.999882)
			(xy 165.944054 -312.999882) (xy 165.948014 -312.950828) (xy 165.959791 -312.903044) (xy 165.979082 -312.857768)
			(xy 166.005385 -312.816172) (xy 166.03802 -312.779335) (xy 166.076141 -312.74821) (xy 166.118762 -312.723603)
			(xy 166.164778 -312.706151) (xy 166.212997 -312.696307) (xy 166.262172 -312.694326) (xy 166.311027 -312.700258)
			(xy 166.358298 -312.71395) (xy 166.40276 -312.735048) (xy 166.443263 -312.763004) (xy 166.478756 -312.797096)
			(xy 166.508321 -312.83644) (xy 166.531192 -312.880017) (xy 166.546776 -312.926698) (xy 166.554671 -312.975275)
			(xy 166.555166 -312.999882) (xy 183.044096 -312.999882) (xy 183.048056 -312.950828) (xy 183.059833 -312.903044)
			(xy 183.079124 -312.857768) (xy 183.105427 -312.816172) (xy 183.138062 -312.779335) (xy 183.176183 -312.74821)
			(xy 183.218804 -312.723603) (xy 183.26482 -312.706151) (xy 183.313039 -312.696307) (xy 183.362214 -312.694326)
			(xy 183.411069 -312.700258) (xy 183.45834 -312.71395) (xy 183.502802 -312.735048) (xy 183.543305 -312.763004)
			(xy 183.578798 -312.797096) (xy 183.608363 -312.83644) (xy 183.631234 -312.880017) (xy 183.646818 -312.926698)
			(xy 183.654713 -312.975275) (xy 183.655208 -312.999882) (xy 184.94427 -312.999882) (xy 184.94823 -312.950828)
			(xy 184.960007 -312.903044) (xy 184.979298 -312.857768) (xy 185.005601 -312.816172) (xy 185.038236 -312.779335)
			(xy 185.076357 -312.74821) (xy 185.118978 -312.723603) (xy 185.164994 -312.706151) (xy 185.213213 -312.696307)
			(xy 185.262388 -312.694326) (xy 185.311243 -312.700258) (xy 185.358514 -312.71395) (xy 185.402976 -312.735048)
			(xy 185.443479 -312.763004) (xy 185.478972 -312.797096) (xy 185.508537 -312.83644) (xy 185.531408 -312.880017)
			(xy 185.546992 -312.926698) (xy 185.554887 -312.975275) (xy 185.555382 -312.999882) (xy 186.84419 -312.999882)
			(xy 186.84815 -312.950828) (xy 186.859927 -312.903044) (xy 186.879218 -312.857768) (xy 186.905521 -312.816172)
			(xy 186.938156 -312.779335) (xy 186.976277 -312.74821) (xy 187.018898 -312.723603) (xy 187.064914 -312.706151)
			(xy 187.113133 -312.696307) (xy 187.162308 -312.694326) (xy 187.211163 -312.700258) (xy 187.258434 -312.71395)
			(xy 187.302896 -312.735048) (xy 187.343399 -312.763004) (xy 187.378892 -312.797096) (xy 187.408457 -312.83644)
			(xy 187.431328 -312.880017) (xy 187.446912 -312.926698) (xy 187.454807 -312.975275) (xy 187.455302 -312.999882)
			(xy 188.74411 -312.999882) (xy 188.74807 -312.950828) (xy 188.759847 -312.903044) (xy 188.779138 -312.857768)
			(xy 188.805441 -312.816172) (xy 188.838076 -312.779335) (xy 188.876197 -312.74821) (xy 188.918818 -312.723603)
			(xy 188.964834 -312.706151) (xy 189.013053 -312.696307) (xy 189.062228 -312.694326) (xy 189.111083 -312.700258)
			(xy 189.158354 -312.71395) (xy 189.202816 -312.735048) (xy 189.243319 -312.763004) (xy 189.278812 -312.797096)
			(xy 189.308377 -312.83644) (xy 189.331248 -312.880017) (xy 189.346832 -312.926698) (xy 189.354727 -312.975275)
			(xy 189.355222 -312.999882) (xy 276.343884 -312.999882) (xy 276.347844 -312.950828) (xy 276.359621 -312.903044)
			(xy 276.378912 -312.857768) (xy 276.405215 -312.816172) (xy 276.43785 -312.779335) (xy 276.475971 -312.74821)
			(xy 276.518592 -312.723603) (xy 276.564608 -312.706151) (xy 276.612827 -312.696307) (xy 276.662002 -312.694326)
			(xy 276.710857 -312.700258) (xy 276.758128 -312.71395) (xy 276.80259 -312.735048) (xy 276.843093 -312.763004)
			(xy 276.878586 -312.797096) (xy 276.908151 -312.83644) (xy 276.931022 -312.880017) (xy 276.946606 -312.926698)
			(xy 276.954501 -312.975275) (xy 276.954996 -312.999882) (xy 278.244058 -312.999882) (xy 278.248018 -312.950828)
			(xy 278.259795 -312.903044) (xy 278.279086 -312.857768) (xy 278.305389 -312.816172) (xy 278.338024 -312.779335)
			(xy 278.376145 -312.74821) (xy 278.418766 -312.723603) (xy 278.464782 -312.706151) (xy 278.513001 -312.696307)
			(xy 278.562176 -312.694326) (xy 278.611031 -312.700258) (xy 278.658302 -312.71395) (xy 278.702764 -312.735048)
			(xy 278.743267 -312.763004) (xy 278.77876 -312.797096) (xy 278.808325 -312.83644) (xy 278.831196 -312.880017)
			(xy 278.84678 -312.926698) (xy 278.854675 -312.975275) (xy 278.85517 -312.999882) (xy 280.143978 -312.999882)
			(xy 280.147938 -312.950828) (xy 280.159715 -312.903044) (xy 280.179006 -312.857768) (xy 280.205309 -312.816172)
			(xy 280.237944 -312.779335) (xy 280.276065 -312.74821) (xy 280.318686 -312.723603) (xy 280.364702 -312.706151)
			(xy 280.412921 -312.696307) (xy 280.462096 -312.694326) (xy 280.510951 -312.700258) (xy 280.558222 -312.71395)
			(xy 280.602684 -312.735048) (xy 280.643187 -312.763004) (xy 280.67868 -312.797096) (xy 280.708245 -312.83644)
			(xy 280.731116 -312.880017) (xy 280.7467 -312.926698) (xy 280.754595 -312.975275) (xy 280.75509 -312.999882)
			(xy 282.043898 -312.999882) (xy 282.047858 -312.950828) (xy 282.059635 -312.903044) (xy 282.078926 -312.857768)
			(xy 282.105229 -312.816172) (xy 282.137864 -312.779335) (xy 282.175985 -312.74821) (xy 282.218606 -312.723603)
			(xy 282.264622 -312.706151) (xy 282.312841 -312.696307) (xy 282.362016 -312.694326) (xy 282.410871 -312.700258)
			(xy 282.458142 -312.71395) (xy 282.502604 -312.735048) (xy 282.543107 -312.763004) (xy 282.5786 -312.797096)
			(xy 282.608165 -312.83644) (xy 282.631036 -312.880017) (xy 282.64662 -312.926698) (xy 282.654515 -312.975275)
			(xy 282.65501 -312.999882) (xy 283.944072 -312.999882) (xy 283.948032 -312.950828) (xy 283.959809 -312.903044)
			(xy 283.9791 -312.857768) (xy 284.005403 -312.816172) (xy 284.038038 -312.779335) (xy 284.076159 -312.74821)
			(xy 284.11878 -312.723603) (xy 284.164796 -312.706151) (xy 284.213015 -312.696307) (xy 284.26219 -312.694326)
			(xy 284.311045 -312.700258) (xy 284.358316 -312.71395) (xy 284.402778 -312.735048) (xy 284.443281 -312.763004)
			(xy 284.478774 -312.797096) (xy 284.508339 -312.83644) (xy 284.53121 -312.880017) (xy 284.546794 -312.926698)
			(xy 284.554689 -312.975275) (xy 284.555184 -312.999882) (xy 285.843992 -312.999882) (xy 285.847952 -312.950828)
			(xy 285.859729 -312.903044) (xy 285.87902 -312.857768) (xy 285.905323 -312.816172) (xy 285.937958 -312.779335)
			(xy 285.976079 -312.74821) (xy 286.0187 -312.723603) (xy 286.064716 -312.706151) (xy 286.112935 -312.696307)
			(xy 286.16211 -312.694326) (xy 286.210965 -312.700258) (xy 286.258236 -312.71395) (xy 286.302698 -312.735048)
			(xy 286.343201 -312.763004) (xy 286.378694 -312.797096) (xy 286.408259 -312.83644) (xy 286.43113 -312.880017)
			(xy 286.446714 -312.926698) (xy 286.454609 -312.975275) (xy 286.455104 -312.999882) (xy 287.743912 -312.999882)
			(xy 287.747872 -312.950828) (xy 287.759649 -312.903044) (xy 287.77894 -312.857768) (xy 287.805243 -312.816172)
			(xy 287.837878 -312.779335) (xy 287.875999 -312.74821) (xy 287.91862 -312.723603) (xy 287.964636 -312.706151)
			(xy 288.012855 -312.696307) (xy 288.06203 -312.694326) (xy 288.110885 -312.700258) (xy 288.158156 -312.71395)
			(xy 288.202618 -312.735048) (xy 288.243121 -312.763004) (xy 288.278614 -312.797096) (xy 288.308179 -312.83644)
			(xy 288.33105 -312.880017) (xy 288.346634 -312.926698) (xy 288.354529 -312.975275) (xy 288.355024 -312.999882)
			(xy 289.644086 -312.999882) (xy 289.648046 -312.950828) (xy 289.659823 -312.903044) (xy 289.679114 -312.857768)
			(xy 289.705417 -312.816172) (xy 289.738052 -312.779335) (xy 289.776173 -312.74821) (xy 289.818794 -312.723603)
			(xy 289.86481 -312.706151) (xy 289.913029 -312.696307) (xy 289.962204 -312.694326) (xy 290.011059 -312.700258)
			(xy 290.05833 -312.71395) (xy 290.102792 -312.735048) (xy 290.143295 -312.763004) (xy 290.178788 -312.797096)
			(xy 290.208353 -312.83644) (xy 290.231224 -312.880017) (xy 290.246808 -312.926698) (xy 290.254703 -312.975275)
			(xy 290.255198 -312.999882) (xy 306.744128 -312.999882) (xy 306.748088 -312.950828) (xy 306.759865 -312.903044)
			(xy 306.779156 -312.857768) (xy 306.805459 -312.816172) (xy 306.838094 -312.779335) (xy 306.876215 -312.74821)
			(xy 306.918836 -312.723603) (xy 306.964852 -312.706151) (xy 307.013071 -312.696307) (xy 307.062246 -312.694326)
			(xy 307.111101 -312.700258) (xy 307.158372 -312.71395) (xy 307.202834 -312.735048) (xy 307.243337 -312.763004)
			(xy 307.27883 -312.797096) (xy 307.308395 -312.83644) (xy 307.331266 -312.880017) (xy 307.34685 -312.926698)
			(xy 307.354745 -312.975275) (xy 307.35524 -312.999882) (xy 308.644048 -312.999882) (xy 308.648008 -312.950828)
			(xy 308.659785 -312.903044) (xy 308.679076 -312.857768) (xy 308.705379 -312.816172) (xy 308.738014 -312.779335)
			(xy 308.776135 -312.74821) (xy 308.818756 -312.723603) (xy 308.864772 -312.706151) (xy 308.912991 -312.696307)
			(xy 308.962166 -312.694326) (xy 309.011021 -312.700258) (xy 309.058292 -312.71395) (xy 309.102754 -312.735048)
			(xy 309.143257 -312.763004) (xy 309.17875 -312.797096) (xy 309.208315 -312.83644) (xy 309.231186 -312.880017)
			(xy 309.24677 -312.926698) (xy 309.254665 -312.975275) (xy 309.25516 -312.999882) (xy 310.543968 -312.999882)
			(xy 310.547928 -312.950828) (xy 310.559705 -312.903044) (xy 310.578996 -312.857768) (xy 310.605299 -312.816172)
			(xy 310.637934 -312.779335) (xy 310.676055 -312.74821) (xy 310.718676 -312.723603) (xy 310.764692 -312.706151)
			(xy 310.812911 -312.696307) (xy 310.862086 -312.694326) (xy 310.910941 -312.700258) (xy 310.958212 -312.71395)
			(xy 311.002674 -312.735048) (xy 311.043177 -312.763004) (xy 311.07867 -312.797096) (xy 311.108235 -312.83644)
			(xy 311.131106 -312.880017) (xy 311.14669 -312.926698) (xy 311.154585 -312.975275) (xy 311.15508 -312.999882)
			(xy 312.443888 -312.999882) (xy 312.447848 -312.950828) (xy 312.459625 -312.903044) (xy 312.478916 -312.857768)
			(xy 312.505219 -312.816172) (xy 312.537854 -312.779335) (xy 312.575975 -312.74821) (xy 312.618596 -312.723603)
			(xy 312.664612 -312.706151) (xy 312.712831 -312.696307) (xy 312.762006 -312.694326) (xy 312.810861 -312.700258)
			(xy 312.858132 -312.71395) (xy 312.902594 -312.735048) (xy 312.943097 -312.763004) (xy 312.97859 -312.797096)
			(xy 313.008155 -312.83644) (xy 313.031026 -312.880017) (xy 313.04661 -312.926698) (xy 313.054505 -312.975275)
			(xy 313.055 -312.999882) (xy 386.744222 -312.999882) (xy 386.748182 -312.950828) (xy 386.759959 -312.903044)
			(xy 386.77925 -312.857768) (xy 386.805553 -312.816172) (xy 386.838188 -312.779335) (xy 386.876309 -312.74821)
			(xy 386.91893 -312.723603) (xy 386.964946 -312.706151) (xy 387.013165 -312.696307) (xy 387.06234 -312.694326)
			(xy 387.111195 -312.700258) (xy 387.158466 -312.71395) (xy 387.202928 -312.735048) (xy 387.243431 -312.763004)
			(xy 387.278924 -312.797096) (xy 387.308489 -312.83644) (xy 387.33136 -312.880017) (xy 387.346944 -312.926698)
			(xy 387.354839 -312.975275) (xy 387.355334 -312.999882) (xy 388.644142 -312.999882) (xy 388.648102 -312.950828)
			(xy 388.659879 -312.903044) (xy 388.67917 -312.857768) (xy 388.705473 -312.816172) (xy 388.738108 -312.779335)
			(xy 388.776229 -312.74821) (xy 388.81885 -312.723603) (xy 388.864866 -312.706151) (xy 388.913085 -312.696307)
			(xy 388.96226 -312.694326) (xy 389.011115 -312.700258) (xy 389.058386 -312.71395) (xy 389.102848 -312.735048)
			(xy 389.143351 -312.763004) (xy 389.178844 -312.797096) (xy 389.208409 -312.83644) (xy 389.23128 -312.880017)
			(xy 389.246864 -312.926698) (xy 389.254759 -312.975275) (xy 389.255254 -312.999882) (xy 390.544062 -312.999882)
			(xy 390.548022 -312.950828) (xy 390.559799 -312.903044) (xy 390.57909 -312.857768) (xy 390.605393 -312.816172)
			(xy 390.638028 -312.779335) (xy 390.676149 -312.74821) (xy 390.71877 -312.723603) (xy 390.764786 -312.706151)
			(xy 390.813005 -312.696307) (xy 390.86218 -312.694326) (xy 390.911035 -312.700258) (xy 390.958306 -312.71395)
			(xy 391.002768 -312.735048) (xy 391.043271 -312.763004) (xy 391.078764 -312.797096) (xy 391.108329 -312.83644)
			(xy 391.1312 -312.880017) (xy 391.146784 -312.926698) (xy 391.154679 -312.975275) (xy 391.155174 -312.999882)
			(xy 392.443982 -312.999882) (xy 392.447942 -312.950828) (xy 392.459719 -312.903044) (xy 392.47901 -312.857768)
			(xy 392.505313 -312.816172) (xy 392.537948 -312.779335) (xy 392.576069 -312.74821) (xy 392.61869 -312.723603)
			(xy 392.664706 -312.706151) (xy 392.712925 -312.696307) (xy 392.7621 -312.694326) (xy 392.810955 -312.700258)
			(xy 392.858226 -312.71395) (xy 392.902688 -312.735048) (xy 392.943191 -312.763004) (xy 392.978684 -312.797096)
			(xy 393.008249 -312.83644) (xy 393.03112 -312.880017) (xy 393.046704 -312.926698) (xy 393.054599 -312.975275)
			(xy 393.055094 -312.999882) (xy 394.344156 -312.999882) (xy 394.348116 -312.950828) (xy 394.359893 -312.903044)
			(xy 394.379184 -312.857768) (xy 394.405487 -312.816172) (xy 394.438122 -312.779335) (xy 394.476243 -312.74821)
			(xy 394.518864 -312.723603) (xy 394.56488 -312.706151) (xy 394.613099 -312.696307) (xy 394.662274 -312.694326)
			(xy 394.711129 -312.700258) (xy 394.7584 -312.71395) (xy 394.802862 -312.735048) (xy 394.843365 -312.763004)
			(xy 394.878858 -312.797096) (xy 394.908423 -312.83644) (xy 394.931294 -312.880017) (xy 394.946878 -312.926698)
			(xy 394.954773 -312.975275) (xy 394.955268 -312.999882) (xy 396.244076 -312.999882) (xy 396.248036 -312.950828)
			(xy 396.259813 -312.903044) (xy 396.279104 -312.857768) (xy 396.305407 -312.816172) (xy 396.338042 -312.779335)
			(xy 396.376163 -312.74821) (xy 396.418784 -312.723603) (xy 396.4648 -312.706151) (xy 396.513019 -312.696307)
			(xy 396.562194 -312.694326) (xy 396.611049 -312.700258) (xy 396.65832 -312.71395) (xy 396.702782 -312.735048)
			(xy 396.743285 -312.763004) (xy 396.778778 -312.797096) (xy 396.808343 -312.83644) (xy 396.831214 -312.880017)
			(xy 396.846798 -312.926698) (xy 396.854693 -312.975275) (xy 396.855188 -312.999882) (xy 398.143996 -312.999882)
			(xy 398.147956 -312.950828) (xy 398.159733 -312.903044) (xy 398.179024 -312.857768) (xy 398.205327 -312.816172)
			(xy 398.237962 -312.779335) (xy 398.276083 -312.74821) (xy 398.318704 -312.723603) (xy 398.36472 -312.706151)
			(xy 398.412939 -312.696307) (xy 398.462114 -312.694326) (xy 398.510969 -312.700258) (xy 398.55824 -312.71395)
			(xy 398.602702 -312.735048) (xy 398.643205 -312.763004) (xy 398.678698 -312.797096) (xy 398.708263 -312.83644)
			(xy 398.731134 -312.880017) (xy 398.746718 -312.926698) (xy 398.754613 -312.975275) (xy 398.755108 -312.999882)
			(xy 415.244038 -312.999882) (xy 415.247998 -312.950828) (xy 415.259775 -312.903044) (xy 415.279066 -312.857768)
			(xy 415.305369 -312.816172) (xy 415.338004 -312.779335) (xy 415.376125 -312.74821) (xy 415.418746 -312.723603)
			(xy 415.464762 -312.706151) (xy 415.512981 -312.696307) (xy 415.562156 -312.694326) (xy 415.611011 -312.700258)
			(xy 415.658282 -312.71395) (xy 415.702744 -312.735048) (xy 415.743247 -312.763004) (xy 415.77874 -312.797096)
			(xy 415.808305 -312.83644) (xy 415.831176 -312.880017) (xy 415.84676 -312.926698) (xy 415.854655 -312.975275)
			(xy 415.85515 -312.999882) (xy 417.144212 -312.999882) (xy 417.148172 -312.950828) (xy 417.159949 -312.903044)
			(xy 417.17924 -312.857768) (xy 417.205543 -312.816172) (xy 417.238178 -312.779335) (xy 417.276299 -312.74821)
			(xy 417.31892 -312.723603) (xy 417.364936 -312.706151) (xy 417.413155 -312.696307) (xy 417.46233 -312.694326)
			(xy 417.511185 -312.700258) (xy 417.558456 -312.71395) (xy 417.602918 -312.735048) (xy 417.643421 -312.763004)
			(xy 417.678914 -312.797096) (xy 417.708479 -312.83644) (xy 417.73135 -312.880017) (xy 417.746934 -312.926698)
			(xy 417.754829 -312.975275) (xy 417.755324 -312.999882) (xy 419.044132 -312.999882) (xy 419.048092 -312.950828)
			(xy 419.059869 -312.903044) (xy 419.07916 -312.857768) (xy 419.105463 -312.816172) (xy 419.138098 -312.779335)
			(xy 419.176219 -312.74821) (xy 419.21884 -312.723603) (xy 419.264856 -312.706151) (xy 419.313075 -312.696307)
			(xy 419.36225 -312.694326) (xy 419.411105 -312.700258) (xy 419.458376 -312.71395) (xy 419.502838 -312.735048)
			(xy 419.543341 -312.763004) (xy 419.578834 -312.797096) (xy 419.608399 -312.83644) (xy 419.63127 -312.880017)
			(xy 419.646854 -312.926698) (xy 419.654749 -312.975275) (xy 419.655244 -312.999882) (xy 420.944052 -312.999882)
			(xy 420.948012 -312.950828) (xy 420.959789 -312.903044) (xy 420.97908 -312.857768) (xy 421.005383 -312.816172)
			(xy 421.038018 -312.779335) (xy 421.076139 -312.74821) (xy 421.11876 -312.723603) (xy 421.164776 -312.706151)
			(xy 421.212995 -312.696307) (xy 421.26217 -312.694326) (xy 421.311025 -312.700258) (xy 421.358296 -312.71395)
			(xy 421.402758 -312.735048) (xy 421.443261 -312.763004) (xy 421.478754 -312.797096) (xy 421.508319 -312.83644)
			(xy 421.53119 -312.880017) (xy 421.546774 -312.926698) (xy 421.554669 -312.975275) (xy 421.555164 -312.999882)
			(xy 421.554669 -313.024489) (xy 421.546774 -313.073066) (xy 421.53119 -313.119747) (xy 421.508319 -313.163324)
			(xy 421.478754 -313.202668) (xy 421.443261 -313.23676) (xy 421.402758 -313.264716) (xy 421.358296 -313.285814)
			(xy 421.311025 -313.299506) (xy 421.26217 -313.305438) (xy 421.212995 -313.303457) (xy 421.164776 -313.293613)
			(xy 421.11876 -313.276161) (xy 421.076139 -313.251554) (xy 421.038018 -313.220429) (xy 421.005383 -313.183592)
			(xy 420.97908 -313.141996) (xy 420.959789 -313.09672) (xy 420.948012 -313.048936) (xy 420.944052 -312.999882)
			(xy 419.655244 -312.999882) (xy 419.654749 -313.024489) (xy 419.646854 -313.073066) (xy 419.63127 -313.119747)
			(xy 419.608399 -313.163324) (xy 419.578834 -313.202668) (xy 419.543341 -313.23676) (xy 419.502838 -313.264716)
			(xy 419.458376 -313.285814) (xy 419.411105 -313.299506) (xy 419.36225 -313.305438) (xy 419.313075 -313.303457)
			(xy 419.264856 -313.293613) (xy 419.21884 -313.276161) (xy 419.176219 -313.251554) (xy 419.138098 -313.220429)
			(xy 419.105463 -313.183592) (xy 419.07916 -313.141996) (xy 419.059869 -313.09672) (xy 419.048092 -313.048936)
			(xy 419.044132 -312.999882) (xy 417.755324 -312.999882) (xy 417.754829 -313.024489) (xy 417.746934 -313.073066)
			(xy 417.73135 -313.119747) (xy 417.708479 -313.163324) (xy 417.678914 -313.202668) (xy 417.643421 -313.23676)
			(xy 417.602918 -313.264716) (xy 417.558456 -313.285814) (xy 417.511185 -313.299506) (xy 417.46233 -313.305438)
			(xy 417.413155 -313.303457) (xy 417.364936 -313.293613) (xy 417.31892 -313.276161) (xy 417.276299 -313.251554)
			(xy 417.238178 -313.220429) (xy 417.205543 -313.183592) (xy 417.17924 -313.141996) (xy 417.159949 -313.09672)
			(xy 417.148172 -313.048936) (xy 417.144212 -312.999882) (xy 415.85515 -312.999882) (xy 415.854655 -313.024489)
			(xy 415.84676 -313.073066) (xy 415.831176 -313.119747) (xy 415.808305 -313.163324) (xy 415.77874 -313.202668)
			(xy 415.743247 -313.23676) (xy 415.702744 -313.264716) (xy 415.658282 -313.285814) (xy 415.611011 -313.299506)
			(xy 415.562156 -313.305438) (xy 415.512981 -313.303457) (xy 415.464762 -313.293613) (xy 415.418746 -313.276161)
			(xy 415.376125 -313.251554) (xy 415.338004 -313.220429) (xy 415.305369 -313.183592) (xy 415.279066 -313.141996)
			(xy 415.259775 -313.09672) (xy 415.247998 -313.048936) (xy 415.244038 -312.999882) (xy 398.755108 -312.999882)
			(xy 398.754613 -313.024489) (xy 398.746718 -313.073066) (xy 398.731134 -313.119747) (xy 398.708263 -313.163324)
			(xy 398.678698 -313.202668) (xy 398.643205 -313.23676) (xy 398.602702 -313.264716) (xy 398.55824 -313.285814)
			(xy 398.510969 -313.299506) (xy 398.462114 -313.305438) (xy 398.412939 -313.303457) (xy 398.36472 -313.293613)
			(xy 398.318704 -313.276161) (xy 398.276083 -313.251554) (xy 398.237962 -313.220429) (xy 398.205327 -313.183592)
			(xy 398.179024 -313.141996) (xy 398.159733 -313.09672) (xy 398.147956 -313.048936) (xy 398.143996 -312.999882)
			(xy 396.855188 -312.999882) (xy 396.854693 -313.024489) (xy 396.846798 -313.073066) (xy 396.831214 -313.119747)
			(xy 396.808343 -313.163324) (xy 396.778778 -313.202668) (xy 396.743285 -313.23676) (xy 396.702782 -313.264716)
			(xy 396.65832 -313.285814) (xy 396.611049 -313.299506) (xy 396.562194 -313.305438) (xy 396.513019 -313.303457)
			(xy 396.4648 -313.293613) (xy 396.418784 -313.276161) (xy 396.376163 -313.251554) (xy 396.338042 -313.220429)
			(xy 396.305407 -313.183592) (xy 396.279104 -313.141996) (xy 396.259813 -313.09672) (xy 396.248036 -313.048936)
			(xy 396.244076 -312.999882) (xy 394.955268 -312.999882) (xy 394.954773 -313.024489) (xy 394.946878 -313.073066)
			(xy 394.931294 -313.119747) (xy 394.908423 -313.163324) (xy 394.878858 -313.202668) (xy 394.843365 -313.23676)
			(xy 394.802862 -313.264716) (xy 394.7584 -313.285814) (xy 394.711129 -313.299506) (xy 394.662274 -313.305438)
			(xy 394.613099 -313.303457) (xy 394.56488 -313.293613) (xy 394.518864 -313.276161) (xy 394.476243 -313.251554)
			(xy 394.438122 -313.220429) (xy 394.405487 -313.183592) (xy 394.379184 -313.141996) (xy 394.359893 -313.09672)
			(xy 394.348116 -313.048936) (xy 394.344156 -312.999882) (xy 393.055094 -312.999882) (xy 393.054599 -313.024489)
			(xy 393.046704 -313.073066) (xy 393.03112 -313.119747) (xy 393.008249 -313.163324) (xy 392.978684 -313.202668)
			(xy 392.943191 -313.23676) (xy 392.902688 -313.264716) (xy 392.858226 -313.285814) (xy 392.810955 -313.299506)
			(xy 392.7621 -313.305438) (xy 392.712925 -313.303457) (xy 392.664706 -313.293613) (xy 392.61869 -313.276161)
			(xy 392.576069 -313.251554) (xy 392.537948 -313.220429) (xy 392.505313 -313.183592) (xy 392.47901 -313.141996)
			(xy 392.459719 -313.09672) (xy 392.447942 -313.048936) (xy 392.443982 -312.999882) (xy 391.155174 -312.999882)
			(xy 391.154679 -313.024489) (xy 391.146784 -313.073066) (xy 391.1312 -313.119747) (xy 391.108329 -313.163324)
			(xy 391.078764 -313.202668) (xy 391.043271 -313.23676) (xy 391.002768 -313.264716) (xy 390.958306 -313.285814)
			(xy 390.911035 -313.299506) (xy 390.86218 -313.305438) (xy 390.813005 -313.303457) (xy 390.764786 -313.293613)
			(xy 390.71877 -313.276161) (xy 390.676149 -313.251554) (xy 390.638028 -313.220429) (xy 390.605393 -313.183592)
			(xy 390.57909 -313.141996) (xy 390.559799 -313.09672) (xy 390.548022 -313.048936) (xy 390.544062 -312.999882)
			(xy 389.255254 -312.999882) (xy 389.254759 -313.024489) (xy 389.246864 -313.073066) (xy 389.23128 -313.119747)
			(xy 389.208409 -313.163324) (xy 389.178844 -313.202668) (xy 389.143351 -313.23676) (xy 389.102848 -313.264716)
			(xy 389.058386 -313.285814) (xy 389.011115 -313.299506) (xy 388.96226 -313.305438) (xy 388.913085 -313.303457)
			(xy 388.864866 -313.293613) (xy 388.81885 -313.276161) (xy 388.776229 -313.251554) (xy 388.738108 -313.220429)
			(xy 388.705473 -313.183592) (xy 388.67917 -313.141996) (xy 388.659879 -313.09672) (xy 388.648102 -313.048936)
			(xy 388.644142 -312.999882) (xy 387.355334 -312.999882) (xy 387.354839 -313.024489) (xy 387.346944 -313.073066)
			(xy 387.33136 -313.119747) (xy 387.308489 -313.163324) (xy 387.278924 -313.202668) (xy 387.243431 -313.23676)
			(xy 387.202928 -313.264716) (xy 387.158466 -313.285814) (xy 387.111195 -313.299506) (xy 387.06234 -313.305438)
			(xy 387.013165 -313.303457) (xy 386.964946 -313.293613) (xy 386.91893 -313.276161) (xy 386.876309 -313.251554)
			(xy 386.838188 -313.220429) (xy 386.805553 -313.183592) (xy 386.77925 -313.141996) (xy 386.759959 -313.09672)
			(xy 386.748182 -313.048936) (xy 386.744222 -312.999882) (xy 313.055 -312.999882) (xy 313.054505 -313.024489)
			(xy 313.04661 -313.073066) (xy 313.031026 -313.119747) (xy 313.008155 -313.163324) (xy 312.97859 -313.202668)
			(xy 312.943097 -313.23676) (xy 312.902594 -313.264716) (xy 312.858132 -313.285814) (xy 312.810861 -313.299506)
			(xy 312.762006 -313.305438) (xy 312.712831 -313.303457) (xy 312.664612 -313.293613) (xy 312.618596 -313.276161)
			(xy 312.575975 -313.251554) (xy 312.537854 -313.220429) (xy 312.505219 -313.183592) (xy 312.478916 -313.141996)
			(xy 312.459625 -313.09672) (xy 312.447848 -313.048936) (xy 312.443888 -312.999882) (xy 311.15508 -312.999882)
			(xy 311.154585 -313.024489) (xy 311.14669 -313.073066) (xy 311.131106 -313.119747) (xy 311.108235 -313.163324)
			(xy 311.07867 -313.202668) (xy 311.043177 -313.23676) (xy 311.002674 -313.264716) (xy 310.958212 -313.285814)
			(xy 310.910941 -313.299506) (xy 310.862086 -313.305438) (xy 310.812911 -313.303457) (xy 310.764692 -313.293613)
			(xy 310.718676 -313.276161) (xy 310.676055 -313.251554) (xy 310.637934 -313.220429) (xy 310.605299 -313.183592)
			(xy 310.578996 -313.141996) (xy 310.559705 -313.09672) (xy 310.547928 -313.048936) (xy 310.543968 -312.999882)
			(xy 309.25516 -312.999882) (xy 309.254665 -313.024489) (xy 309.24677 -313.073066) (xy 309.231186 -313.119747)
			(xy 309.208315 -313.163324) (xy 309.17875 -313.202668) (xy 309.143257 -313.23676) (xy 309.102754 -313.264716)
			(xy 309.058292 -313.285814) (xy 309.011021 -313.299506) (xy 308.962166 -313.305438) (xy 308.912991 -313.303457)
			(xy 308.864772 -313.293613) (xy 308.818756 -313.276161) (xy 308.776135 -313.251554) (xy 308.738014 -313.220429)
			(xy 308.705379 -313.183592) (xy 308.679076 -313.141996) (xy 308.659785 -313.09672) (xy 308.648008 -313.048936)
			(xy 308.644048 -312.999882) (xy 307.35524 -312.999882) (xy 307.354745 -313.024489) (xy 307.34685 -313.073066)
			(xy 307.331266 -313.119747) (xy 307.308395 -313.163324) (xy 307.27883 -313.202668) (xy 307.243337 -313.23676)
			(xy 307.202834 -313.264716) (xy 307.158372 -313.285814) (xy 307.111101 -313.299506) (xy 307.062246 -313.305438)
			(xy 307.013071 -313.303457) (xy 306.964852 -313.293613) (xy 306.918836 -313.276161) (xy 306.876215 -313.251554)
			(xy 306.838094 -313.220429) (xy 306.805459 -313.183592) (xy 306.779156 -313.141996) (xy 306.759865 -313.09672)
			(xy 306.748088 -313.048936) (xy 306.744128 -312.999882) (xy 290.255198 -312.999882) (xy 290.254703 -313.024489)
			(xy 290.246808 -313.073066) (xy 290.231224 -313.119747) (xy 290.208353 -313.163324) (xy 290.178788 -313.202668)
			(xy 290.143295 -313.23676) (xy 290.102792 -313.264716) (xy 290.05833 -313.285814) (xy 290.011059 -313.299506)
			(xy 289.962204 -313.305438) (xy 289.913029 -313.303457) (xy 289.86481 -313.293613) (xy 289.818794 -313.276161)
			(xy 289.776173 -313.251554) (xy 289.738052 -313.220429) (xy 289.705417 -313.183592) (xy 289.679114 -313.141996)
			(xy 289.659823 -313.09672) (xy 289.648046 -313.048936) (xy 289.644086 -312.999882) (xy 288.355024 -312.999882)
			(xy 288.354529 -313.024489) (xy 288.346634 -313.073066) (xy 288.33105 -313.119747) (xy 288.308179 -313.163324)
			(xy 288.278614 -313.202668) (xy 288.243121 -313.23676) (xy 288.202618 -313.264716) (xy 288.158156 -313.285814)
			(xy 288.110885 -313.299506) (xy 288.06203 -313.305438) (xy 288.012855 -313.303457) (xy 287.964636 -313.293613)
			(xy 287.91862 -313.276161) (xy 287.875999 -313.251554) (xy 287.837878 -313.220429) (xy 287.805243 -313.183592)
			(xy 287.77894 -313.141996) (xy 287.759649 -313.09672) (xy 287.747872 -313.048936) (xy 287.743912 -312.999882)
			(xy 286.455104 -312.999882) (xy 286.454609 -313.024489) (xy 286.446714 -313.073066) (xy 286.43113 -313.119747)
			(xy 286.408259 -313.163324) (xy 286.378694 -313.202668) (xy 286.343201 -313.23676) (xy 286.302698 -313.264716)
			(xy 286.258236 -313.285814) (xy 286.210965 -313.299506) (xy 286.16211 -313.305438) (xy 286.112935 -313.303457)
			(xy 286.064716 -313.293613) (xy 286.0187 -313.276161) (xy 285.976079 -313.251554) (xy 285.937958 -313.220429)
			(xy 285.905323 -313.183592) (xy 285.87902 -313.141996) (xy 285.859729 -313.09672) (xy 285.847952 -313.048936)
			(xy 285.843992 -312.999882) (xy 284.555184 -312.999882) (xy 284.554689 -313.024489) (xy 284.546794 -313.073066)
			(xy 284.53121 -313.119747) (xy 284.508339 -313.163324) (xy 284.478774 -313.202668) (xy 284.443281 -313.23676)
			(xy 284.402778 -313.264716) (xy 284.358316 -313.285814) (xy 284.311045 -313.299506) (xy 284.26219 -313.305438)
			(xy 284.213015 -313.303457) (xy 284.164796 -313.293613) (xy 284.11878 -313.276161) (xy 284.076159 -313.251554)
			(xy 284.038038 -313.220429) (xy 284.005403 -313.183592) (xy 283.9791 -313.141996) (xy 283.959809 -313.09672)
			(xy 283.948032 -313.048936) (xy 283.944072 -312.999882) (xy 282.65501 -312.999882) (xy 282.654515 -313.024489)
			(xy 282.64662 -313.073066) (xy 282.631036 -313.119747) (xy 282.608165 -313.163324) (xy 282.5786 -313.202668)
			(xy 282.543107 -313.23676) (xy 282.502604 -313.264716) (xy 282.458142 -313.285814) (xy 282.410871 -313.299506)
			(xy 282.362016 -313.305438) (xy 282.312841 -313.303457) (xy 282.264622 -313.293613) (xy 282.218606 -313.276161)
			(xy 282.175985 -313.251554) (xy 282.137864 -313.220429) (xy 282.105229 -313.183592) (xy 282.078926 -313.141996)
			(xy 282.059635 -313.09672) (xy 282.047858 -313.048936) (xy 282.043898 -312.999882) (xy 280.75509 -312.999882)
			(xy 280.754595 -313.024489) (xy 280.7467 -313.073066) (xy 280.731116 -313.119747) (xy 280.708245 -313.163324)
			(xy 280.67868 -313.202668) (xy 280.643187 -313.23676) (xy 280.602684 -313.264716) (xy 280.558222 -313.285814)
			(xy 280.510951 -313.299506) (xy 280.462096 -313.305438) (xy 280.412921 -313.303457) (xy 280.364702 -313.293613)
			(xy 280.318686 -313.276161) (xy 280.276065 -313.251554) (xy 280.237944 -313.220429) (xy 280.205309 -313.183592)
			(xy 280.179006 -313.141996) (xy 280.159715 -313.09672) (xy 280.147938 -313.048936) (xy 280.143978 -312.999882)
			(xy 278.85517 -312.999882) (xy 278.854675 -313.024489) (xy 278.84678 -313.073066) (xy 278.831196 -313.119747)
			(xy 278.808325 -313.163324) (xy 278.77876 -313.202668) (xy 278.743267 -313.23676) (xy 278.702764 -313.264716)
			(xy 278.658302 -313.285814) (xy 278.611031 -313.299506) (xy 278.562176 -313.305438) (xy 278.513001 -313.303457)
			(xy 278.464782 -313.293613) (xy 278.418766 -313.276161) (xy 278.376145 -313.251554) (xy 278.338024 -313.220429)
			(xy 278.305389 -313.183592) (xy 278.279086 -313.141996) (xy 278.259795 -313.09672) (xy 278.248018 -313.048936)
			(xy 278.244058 -312.999882) (xy 276.954996 -312.999882) (xy 276.954501 -313.024489) (xy 276.946606 -313.073066)
			(xy 276.931022 -313.119747) (xy 276.908151 -313.163324) (xy 276.878586 -313.202668) (xy 276.843093 -313.23676)
			(xy 276.80259 -313.264716) (xy 276.758128 -313.285814) (xy 276.710857 -313.299506) (xy 276.662002 -313.305438)
			(xy 276.612827 -313.303457) (xy 276.564608 -313.293613) (xy 276.518592 -313.276161) (xy 276.475971 -313.251554)
			(xy 276.43785 -313.220429) (xy 276.405215 -313.183592) (xy 276.378912 -313.141996) (xy 276.359621 -313.09672)
			(xy 276.347844 -313.048936) (xy 276.343884 -312.999882) (xy 189.355222 -312.999882) (xy 189.354727 -313.024489)
			(xy 189.346832 -313.073066) (xy 189.331248 -313.119747) (xy 189.308377 -313.163324) (xy 189.278812 -313.202668)
			(xy 189.243319 -313.23676) (xy 189.202816 -313.264716) (xy 189.158354 -313.285814) (xy 189.111083 -313.299506)
			(xy 189.062228 -313.305438) (xy 189.013053 -313.303457) (xy 188.964834 -313.293613) (xy 188.918818 -313.276161)
			(xy 188.876197 -313.251554) (xy 188.838076 -313.220429) (xy 188.805441 -313.183592) (xy 188.779138 -313.141996)
			(xy 188.759847 -313.09672) (xy 188.74807 -313.048936) (xy 188.74411 -312.999882) (xy 187.455302 -312.999882)
			(xy 187.454807 -313.024489) (xy 187.446912 -313.073066) (xy 187.431328 -313.119747) (xy 187.408457 -313.163324)
			(xy 187.378892 -313.202668) (xy 187.343399 -313.23676) (xy 187.302896 -313.264716) (xy 187.258434 -313.285814)
			(xy 187.211163 -313.299506) (xy 187.162308 -313.305438) (xy 187.113133 -313.303457) (xy 187.064914 -313.293613)
			(xy 187.018898 -313.276161) (xy 186.976277 -313.251554) (xy 186.938156 -313.220429) (xy 186.905521 -313.183592)
			(xy 186.879218 -313.141996) (xy 186.859927 -313.09672) (xy 186.84815 -313.048936) (xy 186.84419 -312.999882)
			(xy 185.555382 -312.999882) (xy 185.554887 -313.024489) (xy 185.546992 -313.073066) (xy 185.531408 -313.119747)
			(xy 185.508537 -313.163324) (xy 185.478972 -313.202668) (xy 185.443479 -313.23676) (xy 185.402976 -313.264716)
			(xy 185.358514 -313.285814) (xy 185.311243 -313.299506) (xy 185.262388 -313.305438) (xy 185.213213 -313.303457)
			(xy 185.164994 -313.293613) (xy 185.118978 -313.276161) (xy 185.076357 -313.251554) (xy 185.038236 -313.220429)
			(xy 185.005601 -313.183592) (xy 184.979298 -313.141996) (xy 184.960007 -313.09672) (xy 184.94823 -313.048936)
			(xy 184.94427 -312.999882) (xy 183.655208 -312.999882) (xy 183.654713 -313.024489) (xy 183.646818 -313.073066)
			(xy 183.631234 -313.119747) (xy 183.608363 -313.163324) (xy 183.578798 -313.202668) (xy 183.543305 -313.23676)
			(xy 183.502802 -313.264716) (xy 183.45834 -313.285814) (xy 183.411069 -313.299506) (xy 183.362214 -313.305438)
			(xy 183.313039 -313.303457) (xy 183.26482 -313.293613) (xy 183.218804 -313.276161) (xy 183.176183 -313.251554)
			(xy 183.138062 -313.220429) (xy 183.105427 -313.183592) (xy 183.079124 -313.141996) (xy 183.059833 -313.09672)
			(xy 183.048056 -313.048936) (xy 183.044096 -312.999882) (xy 166.555166 -312.999882) (xy 166.554671 -313.024489)
			(xy 166.546776 -313.073066) (xy 166.531192 -313.119747) (xy 166.508321 -313.163324) (xy 166.478756 -313.202668)
			(xy 166.443263 -313.23676) (xy 166.40276 -313.264716) (xy 166.358298 -313.285814) (xy 166.311027 -313.299506)
			(xy 166.262172 -313.305438) (xy 166.212997 -313.303457) (xy 166.164778 -313.293613) (xy 166.118762 -313.276161)
			(xy 166.076141 -313.251554) (xy 166.03802 -313.220429) (xy 166.005385 -313.183592) (xy 165.979082 -313.141996)
			(xy 165.959791 -313.09672) (xy 165.948014 -313.048936) (xy 165.944054 -312.999882) (xy 164.655246 -312.999882)
			(xy 164.654751 -313.024489) (xy 164.646856 -313.073066) (xy 164.631272 -313.119747) (xy 164.608401 -313.163324)
			(xy 164.578836 -313.202668) (xy 164.543343 -313.23676) (xy 164.50284 -313.264716) (xy 164.458378 -313.285814)
			(xy 164.411107 -313.299506) (xy 164.362252 -313.305438) (xy 164.313077 -313.303457) (xy 164.264858 -313.293613)
			(xy 164.218842 -313.276161) (xy 164.176221 -313.251554) (xy 164.1381 -313.220429) (xy 164.105465 -313.183592)
			(xy 164.079162 -313.141996) (xy 164.059871 -313.09672) (xy 164.048094 -313.048936) (xy 164.044134 -312.999882)
			(xy 162.755326 -312.999882) (xy 162.754831 -313.024489) (xy 162.746936 -313.073066) (xy 162.731352 -313.119747)
			(xy 162.708481 -313.163324) (xy 162.678916 -313.202668) (xy 162.643423 -313.23676) (xy 162.60292 -313.264716)
			(xy 162.558458 -313.285814) (xy 162.511187 -313.299506) (xy 162.462332 -313.305438) (xy 162.413157 -313.303457)
			(xy 162.364938 -313.293613) (xy 162.318922 -313.276161) (xy 162.276301 -313.251554) (xy 162.23818 -313.220429)
			(xy 162.205545 -313.183592) (xy 162.179242 -313.141996) (xy 162.159951 -313.09672) (xy 162.148174 -313.048936)
			(xy 162.144214 -312.999882) (xy 160.855152 -312.999882) (xy 160.854657 -313.024489) (xy 160.846762 -313.073066)
			(xy 160.831178 -313.119747) (xy 160.808307 -313.163324) (xy 160.778742 -313.202668) (xy 160.743249 -313.23676)
			(xy 160.702746 -313.264716) (xy 160.658284 -313.285814) (xy 160.611013 -313.299506) (xy 160.562158 -313.305438)
			(xy 160.512983 -313.303457) (xy 160.464764 -313.293613) (xy 160.418748 -313.276161) (xy 160.376127 -313.251554)
			(xy 160.338006 -313.220429) (xy 160.305371 -313.183592) (xy 160.279068 -313.141996) (xy 160.259777 -313.09672)
			(xy 160.248 -313.048936) (xy 160.24404 -312.999882) (xy 158.955232 -312.999882) (xy 158.954737 -313.024489)
			(xy 158.946842 -313.073066) (xy 158.931258 -313.119747) (xy 158.908387 -313.163324) (xy 158.878822 -313.202668)
			(xy 158.843329 -313.23676) (xy 158.802826 -313.264716) (xy 158.758364 -313.285814) (xy 158.711093 -313.299506)
			(xy 158.662238 -313.305438) (xy 158.613063 -313.303457) (xy 158.564844 -313.293613) (xy 158.518828 -313.276161)
			(xy 158.476207 -313.251554) (xy 158.438086 -313.220429) (xy 158.405451 -313.183592) (xy 158.379148 -313.141996)
			(xy 158.359857 -313.09672) (xy 158.34808 -313.048936) (xy 158.34412 -312.999882) (xy 157.055312 -312.999882)
			(xy 157.054817 -313.024489) (xy 157.046922 -313.073066) (xy 157.031338 -313.119747) (xy 157.008467 -313.163324)
			(xy 156.978902 -313.202668) (xy 156.943409 -313.23676) (xy 156.902906 -313.264716) (xy 156.858444 -313.285814)
			(xy 156.811173 -313.299506) (xy 156.762318 -313.305438) (xy 156.713143 -313.303457) (xy 156.664924 -313.293613)
			(xy 156.618908 -313.276161) (xy 156.576287 -313.251554) (xy 156.538166 -313.220429) (xy 156.505531 -313.183592)
			(xy 156.479228 -313.141996) (xy 156.459937 -313.09672) (xy 156.44816 -313.048936) (xy 156.4442 -312.999882)
			(xy 155.155392 -312.999882) (xy 155.154897 -313.024489) (xy 155.147002 -313.073066) (xy 155.131418 -313.119747)
			(xy 155.108547 -313.163324) (xy 155.078982 -313.202668) (xy 155.043489 -313.23676) (xy 155.002986 -313.264716)
			(xy 154.958524 -313.285814) (xy 154.911253 -313.299506) (xy 154.862398 -313.305438) (xy 154.813223 -313.303457)
			(xy 154.765004 -313.293613) (xy 154.718988 -313.276161) (xy 154.676367 -313.251554) (xy 154.638246 -313.220429)
			(xy 154.605611 -313.183592) (xy 154.579308 -313.141996) (xy 154.560017 -313.09672) (xy 154.54824 -313.048936)
			(xy 154.54428 -312.999882) (xy 80.855058 -312.999882) (xy 80.854563 -313.024489) (xy 80.846668 -313.073066)
			(xy 80.831084 -313.119747) (xy 80.808213 -313.163324) (xy 80.778648 -313.202668) (xy 80.743155 -313.23676)
			(xy 80.702652 -313.264716) (xy 80.65819 -313.285814) (xy 80.610919 -313.299506) (xy 80.562064 -313.305438)
			(xy 80.512889 -313.303457) (xy 80.46467 -313.293613) (xy 80.418654 -313.276161) (xy 80.376033 -313.251554)
			(xy 80.337912 -313.220429) (xy 80.305277 -313.183592) (xy 80.278974 -313.141996) (xy 80.259683 -313.09672)
			(xy 80.247906 -313.048936) (xy 80.243946 -312.999882) (xy 78.955138 -312.999882) (xy 78.954643 -313.024489)
			(xy 78.946748 -313.073066) (xy 78.931164 -313.119747) (xy 78.908293 -313.163324) (xy 78.878728 -313.202668)
			(xy 78.843235 -313.23676) (xy 78.802732 -313.264716) (xy 78.75827 -313.285814) (xy 78.710999 -313.299506)
			(xy 78.662144 -313.305438) (xy 78.612969 -313.303457) (xy 78.56475 -313.293613) (xy 78.518734 -313.276161)
			(xy 78.476113 -313.251554) (xy 78.437992 -313.220429) (xy 78.405357 -313.183592) (xy 78.379054 -313.141996)
			(xy 78.359763 -313.09672) (xy 78.347986 -313.048936) (xy 78.344026 -312.999882) (xy 77.055218 -312.999882)
			(xy 77.054723 -313.024489) (xy 77.046828 -313.073066) (xy 77.031244 -313.119747) (xy 77.008373 -313.163324)
			(xy 76.978808 -313.202668) (xy 76.943315 -313.23676) (xy 76.902812 -313.264716) (xy 76.85835 -313.285814)
			(xy 76.811079 -313.299506) (xy 76.762224 -313.305438) (xy 76.713049 -313.303457) (xy 76.66483 -313.293613)
			(xy 76.618814 -313.276161) (xy 76.576193 -313.251554) (xy 76.538072 -313.220429) (xy 76.505437 -313.183592)
			(xy 76.479134 -313.141996) (xy 76.459843 -313.09672) (xy 76.448066 -313.048936) (xy 76.444106 -312.999882)
			(xy 75.155298 -312.999882) (xy 75.154803 -313.024489) (xy 75.146908 -313.073066) (xy 75.131324 -313.119747)
			(xy 75.108453 -313.163324) (xy 75.078888 -313.202668) (xy 75.043395 -313.23676) (xy 75.002892 -313.264716)
			(xy 74.95843 -313.285814) (xy 74.911159 -313.299506) (xy 74.862304 -313.305438) (xy 74.813129 -313.303457)
			(xy 74.76491 -313.293613) (xy 74.718894 -313.276161) (xy 74.676273 -313.251554) (xy 74.638152 -313.220429)
			(xy 74.605517 -313.183592) (xy 74.579214 -313.141996) (xy 74.559923 -313.09672) (xy 74.548146 -313.048936)
			(xy 74.544186 -312.999882) (xy 58.055256 -312.999882) (xy 58.054761 -313.024489) (xy 58.046866 -313.073066)
			(xy 58.031282 -313.119747) (xy 58.008411 -313.163324) (xy 57.978846 -313.202668) (xy 57.943353 -313.23676)
			(xy 57.90285 -313.264716) (xy 57.858388 -313.285814) (xy 57.811117 -313.299506) (xy 57.762262 -313.305438)
			(xy 57.713087 -313.303457) (xy 57.664868 -313.293613) (xy 57.618852 -313.276161) (xy 57.576231 -313.251554)
			(xy 57.53811 -313.220429) (xy 57.505475 -313.183592) (xy 57.479172 -313.141996) (xy 57.459881 -313.09672)
			(xy 57.448104 -313.048936) (xy 57.444144 -312.999882) (xy 56.155082 -312.999882) (xy 56.154587 -313.024489)
			(xy 56.146692 -313.073066) (xy 56.131108 -313.119747) (xy 56.108237 -313.163324) (xy 56.078672 -313.202668)
			(xy 56.043179 -313.23676) (xy 56.002676 -313.264716) (xy 55.958214 -313.285814) (xy 55.910943 -313.299506)
			(xy 55.862088 -313.305438) (xy 55.812913 -313.303457) (xy 55.764694 -313.293613) (xy 55.718678 -313.276161)
			(xy 55.676057 -313.251554) (xy 55.637936 -313.220429) (xy 55.605301 -313.183592) (xy 55.578998 -313.141996)
			(xy 55.559707 -313.09672) (xy 55.54793 -313.048936) (xy 55.54397 -312.999882) (xy 54.255162 -312.999882)
			(xy 54.254667 -313.024489) (xy 54.246772 -313.073066) (xy 54.231188 -313.119747) (xy 54.208317 -313.163324)
			(xy 54.178752 -313.202668) (xy 54.143259 -313.23676) (xy 54.102756 -313.264716) (xy 54.058294 -313.285814)
			(xy 54.011023 -313.299506) (xy 53.962168 -313.305438) (xy 53.912993 -313.303457) (xy 53.864774 -313.293613)
			(xy 53.818758 -313.276161) (xy 53.776137 -313.251554) (xy 53.738016 -313.220429) (xy 53.705381 -313.183592)
			(xy 53.679078 -313.141996) (xy 53.659787 -313.09672) (xy 53.64801 -313.048936) (xy 53.64405 -312.999882)
			(xy 52.355242 -312.999882) (xy 52.354747 -313.024489) (xy 52.346852 -313.073066) (xy 52.331268 -313.119747)
			(xy 52.308397 -313.163324) (xy 52.278832 -313.202668) (xy 52.243339 -313.23676) (xy 52.202836 -313.264716)
			(xy 52.158374 -313.285814) (xy 52.111103 -313.299506) (xy 52.062248 -313.305438) (xy 52.013073 -313.303457)
			(xy 51.964854 -313.293613) (xy 51.918838 -313.276161) (xy 51.876217 -313.251554) (xy 51.838096 -313.220429)
			(xy 51.805461 -313.183592) (xy 51.779158 -313.141996) (xy 51.759867 -313.09672) (xy 51.74809 -313.048936)
			(xy 51.74413 -312.999882) (xy 50.455068 -312.999882) (xy 50.454573 -313.024489) (xy 50.446678 -313.073066)
			(xy 50.431094 -313.119747) (xy 50.408223 -313.163324) (xy 50.378658 -313.202668) (xy 50.343165 -313.23676)
			(xy 50.302662 -313.264716) (xy 50.2582 -313.285814) (xy 50.210929 -313.299506) (xy 50.162074 -313.305438)
			(xy 50.112899 -313.303457) (xy 50.06468 -313.293613) (xy 50.018664 -313.276161) (xy 49.976043 -313.251554)
			(xy 49.937922 -313.220429) (xy 49.905287 -313.183592) (xy 49.878984 -313.141996) (xy 49.859693 -313.09672)
			(xy 49.847916 -313.048936) (xy 49.843956 -312.999882) (xy 48.555148 -312.999882) (xy 48.554653 -313.024489)
			(xy 48.546758 -313.073066) (xy 48.531174 -313.119747) (xy 48.508303 -313.163324) (xy 48.478738 -313.202668)
			(xy 48.443245 -313.23676) (xy 48.402742 -313.264716) (xy 48.35828 -313.285814) (xy 48.311009 -313.299506)
			(xy 48.262154 -313.305438) (xy 48.212979 -313.303457) (xy 48.16476 -313.293613) (xy 48.118744 -313.276161)
			(xy 48.076123 -313.251554) (xy 48.038002 -313.220429) (xy 48.005367 -313.183592) (xy 47.979064 -313.141996)
			(xy 47.959773 -313.09672) (xy 47.947996 -313.048936) (xy 47.944036 -312.999882) (xy 46.655228 -312.999882)
			(xy 46.654733 -313.024489) (xy 46.646838 -313.073066) (xy 46.631254 -313.119747) (xy 46.608383 -313.163324)
			(xy 46.578818 -313.202668) (xy 46.543325 -313.23676) (xy 46.502822 -313.264716) (xy 46.45836 -313.285814)
			(xy 46.411089 -313.299506) (xy 46.362234 -313.305438) (xy 46.313059 -313.303457) (xy 46.26484 -313.293613)
			(xy 46.218824 -313.276161) (xy 46.176203 -313.251554) (xy 46.138082 -313.220429) (xy 46.105447 -313.183592)
			(xy 46.079144 -313.141996) (xy 46.059853 -313.09672) (xy 46.048076 -313.048936) (xy 46.044116 -312.999882)
			(xy 44.755054 -312.999882) (xy 44.754559 -313.024489) (xy 44.746664 -313.073066) (xy 44.73108 -313.119747)
			(xy 44.708209 -313.163324) (xy 44.678644 -313.202668) (xy 44.643151 -313.23676) (xy 44.602648 -313.264716)
			(xy 44.558186 -313.285814) (xy 44.510915 -313.299506) (xy 44.46206 -313.305438) (xy 44.412885 -313.303457)
			(xy 44.364666 -313.293613) (xy 44.31865 -313.276161) (xy 44.276029 -313.251554) (xy 44.237908 -313.220429)
			(xy 44.205273 -313.183592) (xy 44.17897 -313.141996) (xy 44.159679 -313.09672) (xy 44.147902 -313.048936)
			(xy 44.143942 -312.999882) (xy 0.508 -312.999882) (xy 0.508 -313.949842) (xy 44.143942 -313.949842)
			(xy 44.147902 -313.900788) (xy 44.159679 -313.853004) (xy 44.17897 -313.807728) (xy 44.205273 -313.766132)
			(xy 44.237908 -313.729295) (xy 44.276029 -313.69817) (xy 44.31865 -313.673563) (xy 44.364666 -313.656111)
			(xy 44.412885 -313.646267) (xy 44.46206 -313.644286) (xy 44.510915 -313.650218) (xy 44.558186 -313.66391)
			(xy 44.602648 -313.685008) (xy 44.643151 -313.712964) (xy 44.678644 -313.747056) (xy 44.708209 -313.7864)
			(xy 44.73108 -313.829977) (xy 44.746664 -313.876658) (xy 44.754559 -313.925235) (xy 44.755054 -313.949842)
			(xy 46.044116 -313.949842) (xy 46.048076 -313.900788) (xy 46.059853 -313.853004) (xy 46.079144 -313.807728)
			(xy 46.105447 -313.766132) (xy 46.138082 -313.729295) (xy 46.176203 -313.69817) (xy 46.218824 -313.673563)
			(xy 46.26484 -313.656111) (xy 46.313059 -313.646267) (xy 46.362234 -313.644286) (xy 46.411089 -313.650218)
			(xy 46.45836 -313.66391) (xy 46.502822 -313.685008) (xy 46.543325 -313.712964) (xy 46.578818 -313.747056)
			(xy 46.608383 -313.7864) (xy 46.631254 -313.829977) (xy 46.646838 -313.876658) (xy 46.654733 -313.925235)
			(xy 46.655228 -313.949842) (xy 47.944036 -313.949842) (xy 47.947996 -313.900788) (xy 47.959773 -313.853004)
			(xy 47.979064 -313.807728) (xy 48.005367 -313.766132) (xy 48.038002 -313.729295) (xy 48.076123 -313.69817)
			(xy 48.118744 -313.673563) (xy 48.16476 -313.656111) (xy 48.212979 -313.646267) (xy 48.262154 -313.644286)
			(xy 48.311009 -313.650218) (xy 48.35828 -313.66391) (xy 48.402742 -313.685008) (xy 48.443245 -313.712964)
			(xy 48.478738 -313.747056) (xy 48.508303 -313.7864) (xy 48.531174 -313.829977) (xy 48.546758 -313.876658)
			(xy 48.554653 -313.925235) (xy 48.555148 -313.949842) (xy 49.843956 -313.949842) (xy 49.847916 -313.900788)
			(xy 49.859693 -313.853004) (xy 49.878984 -313.807728) (xy 49.905287 -313.766132) (xy 49.937922 -313.729295)
			(xy 49.976043 -313.69817) (xy 50.018664 -313.673563) (xy 50.06468 -313.656111) (xy 50.112899 -313.646267)
			(xy 50.162074 -313.644286) (xy 50.210929 -313.650218) (xy 50.2582 -313.66391) (xy 50.302662 -313.685008)
			(xy 50.343165 -313.712964) (xy 50.378658 -313.747056) (xy 50.408223 -313.7864) (xy 50.431094 -313.829977)
			(xy 50.446678 -313.876658) (xy 50.454573 -313.925235) (xy 50.455068 -313.949842) (xy 51.74413 -313.949842)
			(xy 51.74809 -313.900788) (xy 51.759867 -313.853004) (xy 51.779158 -313.807728) (xy 51.805461 -313.766132)
			(xy 51.838096 -313.729295) (xy 51.876217 -313.69817) (xy 51.918838 -313.673563) (xy 51.964854 -313.656111)
			(xy 52.013073 -313.646267) (xy 52.062248 -313.644286) (xy 52.111103 -313.650218) (xy 52.158374 -313.66391)
			(xy 52.202836 -313.685008) (xy 52.243339 -313.712964) (xy 52.278832 -313.747056) (xy 52.308397 -313.7864)
			(xy 52.331268 -313.829977) (xy 52.346852 -313.876658) (xy 52.354747 -313.925235) (xy 52.355242 -313.949842)
			(xy 53.64405 -313.949842) (xy 53.64801 -313.900788) (xy 53.659787 -313.853004) (xy 53.679078 -313.807728)
			(xy 53.705381 -313.766132) (xy 53.738016 -313.729295) (xy 53.776137 -313.69817) (xy 53.818758 -313.673563)
			(xy 53.864774 -313.656111) (xy 53.912993 -313.646267) (xy 53.962168 -313.644286) (xy 54.011023 -313.650218)
			(xy 54.058294 -313.66391) (xy 54.102756 -313.685008) (xy 54.143259 -313.712964) (xy 54.178752 -313.747056)
			(xy 54.208317 -313.7864) (xy 54.231188 -313.829977) (xy 54.246772 -313.876658) (xy 54.254667 -313.925235)
			(xy 54.255162 -313.949842) (xy 55.54397 -313.949842) (xy 55.54793 -313.900788) (xy 55.559707 -313.853004)
			(xy 55.578998 -313.807728) (xy 55.605301 -313.766132) (xy 55.637936 -313.729295) (xy 55.676057 -313.69817)
			(xy 55.718678 -313.673563) (xy 55.764694 -313.656111) (xy 55.812913 -313.646267) (xy 55.862088 -313.644286)
			(xy 55.910943 -313.650218) (xy 55.958214 -313.66391) (xy 56.002676 -313.685008) (xy 56.043179 -313.712964)
			(xy 56.078672 -313.747056) (xy 56.108237 -313.7864) (xy 56.131108 -313.829977) (xy 56.146692 -313.876658)
			(xy 56.154587 -313.925235) (xy 56.155082 -313.949842) (xy 57.444144 -313.949842) (xy 57.448104 -313.900788)
			(xy 57.459881 -313.853004) (xy 57.479172 -313.807728) (xy 57.505475 -313.766132) (xy 57.53811 -313.729295)
			(xy 57.576231 -313.69817) (xy 57.618852 -313.673563) (xy 57.664868 -313.656111) (xy 57.713087 -313.646267)
			(xy 57.762262 -313.644286) (xy 57.811117 -313.650218) (xy 57.858388 -313.66391) (xy 57.90285 -313.685008)
			(xy 57.943353 -313.712964) (xy 57.978846 -313.747056) (xy 58.008411 -313.7864) (xy 58.031282 -313.829977)
			(xy 58.046866 -313.876658) (xy 58.054761 -313.925235) (xy 58.055256 -313.949842) (xy 74.544186 -313.949842)
			(xy 74.548146 -313.900788) (xy 74.559923 -313.853004) (xy 74.579214 -313.807728) (xy 74.605517 -313.766132)
			(xy 74.638152 -313.729295) (xy 74.676273 -313.69817) (xy 74.718894 -313.673563) (xy 74.76491 -313.656111)
			(xy 74.813129 -313.646267) (xy 74.862304 -313.644286) (xy 74.911159 -313.650218) (xy 74.95843 -313.66391)
			(xy 75.002892 -313.685008) (xy 75.043395 -313.712964) (xy 75.078888 -313.747056) (xy 75.108453 -313.7864)
			(xy 75.131324 -313.829977) (xy 75.146908 -313.876658) (xy 75.154803 -313.925235) (xy 75.155298 -313.949842)
			(xy 76.444106 -313.949842) (xy 76.448066 -313.900788) (xy 76.459843 -313.853004) (xy 76.479134 -313.807728)
			(xy 76.505437 -313.766132) (xy 76.538072 -313.729295) (xy 76.576193 -313.69817) (xy 76.618814 -313.673563)
			(xy 76.66483 -313.656111) (xy 76.713049 -313.646267) (xy 76.762224 -313.644286) (xy 76.811079 -313.650218)
			(xy 76.85835 -313.66391) (xy 76.902812 -313.685008) (xy 76.943315 -313.712964) (xy 76.978808 -313.747056)
			(xy 77.008373 -313.7864) (xy 77.031244 -313.829977) (xy 77.046828 -313.876658) (xy 77.054723 -313.925235)
			(xy 77.055218 -313.949842) (xy 78.344026 -313.949842) (xy 78.347986 -313.900788) (xy 78.359763 -313.853004)
			(xy 78.379054 -313.807728) (xy 78.405357 -313.766132) (xy 78.437992 -313.729295) (xy 78.476113 -313.69817)
			(xy 78.518734 -313.673563) (xy 78.56475 -313.656111) (xy 78.612969 -313.646267) (xy 78.662144 -313.644286)
			(xy 78.710999 -313.650218) (xy 78.75827 -313.66391) (xy 78.802732 -313.685008) (xy 78.843235 -313.712964)
			(xy 78.878728 -313.747056) (xy 78.908293 -313.7864) (xy 78.931164 -313.829977) (xy 78.946748 -313.876658)
			(xy 78.954643 -313.925235) (xy 78.955138 -313.949842) (xy 80.243946 -313.949842) (xy 80.247906 -313.900788)
			(xy 80.259683 -313.853004) (xy 80.278974 -313.807728) (xy 80.305277 -313.766132) (xy 80.337912 -313.729295)
			(xy 80.376033 -313.69817) (xy 80.418654 -313.673563) (xy 80.46467 -313.656111) (xy 80.512889 -313.646267)
			(xy 80.562064 -313.644286) (xy 80.610919 -313.650218) (xy 80.65819 -313.66391) (xy 80.702652 -313.685008)
			(xy 80.743155 -313.712964) (xy 80.778648 -313.747056) (xy 80.808213 -313.7864) (xy 80.831084 -313.829977)
			(xy 80.846668 -313.876658) (xy 80.854563 -313.925235) (xy 80.855058 -313.949842) (xy 154.54428 -313.949842)
			(xy 154.54824 -313.900788) (xy 154.560017 -313.853004) (xy 154.579308 -313.807728) (xy 154.605611 -313.766132)
			(xy 154.638246 -313.729295) (xy 154.676367 -313.69817) (xy 154.718988 -313.673563) (xy 154.765004 -313.656111)
			(xy 154.813223 -313.646267) (xy 154.862398 -313.644286) (xy 154.911253 -313.650218) (xy 154.958524 -313.66391)
			(xy 155.002986 -313.685008) (xy 155.043489 -313.712964) (xy 155.078982 -313.747056) (xy 155.108547 -313.7864)
			(xy 155.131418 -313.829977) (xy 155.147002 -313.876658) (xy 155.154897 -313.925235) (xy 155.155392 -313.949842)
			(xy 156.4442 -313.949842) (xy 156.44816 -313.900788) (xy 156.459937 -313.853004) (xy 156.479228 -313.807728)
			(xy 156.505531 -313.766132) (xy 156.538166 -313.729295) (xy 156.576287 -313.69817) (xy 156.618908 -313.673563)
			(xy 156.664924 -313.656111) (xy 156.713143 -313.646267) (xy 156.762318 -313.644286) (xy 156.811173 -313.650218)
			(xy 156.858444 -313.66391) (xy 156.902906 -313.685008) (xy 156.943409 -313.712964) (xy 156.978902 -313.747056)
			(xy 157.008467 -313.7864) (xy 157.031338 -313.829977) (xy 157.046922 -313.876658) (xy 157.054817 -313.925235)
			(xy 157.055312 -313.949842) (xy 158.34412 -313.949842) (xy 158.34808 -313.900788) (xy 158.359857 -313.853004)
			(xy 158.379148 -313.807728) (xy 158.405451 -313.766132) (xy 158.438086 -313.729295) (xy 158.476207 -313.69817)
			(xy 158.518828 -313.673563) (xy 158.564844 -313.656111) (xy 158.613063 -313.646267) (xy 158.662238 -313.644286)
			(xy 158.711093 -313.650218) (xy 158.758364 -313.66391) (xy 158.802826 -313.685008) (xy 158.843329 -313.712964)
			(xy 158.878822 -313.747056) (xy 158.908387 -313.7864) (xy 158.931258 -313.829977) (xy 158.946842 -313.876658)
			(xy 158.954737 -313.925235) (xy 158.955232 -313.949842) (xy 160.24404 -313.949842) (xy 160.248 -313.900788)
			(xy 160.259777 -313.853004) (xy 160.279068 -313.807728) (xy 160.305371 -313.766132) (xy 160.338006 -313.729295)
			(xy 160.376127 -313.69817) (xy 160.418748 -313.673563) (xy 160.464764 -313.656111) (xy 160.512983 -313.646267)
			(xy 160.562158 -313.644286) (xy 160.611013 -313.650218) (xy 160.658284 -313.66391) (xy 160.702746 -313.685008)
			(xy 160.743249 -313.712964) (xy 160.778742 -313.747056) (xy 160.808307 -313.7864) (xy 160.831178 -313.829977)
			(xy 160.846762 -313.876658) (xy 160.854657 -313.925235) (xy 160.855152 -313.949842) (xy 162.144214 -313.949842)
			(xy 162.148174 -313.900788) (xy 162.159951 -313.853004) (xy 162.179242 -313.807728) (xy 162.205545 -313.766132)
			(xy 162.23818 -313.729295) (xy 162.276301 -313.69817) (xy 162.318922 -313.673563) (xy 162.364938 -313.656111)
			(xy 162.413157 -313.646267) (xy 162.462332 -313.644286) (xy 162.511187 -313.650218) (xy 162.558458 -313.66391)
			(xy 162.60292 -313.685008) (xy 162.643423 -313.712964) (xy 162.678916 -313.747056) (xy 162.708481 -313.7864)
			(xy 162.731352 -313.829977) (xy 162.746936 -313.876658) (xy 162.754831 -313.925235) (xy 162.755326 -313.949842)
			(xy 164.044134 -313.949842) (xy 164.048094 -313.900788) (xy 164.059871 -313.853004) (xy 164.079162 -313.807728)
			(xy 164.105465 -313.766132) (xy 164.1381 -313.729295) (xy 164.176221 -313.69817) (xy 164.218842 -313.673563)
			(xy 164.264858 -313.656111) (xy 164.313077 -313.646267) (xy 164.362252 -313.644286) (xy 164.411107 -313.650218)
			(xy 164.458378 -313.66391) (xy 164.50284 -313.685008) (xy 164.543343 -313.712964) (xy 164.578836 -313.747056)
			(xy 164.608401 -313.7864) (xy 164.631272 -313.829977) (xy 164.646856 -313.876658) (xy 164.654751 -313.925235)
			(xy 164.655246 -313.949842) (xy 165.944054 -313.949842) (xy 165.948014 -313.900788) (xy 165.959791 -313.853004)
			(xy 165.979082 -313.807728) (xy 166.005385 -313.766132) (xy 166.03802 -313.729295) (xy 166.076141 -313.69817)
			(xy 166.118762 -313.673563) (xy 166.164778 -313.656111) (xy 166.212997 -313.646267) (xy 166.262172 -313.644286)
			(xy 166.311027 -313.650218) (xy 166.358298 -313.66391) (xy 166.40276 -313.685008) (xy 166.443263 -313.712964)
			(xy 166.478756 -313.747056) (xy 166.508321 -313.7864) (xy 166.531192 -313.829977) (xy 166.546776 -313.876658)
			(xy 166.554671 -313.925235) (xy 166.555166 -313.949842) (xy 183.044096 -313.949842) (xy 183.048056 -313.900788)
			(xy 183.059833 -313.853004) (xy 183.079124 -313.807728) (xy 183.105427 -313.766132) (xy 183.138062 -313.729295)
			(xy 183.176183 -313.69817) (xy 183.218804 -313.673563) (xy 183.26482 -313.656111) (xy 183.313039 -313.646267)
			(xy 183.362214 -313.644286) (xy 183.411069 -313.650218) (xy 183.45834 -313.66391) (xy 183.502802 -313.685008)
			(xy 183.543305 -313.712964) (xy 183.578798 -313.747056) (xy 183.608363 -313.7864) (xy 183.631234 -313.829977)
			(xy 183.646818 -313.876658) (xy 183.654713 -313.925235) (xy 183.655208 -313.949842) (xy 184.94427 -313.949842)
			(xy 184.94823 -313.900788) (xy 184.960007 -313.853004) (xy 184.979298 -313.807728) (xy 185.005601 -313.766132)
			(xy 185.038236 -313.729295) (xy 185.076357 -313.69817) (xy 185.118978 -313.673563) (xy 185.164994 -313.656111)
			(xy 185.213213 -313.646267) (xy 185.262388 -313.644286) (xy 185.311243 -313.650218) (xy 185.358514 -313.66391)
			(xy 185.402976 -313.685008) (xy 185.443479 -313.712964) (xy 185.478972 -313.747056) (xy 185.508537 -313.7864)
			(xy 185.531408 -313.829977) (xy 185.546992 -313.876658) (xy 185.554887 -313.925235) (xy 185.555382 -313.949842)
			(xy 186.84419 -313.949842) (xy 186.84815 -313.900788) (xy 186.859927 -313.853004) (xy 186.879218 -313.807728)
			(xy 186.905521 -313.766132) (xy 186.938156 -313.729295) (xy 186.976277 -313.69817) (xy 187.018898 -313.673563)
			(xy 187.064914 -313.656111) (xy 187.113133 -313.646267) (xy 187.162308 -313.644286) (xy 187.211163 -313.650218)
			(xy 187.258434 -313.66391) (xy 187.302896 -313.685008) (xy 187.343399 -313.712964) (xy 187.378892 -313.747056)
			(xy 187.408457 -313.7864) (xy 187.431328 -313.829977) (xy 187.446912 -313.876658) (xy 187.454807 -313.925235)
			(xy 187.455302 -313.949842) (xy 188.74411 -313.949842) (xy 188.74807 -313.900788) (xy 188.759847 -313.853004)
			(xy 188.779138 -313.807728) (xy 188.805441 -313.766132) (xy 188.838076 -313.729295) (xy 188.876197 -313.69817)
			(xy 188.918818 -313.673563) (xy 188.964834 -313.656111) (xy 189.013053 -313.646267) (xy 189.062228 -313.644286)
			(xy 189.111083 -313.650218) (xy 189.158354 -313.66391) (xy 189.202816 -313.685008) (xy 189.243319 -313.712964)
			(xy 189.278812 -313.747056) (xy 189.308377 -313.7864) (xy 189.331248 -313.829977) (xy 189.346832 -313.876658)
			(xy 189.354727 -313.925235) (xy 189.355222 -313.949842) (xy 276.343884 -313.949842) (xy 276.347844 -313.900788)
			(xy 276.359621 -313.853004) (xy 276.378912 -313.807728) (xy 276.405215 -313.766132) (xy 276.43785 -313.729295)
			(xy 276.475971 -313.69817) (xy 276.518592 -313.673563) (xy 276.564608 -313.656111) (xy 276.612827 -313.646267)
			(xy 276.662002 -313.644286) (xy 276.710857 -313.650218) (xy 276.758128 -313.66391) (xy 276.80259 -313.685008)
			(xy 276.843093 -313.712964) (xy 276.878586 -313.747056) (xy 276.908151 -313.7864) (xy 276.931022 -313.829977)
			(xy 276.946606 -313.876658) (xy 276.954501 -313.925235) (xy 276.954996 -313.949842) (xy 278.244058 -313.949842)
			(xy 278.248018 -313.900788) (xy 278.259795 -313.853004) (xy 278.279086 -313.807728) (xy 278.305389 -313.766132)
			(xy 278.338024 -313.729295) (xy 278.376145 -313.69817) (xy 278.418766 -313.673563) (xy 278.464782 -313.656111)
			(xy 278.513001 -313.646267) (xy 278.562176 -313.644286) (xy 278.611031 -313.650218) (xy 278.658302 -313.66391)
			(xy 278.702764 -313.685008) (xy 278.743267 -313.712964) (xy 278.77876 -313.747056) (xy 278.808325 -313.7864)
			(xy 278.831196 -313.829977) (xy 278.84678 -313.876658) (xy 278.854675 -313.925235) (xy 278.85517 -313.949842)
			(xy 280.143978 -313.949842) (xy 280.147938 -313.900788) (xy 280.159715 -313.853004) (xy 280.179006 -313.807728)
			(xy 280.205309 -313.766132) (xy 280.237944 -313.729295) (xy 280.276065 -313.69817) (xy 280.318686 -313.673563)
			(xy 280.364702 -313.656111) (xy 280.412921 -313.646267) (xy 280.462096 -313.644286) (xy 280.510951 -313.650218)
			(xy 280.558222 -313.66391) (xy 280.602684 -313.685008) (xy 280.643187 -313.712964) (xy 280.67868 -313.747056)
			(xy 280.708245 -313.7864) (xy 280.731116 -313.829977) (xy 280.7467 -313.876658) (xy 280.754595 -313.925235)
			(xy 280.75509 -313.949842) (xy 282.043898 -313.949842) (xy 282.047858 -313.900788) (xy 282.059635 -313.853004)
			(xy 282.078926 -313.807728) (xy 282.105229 -313.766132) (xy 282.137864 -313.729295) (xy 282.175985 -313.69817)
			(xy 282.218606 -313.673563) (xy 282.264622 -313.656111) (xy 282.312841 -313.646267) (xy 282.362016 -313.644286)
			(xy 282.410871 -313.650218) (xy 282.458142 -313.66391) (xy 282.502604 -313.685008) (xy 282.543107 -313.712964)
			(xy 282.5786 -313.747056) (xy 282.608165 -313.7864) (xy 282.631036 -313.829977) (xy 282.64662 -313.876658)
			(xy 282.654515 -313.925235) (xy 282.65501 -313.949842) (xy 283.944072 -313.949842) (xy 283.948032 -313.900788)
			(xy 283.959809 -313.853004) (xy 283.9791 -313.807728) (xy 284.005403 -313.766132) (xy 284.038038 -313.729295)
			(xy 284.076159 -313.69817) (xy 284.11878 -313.673563) (xy 284.164796 -313.656111) (xy 284.213015 -313.646267)
			(xy 284.26219 -313.644286) (xy 284.311045 -313.650218) (xy 284.358316 -313.66391) (xy 284.402778 -313.685008)
			(xy 284.443281 -313.712964) (xy 284.478774 -313.747056) (xy 284.508339 -313.7864) (xy 284.53121 -313.829977)
			(xy 284.546794 -313.876658) (xy 284.554689 -313.925235) (xy 284.555184 -313.949842) (xy 285.843992 -313.949842)
			(xy 285.847952 -313.900788) (xy 285.859729 -313.853004) (xy 285.87902 -313.807728) (xy 285.905323 -313.766132)
			(xy 285.937958 -313.729295) (xy 285.976079 -313.69817) (xy 286.0187 -313.673563) (xy 286.064716 -313.656111)
			(xy 286.112935 -313.646267) (xy 286.16211 -313.644286) (xy 286.210965 -313.650218) (xy 286.258236 -313.66391)
			(xy 286.302698 -313.685008) (xy 286.343201 -313.712964) (xy 286.378694 -313.747056) (xy 286.408259 -313.7864)
			(xy 286.43113 -313.829977) (xy 286.446714 -313.876658) (xy 286.454609 -313.925235) (xy 286.455104 -313.949842)
			(xy 287.743912 -313.949842) (xy 287.747872 -313.900788) (xy 287.759649 -313.853004) (xy 287.77894 -313.807728)
			(xy 287.805243 -313.766132) (xy 287.837878 -313.729295) (xy 287.875999 -313.69817) (xy 287.91862 -313.673563)
			(xy 287.964636 -313.656111) (xy 288.012855 -313.646267) (xy 288.06203 -313.644286) (xy 288.110885 -313.650218)
			(xy 288.158156 -313.66391) (xy 288.202618 -313.685008) (xy 288.243121 -313.712964) (xy 288.278614 -313.747056)
			(xy 288.308179 -313.7864) (xy 288.33105 -313.829977) (xy 288.346634 -313.876658) (xy 288.354529 -313.925235)
			(xy 288.355024 -313.949842) (xy 289.644086 -313.949842) (xy 289.648046 -313.900788) (xy 289.659823 -313.853004)
			(xy 289.679114 -313.807728) (xy 289.705417 -313.766132) (xy 289.738052 -313.729295) (xy 289.776173 -313.69817)
			(xy 289.818794 -313.673563) (xy 289.86481 -313.656111) (xy 289.913029 -313.646267) (xy 289.962204 -313.644286)
			(xy 290.011059 -313.650218) (xy 290.05833 -313.66391) (xy 290.102792 -313.685008) (xy 290.143295 -313.712964)
			(xy 290.178788 -313.747056) (xy 290.208353 -313.7864) (xy 290.231224 -313.829977) (xy 290.246808 -313.876658)
			(xy 290.254703 -313.925235) (xy 290.255198 -313.949842) (xy 306.744128 -313.949842) (xy 306.748088 -313.900788)
			(xy 306.759865 -313.853004) (xy 306.779156 -313.807728) (xy 306.805459 -313.766132) (xy 306.838094 -313.729295)
			(xy 306.876215 -313.69817) (xy 306.918836 -313.673563) (xy 306.964852 -313.656111) (xy 307.013071 -313.646267)
			(xy 307.062246 -313.644286) (xy 307.111101 -313.650218) (xy 307.158372 -313.66391) (xy 307.202834 -313.685008)
			(xy 307.243337 -313.712964) (xy 307.27883 -313.747056) (xy 307.308395 -313.7864) (xy 307.331266 -313.829977)
			(xy 307.34685 -313.876658) (xy 307.354745 -313.925235) (xy 307.35524 -313.949842) (xy 308.644048 -313.949842)
			(xy 308.648008 -313.900788) (xy 308.659785 -313.853004) (xy 308.679076 -313.807728) (xy 308.705379 -313.766132)
			(xy 308.738014 -313.729295) (xy 308.776135 -313.69817) (xy 308.818756 -313.673563) (xy 308.864772 -313.656111)
			(xy 308.912991 -313.646267) (xy 308.962166 -313.644286) (xy 309.011021 -313.650218) (xy 309.058292 -313.66391)
			(xy 309.102754 -313.685008) (xy 309.143257 -313.712964) (xy 309.17875 -313.747056) (xy 309.208315 -313.7864)
			(xy 309.231186 -313.829977) (xy 309.24677 -313.876658) (xy 309.254665 -313.925235) (xy 309.25516 -313.949842)
			(xy 310.543968 -313.949842) (xy 310.547928 -313.900788) (xy 310.559705 -313.853004) (xy 310.578996 -313.807728)
			(xy 310.605299 -313.766132) (xy 310.637934 -313.729295) (xy 310.676055 -313.69817) (xy 310.718676 -313.673563)
			(xy 310.764692 -313.656111) (xy 310.812911 -313.646267) (xy 310.862086 -313.644286) (xy 310.910941 -313.650218)
			(xy 310.958212 -313.66391) (xy 311.002674 -313.685008) (xy 311.043177 -313.712964) (xy 311.07867 -313.747056)
			(xy 311.108235 -313.7864) (xy 311.131106 -313.829977) (xy 311.14669 -313.876658) (xy 311.154585 -313.925235)
			(xy 311.15508 -313.949842) (xy 312.443888 -313.949842) (xy 312.447848 -313.900788) (xy 312.459625 -313.853004)
			(xy 312.478916 -313.807728) (xy 312.505219 -313.766132) (xy 312.537854 -313.729295) (xy 312.575975 -313.69817)
			(xy 312.618596 -313.673563) (xy 312.664612 -313.656111) (xy 312.712831 -313.646267) (xy 312.762006 -313.644286)
			(xy 312.810861 -313.650218) (xy 312.858132 -313.66391) (xy 312.902594 -313.685008) (xy 312.943097 -313.712964)
			(xy 312.97859 -313.747056) (xy 313.008155 -313.7864) (xy 313.031026 -313.829977) (xy 313.04661 -313.876658)
			(xy 313.054505 -313.925235) (xy 313.055 -313.949842) (xy 386.744222 -313.949842) (xy 386.748182 -313.900788)
			(xy 386.759959 -313.853004) (xy 386.77925 -313.807728) (xy 386.805553 -313.766132) (xy 386.838188 -313.729295)
			(xy 386.876309 -313.69817) (xy 386.91893 -313.673563) (xy 386.964946 -313.656111) (xy 387.013165 -313.646267)
			(xy 387.06234 -313.644286) (xy 387.111195 -313.650218) (xy 387.158466 -313.66391) (xy 387.202928 -313.685008)
			(xy 387.243431 -313.712964) (xy 387.278924 -313.747056) (xy 387.308489 -313.7864) (xy 387.33136 -313.829977)
			(xy 387.346944 -313.876658) (xy 387.354839 -313.925235) (xy 387.355334 -313.949842) (xy 388.644142 -313.949842)
			(xy 388.648102 -313.900788) (xy 388.659879 -313.853004) (xy 388.67917 -313.807728) (xy 388.705473 -313.766132)
			(xy 388.738108 -313.729295) (xy 388.776229 -313.69817) (xy 388.81885 -313.673563) (xy 388.864866 -313.656111)
			(xy 388.913085 -313.646267) (xy 388.96226 -313.644286) (xy 389.011115 -313.650218) (xy 389.058386 -313.66391)
			(xy 389.102848 -313.685008) (xy 389.143351 -313.712964) (xy 389.178844 -313.747056) (xy 389.208409 -313.7864)
			(xy 389.23128 -313.829977) (xy 389.246864 -313.876658) (xy 389.254759 -313.925235) (xy 389.255254 -313.949842)
			(xy 390.544062 -313.949842) (xy 390.548022 -313.900788) (xy 390.559799 -313.853004) (xy 390.57909 -313.807728)
			(xy 390.605393 -313.766132) (xy 390.638028 -313.729295) (xy 390.676149 -313.69817) (xy 390.71877 -313.673563)
			(xy 390.764786 -313.656111) (xy 390.813005 -313.646267) (xy 390.86218 -313.644286) (xy 390.911035 -313.650218)
			(xy 390.958306 -313.66391) (xy 391.002768 -313.685008) (xy 391.043271 -313.712964) (xy 391.078764 -313.747056)
			(xy 391.108329 -313.7864) (xy 391.1312 -313.829977) (xy 391.146784 -313.876658) (xy 391.154679 -313.925235)
			(xy 391.155174 -313.949842) (xy 392.443982 -313.949842) (xy 392.447942 -313.900788) (xy 392.459719 -313.853004)
			(xy 392.47901 -313.807728) (xy 392.505313 -313.766132) (xy 392.537948 -313.729295) (xy 392.576069 -313.69817)
			(xy 392.61869 -313.673563) (xy 392.664706 -313.656111) (xy 392.712925 -313.646267) (xy 392.7621 -313.644286)
			(xy 392.810955 -313.650218) (xy 392.858226 -313.66391) (xy 392.902688 -313.685008) (xy 392.943191 -313.712964)
			(xy 392.978684 -313.747056) (xy 393.008249 -313.7864) (xy 393.03112 -313.829977) (xy 393.046704 -313.876658)
			(xy 393.054599 -313.925235) (xy 393.055094 -313.949842) (xy 394.344156 -313.949842) (xy 394.348116 -313.900788)
			(xy 394.359893 -313.853004) (xy 394.379184 -313.807728) (xy 394.405487 -313.766132) (xy 394.438122 -313.729295)
			(xy 394.476243 -313.69817) (xy 394.518864 -313.673563) (xy 394.56488 -313.656111) (xy 394.613099 -313.646267)
			(xy 394.662274 -313.644286) (xy 394.711129 -313.650218) (xy 394.7584 -313.66391) (xy 394.802862 -313.685008)
			(xy 394.843365 -313.712964) (xy 394.878858 -313.747056) (xy 394.908423 -313.7864) (xy 394.931294 -313.829977)
			(xy 394.946878 -313.876658) (xy 394.954773 -313.925235) (xy 394.955268 -313.949842) (xy 396.244076 -313.949842)
			(xy 396.248036 -313.900788) (xy 396.259813 -313.853004) (xy 396.279104 -313.807728) (xy 396.305407 -313.766132)
			(xy 396.338042 -313.729295) (xy 396.376163 -313.69817) (xy 396.418784 -313.673563) (xy 396.4648 -313.656111)
			(xy 396.513019 -313.646267) (xy 396.562194 -313.644286) (xy 396.611049 -313.650218) (xy 396.65832 -313.66391)
			(xy 396.702782 -313.685008) (xy 396.743285 -313.712964) (xy 396.778778 -313.747056) (xy 396.808343 -313.7864)
			(xy 396.831214 -313.829977) (xy 396.846798 -313.876658) (xy 396.854693 -313.925235) (xy 396.855188 -313.949842)
			(xy 398.143996 -313.949842) (xy 398.147956 -313.900788) (xy 398.159733 -313.853004) (xy 398.179024 -313.807728)
			(xy 398.205327 -313.766132) (xy 398.237962 -313.729295) (xy 398.276083 -313.69817) (xy 398.318704 -313.673563)
			(xy 398.36472 -313.656111) (xy 398.412939 -313.646267) (xy 398.462114 -313.644286) (xy 398.510969 -313.650218)
			(xy 398.55824 -313.66391) (xy 398.602702 -313.685008) (xy 398.643205 -313.712964) (xy 398.678698 -313.747056)
			(xy 398.708263 -313.7864) (xy 398.731134 -313.829977) (xy 398.746718 -313.876658) (xy 398.754613 -313.925235)
			(xy 398.755108 -313.949842) (xy 415.244038 -313.949842) (xy 415.247998 -313.900788) (xy 415.259775 -313.853004)
			(xy 415.279066 -313.807728) (xy 415.305369 -313.766132) (xy 415.338004 -313.729295) (xy 415.376125 -313.69817)
			(xy 415.418746 -313.673563) (xy 415.464762 -313.656111) (xy 415.512981 -313.646267) (xy 415.562156 -313.644286)
			(xy 415.611011 -313.650218) (xy 415.658282 -313.66391) (xy 415.702744 -313.685008) (xy 415.743247 -313.712964)
			(xy 415.77874 -313.747056) (xy 415.808305 -313.7864) (xy 415.831176 -313.829977) (xy 415.84676 -313.876658)
			(xy 415.854655 -313.925235) (xy 415.85515 -313.949842) (xy 417.144212 -313.949842) (xy 417.148172 -313.900788)
			(xy 417.159949 -313.853004) (xy 417.17924 -313.807728) (xy 417.205543 -313.766132) (xy 417.238178 -313.729295)
			(xy 417.276299 -313.69817) (xy 417.31892 -313.673563) (xy 417.364936 -313.656111) (xy 417.413155 -313.646267)
			(xy 417.46233 -313.644286) (xy 417.511185 -313.650218) (xy 417.558456 -313.66391) (xy 417.602918 -313.685008)
			(xy 417.643421 -313.712964) (xy 417.678914 -313.747056) (xy 417.708479 -313.7864) (xy 417.73135 -313.829977)
			(xy 417.746934 -313.876658) (xy 417.754829 -313.925235) (xy 417.755324 -313.949842) (xy 419.044132 -313.949842)
			(xy 419.048092 -313.900788) (xy 419.059869 -313.853004) (xy 419.07916 -313.807728) (xy 419.105463 -313.766132)
			(xy 419.138098 -313.729295) (xy 419.176219 -313.69817) (xy 419.21884 -313.673563) (xy 419.264856 -313.656111)
			(xy 419.313075 -313.646267) (xy 419.36225 -313.644286) (xy 419.411105 -313.650218) (xy 419.458376 -313.66391)
			(xy 419.502838 -313.685008) (xy 419.543341 -313.712964) (xy 419.578834 -313.747056) (xy 419.608399 -313.7864)
			(xy 419.63127 -313.829977) (xy 419.646854 -313.876658) (xy 419.654749 -313.925235) (xy 419.655244 -313.949842)
			(xy 420.944052 -313.949842) (xy 420.948012 -313.900788) (xy 420.959789 -313.853004) (xy 420.97908 -313.807728)
			(xy 421.005383 -313.766132) (xy 421.038018 -313.729295) (xy 421.076139 -313.69817) (xy 421.11876 -313.673563)
			(xy 421.164776 -313.656111) (xy 421.212995 -313.646267) (xy 421.26217 -313.644286) (xy 421.311025 -313.650218)
			(xy 421.358296 -313.66391) (xy 421.402758 -313.685008) (xy 421.443261 -313.712964) (xy 421.478754 -313.747056)
			(xy 421.508319 -313.7864) (xy 421.53119 -313.829977) (xy 421.546774 -313.876658) (xy 421.554669 -313.925235)
			(xy 421.555164 -313.949842) (xy 421.554669 -313.974449) (xy 421.546774 -314.023026) (xy 421.53119 -314.069707)
			(xy 421.508319 -314.113284) (xy 421.478754 -314.152628) (xy 421.443261 -314.18672) (xy 421.402758 -314.214676)
			(xy 421.358296 -314.235774) (xy 421.311025 -314.249466) (xy 421.26217 -314.255398) (xy 421.212995 -314.253417)
			(xy 421.164776 -314.243573) (xy 421.11876 -314.226121) (xy 421.076139 -314.201514) (xy 421.038018 -314.170389)
			(xy 421.005383 -314.133552) (xy 420.97908 -314.091956) (xy 420.959789 -314.04668) (xy 420.948012 -313.998896)
			(xy 420.944052 -313.949842) (xy 419.655244 -313.949842) (xy 419.654749 -313.974449) (xy 419.646854 -314.023026)
			(xy 419.63127 -314.069707) (xy 419.608399 -314.113284) (xy 419.578834 -314.152628) (xy 419.543341 -314.18672)
			(xy 419.502838 -314.214676) (xy 419.458376 -314.235774) (xy 419.411105 -314.249466) (xy 419.36225 -314.255398)
			(xy 419.313075 -314.253417) (xy 419.264856 -314.243573) (xy 419.21884 -314.226121) (xy 419.176219 -314.201514)
			(xy 419.138098 -314.170389) (xy 419.105463 -314.133552) (xy 419.07916 -314.091956) (xy 419.059869 -314.04668)
			(xy 419.048092 -313.998896) (xy 419.044132 -313.949842) (xy 417.755324 -313.949842) (xy 417.754829 -313.974449)
			(xy 417.746934 -314.023026) (xy 417.73135 -314.069707) (xy 417.708479 -314.113284) (xy 417.678914 -314.152628)
			(xy 417.643421 -314.18672) (xy 417.602918 -314.214676) (xy 417.558456 -314.235774) (xy 417.511185 -314.249466)
			(xy 417.46233 -314.255398) (xy 417.413155 -314.253417) (xy 417.364936 -314.243573) (xy 417.31892 -314.226121)
			(xy 417.276299 -314.201514) (xy 417.238178 -314.170389) (xy 417.205543 -314.133552) (xy 417.17924 -314.091956)
			(xy 417.159949 -314.04668) (xy 417.148172 -313.998896) (xy 417.144212 -313.949842) (xy 415.85515 -313.949842)
			(xy 415.854655 -313.974449) (xy 415.84676 -314.023026) (xy 415.831176 -314.069707) (xy 415.808305 -314.113284)
			(xy 415.77874 -314.152628) (xy 415.743247 -314.18672) (xy 415.702744 -314.214676) (xy 415.658282 -314.235774)
			(xy 415.611011 -314.249466) (xy 415.562156 -314.255398) (xy 415.512981 -314.253417) (xy 415.464762 -314.243573)
			(xy 415.418746 -314.226121) (xy 415.376125 -314.201514) (xy 415.338004 -314.170389) (xy 415.305369 -314.133552)
			(xy 415.279066 -314.091956) (xy 415.259775 -314.04668) (xy 415.247998 -313.998896) (xy 415.244038 -313.949842)
			(xy 398.755108 -313.949842) (xy 398.754613 -313.974449) (xy 398.746718 -314.023026) (xy 398.731134 -314.069707)
			(xy 398.708263 -314.113284) (xy 398.678698 -314.152628) (xy 398.643205 -314.18672) (xy 398.602702 -314.214676)
			(xy 398.55824 -314.235774) (xy 398.510969 -314.249466) (xy 398.462114 -314.255398) (xy 398.412939 -314.253417)
			(xy 398.36472 -314.243573) (xy 398.318704 -314.226121) (xy 398.276083 -314.201514) (xy 398.237962 -314.170389)
			(xy 398.205327 -314.133552) (xy 398.179024 -314.091956) (xy 398.159733 -314.04668) (xy 398.147956 -313.998896)
			(xy 398.143996 -313.949842) (xy 396.855188 -313.949842) (xy 396.854693 -313.974449) (xy 396.846798 -314.023026)
			(xy 396.831214 -314.069707) (xy 396.808343 -314.113284) (xy 396.778778 -314.152628) (xy 396.743285 -314.18672)
			(xy 396.702782 -314.214676) (xy 396.65832 -314.235774) (xy 396.611049 -314.249466) (xy 396.562194 -314.255398)
			(xy 396.513019 -314.253417) (xy 396.4648 -314.243573) (xy 396.418784 -314.226121) (xy 396.376163 -314.201514)
			(xy 396.338042 -314.170389) (xy 396.305407 -314.133552) (xy 396.279104 -314.091956) (xy 396.259813 -314.04668)
			(xy 396.248036 -313.998896) (xy 396.244076 -313.949842) (xy 394.955268 -313.949842) (xy 394.954773 -313.974449)
			(xy 394.946878 -314.023026) (xy 394.931294 -314.069707) (xy 394.908423 -314.113284) (xy 394.878858 -314.152628)
			(xy 394.843365 -314.18672) (xy 394.802862 -314.214676) (xy 394.7584 -314.235774) (xy 394.711129 -314.249466)
			(xy 394.662274 -314.255398) (xy 394.613099 -314.253417) (xy 394.56488 -314.243573) (xy 394.518864 -314.226121)
			(xy 394.476243 -314.201514) (xy 394.438122 -314.170389) (xy 394.405487 -314.133552) (xy 394.379184 -314.091956)
			(xy 394.359893 -314.04668) (xy 394.348116 -313.998896) (xy 394.344156 -313.949842) (xy 393.055094 -313.949842)
			(xy 393.054599 -313.974449) (xy 393.046704 -314.023026) (xy 393.03112 -314.069707) (xy 393.008249 -314.113284)
			(xy 392.978684 -314.152628) (xy 392.943191 -314.18672) (xy 392.902688 -314.214676) (xy 392.858226 -314.235774)
			(xy 392.810955 -314.249466) (xy 392.7621 -314.255398) (xy 392.712925 -314.253417) (xy 392.664706 -314.243573)
			(xy 392.61869 -314.226121) (xy 392.576069 -314.201514) (xy 392.537948 -314.170389) (xy 392.505313 -314.133552)
			(xy 392.47901 -314.091956) (xy 392.459719 -314.04668) (xy 392.447942 -313.998896) (xy 392.443982 -313.949842)
			(xy 391.155174 -313.949842) (xy 391.154679 -313.974449) (xy 391.146784 -314.023026) (xy 391.1312 -314.069707)
			(xy 391.108329 -314.113284) (xy 391.078764 -314.152628) (xy 391.043271 -314.18672) (xy 391.002768 -314.214676)
			(xy 390.958306 -314.235774) (xy 390.911035 -314.249466) (xy 390.86218 -314.255398) (xy 390.813005 -314.253417)
			(xy 390.764786 -314.243573) (xy 390.71877 -314.226121) (xy 390.676149 -314.201514) (xy 390.638028 -314.170389)
			(xy 390.605393 -314.133552) (xy 390.57909 -314.091956) (xy 390.559799 -314.04668) (xy 390.548022 -313.998896)
			(xy 390.544062 -313.949842) (xy 389.255254 -313.949842) (xy 389.254759 -313.974449) (xy 389.246864 -314.023026)
			(xy 389.23128 -314.069707) (xy 389.208409 -314.113284) (xy 389.178844 -314.152628) (xy 389.143351 -314.18672)
			(xy 389.102848 -314.214676) (xy 389.058386 -314.235774) (xy 389.011115 -314.249466) (xy 388.96226 -314.255398)
			(xy 388.913085 -314.253417) (xy 388.864866 -314.243573) (xy 388.81885 -314.226121) (xy 388.776229 -314.201514)
			(xy 388.738108 -314.170389) (xy 388.705473 -314.133552) (xy 388.67917 -314.091956) (xy 388.659879 -314.04668)
			(xy 388.648102 -313.998896) (xy 388.644142 -313.949842) (xy 387.355334 -313.949842) (xy 387.354839 -313.974449)
			(xy 387.346944 -314.023026) (xy 387.33136 -314.069707) (xy 387.308489 -314.113284) (xy 387.278924 -314.152628)
			(xy 387.243431 -314.18672) (xy 387.202928 -314.214676) (xy 387.158466 -314.235774) (xy 387.111195 -314.249466)
			(xy 387.06234 -314.255398) (xy 387.013165 -314.253417) (xy 386.964946 -314.243573) (xy 386.91893 -314.226121)
			(xy 386.876309 -314.201514) (xy 386.838188 -314.170389) (xy 386.805553 -314.133552) (xy 386.77925 -314.091956)
			(xy 386.759959 -314.04668) (xy 386.748182 -313.998896) (xy 386.744222 -313.949842) (xy 313.055 -313.949842)
			(xy 313.054505 -313.974449) (xy 313.04661 -314.023026) (xy 313.031026 -314.069707) (xy 313.008155 -314.113284)
			(xy 312.97859 -314.152628) (xy 312.943097 -314.18672) (xy 312.902594 -314.214676) (xy 312.858132 -314.235774)
			(xy 312.810861 -314.249466) (xy 312.762006 -314.255398) (xy 312.712831 -314.253417) (xy 312.664612 -314.243573)
			(xy 312.618596 -314.226121) (xy 312.575975 -314.201514) (xy 312.537854 -314.170389) (xy 312.505219 -314.133552)
			(xy 312.478916 -314.091956) (xy 312.459625 -314.04668) (xy 312.447848 -313.998896) (xy 312.443888 -313.949842)
			(xy 311.15508 -313.949842) (xy 311.154585 -313.974449) (xy 311.14669 -314.023026) (xy 311.131106 -314.069707)
			(xy 311.108235 -314.113284) (xy 311.07867 -314.152628) (xy 311.043177 -314.18672) (xy 311.002674 -314.214676)
			(xy 310.958212 -314.235774) (xy 310.910941 -314.249466) (xy 310.862086 -314.255398) (xy 310.812911 -314.253417)
			(xy 310.764692 -314.243573) (xy 310.718676 -314.226121) (xy 310.676055 -314.201514) (xy 310.637934 -314.170389)
			(xy 310.605299 -314.133552) (xy 310.578996 -314.091956) (xy 310.559705 -314.04668) (xy 310.547928 -313.998896)
			(xy 310.543968 -313.949842) (xy 309.25516 -313.949842) (xy 309.254665 -313.974449) (xy 309.24677 -314.023026)
			(xy 309.231186 -314.069707) (xy 309.208315 -314.113284) (xy 309.17875 -314.152628) (xy 309.143257 -314.18672)
			(xy 309.102754 -314.214676) (xy 309.058292 -314.235774) (xy 309.011021 -314.249466) (xy 308.962166 -314.255398)
			(xy 308.912991 -314.253417) (xy 308.864772 -314.243573) (xy 308.818756 -314.226121) (xy 308.776135 -314.201514)
			(xy 308.738014 -314.170389) (xy 308.705379 -314.133552) (xy 308.679076 -314.091956) (xy 308.659785 -314.04668)
			(xy 308.648008 -313.998896) (xy 308.644048 -313.949842) (xy 307.35524 -313.949842) (xy 307.354745 -313.974449)
			(xy 307.34685 -314.023026) (xy 307.331266 -314.069707) (xy 307.308395 -314.113284) (xy 307.27883 -314.152628)
			(xy 307.243337 -314.18672) (xy 307.202834 -314.214676) (xy 307.158372 -314.235774) (xy 307.111101 -314.249466)
			(xy 307.062246 -314.255398) (xy 307.013071 -314.253417) (xy 306.964852 -314.243573) (xy 306.918836 -314.226121)
			(xy 306.876215 -314.201514) (xy 306.838094 -314.170389) (xy 306.805459 -314.133552) (xy 306.779156 -314.091956)
			(xy 306.759865 -314.04668) (xy 306.748088 -313.998896) (xy 306.744128 -313.949842) (xy 290.255198 -313.949842)
			(xy 290.254703 -313.974449) (xy 290.246808 -314.023026) (xy 290.231224 -314.069707) (xy 290.208353 -314.113284)
			(xy 290.178788 -314.152628) (xy 290.143295 -314.18672) (xy 290.102792 -314.214676) (xy 290.05833 -314.235774)
			(xy 290.011059 -314.249466) (xy 289.962204 -314.255398) (xy 289.913029 -314.253417) (xy 289.86481 -314.243573)
			(xy 289.818794 -314.226121) (xy 289.776173 -314.201514) (xy 289.738052 -314.170389) (xy 289.705417 -314.133552)
			(xy 289.679114 -314.091956) (xy 289.659823 -314.04668) (xy 289.648046 -313.998896) (xy 289.644086 -313.949842)
			(xy 288.355024 -313.949842) (xy 288.354529 -313.974449) (xy 288.346634 -314.023026) (xy 288.33105 -314.069707)
			(xy 288.308179 -314.113284) (xy 288.278614 -314.152628) (xy 288.243121 -314.18672) (xy 288.202618 -314.214676)
			(xy 288.158156 -314.235774) (xy 288.110885 -314.249466) (xy 288.06203 -314.255398) (xy 288.012855 -314.253417)
			(xy 287.964636 -314.243573) (xy 287.91862 -314.226121) (xy 287.875999 -314.201514) (xy 287.837878 -314.170389)
			(xy 287.805243 -314.133552) (xy 287.77894 -314.091956) (xy 287.759649 -314.04668) (xy 287.747872 -313.998896)
			(xy 287.743912 -313.949842) (xy 286.455104 -313.949842) (xy 286.454609 -313.974449) (xy 286.446714 -314.023026)
			(xy 286.43113 -314.069707) (xy 286.408259 -314.113284) (xy 286.378694 -314.152628) (xy 286.343201 -314.18672)
			(xy 286.302698 -314.214676) (xy 286.258236 -314.235774) (xy 286.210965 -314.249466) (xy 286.16211 -314.255398)
			(xy 286.112935 -314.253417) (xy 286.064716 -314.243573) (xy 286.0187 -314.226121) (xy 285.976079 -314.201514)
			(xy 285.937958 -314.170389) (xy 285.905323 -314.133552) (xy 285.87902 -314.091956) (xy 285.859729 -314.04668)
			(xy 285.847952 -313.998896) (xy 285.843992 -313.949842) (xy 284.555184 -313.949842) (xy 284.554689 -313.974449)
			(xy 284.546794 -314.023026) (xy 284.53121 -314.069707) (xy 284.508339 -314.113284) (xy 284.478774 -314.152628)
			(xy 284.443281 -314.18672) (xy 284.402778 -314.214676) (xy 284.358316 -314.235774) (xy 284.311045 -314.249466)
			(xy 284.26219 -314.255398) (xy 284.213015 -314.253417) (xy 284.164796 -314.243573) (xy 284.11878 -314.226121)
			(xy 284.076159 -314.201514) (xy 284.038038 -314.170389) (xy 284.005403 -314.133552) (xy 283.9791 -314.091956)
			(xy 283.959809 -314.04668) (xy 283.948032 -313.998896) (xy 283.944072 -313.949842) (xy 282.65501 -313.949842)
			(xy 282.654515 -313.974449) (xy 282.64662 -314.023026) (xy 282.631036 -314.069707) (xy 282.608165 -314.113284)
			(xy 282.5786 -314.152628) (xy 282.543107 -314.18672) (xy 282.502604 -314.214676) (xy 282.458142 -314.235774)
			(xy 282.410871 -314.249466) (xy 282.362016 -314.255398) (xy 282.312841 -314.253417) (xy 282.264622 -314.243573)
			(xy 282.218606 -314.226121) (xy 282.175985 -314.201514) (xy 282.137864 -314.170389) (xy 282.105229 -314.133552)
			(xy 282.078926 -314.091956) (xy 282.059635 -314.04668) (xy 282.047858 -313.998896) (xy 282.043898 -313.949842)
			(xy 280.75509 -313.949842) (xy 280.754595 -313.974449) (xy 280.7467 -314.023026) (xy 280.731116 -314.069707)
			(xy 280.708245 -314.113284) (xy 280.67868 -314.152628) (xy 280.643187 -314.18672) (xy 280.602684 -314.214676)
			(xy 280.558222 -314.235774) (xy 280.510951 -314.249466) (xy 280.462096 -314.255398) (xy 280.412921 -314.253417)
			(xy 280.364702 -314.243573) (xy 280.318686 -314.226121) (xy 280.276065 -314.201514) (xy 280.237944 -314.170389)
			(xy 280.205309 -314.133552) (xy 280.179006 -314.091956) (xy 280.159715 -314.04668) (xy 280.147938 -313.998896)
			(xy 280.143978 -313.949842) (xy 278.85517 -313.949842) (xy 278.854675 -313.974449) (xy 278.84678 -314.023026)
			(xy 278.831196 -314.069707) (xy 278.808325 -314.113284) (xy 278.77876 -314.152628) (xy 278.743267 -314.18672)
			(xy 278.702764 -314.214676) (xy 278.658302 -314.235774) (xy 278.611031 -314.249466) (xy 278.562176 -314.255398)
			(xy 278.513001 -314.253417) (xy 278.464782 -314.243573) (xy 278.418766 -314.226121) (xy 278.376145 -314.201514)
			(xy 278.338024 -314.170389) (xy 278.305389 -314.133552) (xy 278.279086 -314.091956) (xy 278.259795 -314.04668)
			(xy 278.248018 -313.998896) (xy 278.244058 -313.949842) (xy 276.954996 -313.949842) (xy 276.954501 -313.974449)
			(xy 276.946606 -314.023026) (xy 276.931022 -314.069707) (xy 276.908151 -314.113284) (xy 276.878586 -314.152628)
			(xy 276.843093 -314.18672) (xy 276.80259 -314.214676) (xy 276.758128 -314.235774) (xy 276.710857 -314.249466)
			(xy 276.662002 -314.255398) (xy 276.612827 -314.253417) (xy 276.564608 -314.243573) (xy 276.518592 -314.226121)
			(xy 276.475971 -314.201514) (xy 276.43785 -314.170389) (xy 276.405215 -314.133552) (xy 276.378912 -314.091956)
			(xy 276.359621 -314.04668) (xy 276.347844 -313.998896) (xy 276.343884 -313.949842) (xy 189.355222 -313.949842)
			(xy 189.354727 -313.974449) (xy 189.346832 -314.023026) (xy 189.331248 -314.069707) (xy 189.308377 -314.113284)
			(xy 189.278812 -314.152628) (xy 189.243319 -314.18672) (xy 189.202816 -314.214676) (xy 189.158354 -314.235774)
			(xy 189.111083 -314.249466) (xy 189.062228 -314.255398) (xy 189.013053 -314.253417) (xy 188.964834 -314.243573)
			(xy 188.918818 -314.226121) (xy 188.876197 -314.201514) (xy 188.838076 -314.170389) (xy 188.805441 -314.133552)
			(xy 188.779138 -314.091956) (xy 188.759847 -314.04668) (xy 188.74807 -313.998896) (xy 188.74411 -313.949842)
			(xy 187.455302 -313.949842) (xy 187.454807 -313.974449) (xy 187.446912 -314.023026) (xy 187.431328 -314.069707)
			(xy 187.408457 -314.113284) (xy 187.378892 -314.152628) (xy 187.343399 -314.18672) (xy 187.302896 -314.214676)
			(xy 187.258434 -314.235774) (xy 187.211163 -314.249466) (xy 187.162308 -314.255398) (xy 187.113133 -314.253417)
			(xy 187.064914 -314.243573) (xy 187.018898 -314.226121) (xy 186.976277 -314.201514) (xy 186.938156 -314.170389)
			(xy 186.905521 -314.133552) (xy 186.879218 -314.091956) (xy 186.859927 -314.04668) (xy 186.84815 -313.998896)
			(xy 186.84419 -313.949842) (xy 185.555382 -313.949842) (xy 185.554887 -313.974449) (xy 185.546992 -314.023026)
			(xy 185.531408 -314.069707) (xy 185.508537 -314.113284) (xy 185.478972 -314.152628) (xy 185.443479 -314.18672)
			(xy 185.402976 -314.214676) (xy 185.358514 -314.235774) (xy 185.311243 -314.249466) (xy 185.262388 -314.255398)
			(xy 185.213213 -314.253417) (xy 185.164994 -314.243573) (xy 185.118978 -314.226121) (xy 185.076357 -314.201514)
			(xy 185.038236 -314.170389) (xy 185.005601 -314.133552) (xy 184.979298 -314.091956) (xy 184.960007 -314.04668)
			(xy 184.94823 -313.998896) (xy 184.94427 -313.949842) (xy 183.655208 -313.949842) (xy 183.654713 -313.974449)
			(xy 183.646818 -314.023026) (xy 183.631234 -314.069707) (xy 183.608363 -314.113284) (xy 183.578798 -314.152628)
			(xy 183.543305 -314.18672) (xy 183.502802 -314.214676) (xy 183.45834 -314.235774) (xy 183.411069 -314.249466)
			(xy 183.362214 -314.255398) (xy 183.313039 -314.253417) (xy 183.26482 -314.243573) (xy 183.218804 -314.226121)
			(xy 183.176183 -314.201514) (xy 183.138062 -314.170389) (xy 183.105427 -314.133552) (xy 183.079124 -314.091956)
			(xy 183.059833 -314.04668) (xy 183.048056 -313.998896) (xy 183.044096 -313.949842) (xy 166.555166 -313.949842)
			(xy 166.554671 -313.974449) (xy 166.546776 -314.023026) (xy 166.531192 -314.069707) (xy 166.508321 -314.113284)
			(xy 166.478756 -314.152628) (xy 166.443263 -314.18672) (xy 166.40276 -314.214676) (xy 166.358298 -314.235774)
			(xy 166.311027 -314.249466) (xy 166.262172 -314.255398) (xy 166.212997 -314.253417) (xy 166.164778 -314.243573)
			(xy 166.118762 -314.226121) (xy 166.076141 -314.201514) (xy 166.03802 -314.170389) (xy 166.005385 -314.133552)
			(xy 165.979082 -314.091956) (xy 165.959791 -314.04668) (xy 165.948014 -313.998896) (xy 165.944054 -313.949842)
			(xy 164.655246 -313.949842) (xy 164.654751 -313.974449) (xy 164.646856 -314.023026) (xy 164.631272 -314.069707)
			(xy 164.608401 -314.113284) (xy 164.578836 -314.152628) (xy 164.543343 -314.18672) (xy 164.50284 -314.214676)
			(xy 164.458378 -314.235774) (xy 164.411107 -314.249466) (xy 164.362252 -314.255398) (xy 164.313077 -314.253417)
			(xy 164.264858 -314.243573) (xy 164.218842 -314.226121) (xy 164.176221 -314.201514) (xy 164.1381 -314.170389)
			(xy 164.105465 -314.133552) (xy 164.079162 -314.091956) (xy 164.059871 -314.04668) (xy 164.048094 -313.998896)
			(xy 164.044134 -313.949842) (xy 162.755326 -313.949842) (xy 162.754831 -313.974449) (xy 162.746936 -314.023026)
			(xy 162.731352 -314.069707) (xy 162.708481 -314.113284) (xy 162.678916 -314.152628) (xy 162.643423 -314.18672)
			(xy 162.60292 -314.214676) (xy 162.558458 -314.235774) (xy 162.511187 -314.249466) (xy 162.462332 -314.255398)
			(xy 162.413157 -314.253417) (xy 162.364938 -314.243573) (xy 162.318922 -314.226121) (xy 162.276301 -314.201514)
			(xy 162.23818 -314.170389) (xy 162.205545 -314.133552) (xy 162.179242 -314.091956) (xy 162.159951 -314.04668)
			(xy 162.148174 -313.998896) (xy 162.144214 -313.949842) (xy 160.855152 -313.949842) (xy 160.854657 -313.974449)
			(xy 160.846762 -314.023026) (xy 160.831178 -314.069707) (xy 160.808307 -314.113284) (xy 160.778742 -314.152628)
			(xy 160.743249 -314.18672) (xy 160.702746 -314.214676) (xy 160.658284 -314.235774) (xy 160.611013 -314.249466)
			(xy 160.562158 -314.255398) (xy 160.512983 -314.253417) (xy 160.464764 -314.243573) (xy 160.418748 -314.226121)
			(xy 160.376127 -314.201514) (xy 160.338006 -314.170389) (xy 160.305371 -314.133552) (xy 160.279068 -314.091956)
			(xy 160.259777 -314.04668) (xy 160.248 -313.998896) (xy 160.24404 -313.949842) (xy 158.955232 -313.949842)
			(xy 158.954737 -313.974449) (xy 158.946842 -314.023026) (xy 158.931258 -314.069707) (xy 158.908387 -314.113284)
			(xy 158.878822 -314.152628) (xy 158.843329 -314.18672) (xy 158.802826 -314.214676) (xy 158.758364 -314.235774)
			(xy 158.711093 -314.249466) (xy 158.662238 -314.255398) (xy 158.613063 -314.253417) (xy 158.564844 -314.243573)
			(xy 158.518828 -314.226121) (xy 158.476207 -314.201514) (xy 158.438086 -314.170389) (xy 158.405451 -314.133552)
			(xy 158.379148 -314.091956) (xy 158.359857 -314.04668) (xy 158.34808 -313.998896) (xy 158.34412 -313.949842)
			(xy 157.055312 -313.949842) (xy 157.054817 -313.974449) (xy 157.046922 -314.023026) (xy 157.031338 -314.069707)
			(xy 157.008467 -314.113284) (xy 156.978902 -314.152628) (xy 156.943409 -314.18672) (xy 156.902906 -314.214676)
			(xy 156.858444 -314.235774) (xy 156.811173 -314.249466) (xy 156.762318 -314.255398) (xy 156.713143 -314.253417)
			(xy 156.664924 -314.243573) (xy 156.618908 -314.226121) (xy 156.576287 -314.201514) (xy 156.538166 -314.170389)
			(xy 156.505531 -314.133552) (xy 156.479228 -314.091956) (xy 156.459937 -314.04668) (xy 156.44816 -313.998896)
			(xy 156.4442 -313.949842) (xy 155.155392 -313.949842) (xy 155.154897 -313.974449) (xy 155.147002 -314.023026)
			(xy 155.131418 -314.069707) (xy 155.108547 -314.113284) (xy 155.078982 -314.152628) (xy 155.043489 -314.18672)
			(xy 155.002986 -314.214676) (xy 154.958524 -314.235774) (xy 154.911253 -314.249466) (xy 154.862398 -314.255398)
			(xy 154.813223 -314.253417) (xy 154.765004 -314.243573) (xy 154.718988 -314.226121) (xy 154.676367 -314.201514)
			(xy 154.638246 -314.170389) (xy 154.605611 -314.133552) (xy 154.579308 -314.091956) (xy 154.560017 -314.04668)
			(xy 154.54824 -313.998896) (xy 154.54428 -313.949842) (xy 80.855058 -313.949842) (xy 80.854563 -313.974449)
			(xy 80.846668 -314.023026) (xy 80.831084 -314.069707) (xy 80.808213 -314.113284) (xy 80.778648 -314.152628)
			(xy 80.743155 -314.18672) (xy 80.702652 -314.214676) (xy 80.65819 -314.235774) (xy 80.610919 -314.249466)
			(xy 80.562064 -314.255398) (xy 80.512889 -314.253417) (xy 80.46467 -314.243573) (xy 80.418654 -314.226121)
			(xy 80.376033 -314.201514) (xy 80.337912 -314.170389) (xy 80.305277 -314.133552) (xy 80.278974 -314.091956)
			(xy 80.259683 -314.04668) (xy 80.247906 -313.998896) (xy 80.243946 -313.949842) (xy 78.955138 -313.949842)
			(xy 78.954643 -313.974449) (xy 78.946748 -314.023026) (xy 78.931164 -314.069707) (xy 78.908293 -314.113284)
			(xy 78.878728 -314.152628) (xy 78.843235 -314.18672) (xy 78.802732 -314.214676) (xy 78.75827 -314.235774)
			(xy 78.710999 -314.249466) (xy 78.662144 -314.255398) (xy 78.612969 -314.253417) (xy 78.56475 -314.243573)
			(xy 78.518734 -314.226121) (xy 78.476113 -314.201514) (xy 78.437992 -314.170389) (xy 78.405357 -314.133552)
			(xy 78.379054 -314.091956) (xy 78.359763 -314.04668) (xy 78.347986 -313.998896) (xy 78.344026 -313.949842)
			(xy 77.055218 -313.949842) (xy 77.054723 -313.974449) (xy 77.046828 -314.023026) (xy 77.031244 -314.069707)
			(xy 77.008373 -314.113284) (xy 76.978808 -314.152628) (xy 76.943315 -314.18672) (xy 76.902812 -314.214676)
			(xy 76.85835 -314.235774) (xy 76.811079 -314.249466) (xy 76.762224 -314.255398) (xy 76.713049 -314.253417)
			(xy 76.66483 -314.243573) (xy 76.618814 -314.226121) (xy 76.576193 -314.201514) (xy 76.538072 -314.170389)
			(xy 76.505437 -314.133552) (xy 76.479134 -314.091956) (xy 76.459843 -314.04668) (xy 76.448066 -313.998896)
			(xy 76.444106 -313.949842) (xy 75.155298 -313.949842) (xy 75.154803 -313.974449) (xy 75.146908 -314.023026)
			(xy 75.131324 -314.069707) (xy 75.108453 -314.113284) (xy 75.078888 -314.152628) (xy 75.043395 -314.18672)
			(xy 75.002892 -314.214676) (xy 74.95843 -314.235774) (xy 74.911159 -314.249466) (xy 74.862304 -314.255398)
			(xy 74.813129 -314.253417) (xy 74.76491 -314.243573) (xy 74.718894 -314.226121) (xy 74.676273 -314.201514)
			(xy 74.638152 -314.170389) (xy 74.605517 -314.133552) (xy 74.579214 -314.091956) (xy 74.559923 -314.04668)
			(xy 74.548146 -313.998896) (xy 74.544186 -313.949842) (xy 58.055256 -313.949842) (xy 58.054761 -313.974449)
			(xy 58.046866 -314.023026) (xy 58.031282 -314.069707) (xy 58.008411 -314.113284) (xy 57.978846 -314.152628)
			(xy 57.943353 -314.18672) (xy 57.90285 -314.214676) (xy 57.858388 -314.235774) (xy 57.811117 -314.249466)
			(xy 57.762262 -314.255398) (xy 57.713087 -314.253417) (xy 57.664868 -314.243573) (xy 57.618852 -314.226121)
			(xy 57.576231 -314.201514) (xy 57.53811 -314.170389) (xy 57.505475 -314.133552) (xy 57.479172 -314.091956)
			(xy 57.459881 -314.04668) (xy 57.448104 -313.998896) (xy 57.444144 -313.949842) (xy 56.155082 -313.949842)
			(xy 56.154587 -313.974449) (xy 56.146692 -314.023026) (xy 56.131108 -314.069707) (xy 56.108237 -314.113284)
			(xy 56.078672 -314.152628) (xy 56.043179 -314.18672) (xy 56.002676 -314.214676) (xy 55.958214 -314.235774)
			(xy 55.910943 -314.249466) (xy 55.862088 -314.255398) (xy 55.812913 -314.253417) (xy 55.764694 -314.243573)
			(xy 55.718678 -314.226121) (xy 55.676057 -314.201514) (xy 55.637936 -314.170389) (xy 55.605301 -314.133552)
			(xy 55.578998 -314.091956) (xy 55.559707 -314.04668) (xy 55.54793 -313.998896) (xy 55.54397 -313.949842)
			(xy 54.255162 -313.949842) (xy 54.254667 -313.974449) (xy 54.246772 -314.023026) (xy 54.231188 -314.069707)
			(xy 54.208317 -314.113284) (xy 54.178752 -314.152628) (xy 54.143259 -314.18672) (xy 54.102756 -314.214676)
			(xy 54.058294 -314.235774) (xy 54.011023 -314.249466) (xy 53.962168 -314.255398) (xy 53.912993 -314.253417)
			(xy 53.864774 -314.243573) (xy 53.818758 -314.226121) (xy 53.776137 -314.201514) (xy 53.738016 -314.170389)
			(xy 53.705381 -314.133552) (xy 53.679078 -314.091956) (xy 53.659787 -314.04668) (xy 53.64801 -313.998896)
			(xy 53.64405 -313.949842) (xy 52.355242 -313.949842) (xy 52.354747 -313.974449) (xy 52.346852 -314.023026)
			(xy 52.331268 -314.069707) (xy 52.308397 -314.113284) (xy 52.278832 -314.152628) (xy 52.243339 -314.18672)
			(xy 52.202836 -314.214676) (xy 52.158374 -314.235774) (xy 52.111103 -314.249466) (xy 52.062248 -314.255398)
			(xy 52.013073 -314.253417) (xy 51.964854 -314.243573) (xy 51.918838 -314.226121) (xy 51.876217 -314.201514)
			(xy 51.838096 -314.170389) (xy 51.805461 -314.133552) (xy 51.779158 -314.091956) (xy 51.759867 -314.04668)
			(xy 51.74809 -313.998896) (xy 51.74413 -313.949842) (xy 50.455068 -313.949842) (xy 50.454573 -313.974449)
			(xy 50.446678 -314.023026) (xy 50.431094 -314.069707) (xy 50.408223 -314.113284) (xy 50.378658 -314.152628)
			(xy 50.343165 -314.18672) (xy 50.302662 -314.214676) (xy 50.2582 -314.235774) (xy 50.210929 -314.249466)
			(xy 50.162074 -314.255398) (xy 50.112899 -314.253417) (xy 50.06468 -314.243573) (xy 50.018664 -314.226121)
			(xy 49.976043 -314.201514) (xy 49.937922 -314.170389) (xy 49.905287 -314.133552) (xy 49.878984 -314.091956)
			(xy 49.859693 -314.04668) (xy 49.847916 -313.998896) (xy 49.843956 -313.949842) (xy 48.555148 -313.949842)
			(xy 48.554653 -313.974449) (xy 48.546758 -314.023026) (xy 48.531174 -314.069707) (xy 48.508303 -314.113284)
			(xy 48.478738 -314.152628) (xy 48.443245 -314.18672) (xy 48.402742 -314.214676) (xy 48.35828 -314.235774)
			(xy 48.311009 -314.249466) (xy 48.262154 -314.255398) (xy 48.212979 -314.253417) (xy 48.16476 -314.243573)
			(xy 48.118744 -314.226121) (xy 48.076123 -314.201514) (xy 48.038002 -314.170389) (xy 48.005367 -314.133552)
			(xy 47.979064 -314.091956) (xy 47.959773 -314.04668) (xy 47.947996 -313.998896) (xy 47.944036 -313.949842)
			(xy 46.655228 -313.949842) (xy 46.654733 -313.974449) (xy 46.646838 -314.023026) (xy 46.631254 -314.069707)
			(xy 46.608383 -314.113284) (xy 46.578818 -314.152628) (xy 46.543325 -314.18672) (xy 46.502822 -314.214676)
			(xy 46.45836 -314.235774) (xy 46.411089 -314.249466) (xy 46.362234 -314.255398) (xy 46.313059 -314.253417)
			(xy 46.26484 -314.243573) (xy 46.218824 -314.226121) (xy 46.176203 -314.201514) (xy 46.138082 -314.170389)
			(xy 46.105447 -314.133552) (xy 46.079144 -314.091956) (xy 46.059853 -314.04668) (xy 46.048076 -313.998896)
			(xy 46.044116 -313.949842) (xy 44.755054 -313.949842) (xy 44.754559 -313.974449) (xy 44.746664 -314.023026)
			(xy 44.73108 -314.069707) (xy 44.708209 -314.113284) (xy 44.678644 -314.152628) (xy 44.643151 -314.18672)
			(xy 44.602648 -314.214676) (xy 44.558186 -314.235774) (xy 44.510915 -314.249466) (xy 44.46206 -314.255398)
			(xy 44.412885 -314.253417) (xy 44.364666 -314.243573) (xy 44.31865 -314.226121) (xy 44.276029 -314.201514)
			(xy 44.237908 -314.170389) (xy 44.205273 -314.133552) (xy 44.17897 -314.091956) (xy 44.159679 -314.04668)
			(xy 44.147902 -313.998896) (xy 44.143942 -313.949842) (xy 0.508 -313.949842) (xy 0.508 -314.899802)
			(xy 81.19416 -314.899802) (xy 81.19812 -314.850748) (xy 81.209897 -314.802964) (xy 81.229188 -314.757688)
			(xy 81.255491 -314.716092) (xy 81.288126 -314.679255) (xy 81.326247 -314.64813) (xy 81.368868 -314.623523)
			(xy 81.414884 -314.606071) (xy 81.463103 -314.596227) (xy 81.512278 -314.594246) (xy 81.561133 -314.600178)
			(xy 81.608404 -314.61387) (xy 81.652866 -314.634968) (xy 81.693369 -314.662924) (xy 81.728862 -314.697016)
			(xy 81.758427 -314.73636) (xy 81.781298 -314.779937) (xy 81.796882 -314.826618) (xy 81.804777 -314.875195)
			(xy 81.805272 -314.899802) (xy 82.14412 -314.899802) (xy 82.14808 -314.850748) (xy 82.159857 -314.802964)
			(xy 82.179148 -314.757688) (xy 82.205451 -314.716092) (xy 82.238086 -314.679255) (xy 82.276207 -314.64813)
			(xy 82.318828 -314.623523) (xy 82.364844 -314.606071) (xy 82.413063 -314.596227) (xy 82.462238 -314.594246)
			(xy 82.511093 -314.600178) (xy 82.558364 -314.61387) (xy 82.602826 -314.634968) (xy 82.643329 -314.662924)
			(xy 82.678822 -314.697016) (xy 82.708387 -314.73636) (xy 82.731258 -314.779937) (xy 82.746842 -314.826618)
			(xy 82.754737 -314.875195) (xy 82.755232 -314.899802) (xy 152.644106 -314.899802) (xy 152.648066 -314.850748)
			(xy 152.659843 -314.802964) (xy 152.679134 -314.757688) (xy 152.705437 -314.716092) (xy 152.738072 -314.679255)
			(xy 152.776193 -314.64813) (xy 152.818814 -314.623523) (xy 152.86483 -314.606071) (xy 152.913049 -314.596227)
			(xy 152.962224 -314.594246) (xy 153.011079 -314.600178) (xy 153.05835 -314.61387) (xy 153.102812 -314.634968)
			(xy 153.143315 -314.662924) (xy 153.178808 -314.697016) (xy 153.208373 -314.73636) (xy 153.231244 -314.779937)
			(xy 153.246828 -314.826618) (xy 153.254723 -314.875195) (xy 153.255218 -314.899802) (xy 153.594066 -314.899802)
			(xy 153.598026 -314.850748) (xy 153.609803 -314.802964) (xy 153.629094 -314.757688) (xy 153.655397 -314.716092)
			(xy 153.688032 -314.679255) (xy 153.726153 -314.64813) (xy 153.768774 -314.623523) (xy 153.81479 -314.606071)
			(xy 153.863009 -314.596227) (xy 153.912184 -314.594246) (xy 153.961039 -314.600178) (xy 154.00831 -314.61387)
			(xy 154.052772 -314.634968) (xy 154.093275 -314.662924) (xy 154.128768 -314.697016) (xy 154.158333 -314.73636)
			(xy 154.181204 -314.779937) (xy 154.196788 -314.826618) (xy 154.204683 -314.875195) (xy 154.205178 -314.899802)
			(xy 313.394102 -314.899802) (xy 313.398062 -314.850748) (xy 313.409839 -314.802964) (xy 313.42913 -314.757688)
			(xy 313.455433 -314.716092) (xy 313.488068 -314.679255) (xy 313.526189 -314.64813) (xy 313.56881 -314.623523)
			(xy 313.614826 -314.606071) (xy 313.663045 -314.596227) (xy 313.71222 -314.594246) (xy 313.761075 -314.600178)
			(xy 313.808346 -314.61387) (xy 313.852808 -314.634968) (xy 313.893311 -314.662924) (xy 313.928804 -314.697016)
			(xy 313.958369 -314.73636) (xy 313.98124 -314.779937) (xy 313.996824 -314.826618) (xy 314.004719 -314.875195)
			(xy 314.005214 -314.899802) (xy 314.344062 -314.899802) (xy 314.348022 -314.850748) (xy 314.359799 -314.802964)
			(xy 314.37909 -314.757688) (xy 314.405393 -314.716092) (xy 314.438028 -314.679255) (xy 314.476149 -314.64813)
			(xy 314.51877 -314.623523) (xy 314.564786 -314.606071) (xy 314.613005 -314.596227) (xy 314.66218 -314.594246)
			(xy 314.711035 -314.600178) (xy 314.758306 -314.61387) (xy 314.802768 -314.634968) (xy 314.843271 -314.662924)
			(xy 314.878764 -314.697016) (xy 314.908329 -314.73636) (xy 314.9312 -314.779937) (xy 314.946784 -314.826618)
			(xy 314.954679 -314.875195) (xy 314.955174 -314.899802) (xy 384.844048 -314.899802) (xy 384.848008 -314.850748)
			(xy 384.859785 -314.802964) (xy 384.879076 -314.757688) (xy 384.905379 -314.716092) (xy 384.938014 -314.679255)
			(xy 384.976135 -314.64813) (xy 385.018756 -314.623523) (xy 385.064772 -314.606071) (xy 385.112991 -314.596227)
			(xy 385.162166 -314.594246) (xy 385.211021 -314.600178) (xy 385.258292 -314.61387) (xy 385.302754 -314.634968)
			(xy 385.343257 -314.662924) (xy 385.37875 -314.697016) (xy 385.408315 -314.73636) (xy 385.431186 -314.779937)
			(xy 385.44677 -314.826618) (xy 385.454665 -314.875195) (xy 385.45516 -314.899802) (xy 385.794008 -314.899802)
			(xy 385.797968 -314.850748) (xy 385.809745 -314.802964) (xy 385.829036 -314.757688) (xy 385.855339 -314.716092)
			(xy 385.887974 -314.679255) (xy 385.926095 -314.64813) (xy 385.968716 -314.623523) (xy 386.014732 -314.606071)
			(xy 386.062951 -314.596227) (xy 386.112126 -314.594246) (xy 386.160981 -314.600178) (xy 386.208252 -314.61387)
			(xy 386.252714 -314.634968) (xy 386.293217 -314.662924) (xy 386.32871 -314.697016) (xy 386.358275 -314.73636)
			(xy 386.381146 -314.779937) (xy 386.39673 -314.826618) (xy 386.404625 -314.875195) (xy 386.40512 -314.899802)
			(xy 386.404625 -314.924409) (xy 386.39673 -314.972986) (xy 386.381146 -315.019667) (xy 386.358275 -315.063244)
			(xy 386.32871 -315.102588) (xy 386.293217 -315.13668) (xy 386.252714 -315.164636) (xy 386.208252 -315.185734)
			(xy 386.160981 -315.199426) (xy 386.112126 -315.205358) (xy 386.062951 -315.203377) (xy 386.014732 -315.193533)
			(xy 385.968716 -315.176081) (xy 385.926095 -315.151474) (xy 385.887974 -315.120349) (xy 385.855339 -315.083512)
			(xy 385.829036 -315.041916) (xy 385.809745 -314.99664) (xy 385.797968 -314.948856) (xy 385.794008 -314.899802)
			(xy 385.45516 -314.899802) (xy 385.454665 -314.924409) (xy 385.44677 -314.972986) (xy 385.431186 -315.019667)
			(xy 385.408315 -315.063244) (xy 385.37875 -315.102588) (xy 385.343257 -315.13668) (xy 385.302754 -315.164636)
			(xy 385.258292 -315.185734) (xy 385.211021 -315.199426) (xy 385.162166 -315.205358) (xy 385.112991 -315.203377)
			(xy 385.064772 -315.193533) (xy 385.018756 -315.176081) (xy 384.976135 -315.151474) (xy 384.938014 -315.120349)
			(xy 384.905379 -315.083512) (xy 384.879076 -315.041916) (xy 384.859785 -314.99664) (xy 384.848008 -314.948856)
			(xy 384.844048 -314.899802) (xy 314.955174 -314.899802) (xy 314.954679 -314.924409) (xy 314.946784 -314.972986)
			(xy 314.9312 -315.019667) (xy 314.908329 -315.063244) (xy 314.878764 -315.102588) (xy 314.843271 -315.13668)
			(xy 314.802768 -315.164636) (xy 314.758306 -315.185734) (xy 314.711035 -315.199426) (xy 314.66218 -315.205358)
			(xy 314.613005 -315.203377) (xy 314.564786 -315.193533) (xy 314.51877 -315.176081) (xy 314.476149 -315.151474)
			(xy 314.438028 -315.120349) (xy 314.405393 -315.083512) (xy 314.37909 -315.041916) (xy 314.359799 -314.99664)
			(xy 314.348022 -314.948856) (xy 314.344062 -314.899802) (xy 314.005214 -314.899802) (xy 314.004719 -314.924409)
			(xy 313.996824 -314.972986) (xy 313.98124 -315.019667) (xy 313.958369 -315.063244) (xy 313.928804 -315.102588)
			(xy 313.893311 -315.13668) (xy 313.852808 -315.164636) (xy 313.808346 -315.185734) (xy 313.761075 -315.199426)
			(xy 313.71222 -315.205358) (xy 313.663045 -315.203377) (xy 313.614826 -315.193533) (xy 313.56881 -315.176081)
			(xy 313.526189 -315.151474) (xy 313.488068 -315.120349) (xy 313.455433 -315.083512) (xy 313.42913 -315.041916)
			(xy 313.409839 -314.99664) (xy 313.398062 -314.948856) (xy 313.394102 -314.899802) (xy 154.205178 -314.899802)
			(xy 154.204683 -314.924409) (xy 154.196788 -314.972986) (xy 154.181204 -315.019667) (xy 154.158333 -315.063244)
			(xy 154.128768 -315.102588) (xy 154.093275 -315.13668) (xy 154.052772 -315.164636) (xy 154.00831 -315.185734)
			(xy 153.961039 -315.199426) (xy 153.912184 -315.205358) (xy 153.863009 -315.203377) (xy 153.81479 -315.193533)
			(xy 153.768774 -315.176081) (xy 153.726153 -315.151474) (xy 153.688032 -315.120349) (xy 153.655397 -315.083512)
			(xy 153.629094 -315.041916) (xy 153.609803 -314.99664) (xy 153.598026 -314.948856) (xy 153.594066 -314.899802)
			(xy 153.255218 -314.899802) (xy 153.254723 -314.924409) (xy 153.246828 -314.972986) (xy 153.231244 -315.019667)
			(xy 153.208373 -315.063244) (xy 153.178808 -315.102588) (xy 153.143315 -315.13668) (xy 153.102812 -315.164636)
			(xy 153.05835 -315.185734) (xy 153.011079 -315.199426) (xy 152.962224 -315.205358) (xy 152.913049 -315.203377)
			(xy 152.86483 -315.193533) (xy 152.818814 -315.176081) (xy 152.776193 -315.151474) (xy 152.738072 -315.120349)
			(xy 152.705437 -315.083512) (xy 152.679134 -315.041916) (xy 152.659843 -314.99664) (xy 152.648066 -314.948856)
			(xy 152.644106 -314.899802) (xy 82.755232 -314.899802) (xy 82.754737 -314.924409) (xy 82.746842 -314.972986)
			(xy 82.731258 -315.019667) (xy 82.708387 -315.063244) (xy 82.678822 -315.102588) (xy 82.643329 -315.13668)
			(xy 82.602826 -315.164636) (xy 82.558364 -315.185734) (xy 82.511093 -315.199426) (xy 82.462238 -315.205358)
			(xy 82.413063 -315.203377) (xy 82.364844 -315.193533) (xy 82.318828 -315.176081) (xy 82.276207 -315.151474)
			(xy 82.238086 -315.120349) (xy 82.205451 -315.083512) (xy 82.179148 -315.041916) (xy 82.159857 -314.99664)
			(xy 82.14808 -314.948856) (xy 82.14412 -314.899802) (xy 81.805272 -314.899802) (xy 81.804777 -314.924409)
			(xy 81.796882 -314.972986) (xy 81.781298 -315.019667) (xy 81.758427 -315.063244) (xy 81.728862 -315.102588)
			(xy 81.693369 -315.13668) (xy 81.652866 -315.164636) (xy 81.608404 -315.185734) (xy 81.561133 -315.199426)
			(xy 81.512278 -315.205358) (xy 81.463103 -315.203377) (xy 81.414884 -315.193533) (xy 81.368868 -315.176081)
			(xy 81.326247 -315.151474) (xy 81.288126 -315.120349) (xy 81.255491 -315.083512) (xy 81.229188 -315.041916)
			(xy 81.209897 -314.99664) (xy 81.19812 -314.948856) (xy 81.19416 -314.899802) (xy 0.508 -314.899802)
			(xy 0.508 -315.849762) (xy 50.79417 -315.849762) (xy 50.79813 -315.800708) (xy 50.809907 -315.752924)
			(xy 50.829198 -315.707648) (xy 50.855501 -315.666052) (xy 50.888136 -315.629215) (xy 50.926257 -315.59809)
			(xy 50.968878 -315.573483) (xy 51.014894 -315.556031) (xy 51.063113 -315.546187) (xy 51.112288 -315.544206)
			(xy 51.161143 -315.550138) (xy 51.208414 -315.56383) (xy 51.252876 -315.584928) (xy 51.293379 -315.612884)
			(xy 51.328872 -315.646976) (xy 51.358437 -315.68632) (xy 51.381308 -315.729897) (xy 51.396892 -315.776578)
			(xy 51.404787 -315.825155) (xy 51.405282 -315.849762) (xy 52.69409 -315.849762) (xy 52.69805 -315.800708)
			(xy 52.709827 -315.752924) (xy 52.729118 -315.707648) (xy 52.755421 -315.666052) (xy 52.788056 -315.629215)
			(xy 52.826177 -315.59809) (xy 52.868798 -315.573483) (xy 52.914814 -315.556031) (xy 52.963033 -315.546187)
			(xy 53.012208 -315.544206) (xy 53.061063 -315.550138) (xy 53.108334 -315.56383) (xy 53.152796 -315.584928)
			(xy 53.193299 -315.612884) (xy 53.228792 -315.646976) (xy 53.258357 -315.68632) (xy 53.281228 -315.729897)
			(xy 53.296812 -315.776578) (xy 53.304707 -315.825155) (xy 53.305202 -315.849762) (xy 54.59401 -315.849762)
			(xy 54.59797 -315.800708) (xy 54.609747 -315.752924) (xy 54.629038 -315.707648) (xy 54.655341 -315.666052)
			(xy 54.687976 -315.629215) (xy 54.726097 -315.59809) (xy 54.768718 -315.573483) (xy 54.814734 -315.556031)
			(xy 54.862953 -315.546187) (xy 54.912128 -315.544206) (xy 54.960983 -315.550138) (xy 55.008254 -315.56383)
			(xy 55.052716 -315.584928) (xy 55.093219 -315.612884) (xy 55.128712 -315.646976) (xy 55.158277 -315.68632)
			(xy 55.181148 -315.729897) (xy 55.196732 -315.776578) (xy 55.204627 -315.825155) (xy 55.205122 -315.849762)
			(xy 56.494184 -315.849762) (xy 56.498144 -315.800708) (xy 56.509921 -315.752924) (xy 56.529212 -315.707648)
			(xy 56.555515 -315.666052) (xy 56.58815 -315.629215) (xy 56.626271 -315.59809) (xy 56.668892 -315.573483)
			(xy 56.714908 -315.556031) (xy 56.763127 -315.546187) (xy 56.812302 -315.544206) (xy 56.861157 -315.550138)
			(xy 56.908428 -315.56383) (xy 56.95289 -315.584928) (xy 56.993393 -315.612884) (xy 57.028886 -315.646976)
			(xy 57.058451 -315.68632) (xy 57.081322 -315.729897) (xy 57.096906 -315.776578) (xy 57.104801 -315.825155)
			(xy 57.105296 -315.849762) (xy 58.394104 -315.849762) (xy 58.398064 -315.800708) (xy 58.409841 -315.752924)
			(xy 58.429132 -315.707648) (xy 58.455435 -315.666052) (xy 58.48807 -315.629215) (xy 58.526191 -315.59809)
			(xy 58.568812 -315.573483) (xy 58.614828 -315.556031) (xy 58.663047 -315.546187) (xy 58.712222 -315.544206)
			(xy 58.761077 -315.550138) (xy 58.808348 -315.56383) (xy 58.85281 -315.584928) (xy 58.893313 -315.612884)
			(xy 58.928806 -315.646976) (xy 58.958371 -315.68632) (xy 58.981242 -315.729897) (xy 58.996826 -315.776578)
			(xy 59.004721 -315.825155) (xy 59.005216 -315.849762) (xy 60.294024 -315.849762) (xy 60.297984 -315.800708)
			(xy 60.309761 -315.752924) (xy 60.329052 -315.707648) (xy 60.355355 -315.666052) (xy 60.38799 -315.629215)
			(xy 60.426111 -315.59809) (xy 60.468732 -315.573483) (xy 60.514748 -315.556031) (xy 60.562967 -315.546187)
			(xy 60.612142 -315.544206) (xy 60.660997 -315.550138) (xy 60.708268 -315.56383) (xy 60.75273 -315.584928)
			(xy 60.793233 -315.612884) (xy 60.828726 -315.646976) (xy 60.858291 -315.68632) (xy 60.881162 -315.729897)
			(xy 60.896746 -315.776578) (xy 60.904641 -315.825155) (xy 60.905136 -315.849762) (xy 62.193944 -315.849762)
			(xy 62.197904 -315.800708) (xy 62.209681 -315.752924) (xy 62.228972 -315.707648) (xy 62.255275 -315.666052)
			(xy 62.28791 -315.629215) (xy 62.326031 -315.59809) (xy 62.368652 -315.573483) (xy 62.414668 -315.556031)
			(xy 62.462887 -315.546187) (xy 62.512062 -315.544206) (xy 62.560917 -315.550138) (xy 62.608188 -315.56383)
			(xy 62.65265 -315.584928) (xy 62.693153 -315.612884) (xy 62.728646 -315.646976) (xy 62.758211 -315.68632)
			(xy 62.781082 -315.729897) (xy 62.796666 -315.776578) (xy 62.804561 -315.825155) (xy 62.805056 -315.849762)
			(xy 64.094118 -315.849762) (xy 64.098078 -315.800708) (xy 64.109855 -315.752924) (xy 64.129146 -315.707648)
			(xy 64.155449 -315.666052) (xy 64.188084 -315.629215) (xy 64.226205 -315.59809) (xy 64.268826 -315.573483)
			(xy 64.314842 -315.556031) (xy 64.363061 -315.546187) (xy 64.412236 -315.544206) (xy 64.461091 -315.550138)
			(xy 64.508362 -315.56383) (xy 64.552824 -315.584928) (xy 64.593327 -315.612884) (xy 64.62882 -315.646976)
			(xy 64.658385 -315.68632) (xy 64.681256 -315.729897) (xy 64.69684 -315.776578) (xy 64.704735 -315.825155)
			(xy 64.70523 -315.849762) (xy 73.593972 -315.849762) (xy 73.597932 -315.800708) (xy 73.609709 -315.752924)
			(xy 73.629 -315.707648) (xy 73.655303 -315.666052) (xy 73.687938 -315.629215) (xy 73.726059 -315.59809)
			(xy 73.76868 -315.573483) (xy 73.814696 -315.556031) (xy 73.862915 -315.546187) (xy 73.91209 -315.544206)
			(xy 73.960945 -315.550138) (xy 74.008216 -315.56383) (xy 74.052678 -315.584928) (xy 74.093181 -315.612884)
			(xy 74.128674 -315.646976) (xy 74.158239 -315.68632) (xy 74.18111 -315.729897) (xy 74.196694 -315.776578)
			(xy 74.204589 -315.825155) (xy 74.205084 -315.849762) (xy 75.494146 -315.849762) (xy 75.498106 -315.800708)
			(xy 75.509883 -315.752924) (xy 75.529174 -315.707648) (xy 75.555477 -315.666052) (xy 75.588112 -315.629215)
			(xy 75.626233 -315.59809) (xy 75.668854 -315.573483) (xy 75.71487 -315.556031) (xy 75.763089 -315.546187)
			(xy 75.812264 -315.544206) (xy 75.861119 -315.550138) (xy 75.90839 -315.56383) (xy 75.952852 -315.584928)
			(xy 75.993355 -315.612884) (xy 76.028848 -315.646976) (xy 76.058413 -315.68632) (xy 76.081284 -315.729897)
			(xy 76.096868 -315.776578) (xy 76.104763 -315.825155) (xy 76.105258 -315.849762) (xy 77.394066 -315.849762)
			(xy 77.398026 -315.800708) (xy 77.409803 -315.752924) (xy 77.429094 -315.707648) (xy 77.455397 -315.666052)
			(xy 77.488032 -315.629215) (xy 77.526153 -315.59809) (xy 77.568774 -315.573483) (xy 77.61479 -315.556031)
			(xy 77.663009 -315.546187) (xy 77.712184 -315.544206) (xy 77.761039 -315.550138) (xy 77.80831 -315.56383)
			(xy 77.852772 -315.584928) (xy 77.893275 -315.612884) (xy 77.928768 -315.646976) (xy 77.958333 -315.68632)
			(xy 77.981204 -315.729897) (xy 77.996788 -315.776578) (xy 78.004683 -315.825155) (xy 78.005178 -315.849762)
			(xy 79.293986 -315.849762) (xy 79.297946 -315.800708) (xy 79.309723 -315.752924) (xy 79.329014 -315.707648)
			(xy 79.355317 -315.666052) (xy 79.387952 -315.629215) (xy 79.426073 -315.59809) (xy 79.468694 -315.573483)
			(xy 79.51471 -315.556031) (xy 79.562929 -315.546187) (xy 79.612104 -315.544206) (xy 79.660959 -315.550138)
			(xy 79.70823 -315.56383) (xy 79.752692 -315.584928) (xy 79.793195 -315.612884) (xy 79.828688 -315.646976)
			(xy 79.858253 -315.68632) (xy 79.881124 -315.729897) (xy 79.896708 -315.776578) (xy 79.904603 -315.825155)
			(xy 79.905098 -315.849762) (xy 155.49424 -315.849762) (xy 155.4982 -315.800708) (xy 155.509977 -315.752924)
			(xy 155.529268 -315.707648) (xy 155.555571 -315.666052) (xy 155.588206 -315.629215) (xy 155.626327 -315.59809)
			(xy 155.668948 -315.573483) (xy 155.714964 -315.556031) (xy 155.763183 -315.546187) (xy 155.812358 -315.544206)
			(xy 155.861213 -315.550138) (xy 155.908484 -315.56383) (xy 155.952946 -315.584928) (xy 155.993449 -315.612884)
			(xy 156.028942 -315.646976) (xy 156.058507 -315.68632) (xy 156.081378 -315.729897) (xy 156.096962 -315.776578)
			(xy 156.104857 -315.825155) (xy 156.105352 -315.849762) (xy 157.39416 -315.849762) (xy 157.39812 -315.800708)
			(xy 157.409897 -315.752924) (xy 157.429188 -315.707648) (xy 157.455491 -315.666052) (xy 157.488126 -315.629215)
			(xy 157.526247 -315.59809) (xy 157.568868 -315.573483) (xy 157.614884 -315.556031) (xy 157.663103 -315.546187)
			(xy 157.712278 -315.544206) (xy 157.761133 -315.550138) (xy 157.808404 -315.56383) (xy 157.852866 -315.584928)
			(xy 157.893369 -315.612884) (xy 157.928862 -315.646976) (xy 157.958427 -315.68632) (xy 157.981298 -315.729897)
			(xy 157.996882 -315.776578) (xy 158.004777 -315.825155) (xy 158.005272 -315.849762) (xy 159.29408 -315.849762)
			(xy 159.29804 -315.800708) (xy 159.309817 -315.752924) (xy 159.329108 -315.707648) (xy 159.355411 -315.666052)
			(xy 159.388046 -315.629215) (xy 159.426167 -315.59809) (xy 159.468788 -315.573483) (xy 159.514804 -315.556031)
			(xy 159.563023 -315.546187) (xy 159.612198 -315.544206) (xy 159.661053 -315.550138) (xy 159.708324 -315.56383)
			(xy 159.752786 -315.584928) (xy 159.793289 -315.612884) (xy 159.828782 -315.646976) (xy 159.858347 -315.68632)
			(xy 159.881218 -315.729897) (xy 159.896802 -315.776578) (xy 159.904697 -315.825155) (xy 159.905192 -315.849762)
			(xy 161.194254 -315.849762) (xy 161.198214 -315.800708) (xy 161.209991 -315.752924) (xy 161.229282 -315.707648)
			(xy 161.255585 -315.666052) (xy 161.28822 -315.629215) (xy 161.326341 -315.59809) (xy 161.368962 -315.573483)
			(xy 161.414978 -315.556031) (xy 161.463197 -315.546187) (xy 161.512372 -315.544206) (xy 161.561227 -315.550138)
			(xy 161.608498 -315.56383) (xy 161.65296 -315.584928) (xy 161.693463 -315.612884) (xy 161.728956 -315.646976)
			(xy 161.758521 -315.68632) (xy 161.781392 -315.729897) (xy 161.796976 -315.776578) (xy 161.804871 -315.825155)
			(xy 161.805366 -315.849762) (xy 163.094174 -315.849762) (xy 163.098134 -315.800708) (xy 163.109911 -315.752924)
			(xy 163.129202 -315.707648) (xy 163.155505 -315.666052) (xy 163.18814 -315.629215) (xy 163.226261 -315.59809)
			(xy 163.268882 -315.573483) (xy 163.314898 -315.556031) (xy 163.363117 -315.546187) (xy 163.412292 -315.544206)
			(xy 163.461147 -315.550138) (xy 163.508418 -315.56383) (xy 163.55288 -315.584928) (xy 163.593383 -315.612884)
			(xy 163.628876 -315.646976) (xy 163.658441 -315.68632) (xy 163.681312 -315.729897) (xy 163.696896 -315.776578)
			(xy 163.704791 -315.825155) (xy 163.705286 -315.849762) (xy 164.994094 -315.849762) (xy 164.998054 -315.800708)
			(xy 165.009831 -315.752924) (xy 165.029122 -315.707648) (xy 165.055425 -315.666052) (xy 165.08806 -315.629215)
			(xy 165.126181 -315.59809) (xy 165.168802 -315.573483) (xy 165.214818 -315.556031) (xy 165.263037 -315.546187)
			(xy 165.312212 -315.544206) (xy 165.361067 -315.550138) (xy 165.408338 -315.56383) (xy 165.4528 -315.584928)
			(xy 165.493303 -315.612884) (xy 165.528796 -315.646976) (xy 165.558361 -315.68632) (xy 165.581232 -315.729897)
			(xy 165.596816 -315.776578) (xy 165.604711 -315.825155) (xy 165.605206 -315.849762) (xy 182.094136 -315.849762)
			(xy 182.098096 -315.800708) (xy 182.109873 -315.752924) (xy 182.129164 -315.707648) (xy 182.155467 -315.666052)
			(xy 182.188102 -315.629215) (xy 182.226223 -315.59809) (xy 182.268844 -315.573483) (xy 182.31486 -315.556031)
			(xy 182.363079 -315.546187) (xy 182.412254 -315.544206) (xy 182.461109 -315.550138) (xy 182.50838 -315.56383)
			(xy 182.552842 -315.584928) (xy 182.593345 -315.612884) (xy 182.628838 -315.646976) (xy 182.658403 -315.68632)
			(xy 182.681274 -315.729897) (xy 182.696858 -315.776578) (xy 182.704753 -315.825155) (xy 182.705248 -315.849762)
			(xy 183.994056 -315.849762) (xy 183.998016 -315.800708) (xy 184.009793 -315.752924) (xy 184.029084 -315.707648)
			(xy 184.055387 -315.666052) (xy 184.088022 -315.629215) (xy 184.126143 -315.59809) (xy 184.168764 -315.573483)
			(xy 184.21478 -315.556031) (xy 184.262999 -315.546187) (xy 184.312174 -315.544206) (xy 184.361029 -315.550138)
			(xy 184.4083 -315.56383) (xy 184.452762 -315.584928) (xy 184.493265 -315.612884) (xy 184.528758 -315.646976)
			(xy 184.558323 -315.68632) (xy 184.581194 -315.729897) (xy 184.596778 -315.776578) (xy 184.604673 -315.825155)
			(xy 184.605168 -315.849762) (xy 185.89423 -315.849762) (xy 185.89819 -315.800708) (xy 185.909967 -315.752924)
			(xy 185.929258 -315.707648) (xy 185.955561 -315.666052) (xy 185.988196 -315.629215) (xy 186.026317 -315.59809)
			(xy 186.068938 -315.573483) (xy 186.114954 -315.556031) (xy 186.163173 -315.546187) (xy 186.212348 -315.544206)
			(xy 186.261203 -315.550138) (xy 186.308474 -315.56383) (xy 186.352936 -315.584928) (xy 186.393439 -315.612884)
			(xy 186.428932 -315.646976) (xy 186.458497 -315.68632) (xy 186.481368 -315.729897) (xy 186.496952 -315.776578)
			(xy 186.504847 -315.825155) (xy 186.505342 -315.849762) (xy 187.79415 -315.849762) (xy 187.79811 -315.800708)
			(xy 187.809887 -315.752924) (xy 187.829178 -315.707648) (xy 187.855481 -315.666052) (xy 187.888116 -315.629215)
			(xy 187.926237 -315.59809) (xy 187.968858 -315.573483) (xy 188.014874 -315.556031) (xy 188.063093 -315.546187)
			(xy 188.112268 -315.544206) (xy 188.161123 -315.550138) (xy 188.208394 -315.56383) (xy 188.252856 -315.584928)
			(xy 188.293359 -315.612884) (xy 188.328852 -315.646976) (xy 188.358417 -315.68632) (xy 188.381288 -315.729897)
			(xy 188.396872 -315.776578) (xy 188.404767 -315.825155) (xy 188.405262 -315.849762) (xy 282.994112 -315.849762)
			(xy 282.998072 -315.800708) (xy 283.009849 -315.752924) (xy 283.02914 -315.707648) (xy 283.055443 -315.666052)
			(xy 283.088078 -315.629215) (xy 283.126199 -315.59809) (xy 283.16882 -315.573483) (xy 283.214836 -315.556031)
			(xy 283.263055 -315.546187) (xy 283.31223 -315.544206) (xy 283.361085 -315.550138) (xy 283.408356 -315.56383)
			(xy 283.452818 -315.584928) (xy 283.493321 -315.612884) (xy 283.528814 -315.646976) (xy 283.558379 -315.68632)
			(xy 283.58125 -315.729897) (xy 283.596834 -315.776578) (xy 283.604729 -315.825155) (xy 283.605224 -315.849762)
			(xy 284.894032 -315.849762) (xy 284.897992 -315.800708) (xy 284.909769 -315.752924) (xy 284.92906 -315.707648)
			(xy 284.955363 -315.666052) (xy 284.987998 -315.629215) (xy 285.026119 -315.59809) (xy 285.06874 -315.573483)
			(xy 285.114756 -315.556031) (xy 285.162975 -315.546187) (xy 285.21215 -315.544206) (xy 285.261005 -315.550138)
			(xy 285.308276 -315.56383) (xy 285.352738 -315.584928) (xy 285.393241 -315.612884) (xy 285.428734 -315.646976)
			(xy 285.458299 -315.68632) (xy 285.48117 -315.729897) (xy 285.496754 -315.776578) (xy 285.504649 -315.825155)
			(xy 285.505144 -315.849762) (xy 286.793952 -315.849762) (xy 286.797912 -315.800708) (xy 286.809689 -315.752924)
			(xy 286.82898 -315.707648) (xy 286.855283 -315.666052) (xy 286.887918 -315.629215) (xy 286.926039 -315.59809)
			(xy 286.96866 -315.573483) (xy 287.014676 -315.556031) (xy 287.062895 -315.546187) (xy 287.11207 -315.544206)
			(xy 287.160925 -315.550138) (xy 287.208196 -315.56383) (xy 287.252658 -315.584928) (xy 287.293161 -315.612884)
			(xy 287.328654 -315.646976) (xy 287.358219 -315.68632) (xy 287.38109 -315.729897) (xy 287.396674 -315.776578)
			(xy 287.404569 -315.825155) (xy 287.405064 -315.849762) (xy 288.694126 -315.849762) (xy 288.698086 -315.800708)
			(xy 288.709863 -315.752924) (xy 288.729154 -315.707648) (xy 288.755457 -315.666052) (xy 288.788092 -315.629215)
			(xy 288.826213 -315.59809) (xy 288.868834 -315.573483) (xy 288.91485 -315.556031) (xy 288.963069 -315.546187)
			(xy 289.012244 -315.544206) (xy 289.061099 -315.550138) (xy 289.10837 -315.56383) (xy 289.152832 -315.584928)
			(xy 289.193335 -315.612884) (xy 289.228828 -315.646976) (xy 289.258393 -315.68632) (xy 289.281264 -315.729897)
			(xy 289.296848 -315.776578) (xy 289.304743 -315.825155) (xy 289.305238 -315.849762) (xy 290.594046 -315.849762)
			(xy 290.598006 -315.800708) (xy 290.609783 -315.752924) (xy 290.629074 -315.707648) (xy 290.655377 -315.666052)
			(xy 290.688012 -315.629215) (xy 290.726133 -315.59809) (xy 290.768754 -315.573483) (xy 290.81477 -315.556031)
			(xy 290.862989 -315.546187) (xy 290.912164 -315.544206) (xy 290.961019 -315.550138) (xy 291.00829 -315.56383)
			(xy 291.052752 -315.584928) (xy 291.093255 -315.612884) (xy 291.128748 -315.646976) (xy 291.158313 -315.68632)
			(xy 291.181184 -315.729897) (xy 291.196768 -315.776578) (xy 291.204663 -315.825155) (xy 291.205158 -315.849762)
			(xy 292.493966 -315.849762) (xy 292.497926 -315.800708) (xy 292.509703 -315.752924) (xy 292.528994 -315.707648)
			(xy 292.555297 -315.666052) (xy 292.587932 -315.629215) (xy 292.626053 -315.59809) (xy 292.668674 -315.573483)
			(xy 292.71469 -315.556031) (xy 292.762909 -315.546187) (xy 292.812084 -315.544206) (xy 292.860939 -315.550138)
			(xy 292.90821 -315.56383) (xy 292.952672 -315.584928) (xy 292.993175 -315.612884) (xy 293.028668 -315.646976)
			(xy 293.058233 -315.68632) (xy 293.081104 -315.729897) (xy 293.096688 -315.776578) (xy 293.104583 -315.825155)
			(xy 293.105078 -315.849762) (xy 294.393886 -315.849762) (xy 294.397846 -315.800708) (xy 294.409623 -315.752924)
			(xy 294.428914 -315.707648) (xy 294.455217 -315.666052) (xy 294.487852 -315.629215) (xy 294.525973 -315.59809)
			(xy 294.568594 -315.573483) (xy 294.61461 -315.556031) (xy 294.662829 -315.546187) (xy 294.712004 -315.544206)
			(xy 294.760859 -315.550138) (xy 294.80813 -315.56383) (xy 294.852592 -315.584928) (xy 294.893095 -315.612884)
			(xy 294.928588 -315.646976) (xy 294.958153 -315.68632) (xy 294.981024 -315.729897) (xy 294.996608 -315.776578)
			(xy 295.004503 -315.825155) (xy 295.004998 -315.849762) (xy 296.29406 -315.849762) (xy 296.29802 -315.800708)
			(xy 296.309797 -315.752924) (xy 296.329088 -315.707648) (xy 296.355391 -315.666052) (xy 296.388026 -315.629215)
			(xy 296.426147 -315.59809) (xy 296.468768 -315.573483) (xy 296.514784 -315.556031) (xy 296.563003 -315.546187)
			(xy 296.612178 -315.544206) (xy 296.661033 -315.550138) (xy 296.708304 -315.56383) (xy 296.752766 -315.584928)
			(xy 296.793269 -315.612884) (xy 296.828762 -315.646976) (xy 296.858327 -315.68632) (xy 296.881198 -315.729897)
			(xy 296.896782 -315.776578) (xy 296.904677 -315.825155) (xy 296.905172 -315.849762) (xy 305.793914 -315.849762)
			(xy 305.797874 -315.800708) (xy 305.809651 -315.752924) (xy 305.828942 -315.707648) (xy 305.855245 -315.666052)
			(xy 305.88788 -315.629215) (xy 305.926001 -315.59809) (xy 305.968622 -315.573483) (xy 306.014638 -315.556031)
			(xy 306.062857 -315.546187) (xy 306.112032 -315.544206) (xy 306.160887 -315.550138) (xy 306.208158 -315.56383)
			(xy 306.25262 -315.584928) (xy 306.293123 -315.612884) (xy 306.328616 -315.646976) (xy 306.358181 -315.68632)
			(xy 306.381052 -315.729897) (xy 306.396636 -315.776578) (xy 306.404531 -315.825155) (xy 306.405026 -315.849762)
			(xy 307.694088 -315.849762) (xy 307.698048 -315.800708) (xy 307.709825 -315.752924) (xy 307.729116 -315.707648)
			(xy 307.755419 -315.666052) (xy 307.788054 -315.629215) (xy 307.826175 -315.59809) (xy 307.868796 -315.573483)
			(xy 307.914812 -315.556031) (xy 307.963031 -315.546187) (xy 308.012206 -315.544206) (xy 308.061061 -315.550138)
			(xy 308.108332 -315.56383) (xy 308.152794 -315.584928) (xy 308.193297 -315.612884) (xy 308.22879 -315.646976)
			(xy 308.258355 -315.68632) (xy 308.281226 -315.729897) (xy 308.29681 -315.776578) (xy 308.304705 -315.825155)
			(xy 308.3052 -315.849762) (xy 309.594008 -315.849762) (xy 309.597968 -315.800708) (xy 309.609745 -315.752924)
			(xy 309.629036 -315.707648) (xy 309.655339 -315.666052) (xy 309.687974 -315.629215) (xy 309.726095 -315.59809)
			(xy 309.768716 -315.573483) (xy 309.814732 -315.556031) (xy 309.862951 -315.546187) (xy 309.912126 -315.544206)
			(xy 309.960981 -315.550138) (xy 310.008252 -315.56383) (xy 310.052714 -315.584928) (xy 310.093217 -315.612884)
			(xy 310.12871 -315.646976) (xy 310.158275 -315.68632) (xy 310.181146 -315.729897) (xy 310.19673 -315.776578)
			(xy 310.204625 -315.825155) (xy 310.20512 -315.849762) (xy 311.493928 -315.849762) (xy 311.497888 -315.800708)
			(xy 311.509665 -315.752924) (xy 311.528956 -315.707648) (xy 311.555259 -315.666052) (xy 311.587894 -315.629215)
			(xy 311.626015 -315.59809) (xy 311.668636 -315.573483) (xy 311.714652 -315.556031) (xy 311.762871 -315.546187)
			(xy 311.812046 -315.544206) (xy 311.860901 -315.550138) (xy 311.908172 -315.56383) (xy 311.952634 -315.584928)
			(xy 311.993137 -315.612884) (xy 312.02863 -315.646976) (xy 312.058195 -315.68632) (xy 312.081066 -315.729897)
			(xy 312.09665 -315.776578) (xy 312.104545 -315.825155) (xy 312.10504 -315.849762) (xy 387.694182 -315.849762)
			(xy 387.698142 -315.800708) (xy 387.709919 -315.752924) (xy 387.72921 -315.707648) (xy 387.755513 -315.666052)
			(xy 387.788148 -315.629215) (xy 387.826269 -315.59809) (xy 387.86889 -315.573483) (xy 387.914906 -315.556031)
			(xy 387.963125 -315.546187) (xy 388.0123 -315.544206) (xy 388.061155 -315.550138) (xy 388.108426 -315.56383)
			(xy 388.152888 -315.584928) (xy 388.193391 -315.612884) (xy 388.228884 -315.646976) (xy 388.258449 -315.68632)
			(xy 388.28132 -315.729897) (xy 388.296904 -315.776578) (xy 388.304799 -315.825155) (xy 388.305294 -315.849762)
			(xy 389.594102 -315.849762) (xy 389.598062 -315.800708) (xy 389.609839 -315.752924) (xy 389.62913 -315.707648)
			(xy 389.655433 -315.666052) (xy 389.688068 -315.629215) (xy 389.726189 -315.59809) (xy 389.76881 -315.573483)
			(xy 389.814826 -315.556031) (xy 389.863045 -315.546187) (xy 389.91222 -315.544206) (xy 389.961075 -315.550138)
			(xy 390.008346 -315.56383) (xy 390.052808 -315.584928) (xy 390.093311 -315.612884) (xy 390.128804 -315.646976)
			(xy 390.158369 -315.68632) (xy 390.18124 -315.729897) (xy 390.196824 -315.776578) (xy 390.204719 -315.825155)
			(xy 390.205214 -315.849762) (xy 391.494022 -315.849762) (xy 391.497982 -315.800708) (xy 391.509759 -315.752924)
			(xy 391.52905 -315.707648) (xy 391.555353 -315.666052) (xy 391.587988 -315.629215) (xy 391.626109 -315.59809)
			(xy 391.66873 -315.573483) (xy 391.714746 -315.556031) (xy 391.762965 -315.546187) (xy 391.81214 -315.544206)
			(xy 391.860995 -315.550138) (xy 391.908266 -315.56383) (xy 391.952728 -315.584928) (xy 391.993231 -315.612884)
			(xy 392.028724 -315.646976) (xy 392.058289 -315.68632) (xy 392.08116 -315.729897) (xy 392.096744 -315.776578)
			(xy 392.104639 -315.825155) (xy 392.105134 -315.849762) (xy 393.394196 -315.849762) (xy 393.398156 -315.800708)
			(xy 393.409933 -315.752924) (xy 393.429224 -315.707648) (xy 393.455527 -315.666052) (xy 393.488162 -315.629215)
			(xy 393.526283 -315.59809) (xy 393.568904 -315.573483) (xy 393.61492 -315.556031) (xy 393.663139 -315.546187)
			(xy 393.712314 -315.544206) (xy 393.761169 -315.550138) (xy 393.80844 -315.56383) (xy 393.852902 -315.584928)
			(xy 393.893405 -315.612884) (xy 393.928898 -315.646976) (xy 393.958463 -315.68632) (xy 393.981334 -315.729897)
			(xy 393.996918 -315.776578) (xy 394.004813 -315.825155) (xy 394.005308 -315.849762) (xy 395.294116 -315.849762)
			(xy 395.298076 -315.800708) (xy 395.309853 -315.752924) (xy 395.329144 -315.707648) (xy 395.355447 -315.666052)
			(xy 395.388082 -315.629215) (xy 395.426203 -315.59809) (xy 395.468824 -315.573483) (xy 395.51484 -315.556031)
			(xy 395.563059 -315.546187) (xy 395.612234 -315.544206) (xy 395.661089 -315.550138) (xy 395.70836 -315.56383)
			(xy 395.752822 -315.584928) (xy 395.793325 -315.612884) (xy 395.828818 -315.646976) (xy 395.858383 -315.68632)
			(xy 395.881254 -315.729897) (xy 395.896838 -315.776578) (xy 395.904733 -315.825155) (xy 395.905228 -315.849762)
			(xy 397.194036 -315.849762) (xy 397.197996 -315.800708) (xy 397.209773 -315.752924) (xy 397.229064 -315.707648)
			(xy 397.255367 -315.666052) (xy 397.288002 -315.629215) (xy 397.326123 -315.59809) (xy 397.368744 -315.573483)
			(xy 397.41476 -315.556031) (xy 397.462979 -315.546187) (xy 397.512154 -315.544206) (xy 397.561009 -315.550138)
			(xy 397.60828 -315.56383) (xy 397.652742 -315.584928) (xy 397.693245 -315.612884) (xy 397.728738 -315.646976)
			(xy 397.758303 -315.68632) (xy 397.781174 -315.729897) (xy 397.796758 -315.776578) (xy 397.804653 -315.825155)
			(xy 397.805148 -315.849762) (xy 414.294078 -315.849762) (xy 414.298038 -315.800708) (xy 414.309815 -315.752924)
			(xy 414.329106 -315.707648) (xy 414.355409 -315.666052) (xy 414.388044 -315.629215) (xy 414.426165 -315.59809)
			(xy 414.468786 -315.573483) (xy 414.514802 -315.556031) (xy 414.563021 -315.546187) (xy 414.612196 -315.544206)
			(xy 414.661051 -315.550138) (xy 414.708322 -315.56383) (xy 414.752784 -315.584928) (xy 414.793287 -315.612884)
			(xy 414.82878 -315.646976) (xy 414.858345 -315.68632) (xy 414.881216 -315.729897) (xy 414.8968 -315.776578)
			(xy 414.904695 -315.825155) (xy 414.90519 -315.849762) (xy 416.193998 -315.849762) (xy 416.197958 -315.800708)
			(xy 416.209735 -315.752924) (xy 416.229026 -315.707648) (xy 416.255329 -315.666052) (xy 416.287964 -315.629215)
			(xy 416.326085 -315.59809) (xy 416.368706 -315.573483) (xy 416.414722 -315.556031) (xy 416.462941 -315.546187)
			(xy 416.512116 -315.544206) (xy 416.560971 -315.550138) (xy 416.608242 -315.56383) (xy 416.652704 -315.584928)
			(xy 416.693207 -315.612884) (xy 416.7287 -315.646976) (xy 416.758265 -315.68632) (xy 416.781136 -315.729897)
			(xy 416.79672 -315.776578) (xy 416.804615 -315.825155) (xy 416.80511 -315.849762) (xy 418.094172 -315.849762)
			(xy 418.098132 -315.800708) (xy 418.109909 -315.752924) (xy 418.1292 -315.707648) (xy 418.155503 -315.666052)
			(xy 418.188138 -315.629215) (xy 418.226259 -315.59809) (xy 418.26888 -315.573483) (xy 418.314896 -315.556031)
			(xy 418.363115 -315.546187) (xy 418.41229 -315.544206) (xy 418.461145 -315.550138) (xy 418.508416 -315.56383)
			(xy 418.552878 -315.584928) (xy 418.593381 -315.612884) (xy 418.628874 -315.646976) (xy 418.658439 -315.68632)
			(xy 418.68131 -315.729897) (xy 418.696894 -315.776578) (xy 418.704789 -315.825155) (xy 418.705284 -315.849762)
			(xy 419.994092 -315.849762) (xy 419.998052 -315.800708) (xy 420.009829 -315.752924) (xy 420.02912 -315.707648)
			(xy 420.055423 -315.666052) (xy 420.088058 -315.629215) (xy 420.126179 -315.59809) (xy 420.1688 -315.573483)
			(xy 420.214816 -315.556031) (xy 420.263035 -315.546187) (xy 420.31221 -315.544206) (xy 420.361065 -315.550138)
			(xy 420.408336 -315.56383) (xy 420.452798 -315.584928) (xy 420.493301 -315.612884) (xy 420.528794 -315.646976)
			(xy 420.558359 -315.68632) (xy 420.58123 -315.729897) (xy 420.596814 -315.776578) (xy 420.604709 -315.825155)
			(xy 420.605204 -315.849762) (xy 420.604709 -315.874369) (xy 420.596814 -315.922946) (xy 420.58123 -315.969627)
			(xy 420.558359 -316.013204) (xy 420.528794 -316.052548) (xy 420.493301 -316.08664) (xy 420.452798 -316.114596)
			(xy 420.408336 -316.135694) (xy 420.361065 -316.149386) (xy 420.31221 -316.155318) (xy 420.263035 -316.153337)
			(xy 420.214816 -316.143493) (xy 420.1688 -316.126041) (xy 420.126179 -316.101434) (xy 420.088058 -316.070309)
			(xy 420.055423 -316.033472) (xy 420.02912 -315.991876) (xy 420.009829 -315.9466) (xy 419.998052 -315.898816)
			(xy 419.994092 -315.849762) (xy 418.705284 -315.849762) (xy 418.704789 -315.874369) (xy 418.696894 -315.922946)
			(xy 418.68131 -315.969627) (xy 418.658439 -316.013204) (xy 418.628874 -316.052548) (xy 418.593381 -316.08664)
			(xy 418.552878 -316.114596) (xy 418.508416 -316.135694) (xy 418.461145 -316.149386) (xy 418.41229 -316.155318)
			(xy 418.363115 -316.153337) (xy 418.314896 -316.143493) (xy 418.26888 -316.126041) (xy 418.226259 -316.101434)
			(xy 418.188138 -316.070309) (xy 418.155503 -316.033472) (xy 418.1292 -315.991876) (xy 418.109909 -315.9466)
			(xy 418.098132 -315.898816) (xy 418.094172 -315.849762) (xy 416.80511 -315.849762) (xy 416.804615 -315.874369)
			(xy 416.79672 -315.922946) (xy 416.781136 -315.969627) (xy 416.758265 -316.013204) (xy 416.7287 -316.052548)
			(xy 416.693207 -316.08664) (xy 416.652704 -316.114596) (xy 416.608242 -316.135694) (xy 416.560971 -316.149386)
			(xy 416.512116 -316.155318) (xy 416.462941 -316.153337) (xy 416.414722 -316.143493) (xy 416.368706 -316.126041)
			(xy 416.326085 -316.101434) (xy 416.287964 -316.070309) (xy 416.255329 -316.033472) (xy 416.229026 -315.991876)
			(xy 416.209735 -315.9466) (xy 416.197958 -315.898816) (xy 416.193998 -315.849762) (xy 414.90519 -315.849762)
			(xy 414.904695 -315.874369) (xy 414.8968 -315.922946) (xy 414.881216 -315.969627) (xy 414.858345 -316.013204)
			(xy 414.82878 -316.052548) (xy 414.793287 -316.08664) (xy 414.752784 -316.114596) (xy 414.708322 -316.135694)
			(xy 414.661051 -316.149386) (xy 414.612196 -316.155318) (xy 414.563021 -316.153337) (xy 414.514802 -316.143493)
			(xy 414.468786 -316.126041) (xy 414.426165 -316.101434) (xy 414.388044 -316.070309) (xy 414.355409 -316.033472)
			(xy 414.329106 -315.991876) (xy 414.309815 -315.9466) (xy 414.298038 -315.898816) (xy 414.294078 -315.849762)
			(xy 397.805148 -315.849762) (xy 397.804653 -315.874369) (xy 397.796758 -315.922946) (xy 397.781174 -315.969627)
			(xy 397.758303 -316.013204) (xy 397.728738 -316.052548) (xy 397.693245 -316.08664) (xy 397.652742 -316.114596)
			(xy 397.60828 -316.135694) (xy 397.561009 -316.149386) (xy 397.512154 -316.155318) (xy 397.462979 -316.153337)
			(xy 397.41476 -316.143493) (xy 397.368744 -316.126041) (xy 397.326123 -316.101434) (xy 397.288002 -316.070309)
			(xy 397.255367 -316.033472) (xy 397.229064 -315.991876) (xy 397.209773 -315.9466) (xy 397.197996 -315.898816)
			(xy 397.194036 -315.849762) (xy 395.905228 -315.849762) (xy 395.904733 -315.874369) (xy 395.896838 -315.922946)
			(xy 395.881254 -315.969627) (xy 395.858383 -316.013204) (xy 395.828818 -316.052548) (xy 395.793325 -316.08664)
			(xy 395.752822 -316.114596) (xy 395.70836 -316.135694) (xy 395.661089 -316.149386) (xy 395.612234 -316.155318)
			(xy 395.563059 -316.153337) (xy 395.51484 -316.143493) (xy 395.468824 -316.126041) (xy 395.426203 -316.101434)
			(xy 395.388082 -316.070309) (xy 395.355447 -316.033472) (xy 395.329144 -315.991876) (xy 395.309853 -315.9466)
			(xy 395.298076 -315.898816) (xy 395.294116 -315.849762) (xy 394.005308 -315.849762) (xy 394.004813 -315.874369)
			(xy 393.996918 -315.922946) (xy 393.981334 -315.969627) (xy 393.958463 -316.013204) (xy 393.928898 -316.052548)
			(xy 393.893405 -316.08664) (xy 393.852902 -316.114596) (xy 393.80844 -316.135694) (xy 393.761169 -316.149386)
			(xy 393.712314 -316.155318) (xy 393.663139 -316.153337) (xy 393.61492 -316.143493) (xy 393.568904 -316.126041)
			(xy 393.526283 -316.101434) (xy 393.488162 -316.070309) (xy 393.455527 -316.033472) (xy 393.429224 -315.991876)
			(xy 393.409933 -315.9466) (xy 393.398156 -315.898816) (xy 393.394196 -315.849762) (xy 392.105134 -315.849762)
			(xy 392.104639 -315.874369) (xy 392.096744 -315.922946) (xy 392.08116 -315.969627) (xy 392.058289 -316.013204)
			(xy 392.028724 -316.052548) (xy 391.993231 -316.08664) (xy 391.952728 -316.114596) (xy 391.908266 -316.135694)
			(xy 391.860995 -316.149386) (xy 391.81214 -316.155318) (xy 391.762965 -316.153337) (xy 391.714746 -316.143493)
			(xy 391.66873 -316.126041) (xy 391.626109 -316.101434) (xy 391.587988 -316.070309) (xy 391.555353 -316.033472)
			(xy 391.52905 -315.991876) (xy 391.509759 -315.9466) (xy 391.497982 -315.898816) (xy 391.494022 -315.849762)
			(xy 390.205214 -315.849762) (xy 390.204719 -315.874369) (xy 390.196824 -315.922946) (xy 390.18124 -315.969627)
			(xy 390.158369 -316.013204) (xy 390.128804 -316.052548) (xy 390.093311 -316.08664) (xy 390.052808 -316.114596)
			(xy 390.008346 -316.135694) (xy 389.961075 -316.149386) (xy 389.91222 -316.155318) (xy 389.863045 -316.153337)
			(xy 389.814826 -316.143493) (xy 389.76881 -316.126041) (xy 389.726189 -316.101434) (xy 389.688068 -316.070309)
			(xy 389.655433 -316.033472) (xy 389.62913 -315.991876) (xy 389.609839 -315.9466) (xy 389.598062 -315.898816)
			(xy 389.594102 -315.849762) (xy 388.305294 -315.849762) (xy 388.304799 -315.874369) (xy 388.296904 -315.922946)
			(xy 388.28132 -315.969627) (xy 388.258449 -316.013204) (xy 388.228884 -316.052548) (xy 388.193391 -316.08664)
			(xy 388.152888 -316.114596) (xy 388.108426 -316.135694) (xy 388.061155 -316.149386) (xy 388.0123 -316.155318)
			(xy 387.963125 -316.153337) (xy 387.914906 -316.143493) (xy 387.86889 -316.126041) (xy 387.826269 -316.101434)
			(xy 387.788148 -316.070309) (xy 387.755513 -316.033472) (xy 387.72921 -315.991876) (xy 387.709919 -315.9466)
			(xy 387.698142 -315.898816) (xy 387.694182 -315.849762) (xy 312.10504 -315.849762) (xy 312.104545 -315.874369)
			(xy 312.09665 -315.922946) (xy 312.081066 -315.969627) (xy 312.058195 -316.013204) (xy 312.02863 -316.052548)
			(xy 311.993137 -316.08664) (xy 311.952634 -316.114596) (xy 311.908172 -316.135694) (xy 311.860901 -316.149386)
			(xy 311.812046 -316.155318) (xy 311.762871 -316.153337) (xy 311.714652 -316.143493) (xy 311.668636 -316.126041)
			(xy 311.626015 -316.101434) (xy 311.587894 -316.070309) (xy 311.555259 -316.033472) (xy 311.528956 -315.991876)
			(xy 311.509665 -315.9466) (xy 311.497888 -315.898816) (xy 311.493928 -315.849762) (xy 310.20512 -315.849762)
			(xy 310.204625 -315.874369) (xy 310.19673 -315.922946) (xy 310.181146 -315.969627) (xy 310.158275 -316.013204)
			(xy 310.12871 -316.052548) (xy 310.093217 -316.08664) (xy 310.052714 -316.114596) (xy 310.008252 -316.135694)
			(xy 309.960981 -316.149386) (xy 309.912126 -316.155318) (xy 309.862951 -316.153337) (xy 309.814732 -316.143493)
			(xy 309.768716 -316.126041) (xy 309.726095 -316.101434) (xy 309.687974 -316.070309) (xy 309.655339 -316.033472)
			(xy 309.629036 -315.991876) (xy 309.609745 -315.9466) (xy 309.597968 -315.898816) (xy 309.594008 -315.849762)
			(xy 308.3052 -315.849762) (xy 308.304705 -315.874369) (xy 308.29681 -315.922946) (xy 308.281226 -315.969627)
			(xy 308.258355 -316.013204) (xy 308.22879 -316.052548) (xy 308.193297 -316.08664) (xy 308.152794 -316.114596)
			(xy 308.108332 -316.135694) (xy 308.061061 -316.149386) (xy 308.012206 -316.155318) (xy 307.963031 -316.153337)
			(xy 307.914812 -316.143493) (xy 307.868796 -316.126041) (xy 307.826175 -316.101434) (xy 307.788054 -316.070309)
			(xy 307.755419 -316.033472) (xy 307.729116 -315.991876) (xy 307.709825 -315.9466) (xy 307.698048 -315.898816)
			(xy 307.694088 -315.849762) (xy 306.405026 -315.849762) (xy 306.404531 -315.874369) (xy 306.396636 -315.922946)
			(xy 306.381052 -315.969627) (xy 306.358181 -316.013204) (xy 306.328616 -316.052548) (xy 306.293123 -316.08664)
			(xy 306.25262 -316.114596) (xy 306.208158 -316.135694) (xy 306.160887 -316.149386) (xy 306.112032 -316.155318)
			(xy 306.062857 -316.153337) (xy 306.014638 -316.143493) (xy 305.968622 -316.126041) (xy 305.926001 -316.101434)
			(xy 305.88788 -316.070309) (xy 305.855245 -316.033472) (xy 305.828942 -315.991876) (xy 305.809651 -315.9466)
			(xy 305.797874 -315.898816) (xy 305.793914 -315.849762) (xy 296.905172 -315.849762) (xy 296.904677 -315.874369)
			(xy 296.896782 -315.922946) (xy 296.881198 -315.969627) (xy 296.858327 -316.013204) (xy 296.828762 -316.052548)
			(xy 296.793269 -316.08664) (xy 296.752766 -316.114596) (xy 296.708304 -316.135694) (xy 296.661033 -316.149386)
			(xy 296.612178 -316.155318) (xy 296.563003 -316.153337) (xy 296.514784 -316.143493) (xy 296.468768 -316.126041)
			(xy 296.426147 -316.101434) (xy 296.388026 -316.070309) (xy 296.355391 -316.033472) (xy 296.329088 -315.991876)
			(xy 296.309797 -315.9466) (xy 296.29802 -315.898816) (xy 296.29406 -315.849762) (xy 295.004998 -315.849762)
			(xy 295.004503 -315.874369) (xy 294.996608 -315.922946) (xy 294.981024 -315.969627) (xy 294.958153 -316.013204)
			(xy 294.928588 -316.052548) (xy 294.893095 -316.08664) (xy 294.852592 -316.114596) (xy 294.80813 -316.135694)
			(xy 294.760859 -316.149386) (xy 294.712004 -316.155318) (xy 294.662829 -316.153337) (xy 294.61461 -316.143493)
			(xy 294.568594 -316.126041) (xy 294.525973 -316.101434) (xy 294.487852 -316.070309) (xy 294.455217 -316.033472)
			(xy 294.428914 -315.991876) (xy 294.409623 -315.9466) (xy 294.397846 -315.898816) (xy 294.393886 -315.849762)
			(xy 293.105078 -315.849762) (xy 293.104583 -315.874369) (xy 293.096688 -315.922946) (xy 293.081104 -315.969627)
			(xy 293.058233 -316.013204) (xy 293.028668 -316.052548) (xy 292.993175 -316.08664) (xy 292.952672 -316.114596)
			(xy 292.90821 -316.135694) (xy 292.860939 -316.149386) (xy 292.812084 -316.155318) (xy 292.762909 -316.153337)
			(xy 292.71469 -316.143493) (xy 292.668674 -316.126041) (xy 292.626053 -316.101434) (xy 292.587932 -316.070309)
			(xy 292.555297 -316.033472) (xy 292.528994 -315.991876) (xy 292.509703 -315.9466) (xy 292.497926 -315.898816)
			(xy 292.493966 -315.849762) (xy 291.205158 -315.849762) (xy 291.204663 -315.874369) (xy 291.196768 -315.922946)
			(xy 291.181184 -315.969627) (xy 291.158313 -316.013204) (xy 291.128748 -316.052548) (xy 291.093255 -316.08664)
			(xy 291.052752 -316.114596) (xy 291.00829 -316.135694) (xy 290.961019 -316.149386) (xy 290.912164 -316.155318)
			(xy 290.862989 -316.153337) (xy 290.81477 -316.143493) (xy 290.768754 -316.126041) (xy 290.726133 -316.101434)
			(xy 290.688012 -316.070309) (xy 290.655377 -316.033472) (xy 290.629074 -315.991876) (xy 290.609783 -315.9466)
			(xy 290.598006 -315.898816) (xy 290.594046 -315.849762) (xy 289.305238 -315.849762) (xy 289.304743 -315.874369)
			(xy 289.296848 -315.922946) (xy 289.281264 -315.969627) (xy 289.258393 -316.013204) (xy 289.228828 -316.052548)
			(xy 289.193335 -316.08664) (xy 289.152832 -316.114596) (xy 289.10837 -316.135694) (xy 289.061099 -316.149386)
			(xy 289.012244 -316.155318) (xy 288.963069 -316.153337) (xy 288.91485 -316.143493) (xy 288.868834 -316.126041)
			(xy 288.826213 -316.101434) (xy 288.788092 -316.070309) (xy 288.755457 -316.033472) (xy 288.729154 -315.991876)
			(xy 288.709863 -315.9466) (xy 288.698086 -315.898816) (xy 288.694126 -315.849762) (xy 287.405064 -315.849762)
			(xy 287.404569 -315.874369) (xy 287.396674 -315.922946) (xy 287.38109 -315.969627) (xy 287.358219 -316.013204)
			(xy 287.328654 -316.052548) (xy 287.293161 -316.08664) (xy 287.252658 -316.114596) (xy 287.208196 -316.135694)
			(xy 287.160925 -316.149386) (xy 287.11207 -316.155318) (xy 287.062895 -316.153337) (xy 287.014676 -316.143493)
			(xy 286.96866 -316.126041) (xy 286.926039 -316.101434) (xy 286.887918 -316.070309) (xy 286.855283 -316.033472)
			(xy 286.82898 -315.991876) (xy 286.809689 -315.9466) (xy 286.797912 -315.898816) (xy 286.793952 -315.849762)
			(xy 285.505144 -315.849762) (xy 285.504649 -315.874369) (xy 285.496754 -315.922946) (xy 285.48117 -315.969627)
			(xy 285.458299 -316.013204) (xy 285.428734 -316.052548) (xy 285.393241 -316.08664) (xy 285.352738 -316.114596)
			(xy 285.308276 -316.135694) (xy 285.261005 -316.149386) (xy 285.21215 -316.155318) (xy 285.162975 -316.153337)
			(xy 285.114756 -316.143493) (xy 285.06874 -316.126041) (xy 285.026119 -316.101434) (xy 284.987998 -316.070309)
			(xy 284.955363 -316.033472) (xy 284.92906 -315.991876) (xy 284.909769 -315.9466) (xy 284.897992 -315.898816)
			(xy 284.894032 -315.849762) (xy 283.605224 -315.849762) (xy 283.604729 -315.874369) (xy 283.596834 -315.922946)
			(xy 283.58125 -315.969627) (xy 283.558379 -316.013204) (xy 283.528814 -316.052548) (xy 283.493321 -316.08664)
			(xy 283.452818 -316.114596) (xy 283.408356 -316.135694) (xy 283.361085 -316.149386) (xy 283.31223 -316.155318)
			(xy 283.263055 -316.153337) (xy 283.214836 -316.143493) (xy 283.16882 -316.126041) (xy 283.126199 -316.101434)
			(xy 283.088078 -316.070309) (xy 283.055443 -316.033472) (xy 283.02914 -315.991876) (xy 283.009849 -315.9466)
			(xy 282.998072 -315.898816) (xy 282.994112 -315.849762) (xy 188.405262 -315.849762) (xy 188.404767 -315.874369)
			(xy 188.396872 -315.922946) (xy 188.381288 -315.969627) (xy 188.358417 -316.013204) (xy 188.328852 -316.052548)
			(xy 188.293359 -316.08664) (xy 188.252856 -316.114596) (xy 188.208394 -316.135694) (xy 188.161123 -316.149386)
			(xy 188.112268 -316.155318) (xy 188.063093 -316.153337) (xy 188.014874 -316.143493) (xy 187.968858 -316.126041)
			(xy 187.926237 -316.101434) (xy 187.888116 -316.070309) (xy 187.855481 -316.033472) (xy 187.829178 -315.991876)
			(xy 187.809887 -315.9466) (xy 187.79811 -315.898816) (xy 187.79415 -315.849762) (xy 186.505342 -315.849762)
			(xy 186.504847 -315.874369) (xy 186.496952 -315.922946) (xy 186.481368 -315.969627) (xy 186.458497 -316.013204)
			(xy 186.428932 -316.052548) (xy 186.393439 -316.08664) (xy 186.352936 -316.114596) (xy 186.308474 -316.135694)
			(xy 186.261203 -316.149386) (xy 186.212348 -316.155318) (xy 186.163173 -316.153337) (xy 186.114954 -316.143493)
			(xy 186.068938 -316.126041) (xy 186.026317 -316.101434) (xy 185.988196 -316.070309) (xy 185.955561 -316.033472)
			(xy 185.929258 -315.991876) (xy 185.909967 -315.9466) (xy 185.89819 -315.898816) (xy 185.89423 -315.849762)
			(xy 184.605168 -315.849762) (xy 184.604673 -315.874369) (xy 184.596778 -315.922946) (xy 184.581194 -315.969627)
			(xy 184.558323 -316.013204) (xy 184.528758 -316.052548) (xy 184.493265 -316.08664) (xy 184.452762 -316.114596)
			(xy 184.4083 -316.135694) (xy 184.361029 -316.149386) (xy 184.312174 -316.155318) (xy 184.262999 -316.153337)
			(xy 184.21478 -316.143493) (xy 184.168764 -316.126041) (xy 184.126143 -316.101434) (xy 184.088022 -316.070309)
			(xy 184.055387 -316.033472) (xy 184.029084 -315.991876) (xy 184.009793 -315.9466) (xy 183.998016 -315.898816)
			(xy 183.994056 -315.849762) (xy 182.705248 -315.849762) (xy 182.704753 -315.874369) (xy 182.696858 -315.922946)
			(xy 182.681274 -315.969627) (xy 182.658403 -316.013204) (xy 182.628838 -316.052548) (xy 182.593345 -316.08664)
			(xy 182.552842 -316.114596) (xy 182.50838 -316.135694) (xy 182.461109 -316.149386) (xy 182.412254 -316.155318)
			(xy 182.363079 -316.153337) (xy 182.31486 -316.143493) (xy 182.268844 -316.126041) (xy 182.226223 -316.101434)
			(xy 182.188102 -316.070309) (xy 182.155467 -316.033472) (xy 182.129164 -315.991876) (xy 182.109873 -315.9466)
			(xy 182.098096 -315.898816) (xy 182.094136 -315.849762) (xy 165.605206 -315.849762) (xy 165.604711 -315.874369)
			(xy 165.596816 -315.922946) (xy 165.581232 -315.969627) (xy 165.558361 -316.013204) (xy 165.528796 -316.052548)
			(xy 165.493303 -316.08664) (xy 165.4528 -316.114596) (xy 165.408338 -316.135694) (xy 165.361067 -316.149386)
			(xy 165.312212 -316.155318) (xy 165.263037 -316.153337) (xy 165.214818 -316.143493) (xy 165.168802 -316.126041)
			(xy 165.126181 -316.101434) (xy 165.08806 -316.070309) (xy 165.055425 -316.033472) (xy 165.029122 -315.991876)
			(xy 165.009831 -315.9466) (xy 164.998054 -315.898816) (xy 164.994094 -315.849762) (xy 163.705286 -315.849762)
			(xy 163.704791 -315.874369) (xy 163.696896 -315.922946) (xy 163.681312 -315.969627) (xy 163.658441 -316.013204)
			(xy 163.628876 -316.052548) (xy 163.593383 -316.08664) (xy 163.55288 -316.114596) (xy 163.508418 -316.135694)
			(xy 163.461147 -316.149386) (xy 163.412292 -316.155318) (xy 163.363117 -316.153337) (xy 163.314898 -316.143493)
			(xy 163.268882 -316.126041) (xy 163.226261 -316.101434) (xy 163.18814 -316.070309) (xy 163.155505 -316.033472)
			(xy 163.129202 -315.991876) (xy 163.109911 -315.9466) (xy 163.098134 -315.898816) (xy 163.094174 -315.849762)
			(xy 161.805366 -315.849762) (xy 161.804871 -315.874369) (xy 161.796976 -315.922946) (xy 161.781392 -315.969627)
			(xy 161.758521 -316.013204) (xy 161.728956 -316.052548) (xy 161.693463 -316.08664) (xy 161.65296 -316.114596)
			(xy 161.608498 -316.135694) (xy 161.561227 -316.149386) (xy 161.512372 -316.155318) (xy 161.463197 -316.153337)
			(xy 161.414978 -316.143493) (xy 161.368962 -316.126041) (xy 161.326341 -316.101434) (xy 161.28822 -316.070309)
			(xy 161.255585 -316.033472) (xy 161.229282 -315.991876) (xy 161.209991 -315.9466) (xy 161.198214 -315.898816)
			(xy 161.194254 -315.849762) (xy 159.905192 -315.849762) (xy 159.904697 -315.874369) (xy 159.896802 -315.922946)
			(xy 159.881218 -315.969627) (xy 159.858347 -316.013204) (xy 159.828782 -316.052548) (xy 159.793289 -316.08664)
			(xy 159.752786 -316.114596) (xy 159.708324 -316.135694) (xy 159.661053 -316.149386) (xy 159.612198 -316.155318)
			(xy 159.563023 -316.153337) (xy 159.514804 -316.143493) (xy 159.468788 -316.126041) (xy 159.426167 -316.101434)
			(xy 159.388046 -316.070309) (xy 159.355411 -316.033472) (xy 159.329108 -315.991876) (xy 159.309817 -315.9466)
			(xy 159.29804 -315.898816) (xy 159.29408 -315.849762) (xy 158.005272 -315.849762) (xy 158.004777 -315.874369)
			(xy 157.996882 -315.922946) (xy 157.981298 -315.969627) (xy 157.958427 -316.013204) (xy 157.928862 -316.052548)
			(xy 157.893369 -316.08664) (xy 157.852866 -316.114596) (xy 157.808404 -316.135694) (xy 157.761133 -316.149386)
			(xy 157.712278 -316.155318) (xy 157.663103 -316.153337) (xy 157.614884 -316.143493) (xy 157.568868 -316.126041)
			(xy 157.526247 -316.101434) (xy 157.488126 -316.070309) (xy 157.455491 -316.033472) (xy 157.429188 -315.991876)
			(xy 157.409897 -315.9466) (xy 157.39812 -315.898816) (xy 157.39416 -315.849762) (xy 156.105352 -315.849762)
			(xy 156.104857 -315.874369) (xy 156.096962 -315.922946) (xy 156.081378 -315.969627) (xy 156.058507 -316.013204)
			(xy 156.028942 -316.052548) (xy 155.993449 -316.08664) (xy 155.952946 -316.114596) (xy 155.908484 -316.135694)
			(xy 155.861213 -316.149386) (xy 155.812358 -316.155318) (xy 155.763183 -316.153337) (xy 155.714964 -316.143493)
			(xy 155.668948 -316.126041) (xy 155.626327 -316.101434) (xy 155.588206 -316.070309) (xy 155.555571 -316.033472)
			(xy 155.529268 -315.991876) (xy 155.509977 -315.9466) (xy 155.4982 -315.898816) (xy 155.49424 -315.849762)
			(xy 79.905098 -315.849762) (xy 79.904603 -315.874369) (xy 79.896708 -315.922946) (xy 79.881124 -315.969627)
			(xy 79.858253 -316.013204) (xy 79.828688 -316.052548) (xy 79.793195 -316.08664) (xy 79.752692 -316.114596)
			(xy 79.70823 -316.135694) (xy 79.660959 -316.149386) (xy 79.612104 -316.155318) (xy 79.562929 -316.153337)
			(xy 79.51471 -316.143493) (xy 79.468694 -316.126041) (xy 79.426073 -316.101434) (xy 79.387952 -316.070309)
			(xy 79.355317 -316.033472) (xy 79.329014 -315.991876) (xy 79.309723 -315.9466) (xy 79.297946 -315.898816)
			(xy 79.293986 -315.849762) (xy 78.005178 -315.849762) (xy 78.004683 -315.874369) (xy 77.996788 -315.922946)
			(xy 77.981204 -315.969627) (xy 77.958333 -316.013204) (xy 77.928768 -316.052548) (xy 77.893275 -316.08664)
			(xy 77.852772 -316.114596) (xy 77.80831 -316.135694) (xy 77.761039 -316.149386) (xy 77.712184 -316.155318)
			(xy 77.663009 -316.153337) (xy 77.61479 -316.143493) (xy 77.568774 -316.126041) (xy 77.526153 -316.101434)
			(xy 77.488032 -316.070309) (xy 77.455397 -316.033472) (xy 77.429094 -315.991876) (xy 77.409803 -315.9466)
			(xy 77.398026 -315.898816) (xy 77.394066 -315.849762) (xy 76.105258 -315.849762) (xy 76.104763 -315.874369)
			(xy 76.096868 -315.922946) (xy 76.081284 -315.969627) (xy 76.058413 -316.013204) (xy 76.028848 -316.052548)
			(xy 75.993355 -316.08664) (xy 75.952852 -316.114596) (xy 75.90839 -316.135694) (xy 75.861119 -316.149386)
			(xy 75.812264 -316.155318) (xy 75.763089 -316.153337) (xy 75.71487 -316.143493) (xy 75.668854 -316.126041)
			(xy 75.626233 -316.101434) (xy 75.588112 -316.070309) (xy 75.555477 -316.033472) (xy 75.529174 -315.991876)
			(xy 75.509883 -315.9466) (xy 75.498106 -315.898816) (xy 75.494146 -315.849762) (xy 74.205084 -315.849762)
			(xy 74.204589 -315.874369) (xy 74.196694 -315.922946) (xy 74.18111 -315.969627) (xy 74.158239 -316.013204)
			(xy 74.128674 -316.052548) (xy 74.093181 -316.08664) (xy 74.052678 -316.114596) (xy 74.008216 -316.135694)
			(xy 73.960945 -316.149386) (xy 73.91209 -316.155318) (xy 73.862915 -316.153337) (xy 73.814696 -316.143493)
			(xy 73.76868 -316.126041) (xy 73.726059 -316.101434) (xy 73.687938 -316.070309) (xy 73.655303 -316.033472)
			(xy 73.629 -315.991876) (xy 73.609709 -315.9466) (xy 73.597932 -315.898816) (xy 73.593972 -315.849762)
			(xy 64.70523 -315.849762) (xy 64.704735 -315.874369) (xy 64.69684 -315.922946) (xy 64.681256 -315.969627)
			(xy 64.658385 -316.013204) (xy 64.62882 -316.052548) (xy 64.593327 -316.08664) (xy 64.552824 -316.114596)
			(xy 64.508362 -316.135694) (xy 64.461091 -316.149386) (xy 64.412236 -316.155318) (xy 64.363061 -316.153337)
			(xy 64.314842 -316.143493) (xy 64.268826 -316.126041) (xy 64.226205 -316.101434) (xy 64.188084 -316.070309)
			(xy 64.155449 -316.033472) (xy 64.129146 -315.991876) (xy 64.109855 -315.9466) (xy 64.098078 -315.898816)
			(xy 64.094118 -315.849762) (xy 62.805056 -315.849762) (xy 62.804561 -315.874369) (xy 62.796666 -315.922946)
			(xy 62.781082 -315.969627) (xy 62.758211 -316.013204) (xy 62.728646 -316.052548) (xy 62.693153 -316.08664)
			(xy 62.65265 -316.114596) (xy 62.608188 -316.135694) (xy 62.560917 -316.149386) (xy 62.512062 -316.155318)
			(xy 62.462887 -316.153337) (xy 62.414668 -316.143493) (xy 62.368652 -316.126041) (xy 62.326031 -316.101434)
			(xy 62.28791 -316.070309) (xy 62.255275 -316.033472) (xy 62.228972 -315.991876) (xy 62.209681 -315.9466)
			(xy 62.197904 -315.898816) (xy 62.193944 -315.849762) (xy 60.905136 -315.849762) (xy 60.904641 -315.874369)
			(xy 60.896746 -315.922946) (xy 60.881162 -315.969627) (xy 60.858291 -316.013204) (xy 60.828726 -316.052548)
			(xy 60.793233 -316.08664) (xy 60.75273 -316.114596) (xy 60.708268 -316.135694) (xy 60.660997 -316.149386)
			(xy 60.612142 -316.155318) (xy 60.562967 -316.153337) (xy 60.514748 -316.143493) (xy 60.468732 -316.126041)
			(xy 60.426111 -316.101434) (xy 60.38799 -316.070309) (xy 60.355355 -316.033472) (xy 60.329052 -315.991876)
			(xy 60.309761 -315.9466) (xy 60.297984 -315.898816) (xy 60.294024 -315.849762) (xy 59.005216 -315.849762)
			(xy 59.004721 -315.874369) (xy 58.996826 -315.922946) (xy 58.981242 -315.969627) (xy 58.958371 -316.013204)
			(xy 58.928806 -316.052548) (xy 58.893313 -316.08664) (xy 58.85281 -316.114596) (xy 58.808348 -316.135694)
			(xy 58.761077 -316.149386) (xy 58.712222 -316.155318) (xy 58.663047 -316.153337) (xy 58.614828 -316.143493)
			(xy 58.568812 -316.126041) (xy 58.526191 -316.101434) (xy 58.48807 -316.070309) (xy 58.455435 -316.033472)
			(xy 58.429132 -315.991876) (xy 58.409841 -315.9466) (xy 58.398064 -315.898816) (xy 58.394104 -315.849762)
			(xy 57.105296 -315.849762) (xy 57.104801 -315.874369) (xy 57.096906 -315.922946) (xy 57.081322 -315.969627)
			(xy 57.058451 -316.013204) (xy 57.028886 -316.052548) (xy 56.993393 -316.08664) (xy 56.95289 -316.114596)
			(xy 56.908428 -316.135694) (xy 56.861157 -316.149386) (xy 56.812302 -316.155318) (xy 56.763127 -316.153337)
			(xy 56.714908 -316.143493) (xy 56.668892 -316.126041) (xy 56.626271 -316.101434) (xy 56.58815 -316.070309)
			(xy 56.555515 -316.033472) (xy 56.529212 -315.991876) (xy 56.509921 -315.9466) (xy 56.498144 -315.898816)
			(xy 56.494184 -315.849762) (xy 55.205122 -315.849762) (xy 55.204627 -315.874369) (xy 55.196732 -315.922946)
			(xy 55.181148 -315.969627) (xy 55.158277 -316.013204) (xy 55.128712 -316.052548) (xy 55.093219 -316.08664)
			(xy 55.052716 -316.114596) (xy 55.008254 -316.135694) (xy 54.960983 -316.149386) (xy 54.912128 -316.155318)
			(xy 54.862953 -316.153337) (xy 54.814734 -316.143493) (xy 54.768718 -316.126041) (xy 54.726097 -316.101434)
			(xy 54.687976 -316.070309) (xy 54.655341 -316.033472) (xy 54.629038 -315.991876) (xy 54.609747 -315.9466)
			(xy 54.59797 -315.898816) (xy 54.59401 -315.849762) (xy 53.305202 -315.849762) (xy 53.304707 -315.874369)
			(xy 53.296812 -315.922946) (xy 53.281228 -315.969627) (xy 53.258357 -316.013204) (xy 53.228792 -316.052548)
			(xy 53.193299 -316.08664) (xy 53.152796 -316.114596) (xy 53.108334 -316.135694) (xy 53.061063 -316.149386)
			(xy 53.012208 -316.155318) (xy 52.963033 -316.153337) (xy 52.914814 -316.143493) (xy 52.868798 -316.126041)
			(xy 52.826177 -316.101434) (xy 52.788056 -316.070309) (xy 52.755421 -316.033472) (xy 52.729118 -315.991876)
			(xy 52.709827 -315.9466) (xy 52.69805 -315.898816) (xy 52.69409 -315.849762) (xy 51.405282 -315.849762)
			(xy 51.404787 -315.874369) (xy 51.396892 -315.922946) (xy 51.381308 -315.969627) (xy 51.358437 -316.013204)
			(xy 51.328872 -316.052548) (xy 51.293379 -316.08664) (xy 51.252876 -316.114596) (xy 51.208414 -316.135694)
			(xy 51.161143 -316.149386) (xy 51.112288 -316.155318) (xy 51.063113 -316.153337) (xy 51.014894 -316.143493)
			(xy 50.968878 -316.126041) (xy 50.926257 -316.101434) (xy 50.888136 -316.070309) (xy 50.855501 -316.033472)
			(xy 50.829198 -315.991876) (xy 50.809907 -315.9466) (xy 50.79813 -315.898816) (xy 50.79417 -315.849762)
			(xy 0.508 -315.849762) (xy 0.508 -316.799722) (xy 50.79417 -316.799722) (xy 50.79813 -316.750668)
			(xy 50.809907 -316.702884) (xy 50.829198 -316.657608) (xy 50.855501 -316.616012) (xy 50.888136 -316.579175)
			(xy 50.926257 -316.54805) (xy 50.968878 -316.523443) (xy 51.014894 -316.505991) (xy 51.063113 -316.496147)
			(xy 51.112288 -316.494166) (xy 51.161143 -316.500098) (xy 51.208414 -316.51379) (xy 51.252876 -316.534888)
			(xy 51.293379 -316.562844) (xy 51.328872 -316.596936) (xy 51.358437 -316.63628) (xy 51.381308 -316.679857)
			(xy 51.396892 -316.726538) (xy 51.404787 -316.775115) (xy 51.405282 -316.799722) (xy 52.69409 -316.799722)
			(xy 52.69805 -316.750668) (xy 52.709827 -316.702884) (xy 52.729118 -316.657608) (xy 52.755421 -316.616012)
			(xy 52.788056 -316.579175) (xy 52.826177 -316.54805) (xy 52.868798 -316.523443) (xy 52.914814 -316.505991)
			(xy 52.963033 -316.496147) (xy 53.012208 -316.494166) (xy 53.061063 -316.500098) (xy 53.108334 -316.51379)
			(xy 53.152796 -316.534888) (xy 53.193299 -316.562844) (xy 53.228792 -316.596936) (xy 53.258357 -316.63628)
			(xy 53.281228 -316.679857) (xy 53.296812 -316.726538) (xy 53.304707 -316.775115) (xy 53.305202 -316.799722)
			(xy 54.59401 -316.799722) (xy 54.59797 -316.750668) (xy 54.609747 -316.702884) (xy 54.629038 -316.657608)
			(xy 54.655341 -316.616012) (xy 54.687976 -316.579175) (xy 54.726097 -316.54805) (xy 54.768718 -316.523443)
			(xy 54.814734 -316.505991) (xy 54.862953 -316.496147) (xy 54.912128 -316.494166) (xy 54.960983 -316.500098)
			(xy 55.008254 -316.51379) (xy 55.052716 -316.534888) (xy 55.093219 -316.562844) (xy 55.128712 -316.596936)
			(xy 55.158277 -316.63628) (xy 55.181148 -316.679857) (xy 55.196732 -316.726538) (xy 55.204627 -316.775115)
			(xy 55.205122 -316.799722) (xy 56.494184 -316.799722) (xy 56.498144 -316.750668) (xy 56.509921 -316.702884)
			(xy 56.529212 -316.657608) (xy 56.555515 -316.616012) (xy 56.58815 -316.579175) (xy 56.626271 -316.54805)
			(xy 56.668892 -316.523443) (xy 56.714908 -316.505991) (xy 56.763127 -316.496147) (xy 56.812302 -316.494166)
			(xy 56.861157 -316.500098) (xy 56.908428 -316.51379) (xy 56.95289 -316.534888) (xy 56.993393 -316.562844)
			(xy 57.028886 -316.596936) (xy 57.058451 -316.63628) (xy 57.081322 -316.679857) (xy 57.096906 -316.726538)
			(xy 57.104801 -316.775115) (xy 57.105296 -316.799722) (xy 58.394104 -316.799722) (xy 58.398064 -316.750668)
			(xy 58.409841 -316.702884) (xy 58.429132 -316.657608) (xy 58.455435 -316.616012) (xy 58.48807 -316.579175)
			(xy 58.526191 -316.54805) (xy 58.568812 -316.523443) (xy 58.614828 -316.505991) (xy 58.663047 -316.496147)
			(xy 58.712222 -316.494166) (xy 58.761077 -316.500098) (xy 58.808348 -316.51379) (xy 58.85281 -316.534888)
			(xy 58.893313 -316.562844) (xy 58.928806 -316.596936) (xy 58.958371 -316.63628) (xy 58.981242 -316.679857)
			(xy 58.996826 -316.726538) (xy 59.004721 -316.775115) (xy 59.005216 -316.799722) (xy 60.294024 -316.799722)
			(xy 60.297984 -316.750668) (xy 60.309761 -316.702884) (xy 60.329052 -316.657608) (xy 60.355355 -316.616012)
			(xy 60.38799 -316.579175) (xy 60.426111 -316.54805) (xy 60.468732 -316.523443) (xy 60.514748 -316.505991)
			(xy 60.562967 -316.496147) (xy 60.612142 -316.494166) (xy 60.660997 -316.500098) (xy 60.708268 -316.51379)
			(xy 60.75273 -316.534888) (xy 60.793233 -316.562844) (xy 60.828726 -316.596936) (xy 60.858291 -316.63628)
			(xy 60.881162 -316.679857) (xy 60.896746 -316.726538) (xy 60.904641 -316.775115) (xy 60.905136 -316.799722)
			(xy 62.193944 -316.799722) (xy 62.197904 -316.750668) (xy 62.209681 -316.702884) (xy 62.228972 -316.657608)
			(xy 62.255275 -316.616012) (xy 62.28791 -316.579175) (xy 62.326031 -316.54805) (xy 62.368652 -316.523443)
			(xy 62.414668 -316.505991) (xy 62.462887 -316.496147) (xy 62.512062 -316.494166) (xy 62.560917 -316.500098)
			(xy 62.608188 -316.51379) (xy 62.65265 -316.534888) (xy 62.693153 -316.562844) (xy 62.728646 -316.596936)
			(xy 62.758211 -316.63628) (xy 62.781082 -316.679857) (xy 62.796666 -316.726538) (xy 62.804561 -316.775115)
			(xy 62.805056 -316.799722) (xy 64.094118 -316.799722) (xy 64.098078 -316.750668) (xy 64.109855 -316.702884)
			(xy 64.129146 -316.657608) (xy 64.155449 -316.616012) (xy 64.188084 -316.579175) (xy 64.226205 -316.54805)
			(xy 64.268826 -316.523443) (xy 64.314842 -316.505991) (xy 64.363061 -316.496147) (xy 64.412236 -316.494166)
			(xy 64.461091 -316.500098) (xy 64.508362 -316.51379) (xy 64.552824 -316.534888) (xy 64.593327 -316.562844)
			(xy 64.62882 -316.596936) (xy 64.658385 -316.63628) (xy 64.681256 -316.679857) (xy 64.69684 -316.726538)
			(xy 64.704735 -316.775115) (xy 64.70523 -316.799722) (xy 73.593972 -316.799722) (xy 73.597932 -316.750668)
			(xy 73.609709 -316.702884) (xy 73.629 -316.657608) (xy 73.655303 -316.616012) (xy 73.687938 -316.579175)
			(xy 73.726059 -316.54805) (xy 73.76868 -316.523443) (xy 73.814696 -316.505991) (xy 73.862915 -316.496147)
			(xy 73.91209 -316.494166) (xy 73.960945 -316.500098) (xy 74.008216 -316.51379) (xy 74.052678 -316.534888)
			(xy 74.093181 -316.562844) (xy 74.128674 -316.596936) (xy 74.158239 -316.63628) (xy 74.18111 -316.679857)
			(xy 74.196694 -316.726538) (xy 74.204589 -316.775115) (xy 74.205084 -316.799722) (xy 75.494146 -316.799722)
			(xy 75.498106 -316.750668) (xy 75.509883 -316.702884) (xy 75.529174 -316.657608) (xy 75.555477 -316.616012)
			(xy 75.588112 -316.579175) (xy 75.626233 -316.54805) (xy 75.668854 -316.523443) (xy 75.71487 -316.505991)
			(xy 75.763089 -316.496147) (xy 75.812264 -316.494166) (xy 75.861119 -316.500098) (xy 75.90839 -316.51379)
			(xy 75.952852 -316.534888) (xy 75.993355 -316.562844) (xy 76.028848 -316.596936) (xy 76.058413 -316.63628)
			(xy 76.081284 -316.679857) (xy 76.096868 -316.726538) (xy 76.104763 -316.775115) (xy 76.105258 -316.799722)
			(xy 77.394066 -316.799722) (xy 77.398026 -316.750668) (xy 77.409803 -316.702884) (xy 77.429094 -316.657608)
			(xy 77.455397 -316.616012) (xy 77.488032 -316.579175) (xy 77.526153 -316.54805) (xy 77.568774 -316.523443)
			(xy 77.61479 -316.505991) (xy 77.663009 -316.496147) (xy 77.712184 -316.494166) (xy 77.761039 -316.500098)
			(xy 77.80831 -316.51379) (xy 77.852772 -316.534888) (xy 77.893275 -316.562844) (xy 77.928768 -316.596936)
			(xy 77.958333 -316.63628) (xy 77.981204 -316.679857) (xy 77.996788 -316.726538) (xy 78.004683 -316.775115)
			(xy 78.005178 -316.799722) (xy 79.293986 -316.799722) (xy 79.297946 -316.750668) (xy 79.309723 -316.702884)
			(xy 79.329014 -316.657608) (xy 79.355317 -316.616012) (xy 79.387952 -316.579175) (xy 79.426073 -316.54805)
			(xy 79.468694 -316.523443) (xy 79.51471 -316.505991) (xy 79.562929 -316.496147) (xy 79.612104 -316.494166)
			(xy 79.660959 -316.500098) (xy 79.70823 -316.51379) (xy 79.752692 -316.534888) (xy 79.793195 -316.562844)
			(xy 79.828688 -316.596936) (xy 79.858253 -316.63628) (xy 79.881124 -316.679857) (xy 79.896708 -316.726538)
			(xy 79.904603 -316.775115) (xy 79.905098 -316.799722) (xy 81.19416 -316.799722) (xy 81.19812 -316.750668)
			(xy 81.209897 -316.702884) (xy 81.229188 -316.657608) (xy 81.255491 -316.616012) (xy 81.288126 -316.579175)
			(xy 81.326247 -316.54805) (xy 81.368868 -316.523443) (xy 81.414884 -316.505991) (xy 81.463103 -316.496147)
			(xy 81.512278 -316.494166) (xy 81.561133 -316.500098) (xy 81.608404 -316.51379) (xy 81.652866 -316.534888)
			(xy 81.693369 -316.562844) (xy 81.728862 -316.596936) (xy 81.758427 -316.63628) (xy 81.781298 -316.679857)
			(xy 81.796882 -316.726538) (xy 81.804777 -316.775115) (xy 81.805272 -316.799722) (xy 82.14412 -316.799722)
			(xy 82.14808 -316.750668) (xy 82.159857 -316.702884) (xy 82.179148 -316.657608) (xy 82.205451 -316.616012)
			(xy 82.238086 -316.579175) (xy 82.276207 -316.54805) (xy 82.318828 -316.523443) (xy 82.364844 -316.505991)
			(xy 82.413063 -316.496147) (xy 82.462238 -316.494166) (xy 82.511093 -316.500098) (xy 82.558364 -316.51379)
			(xy 82.602826 -316.534888) (xy 82.643329 -316.562844) (xy 82.678822 -316.596936) (xy 82.708387 -316.63628)
			(xy 82.731258 -316.679857) (xy 82.746842 -316.726538) (xy 82.754737 -316.775115) (xy 82.755232 -316.799722)
			(xy 152.644106 -316.799722) (xy 152.648066 -316.750668) (xy 152.659843 -316.702884) (xy 152.679134 -316.657608)
			(xy 152.705437 -316.616012) (xy 152.738072 -316.579175) (xy 152.776193 -316.54805) (xy 152.818814 -316.523443)
			(xy 152.86483 -316.505991) (xy 152.913049 -316.496147) (xy 152.962224 -316.494166) (xy 153.011079 -316.500098)
			(xy 153.05835 -316.51379) (xy 153.102812 -316.534888) (xy 153.143315 -316.562844) (xy 153.178808 -316.596936)
			(xy 153.208373 -316.63628) (xy 153.231244 -316.679857) (xy 153.246828 -316.726538) (xy 153.254723 -316.775115)
			(xy 153.255218 -316.799722) (xy 153.594066 -316.799722) (xy 153.598026 -316.750668) (xy 153.609803 -316.702884)
			(xy 153.629094 -316.657608) (xy 153.655397 -316.616012) (xy 153.688032 -316.579175) (xy 153.726153 -316.54805)
			(xy 153.768774 -316.523443) (xy 153.81479 -316.505991) (xy 153.863009 -316.496147) (xy 153.912184 -316.494166)
			(xy 153.961039 -316.500098) (xy 154.00831 -316.51379) (xy 154.052772 -316.534888) (xy 154.093275 -316.562844)
			(xy 154.128768 -316.596936) (xy 154.158333 -316.63628) (xy 154.181204 -316.679857) (xy 154.196788 -316.726538)
			(xy 154.204683 -316.775115) (xy 154.205178 -316.799722) (xy 155.49424 -316.799722) (xy 155.4982 -316.750668)
			(xy 155.509977 -316.702884) (xy 155.529268 -316.657608) (xy 155.555571 -316.616012) (xy 155.588206 -316.579175)
			(xy 155.626327 -316.54805) (xy 155.668948 -316.523443) (xy 155.714964 -316.505991) (xy 155.763183 -316.496147)
			(xy 155.812358 -316.494166) (xy 155.861213 -316.500098) (xy 155.908484 -316.51379) (xy 155.952946 -316.534888)
			(xy 155.993449 -316.562844) (xy 156.028942 -316.596936) (xy 156.058507 -316.63628) (xy 156.081378 -316.679857)
			(xy 156.096962 -316.726538) (xy 156.104857 -316.775115) (xy 156.105352 -316.799722) (xy 157.39416 -316.799722)
			(xy 157.39812 -316.750668) (xy 157.409897 -316.702884) (xy 157.429188 -316.657608) (xy 157.455491 -316.616012)
			(xy 157.488126 -316.579175) (xy 157.526247 -316.54805) (xy 157.568868 -316.523443) (xy 157.614884 -316.505991)
			(xy 157.663103 -316.496147) (xy 157.712278 -316.494166) (xy 157.761133 -316.500098) (xy 157.808404 -316.51379)
			(xy 157.852866 -316.534888) (xy 157.893369 -316.562844) (xy 157.928862 -316.596936) (xy 157.958427 -316.63628)
			(xy 157.981298 -316.679857) (xy 157.996882 -316.726538) (xy 158.004777 -316.775115) (xy 158.005272 -316.799722)
			(xy 159.29408 -316.799722) (xy 159.29804 -316.750668) (xy 159.309817 -316.702884) (xy 159.329108 -316.657608)
			(xy 159.355411 -316.616012) (xy 159.388046 -316.579175) (xy 159.426167 -316.54805) (xy 159.468788 -316.523443)
			(xy 159.514804 -316.505991) (xy 159.563023 -316.496147) (xy 159.612198 -316.494166) (xy 159.661053 -316.500098)
			(xy 159.708324 -316.51379) (xy 159.752786 -316.534888) (xy 159.793289 -316.562844) (xy 159.828782 -316.596936)
			(xy 159.858347 -316.63628) (xy 159.881218 -316.679857) (xy 159.896802 -316.726538) (xy 159.904697 -316.775115)
			(xy 159.905192 -316.799722) (xy 161.194254 -316.799722) (xy 161.198214 -316.750668) (xy 161.209991 -316.702884)
			(xy 161.229282 -316.657608) (xy 161.255585 -316.616012) (xy 161.28822 -316.579175) (xy 161.326341 -316.54805)
			(xy 161.368962 -316.523443) (xy 161.414978 -316.505991) (xy 161.463197 -316.496147) (xy 161.512372 -316.494166)
			(xy 161.561227 -316.500098) (xy 161.608498 -316.51379) (xy 161.65296 -316.534888) (xy 161.693463 -316.562844)
			(xy 161.728956 -316.596936) (xy 161.758521 -316.63628) (xy 161.781392 -316.679857) (xy 161.796976 -316.726538)
			(xy 161.804871 -316.775115) (xy 161.805366 -316.799722) (xy 163.094174 -316.799722) (xy 163.098134 -316.750668)
			(xy 163.109911 -316.702884) (xy 163.129202 -316.657608) (xy 163.155505 -316.616012) (xy 163.18814 -316.579175)
			(xy 163.226261 -316.54805) (xy 163.268882 -316.523443) (xy 163.314898 -316.505991) (xy 163.363117 -316.496147)
			(xy 163.412292 -316.494166) (xy 163.461147 -316.500098) (xy 163.508418 -316.51379) (xy 163.55288 -316.534888)
			(xy 163.593383 -316.562844) (xy 163.628876 -316.596936) (xy 163.658441 -316.63628) (xy 163.681312 -316.679857)
			(xy 163.696896 -316.726538) (xy 163.704791 -316.775115) (xy 163.705286 -316.799722) (xy 164.994094 -316.799722)
			(xy 164.998054 -316.750668) (xy 165.009831 -316.702884) (xy 165.029122 -316.657608) (xy 165.055425 -316.616012)
			(xy 165.08806 -316.579175) (xy 165.126181 -316.54805) (xy 165.168802 -316.523443) (xy 165.214818 -316.505991)
			(xy 165.263037 -316.496147) (xy 165.312212 -316.494166) (xy 165.361067 -316.500098) (xy 165.408338 -316.51379)
			(xy 165.4528 -316.534888) (xy 165.493303 -316.562844) (xy 165.528796 -316.596936) (xy 165.558361 -316.63628)
			(xy 165.581232 -316.679857) (xy 165.596816 -316.726538) (xy 165.604711 -316.775115) (xy 165.605206 -316.799722)
			(xy 182.094136 -316.799722) (xy 182.098096 -316.750668) (xy 182.109873 -316.702884) (xy 182.129164 -316.657608)
			(xy 182.155467 -316.616012) (xy 182.188102 -316.579175) (xy 182.226223 -316.54805) (xy 182.268844 -316.523443)
			(xy 182.31486 -316.505991) (xy 182.363079 -316.496147) (xy 182.412254 -316.494166) (xy 182.461109 -316.500098)
			(xy 182.50838 -316.51379) (xy 182.552842 -316.534888) (xy 182.593345 -316.562844) (xy 182.628838 -316.596936)
			(xy 182.658403 -316.63628) (xy 182.681274 -316.679857) (xy 182.696858 -316.726538) (xy 182.704753 -316.775115)
			(xy 182.705248 -316.799722) (xy 183.994056 -316.799722) (xy 183.998016 -316.750668) (xy 184.009793 -316.702884)
			(xy 184.029084 -316.657608) (xy 184.055387 -316.616012) (xy 184.088022 -316.579175) (xy 184.126143 -316.54805)
			(xy 184.168764 -316.523443) (xy 184.21478 -316.505991) (xy 184.262999 -316.496147) (xy 184.312174 -316.494166)
			(xy 184.361029 -316.500098) (xy 184.4083 -316.51379) (xy 184.452762 -316.534888) (xy 184.493265 -316.562844)
			(xy 184.528758 -316.596936) (xy 184.558323 -316.63628) (xy 184.581194 -316.679857) (xy 184.596778 -316.726538)
			(xy 184.604673 -316.775115) (xy 184.605168 -316.799722) (xy 185.89423 -316.799722) (xy 185.89819 -316.750668)
			(xy 185.909967 -316.702884) (xy 185.929258 -316.657608) (xy 185.955561 -316.616012) (xy 185.988196 -316.579175)
			(xy 186.026317 -316.54805) (xy 186.068938 -316.523443) (xy 186.114954 -316.505991) (xy 186.163173 -316.496147)
			(xy 186.212348 -316.494166) (xy 186.261203 -316.500098) (xy 186.308474 -316.51379) (xy 186.352936 -316.534888)
			(xy 186.393439 -316.562844) (xy 186.428932 -316.596936) (xy 186.458497 -316.63628) (xy 186.481368 -316.679857)
			(xy 186.496952 -316.726538) (xy 186.504847 -316.775115) (xy 186.505342 -316.799722) (xy 187.79415 -316.799722)
			(xy 187.79811 -316.750668) (xy 187.809887 -316.702884) (xy 187.829178 -316.657608) (xy 187.855481 -316.616012)
			(xy 187.888116 -316.579175) (xy 187.926237 -316.54805) (xy 187.968858 -316.523443) (xy 188.014874 -316.505991)
			(xy 188.063093 -316.496147) (xy 188.112268 -316.494166) (xy 188.161123 -316.500098) (xy 188.208394 -316.51379)
			(xy 188.252856 -316.534888) (xy 188.293359 -316.562844) (xy 188.328852 -316.596936) (xy 188.358417 -316.63628)
			(xy 188.381288 -316.679857) (xy 188.396872 -316.726538) (xy 188.404767 -316.775115) (xy 188.405262 -316.799722)
			(xy 282.994112 -316.799722) (xy 282.998072 -316.750668) (xy 283.009849 -316.702884) (xy 283.02914 -316.657608)
			(xy 283.055443 -316.616012) (xy 283.088078 -316.579175) (xy 283.126199 -316.54805) (xy 283.16882 -316.523443)
			(xy 283.214836 -316.505991) (xy 283.263055 -316.496147) (xy 283.31223 -316.494166) (xy 283.361085 -316.500098)
			(xy 283.408356 -316.51379) (xy 283.452818 -316.534888) (xy 283.493321 -316.562844) (xy 283.528814 -316.596936)
			(xy 283.558379 -316.63628) (xy 283.58125 -316.679857) (xy 283.596834 -316.726538) (xy 283.604729 -316.775115)
			(xy 283.605224 -316.799722) (xy 284.894032 -316.799722) (xy 284.897992 -316.750668) (xy 284.909769 -316.702884)
			(xy 284.92906 -316.657608) (xy 284.955363 -316.616012) (xy 284.987998 -316.579175) (xy 285.026119 -316.54805)
			(xy 285.06874 -316.523443) (xy 285.114756 -316.505991) (xy 285.162975 -316.496147) (xy 285.21215 -316.494166)
			(xy 285.261005 -316.500098) (xy 285.308276 -316.51379) (xy 285.352738 -316.534888) (xy 285.393241 -316.562844)
			(xy 285.428734 -316.596936) (xy 285.458299 -316.63628) (xy 285.48117 -316.679857) (xy 285.496754 -316.726538)
			(xy 285.504649 -316.775115) (xy 285.505144 -316.799722) (xy 286.793952 -316.799722) (xy 286.797912 -316.750668)
			(xy 286.809689 -316.702884) (xy 286.82898 -316.657608) (xy 286.855283 -316.616012) (xy 286.887918 -316.579175)
			(xy 286.926039 -316.54805) (xy 286.96866 -316.523443) (xy 287.014676 -316.505991) (xy 287.062895 -316.496147)
			(xy 287.11207 -316.494166) (xy 287.160925 -316.500098) (xy 287.208196 -316.51379) (xy 287.252658 -316.534888)
			(xy 287.293161 -316.562844) (xy 287.328654 -316.596936) (xy 287.358219 -316.63628) (xy 287.38109 -316.679857)
			(xy 287.396674 -316.726538) (xy 287.404569 -316.775115) (xy 287.405064 -316.799722) (xy 288.694126 -316.799722)
			(xy 288.698086 -316.750668) (xy 288.709863 -316.702884) (xy 288.729154 -316.657608) (xy 288.755457 -316.616012)
			(xy 288.788092 -316.579175) (xy 288.826213 -316.54805) (xy 288.868834 -316.523443) (xy 288.91485 -316.505991)
			(xy 288.963069 -316.496147) (xy 289.012244 -316.494166) (xy 289.061099 -316.500098) (xy 289.10837 -316.51379)
			(xy 289.152832 -316.534888) (xy 289.193335 -316.562844) (xy 289.228828 -316.596936) (xy 289.258393 -316.63628)
			(xy 289.281264 -316.679857) (xy 289.296848 -316.726538) (xy 289.304743 -316.775115) (xy 289.305238 -316.799722)
			(xy 290.594046 -316.799722) (xy 290.598006 -316.750668) (xy 290.609783 -316.702884) (xy 290.629074 -316.657608)
			(xy 290.655377 -316.616012) (xy 290.688012 -316.579175) (xy 290.726133 -316.54805) (xy 290.768754 -316.523443)
			(xy 290.81477 -316.505991) (xy 290.862989 -316.496147) (xy 290.912164 -316.494166) (xy 290.961019 -316.500098)
			(xy 291.00829 -316.51379) (xy 291.052752 -316.534888) (xy 291.093255 -316.562844) (xy 291.128748 -316.596936)
			(xy 291.158313 -316.63628) (xy 291.181184 -316.679857) (xy 291.196768 -316.726538) (xy 291.204663 -316.775115)
			(xy 291.205158 -316.799722) (xy 292.493966 -316.799722) (xy 292.497926 -316.750668) (xy 292.509703 -316.702884)
			(xy 292.528994 -316.657608) (xy 292.555297 -316.616012) (xy 292.587932 -316.579175) (xy 292.626053 -316.54805)
			(xy 292.668674 -316.523443) (xy 292.71469 -316.505991) (xy 292.762909 -316.496147) (xy 292.812084 -316.494166)
			(xy 292.860939 -316.500098) (xy 292.90821 -316.51379) (xy 292.952672 -316.534888) (xy 292.993175 -316.562844)
			(xy 293.028668 -316.596936) (xy 293.058233 -316.63628) (xy 293.081104 -316.679857) (xy 293.096688 -316.726538)
			(xy 293.104583 -316.775115) (xy 293.105078 -316.799722) (xy 294.393886 -316.799722) (xy 294.397846 -316.750668)
			(xy 294.409623 -316.702884) (xy 294.428914 -316.657608) (xy 294.455217 -316.616012) (xy 294.487852 -316.579175)
			(xy 294.525973 -316.54805) (xy 294.568594 -316.523443) (xy 294.61461 -316.505991) (xy 294.662829 -316.496147)
			(xy 294.712004 -316.494166) (xy 294.760859 -316.500098) (xy 294.80813 -316.51379) (xy 294.852592 -316.534888)
			(xy 294.893095 -316.562844) (xy 294.928588 -316.596936) (xy 294.958153 -316.63628) (xy 294.981024 -316.679857)
			(xy 294.996608 -316.726538) (xy 295.004503 -316.775115) (xy 295.004998 -316.799722) (xy 296.29406 -316.799722)
			(xy 296.29802 -316.750668) (xy 296.309797 -316.702884) (xy 296.329088 -316.657608) (xy 296.355391 -316.616012)
			(xy 296.388026 -316.579175) (xy 296.426147 -316.54805) (xy 296.468768 -316.523443) (xy 296.514784 -316.505991)
			(xy 296.563003 -316.496147) (xy 296.612178 -316.494166) (xy 296.661033 -316.500098) (xy 296.708304 -316.51379)
			(xy 296.752766 -316.534888) (xy 296.793269 -316.562844) (xy 296.828762 -316.596936) (xy 296.858327 -316.63628)
			(xy 296.881198 -316.679857) (xy 296.896782 -316.726538) (xy 296.904677 -316.775115) (xy 296.905172 -316.799722)
			(xy 305.793914 -316.799722) (xy 305.797874 -316.750668) (xy 305.809651 -316.702884) (xy 305.828942 -316.657608)
			(xy 305.855245 -316.616012) (xy 305.88788 -316.579175) (xy 305.926001 -316.54805) (xy 305.968622 -316.523443)
			(xy 306.014638 -316.505991) (xy 306.062857 -316.496147) (xy 306.112032 -316.494166) (xy 306.160887 -316.500098)
			(xy 306.208158 -316.51379) (xy 306.25262 -316.534888) (xy 306.293123 -316.562844) (xy 306.328616 -316.596936)
			(xy 306.358181 -316.63628) (xy 306.381052 -316.679857) (xy 306.396636 -316.726538) (xy 306.404531 -316.775115)
			(xy 306.405026 -316.799722) (xy 307.694088 -316.799722) (xy 307.698048 -316.750668) (xy 307.709825 -316.702884)
			(xy 307.729116 -316.657608) (xy 307.755419 -316.616012) (xy 307.788054 -316.579175) (xy 307.826175 -316.54805)
			(xy 307.868796 -316.523443) (xy 307.914812 -316.505991) (xy 307.963031 -316.496147) (xy 308.012206 -316.494166)
			(xy 308.061061 -316.500098) (xy 308.108332 -316.51379) (xy 308.152794 -316.534888) (xy 308.193297 -316.562844)
			(xy 308.22879 -316.596936) (xy 308.258355 -316.63628) (xy 308.281226 -316.679857) (xy 308.29681 -316.726538)
			(xy 308.304705 -316.775115) (xy 308.3052 -316.799722) (xy 309.594008 -316.799722) (xy 309.597968 -316.750668)
			(xy 309.609745 -316.702884) (xy 309.629036 -316.657608) (xy 309.655339 -316.616012) (xy 309.687974 -316.579175)
			(xy 309.726095 -316.54805) (xy 309.768716 -316.523443) (xy 309.814732 -316.505991) (xy 309.862951 -316.496147)
			(xy 309.912126 -316.494166) (xy 309.960981 -316.500098) (xy 310.008252 -316.51379) (xy 310.052714 -316.534888)
			(xy 310.093217 -316.562844) (xy 310.12871 -316.596936) (xy 310.158275 -316.63628) (xy 310.181146 -316.679857)
			(xy 310.19673 -316.726538) (xy 310.204625 -316.775115) (xy 310.20512 -316.799722) (xy 311.493928 -316.799722)
			(xy 311.497888 -316.750668) (xy 311.509665 -316.702884) (xy 311.528956 -316.657608) (xy 311.555259 -316.616012)
			(xy 311.587894 -316.579175) (xy 311.626015 -316.54805) (xy 311.668636 -316.523443) (xy 311.714652 -316.505991)
			(xy 311.762871 -316.496147) (xy 311.812046 -316.494166) (xy 311.860901 -316.500098) (xy 311.908172 -316.51379)
			(xy 311.952634 -316.534888) (xy 311.993137 -316.562844) (xy 312.02863 -316.596936) (xy 312.058195 -316.63628)
			(xy 312.081066 -316.679857) (xy 312.09665 -316.726538) (xy 312.104545 -316.775115) (xy 312.10504 -316.799722)
			(xy 313.394102 -316.799722) (xy 313.398062 -316.750668) (xy 313.409839 -316.702884) (xy 313.42913 -316.657608)
			(xy 313.455433 -316.616012) (xy 313.488068 -316.579175) (xy 313.526189 -316.54805) (xy 313.56881 -316.523443)
			(xy 313.614826 -316.505991) (xy 313.663045 -316.496147) (xy 313.71222 -316.494166) (xy 313.761075 -316.500098)
			(xy 313.808346 -316.51379) (xy 313.852808 -316.534888) (xy 313.893311 -316.562844) (xy 313.928804 -316.596936)
			(xy 313.958369 -316.63628) (xy 313.98124 -316.679857) (xy 313.996824 -316.726538) (xy 314.004719 -316.775115)
			(xy 314.005214 -316.799722) (xy 314.344062 -316.799722) (xy 314.348022 -316.750668) (xy 314.359799 -316.702884)
			(xy 314.37909 -316.657608) (xy 314.405393 -316.616012) (xy 314.438028 -316.579175) (xy 314.476149 -316.54805)
			(xy 314.51877 -316.523443) (xy 314.564786 -316.505991) (xy 314.613005 -316.496147) (xy 314.66218 -316.494166)
			(xy 314.711035 -316.500098) (xy 314.758306 -316.51379) (xy 314.802768 -316.534888) (xy 314.843271 -316.562844)
			(xy 314.878764 -316.596936) (xy 314.908329 -316.63628) (xy 314.9312 -316.679857) (xy 314.946784 -316.726538)
			(xy 314.954679 -316.775115) (xy 314.955174 -316.799722) (xy 384.844048 -316.799722) (xy 384.848008 -316.750668)
			(xy 384.859785 -316.702884) (xy 384.879076 -316.657608) (xy 384.905379 -316.616012) (xy 384.938014 -316.579175)
			(xy 384.976135 -316.54805) (xy 385.018756 -316.523443) (xy 385.064772 -316.505991) (xy 385.112991 -316.496147)
			(xy 385.162166 -316.494166) (xy 385.211021 -316.500098) (xy 385.258292 -316.51379) (xy 385.302754 -316.534888)
			(xy 385.343257 -316.562844) (xy 385.37875 -316.596936) (xy 385.408315 -316.63628) (xy 385.431186 -316.679857)
			(xy 385.44677 -316.726538) (xy 385.454665 -316.775115) (xy 385.45516 -316.799722) (xy 385.794008 -316.799722)
			(xy 385.797968 -316.750668) (xy 385.809745 -316.702884) (xy 385.829036 -316.657608) (xy 385.855339 -316.616012)
			(xy 385.887974 -316.579175) (xy 385.926095 -316.54805) (xy 385.968716 -316.523443) (xy 386.014732 -316.505991)
			(xy 386.062951 -316.496147) (xy 386.112126 -316.494166) (xy 386.160981 -316.500098) (xy 386.208252 -316.51379)
			(xy 386.252714 -316.534888) (xy 386.293217 -316.562844) (xy 386.32871 -316.596936) (xy 386.358275 -316.63628)
			(xy 386.381146 -316.679857) (xy 386.39673 -316.726538) (xy 386.404625 -316.775115) (xy 386.40512 -316.799722)
			(xy 387.694182 -316.799722) (xy 387.698142 -316.750668) (xy 387.709919 -316.702884) (xy 387.72921 -316.657608)
			(xy 387.755513 -316.616012) (xy 387.788148 -316.579175) (xy 387.826269 -316.54805) (xy 387.86889 -316.523443)
			(xy 387.914906 -316.505991) (xy 387.963125 -316.496147) (xy 388.0123 -316.494166) (xy 388.061155 -316.500098)
			(xy 388.108426 -316.51379) (xy 388.152888 -316.534888) (xy 388.193391 -316.562844) (xy 388.228884 -316.596936)
			(xy 388.258449 -316.63628) (xy 388.28132 -316.679857) (xy 388.296904 -316.726538) (xy 388.304799 -316.775115)
			(xy 388.305294 -316.799722) (xy 389.594102 -316.799722) (xy 389.598062 -316.750668) (xy 389.609839 -316.702884)
			(xy 389.62913 -316.657608) (xy 389.655433 -316.616012) (xy 389.688068 -316.579175) (xy 389.726189 -316.54805)
			(xy 389.76881 -316.523443) (xy 389.814826 -316.505991) (xy 389.863045 -316.496147) (xy 389.91222 -316.494166)
			(xy 389.961075 -316.500098) (xy 390.008346 -316.51379) (xy 390.052808 -316.534888) (xy 390.093311 -316.562844)
			(xy 390.128804 -316.596936) (xy 390.158369 -316.63628) (xy 390.18124 -316.679857) (xy 390.196824 -316.726538)
			(xy 390.204719 -316.775115) (xy 390.205214 -316.799722) (xy 391.494022 -316.799722) (xy 391.497982 -316.750668)
			(xy 391.509759 -316.702884) (xy 391.52905 -316.657608) (xy 391.555353 -316.616012) (xy 391.587988 -316.579175)
			(xy 391.626109 -316.54805) (xy 391.66873 -316.523443) (xy 391.714746 -316.505991) (xy 391.762965 -316.496147)
			(xy 391.81214 -316.494166) (xy 391.860995 -316.500098) (xy 391.908266 -316.51379) (xy 391.952728 -316.534888)
			(xy 391.993231 -316.562844) (xy 392.028724 -316.596936) (xy 392.058289 -316.63628) (xy 392.08116 -316.679857)
			(xy 392.096744 -316.726538) (xy 392.104639 -316.775115) (xy 392.105134 -316.799722) (xy 393.394196 -316.799722)
			(xy 393.398156 -316.750668) (xy 393.409933 -316.702884) (xy 393.429224 -316.657608) (xy 393.455527 -316.616012)
			(xy 393.488162 -316.579175) (xy 393.526283 -316.54805) (xy 393.568904 -316.523443) (xy 393.61492 -316.505991)
			(xy 393.663139 -316.496147) (xy 393.712314 -316.494166) (xy 393.761169 -316.500098) (xy 393.80844 -316.51379)
			(xy 393.852902 -316.534888) (xy 393.893405 -316.562844) (xy 393.928898 -316.596936) (xy 393.958463 -316.63628)
			(xy 393.981334 -316.679857) (xy 393.996918 -316.726538) (xy 394.004813 -316.775115) (xy 394.005308 -316.799722)
			(xy 395.294116 -316.799722) (xy 395.298076 -316.750668) (xy 395.309853 -316.702884) (xy 395.329144 -316.657608)
			(xy 395.355447 -316.616012) (xy 395.388082 -316.579175) (xy 395.426203 -316.54805) (xy 395.468824 -316.523443)
			(xy 395.51484 -316.505991) (xy 395.563059 -316.496147) (xy 395.612234 -316.494166) (xy 395.661089 -316.500098)
			(xy 395.70836 -316.51379) (xy 395.752822 -316.534888) (xy 395.793325 -316.562844) (xy 395.828818 -316.596936)
			(xy 395.858383 -316.63628) (xy 395.881254 -316.679857) (xy 395.896838 -316.726538) (xy 395.904733 -316.775115)
			(xy 395.905228 -316.799722) (xy 397.194036 -316.799722) (xy 397.197996 -316.750668) (xy 397.209773 -316.702884)
			(xy 397.229064 -316.657608) (xy 397.255367 -316.616012) (xy 397.288002 -316.579175) (xy 397.326123 -316.54805)
			(xy 397.368744 -316.523443) (xy 397.41476 -316.505991) (xy 397.462979 -316.496147) (xy 397.512154 -316.494166)
			(xy 397.561009 -316.500098) (xy 397.60828 -316.51379) (xy 397.652742 -316.534888) (xy 397.693245 -316.562844)
			(xy 397.728738 -316.596936) (xy 397.758303 -316.63628) (xy 397.781174 -316.679857) (xy 397.796758 -316.726538)
			(xy 397.804653 -316.775115) (xy 397.805148 -316.799722) (xy 414.294078 -316.799722) (xy 414.298038 -316.750668)
			(xy 414.309815 -316.702884) (xy 414.329106 -316.657608) (xy 414.355409 -316.616012) (xy 414.388044 -316.579175)
			(xy 414.426165 -316.54805) (xy 414.468786 -316.523443) (xy 414.514802 -316.505991) (xy 414.563021 -316.496147)
			(xy 414.612196 -316.494166) (xy 414.661051 -316.500098) (xy 414.708322 -316.51379) (xy 414.752784 -316.534888)
			(xy 414.793287 -316.562844) (xy 414.82878 -316.596936) (xy 414.858345 -316.63628) (xy 414.881216 -316.679857)
			(xy 414.8968 -316.726538) (xy 414.904695 -316.775115) (xy 414.90519 -316.799722) (xy 416.193998 -316.799722)
			(xy 416.197958 -316.750668) (xy 416.209735 -316.702884) (xy 416.229026 -316.657608) (xy 416.255329 -316.616012)
			(xy 416.287964 -316.579175) (xy 416.326085 -316.54805) (xy 416.368706 -316.523443) (xy 416.414722 -316.505991)
			(xy 416.462941 -316.496147) (xy 416.512116 -316.494166) (xy 416.560971 -316.500098) (xy 416.608242 -316.51379)
			(xy 416.652704 -316.534888) (xy 416.693207 -316.562844) (xy 416.7287 -316.596936) (xy 416.758265 -316.63628)
			(xy 416.781136 -316.679857) (xy 416.79672 -316.726538) (xy 416.804615 -316.775115) (xy 416.80511 -316.799722)
			(xy 418.094172 -316.799722) (xy 418.098132 -316.750668) (xy 418.109909 -316.702884) (xy 418.1292 -316.657608)
			(xy 418.155503 -316.616012) (xy 418.188138 -316.579175) (xy 418.226259 -316.54805) (xy 418.26888 -316.523443)
			(xy 418.314896 -316.505991) (xy 418.363115 -316.496147) (xy 418.41229 -316.494166) (xy 418.461145 -316.500098)
			(xy 418.508416 -316.51379) (xy 418.552878 -316.534888) (xy 418.593381 -316.562844) (xy 418.628874 -316.596936)
			(xy 418.658439 -316.63628) (xy 418.68131 -316.679857) (xy 418.696894 -316.726538) (xy 418.704789 -316.775115)
			(xy 418.705284 -316.799722) (xy 419.994092 -316.799722) (xy 419.998052 -316.750668) (xy 420.009829 -316.702884)
			(xy 420.02912 -316.657608) (xy 420.055423 -316.616012) (xy 420.088058 -316.579175) (xy 420.126179 -316.54805)
			(xy 420.1688 -316.523443) (xy 420.214816 -316.505991) (xy 420.263035 -316.496147) (xy 420.31221 -316.494166)
			(xy 420.361065 -316.500098) (xy 420.408336 -316.51379) (xy 420.452798 -316.534888) (xy 420.493301 -316.562844)
			(xy 420.528794 -316.596936) (xy 420.558359 -316.63628) (xy 420.58123 -316.679857) (xy 420.596814 -316.726538)
			(xy 420.604709 -316.775115) (xy 420.605204 -316.799722) (xy 420.604709 -316.824329) (xy 420.596814 -316.872906)
			(xy 420.58123 -316.919587) (xy 420.558359 -316.963164) (xy 420.528794 -317.002508) (xy 420.493301 -317.0366)
			(xy 420.452798 -317.064556) (xy 420.408336 -317.085654) (xy 420.361065 -317.099346) (xy 420.31221 -317.105278)
			(xy 420.263035 -317.103297) (xy 420.214816 -317.093453) (xy 420.1688 -317.076001) (xy 420.126179 -317.051394)
			(xy 420.088058 -317.020269) (xy 420.055423 -316.983432) (xy 420.02912 -316.941836) (xy 420.009829 -316.89656)
			(xy 419.998052 -316.848776) (xy 419.994092 -316.799722) (xy 418.705284 -316.799722) (xy 418.704789 -316.824329)
			(xy 418.696894 -316.872906) (xy 418.68131 -316.919587) (xy 418.658439 -316.963164) (xy 418.628874 -317.002508)
			(xy 418.593381 -317.0366) (xy 418.552878 -317.064556) (xy 418.508416 -317.085654) (xy 418.461145 -317.099346)
			(xy 418.41229 -317.105278) (xy 418.363115 -317.103297) (xy 418.314896 -317.093453) (xy 418.26888 -317.076001)
			(xy 418.226259 -317.051394) (xy 418.188138 -317.020269) (xy 418.155503 -316.983432) (xy 418.1292 -316.941836)
			(xy 418.109909 -316.89656) (xy 418.098132 -316.848776) (xy 418.094172 -316.799722) (xy 416.80511 -316.799722)
			(xy 416.804615 -316.824329) (xy 416.79672 -316.872906) (xy 416.781136 -316.919587) (xy 416.758265 -316.963164)
			(xy 416.7287 -317.002508) (xy 416.693207 -317.0366) (xy 416.652704 -317.064556) (xy 416.608242 -317.085654)
			(xy 416.560971 -317.099346) (xy 416.512116 -317.105278) (xy 416.462941 -317.103297) (xy 416.414722 -317.093453)
			(xy 416.368706 -317.076001) (xy 416.326085 -317.051394) (xy 416.287964 -317.020269) (xy 416.255329 -316.983432)
			(xy 416.229026 -316.941836) (xy 416.209735 -316.89656) (xy 416.197958 -316.848776) (xy 416.193998 -316.799722)
			(xy 414.90519 -316.799722) (xy 414.904695 -316.824329) (xy 414.8968 -316.872906) (xy 414.881216 -316.919587)
			(xy 414.858345 -316.963164) (xy 414.82878 -317.002508) (xy 414.793287 -317.0366) (xy 414.752784 -317.064556)
			(xy 414.708322 -317.085654) (xy 414.661051 -317.099346) (xy 414.612196 -317.105278) (xy 414.563021 -317.103297)
			(xy 414.514802 -317.093453) (xy 414.468786 -317.076001) (xy 414.426165 -317.051394) (xy 414.388044 -317.020269)
			(xy 414.355409 -316.983432) (xy 414.329106 -316.941836) (xy 414.309815 -316.89656) (xy 414.298038 -316.848776)
			(xy 414.294078 -316.799722) (xy 397.805148 -316.799722) (xy 397.804653 -316.824329) (xy 397.796758 -316.872906)
			(xy 397.781174 -316.919587) (xy 397.758303 -316.963164) (xy 397.728738 -317.002508) (xy 397.693245 -317.0366)
			(xy 397.652742 -317.064556) (xy 397.60828 -317.085654) (xy 397.561009 -317.099346) (xy 397.512154 -317.105278)
			(xy 397.462979 -317.103297) (xy 397.41476 -317.093453) (xy 397.368744 -317.076001) (xy 397.326123 -317.051394)
			(xy 397.288002 -317.020269) (xy 397.255367 -316.983432) (xy 397.229064 -316.941836) (xy 397.209773 -316.89656)
			(xy 397.197996 -316.848776) (xy 397.194036 -316.799722) (xy 395.905228 -316.799722) (xy 395.904733 -316.824329)
			(xy 395.896838 -316.872906) (xy 395.881254 -316.919587) (xy 395.858383 -316.963164) (xy 395.828818 -317.002508)
			(xy 395.793325 -317.0366) (xy 395.752822 -317.064556) (xy 395.70836 -317.085654) (xy 395.661089 -317.099346)
			(xy 395.612234 -317.105278) (xy 395.563059 -317.103297) (xy 395.51484 -317.093453) (xy 395.468824 -317.076001)
			(xy 395.426203 -317.051394) (xy 395.388082 -317.020269) (xy 395.355447 -316.983432) (xy 395.329144 -316.941836)
			(xy 395.309853 -316.89656) (xy 395.298076 -316.848776) (xy 395.294116 -316.799722) (xy 394.005308 -316.799722)
			(xy 394.004813 -316.824329) (xy 393.996918 -316.872906) (xy 393.981334 -316.919587) (xy 393.958463 -316.963164)
			(xy 393.928898 -317.002508) (xy 393.893405 -317.0366) (xy 393.852902 -317.064556) (xy 393.80844 -317.085654)
			(xy 393.761169 -317.099346) (xy 393.712314 -317.105278) (xy 393.663139 -317.103297) (xy 393.61492 -317.093453)
			(xy 393.568904 -317.076001) (xy 393.526283 -317.051394) (xy 393.488162 -317.020269) (xy 393.455527 -316.983432)
			(xy 393.429224 -316.941836) (xy 393.409933 -316.89656) (xy 393.398156 -316.848776) (xy 393.394196 -316.799722)
			(xy 392.105134 -316.799722) (xy 392.104639 -316.824329) (xy 392.096744 -316.872906) (xy 392.08116 -316.919587)
			(xy 392.058289 -316.963164) (xy 392.028724 -317.002508) (xy 391.993231 -317.0366) (xy 391.952728 -317.064556)
			(xy 391.908266 -317.085654) (xy 391.860995 -317.099346) (xy 391.81214 -317.105278) (xy 391.762965 -317.103297)
			(xy 391.714746 -317.093453) (xy 391.66873 -317.076001) (xy 391.626109 -317.051394) (xy 391.587988 -317.020269)
			(xy 391.555353 -316.983432) (xy 391.52905 -316.941836) (xy 391.509759 -316.89656) (xy 391.497982 -316.848776)
			(xy 391.494022 -316.799722) (xy 390.205214 -316.799722) (xy 390.204719 -316.824329) (xy 390.196824 -316.872906)
			(xy 390.18124 -316.919587) (xy 390.158369 -316.963164) (xy 390.128804 -317.002508) (xy 390.093311 -317.0366)
			(xy 390.052808 -317.064556) (xy 390.008346 -317.085654) (xy 389.961075 -317.099346) (xy 389.91222 -317.105278)
			(xy 389.863045 -317.103297) (xy 389.814826 -317.093453) (xy 389.76881 -317.076001) (xy 389.726189 -317.051394)
			(xy 389.688068 -317.020269) (xy 389.655433 -316.983432) (xy 389.62913 -316.941836) (xy 389.609839 -316.89656)
			(xy 389.598062 -316.848776) (xy 389.594102 -316.799722) (xy 388.305294 -316.799722) (xy 388.304799 -316.824329)
			(xy 388.296904 -316.872906) (xy 388.28132 -316.919587) (xy 388.258449 -316.963164) (xy 388.228884 -317.002508)
			(xy 388.193391 -317.0366) (xy 388.152888 -317.064556) (xy 388.108426 -317.085654) (xy 388.061155 -317.099346)
			(xy 388.0123 -317.105278) (xy 387.963125 -317.103297) (xy 387.914906 -317.093453) (xy 387.86889 -317.076001)
			(xy 387.826269 -317.051394) (xy 387.788148 -317.020269) (xy 387.755513 -316.983432) (xy 387.72921 -316.941836)
			(xy 387.709919 -316.89656) (xy 387.698142 -316.848776) (xy 387.694182 -316.799722) (xy 386.40512 -316.799722)
			(xy 386.404625 -316.824329) (xy 386.39673 -316.872906) (xy 386.381146 -316.919587) (xy 386.358275 -316.963164)
			(xy 386.32871 -317.002508) (xy 386.293217 -317.0366) (xy 386.252714 -317.064556) (xy 386.208252 -317.085654)
			(xy 386.160981 -317.099346) (xy 386.112126 -317.105278) (xy 386.062951 -317.103297) (xy 386.014732 -317.093453)
			(xy 385.968716 -317.076001) (xy 385.926095 -317.051394) (xy 385.887974 -317.020269) (xy 385.855339 -316.983432)
			(xy 385.829036 -316.941836) (xy 385.809745 -316.89656) (xy 385.797968 -316.848776) (xy 385.794008 -316.799722)
			(xy 385.45516 -316.799722) (xy 385.454665 -316.824329) (xy 385.44677 -316.872906) (xy 385.431186 -316.919587)
			(xy 385.408315 -316.963164) (xy 385.37875 -317.002508) (xy 385.343257 -317.0366) (xy 385.302754 -317.064556)
			(xy 385.258292 -317.085654) (xy 385.211021 -317.099346) (xy 385.162166 -317.105278) (xy 385.112991 -317.103297)
			(xy 385.064772 -317.093453) (xy 385.018756 -317.076001) (xy 384.976135 -317.051394) (xy 384.938014 -317.020269)
			(xy 384.905379 -316.983432) (xy 384.879076 -316.941836) (xy 384.859785 -316.89656) (xy 384.848008 -316.848776)
			(xy 384.844048 -316.799722) (xy 314.955174 -316.799722) (xy 314.954679 -316.824329) (xy 314.946784 -316.872906)
			(xy 314.9312 -316.919587) (xy 314.908329 -316.963164) (xy 314.878764 -317.002508) (xy 314.843271 -317.0366)
			(xy 314.802768 -317.064556) (xy 314.758306 -317.085654) (xy 314.711035 -317.099346) (xy 314.66218 -317.105278)
			(xy 314.613005 -317.103297) (xy 314.564786 -317.093453) (xy 314.51877 -317.076001) (xy 314.476149 -317.051394)
			(xy 314.438028 -317.020269) (xy 314.405393 -316.983432) (xy 314.37909 -316.941836) (xy 314.359799 -316.89656)
			(xy 314.348022 -316.848776) (xy 314.344062 -316.799722) (xy 314.005214 -316.799722) (xy 314.004719 -316.824329)
			(xy 313.996824 -316.872906) (xy 313.98124 -316.919587) (xy 313.958369 -316.963164) (xy 313.928804 -317.002508)
			(xy 313.893311 -317.0366) (xy 313.852808 -317.064556) (xy 313.808346 -317.085654) (xy 313.761075 -317.099346)
			(xy 313.71222 -317.105278) (xy 313.663045 -317.103297) (xy 313.614826 -317.093453) (xy 313.56881 -317.076001)
			(xy 313.526189 -317.051394) (xy 313.488068 -317.020269) (xy 313.455433 -316.983432) (xy 313.42913 -316.941836)
			(xy 313.409839 -316.89656) (xy 313.398062 -316.848776) (xy 313.394102 -316.799722) (xy 312.10504 -316.799722)
			(xy 312.104545 -316.824329) (xy 312.09665 -316.872906) (xy 312.081066 -316.919587) (xy 312.058195 -316.963164)
			(xy 312.02863 -317.002508) (xy 311.993137 -317.0366) (xy 311.952634 -317.064556) (xy 311.908172 -317.085654)
			(xy 311.860901 -317.099346) (xy 311.812046 -317.105278) (xy 311.762871 -317.103297) (xy 311.714652 -317.093453)
			(xy 311.668636 -317.076001) (xy 311.626015 -317.051394) (xy 311.587894 -317.020269) (xy 311.555259 -316.983432)
			(xy 311.528956 -316.941836) (xy 311.509665 -316.89656) (xy 311.497888 -316.848776) (xy 311.493928 -316.799722)
			(xy 310.20512 -316.799722) (xy 310.204625 -316.824329) (xy 310.19673 -316.872906) (xy 310.181146 -316.919587)
			(xy 310.158275 -316.963164) (xy 310.12871 -317.002508) (xy 310.093217 -317.0366) (xy 310.052714 -317.064556)
			(xy 310.008252 -317.085654) (xy 309.960981 -317.099346) (xy 309.912126 -317.105278) (xy 309.862951 -317.103297)
			(xy 309.814732 -317.093453) (xy 309.768716 -317.076001) (xy 309.726095 -317.051394) (xy 309.687974 -317.020269)
			(xy 309.655339 -316.983432) (xy 309.629036 -316.941836) (xy 309.609745 -316.89656) (xy 309.597968 -316.848776)
			(xy 309.594008 -316.799722) (xy 308.3052 -316.799722) (xy 308.304705 -316.824329) (xy 308.29681 -316.872906)
			(xy 308.281226 -316.919587) (xy 308.258355 -316.963164) (xy 308.22879 -317.002508) (xy 308.193297 -317.0366)
			(xy 308.152794 -317.064556) (xy 308.108332 -317.085654) (xy 308.061061 -317.099346) (xy 308.012206 -317.105278)
			(xy 307.963031 -317.103297) (xy 307.914812 -317.093453) (xy 307.868796 -317.076001) (xy 307.826175 -317.051394)
			(xy 307.788054 -317.020269) (xy 307.755419 -316.983432) (xy 307.729116 -316.941836) (xy 307.709825 -316.89656)
			(xy 307.698048 -316.848776) (xy 307.694088 -316.799722) (xy 306.405026 -316.799722) (xy 306.404531 -316.824329)
			(xy 306.396636 -316.872906) (xy 306.381052 -316.919587) (xy 306.358181 -316.963164) (xy 306.328616 -317.002508)
			(xy 306.293123 -317.0366) (xy 306.25262 -317.064556) (xy 306.208158 -317.085654) (xy 306.160887 -317.099346)
			(xy 306.112032 -317.105278) (xy 306.062857 -317.103297) (xy 306.014638 -317.093453) (xy 305.968622 -317.076001)
			(xy 305.926001 -317.051394) (xy 305.88788 -317.020269) (xy 305.855245 -316.983432) (xy 305.828942 -316.941836)
			(xy 305.809651 -316.89656) (xy 305.797874 -316.848776) (xy 305.793914 -316.799722) (xy 296.905172 -316.799722)
			(xy 296.904677 -316.824329) (xy 296.896782 -316.872906) (xy 296.881198 -316.919587) (xy 296.858327 -316.963164)
			(xy 296.828762 -317.002508) (xy 296.793269 -317.0366) (xy 296.752766 -317.064556) (xy 296.708304 -317.085654)
			(xy 296.661033 -317.099346) (xy 296.612178 -317.105278) (xy 296.563003 -317.103297) (xy 296.514784 -317.093453)
			(xy 296.468768 -317.076001) (xy 296.426147 -317.051394) (xy 296.388026 -317.020269) (xy 296.355391 -316.983432)
			(xy 296.329088 -316.941836) (xy 296.309797 -316.89656) (xy 296.29802 -316.848776) (xy 296.29406 -316.799722)
			(xy 295.004998 -316.799722) (xy 295.004503 -316.824329) (xy 294.996608 -316.872906) (xy 294.981024 -316.919587)
			(xy 294.958153 -316.963164) (xy 294.928588 -317.002508) (xy 294.893095 -317.0366) (xy 294.852592 -317.064556)
			(xy 294.80813 -317.085654) (xy 294.760859 -317.099346) (xy 294.712004 -317.105278) (xy 294.662829 -317.103297)
			(xy 294.61461 -317.093453) (xy 294.568594 -317.076001) (xy 294.525973 -317.051394) (xy 294.487852 -317.020269)
			(xy 294.455217 -316.983432) (xy 294.428914 -316.941836) (xy 294.409623 -316.89656) (xy 294.397846 -316.848776)
			(xy 294.393886 -316.799722) (xy 293.105078 -316.799722) (xy 293.104583 -316.824329) (xy 293.096688 -316.872906)
			(xy 293.081104 -316.919587) (xy 293.058233 -316.963164) (xy 293.028668 -317.002508) (xy 292.993175 -317.0366)
			(xy 292.952672 -317.064556) (xy 292.90821 -317.085654) (xy 292.860939 -317.099346) (xy 292.812084 -317.105278)
			(xy 292.762909 -317.103297) (xy 292.71469 -317.093453) (xy 292.668674 -317.076001) (xy 292.626053 -317.051394)
			(xy 292.587932 -317.020269) (xy 292.555297 -316.983432) (xy 292.528994 -316.941836) (xy 292.509703 -316.89656)
			(xy 292.497926 -316.848776) (xy 292.493966 -316.799722) (xy 291.205158 -316.799722) (xy 291.204663 -316.824329)
			(xy 291.196768 -316.872906) (xy 291.181184 -316.919587) (xy 291.158313 -316.963164) (xy 291.128748 -317.002508)
			(xy 291.093255 -317.0366) (xy 291.052752 -317.064556) (xy 291.00829 -317.085654) (xy 290.961019 -317.099346)
			(xy 290.912164 -317.105278) (xy 290.862989 -317.103297) (xy 290.81477 -317.093453) (xy 290.768754 -317.076001)
			(xy 290.726133 -317.051394) (xy 290.688012 -317.020269) (xy 290.655377 -316.983432) (xy 290.629074 -316.941836)
			(xy 290.609783 -316.89656) (xy 290.598006 -316.848776) (xy 290.594046 -316.799722) (xy 289.305238 -316.799722)
			(xy 289.304743 -316.824329) (xy 289.296848 -316.872906) (xy 289.281264 -316.919587) (xy 289.258393 -316.963164)
			(xy 289.228828 -317.002508) (xy 289.193335 -317.0366) (xy 289.152832 -317.064556) (xy 289.10837 -317.085654)
			(xy 289.061099 -317.099346) (xy 289.012244 -317.105278) (xy 288.963069 -317.103297) (xy 288.91485 -317.093453)
			(xy 288.868834 -317.076001) (xy 288.826213 -317.051394) (xy 288.788092 -317.020269) (xy 288.755457 -316.983432)
			(xy 288.729154 -316.941836) (xy 288.709863 -316.89656) (xy 288.698086 -316.848776) (xy 288.694126 -316.799722)
			(xy 287.405064 -316.799722) (xy 287.404569 -316.824329) (xy 287.396674 -316.872906) (xy 287.38109 -316.919587)
			(xy 287.358219 -316.963164) (xy 287.328654 -317.002508) (xy 287.293161 -317.0366) (xy 287.252658 -317.064556)
			(xy 287.208196 -317.085654) (xy 287.160925 -317.099346) (xy 287.11207 -317.105278) (xy 287.062895 -317.103297)
			(xy 287.014676 -317.093453) (xy 286.96866 -317.076001) (xy 286.926039 -317.051394) (xy 286.887918 -317.020269)
			(xy 286.855283 -316.983432) (xy 286.82898 -316.941836) (xy 286.809689 -316.89656) (xy 286.797912 -316.848776)
			(xy 286.793952 -316.799722) (xy 285.505144 -316.799722) (xy 285.504649 -316.824329) (xy 285.496754 -316.872906)
			(xy 285.48117 -316.919587) (xy 285.458299 -316.963164) (xy 285.428734 -317.002508) (xy 285.393241 -317.0366)
			(xy 285.352738 -317.064556) (xy 285.308276 -317.085654) (xy 285.261005 -317.099346) (xy 285.21215 -317.105278)
			(xy 285.162975 -317.103297) (xy 285.114756 -317.093453) (xy 285.06874 -317.076001) (xy 285.026119 -317.051394)
			(xy 284.987998 -317.020269) (xy 284.955363 -316.983432) (xy 284.92906 -316.941836) (xy 284.909769 -316.89656)
			(xy 284.897992 -316.848776) (xy 284.894032 -316.799722) (xy 283.605224 -316.799722) (xy 283.604729 -316.824329)
			(xy 283.596834 -316.872906) (xy 283.58125 -316.919587) (xy 283.558379 -316.963164) (xy 283.528814 -317.002508)
			(xy 283.493321 -317.0366) (xy 283.452818 -317.064556) (xy 283.408356 -317.085654) (xy 283.361085 -317.099346)
			(xy 283.31223 -317.105278) (xy 283.263055 -317.103297) (xy 283.214836 -317.093453) (xy 283.16882 -317.076001)
			(xy 283.126199 -317.051394) (xy 283.088078 -317.020269) (xy 283.055443 -316.983432) (xy 283.02914 -316.941836)
			(xy 283.009849 -316.89656) (xy 282.998072 -316.848776) (xy 282.994112 -316.799722) (xy 188.405262 -316.799722)
			(xy 188.404767 -316.824329) (xy 188.396872 -316.872906) (xy 188.381288 -316.919587) (xy 188.358417 -316.963164)
			(xy 188.328852 -317.002508) (xy 188.293359 -317.0366) (xy 188.252856 -317.064556) (xy 188.208394 -317.085654)
			(xy 188.161123 -317.099346) (xy 188.112268 -317.105278) (xy 188.063093 -317.103297) (xy 188.014874 -317.093453)
			(xy 187.968858 -317.076001) (xy 187.926237 -317.051394) (xy 187.888116 -317.020269) (xy 187.855481 -316.983432)
			(xy 187.829178 -316.941836) (xy 187.809887 -316.89656) (xy 187.79811 -316.848776) (xy 187.79415 -316.799722)
			(xy 186.505342 -316.799722) (xy 186.504847 -316.824329) (xy 186.496952 -316.872906) (xy 186.481368 -316.919587)
			(xy 186.458497 -316.963164) (xy 186.428932 -317.002508) (xy 186.393439 -317.0366) (xy 186.352936 -317.064556)
			(xy 186.308474 -317.085654) (xy 186.261203 -317.099346) (xy 186.212348 -317.105278) (xy 186.163173 -317.103297)
			(xy 186.114954 -317.093453) (xy 186.068938 -317.076001) (xy 186.026317 -317.051394) (xy 185.988196 -317.020269)
			(xy 185.955561 -316.983432) (xy 185.929258 -316.941836) (xy 185.909967 -316.89656) (xy 185.89819 -316.848776)
			(xy 185.89423 -316.799722) (xy 184.605168 -316.799722) (xy 184.604673 -316.824329) (xy 184.596778 -316.872906)
			(xy 184.581194 -316.919587) (xy 184.558323 -316.963164) (xy 184.528758 -317.002508) (xy 184.493265 -317.0366)
			(xy 184.452762 -317.064556) (xy 184.4083 -317.085654) (xy 184.361029 -317.099346) (xy 184.312174 -317.105278)
			(xy 184.262999 -317.103297) (xy 184.21478 -317.093453) (xy 184.168764 -317.076001) (xy 184.126143 -317.051394)
			(xy 184.088022 -317.020269) (xy 184.055387 -316.983432) (xy 184.029084 -316.941836) (xy 184.009793 -316.89656)
			(xy 183.998016 -316.848776) (xy 183.994056 -316.799722) (xy 182.705248 -316.799722) (xy 182.704753 -316.824329)
			(xy 182.696858 -316.872906) (xy 182.681274 -316.919587) (xy 182.658403 -316.963164) (xy 182.628838 -317.002508)
			(xy 182.593345 -317.0366) (xy 182.552842 -317.064556) (xy 182.50838 -317.085654) (xy 182.461109 -317.099346)
			(xy 182.412254 -317.105278) (xy 182.363079 -317.103297) (xy 182.31486 -317.093453) (xy 182.268844 -317.076001)
			(xy 182.226223 -317.051394) (xy 182.188102 -317.020269) (xy 182.155467 -316.983432) (xy 182.129164 -316.941836)
			(xy 182.109873 -316.89656) (xy 182.098096 -316.848776) (xy 182.094136 -316.799722) (xy 165.605206 -316.799722)
			(xy 165.604711 -316.824329) (xy 165.596816 -316.872906) (xy 165.581232 -316.919587) (xy 165.558361 -316.963164)
			(xy 165.528796 -317.002508) (xy 165.493303 -317.0366) (xy 165.4528 -317.064556) (xy 165.408338 -317.085654)
			(xy 165.361067 -317.099346) (xy 165.312212 -317.105278) (xy 165.263037 -317.103297) (xy 165.214818 -317.093453)
			(xy 165.168802 -317.076001) (xy 165.126181 -317.051394) (xy 165.08806 -317.020269) (xy 165.055425 -316.983432)
			(xy 165.029122 -316.941836) (xy 165.009831 -316.89656) (xy 164.998054 -316.848776) (xy 164.994094 -316.799722)
			(xy 163.705286 -316.799722) (xy 163.704791 -316.824329) (xy 163.696896 -316.872906) (xy 163.681312 -316.919587)
			(xy 163.658441 -316.963164) (xy 163.628876 -317.002508) (xy 163.593383 -317.0366) (xy 163.55288 -317.064556)
			(xy 163.508418 -317.085654) (xy 163.461147 -317.099346) (xy 163.412292 -317.105278) (xy 163.363117 -317.103297)
			(xy 163.314898 -317.093453) (xy 163.268882 -317.076001) (xy 163.226261 -317.051394) (xy 163.18814 -317.020269)
			(xy 163.155505 -316.983432) (xy 163.129202 -316.941836) (xy 163.109911 -316.89656) (xy 163.098134 -316.848776)
			(xy 163.094174 -316.799722) (xy 161.805366 -316.799722) (xy 161.804871 -316.824329) (xy 161.796976 -316.872906)
			(xy 161.781392 -316.919587) (xy 161.758521 -316.963164) (xy 161.728956 -317.002508) (xy 161.693463 -317.0366)
			(xy 161.65296 -317.064556) (xy 161.608498 -317.085654) (xy 161.561227 -317.099346) (xy 161.512372 -317.105278)
			(xy 161.463197 -317.103297) (xy 161.414978 -317.093453) (xy 161.368962 -317.076001) (xy 161.326341 -317.051394)
			(xy 161.28822 -317.020269) (xy 161.255585 -316.983432) (xy 161.229282 -316.941836) (xy 161.209991 -316.89656)
			(xy 161.198214 -316.848776) (xy 161.194254 -316.799722) (xy 159.905192 -316.799722) (xy 159.904697 -316.824329)
			(xy 159.896802 -316.872906) (xy 159.881218 -316.919587) (xy 159.858347 -316.963164) (xy 159.828782 -317.002508)
			(xy 159.793289 -317.0366) (xy 159.752786 -317.064556) (xy 159.708324 -317.085654) (xy 159.661053 -317.099346)
			(xy 159.612198 -317.105278) (xy 159.563023 -317.103297) (xy 159.514804 -317.093453) (xy 159.468788 -317.076001)
			(xy 159.426167 -317.051394) (xy 159.388046 -317.020269) (xy 159.355411 -316.983432) (xy 159.329108 -316.941836)
			(xy 159.309817 -316.89656) (xy 159.29804 -316.848776) (xy 159.29408 -316.799722) (xy 158.005272 -316.799722)
			(xy 158.004777 -316.824329) (xy 157.996882 -316.872906) (xy 157.981298 -316.919587) (xy 157.958427 -316.963164)
			(xy 157.928862 -317.002508) (xy 157.893369 -317.0366) (xy 157.852866 -317.064556) (xy 157.808404 -317.085654)
			(xy 157.761133 -317.099346) (xy 157.712278 -317.105278) (xy 157.663103 -317.103297) (xy 157.614884 -317.093453)
			(xy 157.568868 -317.076001) (xy 157.526247 -317.051394) (xy 157.488126 -317.020269) (xy 157.455491 -316.983432)
			(xy 157.429188 -316.941836) (xy 157.409897 -316.89656) (xy 157.39812 -316.848776) (xy 157.39416 -316.799722)
			(xy 156.105352 -316.799722) (xy 156.104857 -316.824329) (xy 156.096962 -316.872906) (xy 156.081378 -316.919587)
			(xy 156.058507 -316.963164) (xy 156.028942 -317.002508) (xy 155.993449 -317.0366) (xy 155.952946 -317.064556)
			(xy 155.908484 -317.085654) (xy 155.861213 -317.099346) (xy 155.812358 -317.105278) (xy 155.763183 -317.103297)
			(xy 155.714964 -317.093453) (xy 155.668948 -317.076001) (xy 155.626327 -317.051394) (xy 155.588206 -317.020269)
			(xy 155.555571 -316.983432) (xy 155.529268 -316.941836) (xy 155.509977 -316.89656) (xy 155.4982 -316.848776)
			(xy 155.49424 -316.799722) (xy 154.205178 -316.799722) (xy 154.204683 -316.824329) (xy 154.196788 -316.872906)
			(xy 154.181204 -316.919587) (xy 154.158333 -316.963164) (xy 154.128768 -317.002508) (xy 154.093275 -317.0366)
			(xy 154.052772 -317.064556) (xy 154.00831 -317.085654) (xy 153.961039 -317.099346) (xy 153.912184 -317.105278)
			(xy 153.863009 -317.103297) (xy 153.81479 -317.093453) (xy 153.768774 -317.076001) (xy 153.726153 -317.051394)
			(xy 153.688032 -317.020269) (xy 153.655397 -316.983432) (xy 153.629094 -316.941836) (xy 153.609803 -316.89656)
			(xy 153.598026 -316.848776) (xy 153.594066 -316.799722) (xy 153.255218 -316.799722) (xy 153.254723 -316.824329)
			(xy 153.246828 -316.872906) (xy 153.231244 -316.919587) (xy 153.208373 -316.963164) (xy 153.178808 -317.002508)
			(xy 153.143315 -317.0366) (xy 153.102812 -317.064556) (xy 153.05835 -317.085654) (xy 153.011079 -317.099346)
			(xy 152.962224 -317.105278) (xy 152.913049 -317.103297) (xy 152.86483 -317.093453) (xy 152.818814 -317.076001)
			(xy 152.776193 -317.051394) (xy 152.738072 -317.020269) (xy 152.705437 -316.983432) (xy 152.679134 -316.941836)
			(xy 152.659843 -316.89656) (xy 152.648066 -316.848776) (xy 152.644106 -316.799722) (xy 82.755232 -316.799722)
			(xy 82.754737 -316.824329) (xy 82.746842 -316.872906) (xy 82.731258 -316.919587) (xy 82.708387 -316.963164)
			(xy 82.678822 -317.002508) (xy 82.643329 -317.0366) (xy 82.602826 -317.064556) (xy 82.558364 -317.085654)
			(xy 82.511093 -317.099346) (xy 82.462238 -317.105278) (xy 82.413063 -317.103297) (xy 82.364844 -317.093453)
			(xy 82.318828 -317.076001) (xy 82.276207 -317.051394) (xy 82.238086 -317.020269) (xy 82.205451 -316.983432)
			(xy 82.179148 -316.941836) (xy 82.159857 -316.89656) (xy 82.14808 -316.848776) (xy 82.14412 -316.799722)
			(xy 81.805272 -316.799722) (xy 81.804777 -316.824329) (xy 81.796882 -316.872906) (xy 81.781298 -316.919587)
			(xy 81.758427 -316.963164) (xy 81.728862 -317.002508) (xy 81.693369 -317.0366) (xy 81.652866 -317.064556)
			(xy 81.608404 -317.085654) (xy 81.561133 -317.099346) (xy 81.512278 -317.105278) (xy 81.463103 -317.103297)
			(xy 81.414884 -317.093453) (xy 81.368868 -317.076001) (xy 81.326247 -317.051394) (xy 81.288126 -317.020269)
			(xy 81.255491 -316.983432) (xy 81.229188 -316.941836) (xy 81.209897 -316.89656) (xy 81.19812 -316.848776)
			(xy 81.19416 -316.799722) (xy 79.905098 -316.799722) (xy 79.904603 -316.824329) (xy 79.896708 -316.872906)
			(xy 79.881124 -316.919587) (xy 79.858253 -316.963164) (xy 79.828688 -317.002508) (xy 79.793195 -317.0366)
			(xy 79.752692 -317.064556) (xy 79.70823 -317.085654) (xy 79.660959 -317.099346) (xy 79.612104 -317.105278)
			(xy 79.562929 -317.103297) (xy 79.51471 -317.093453) (xy 79.468694 -317.076001) (xy 79.426073 -317.051394)
			(xy 79.387952 -317.020269) (xy 79.355317 -316.983432) (xy 79.329014 -316.941836) (xy 79.309723 -316.89656)
			(xy 79.297946 -316.848776) (xy 79.293986 -316.799722) (xy 78.005178 -316.799722) (xy 78.004683 -316.824329)
			(xy 77.996788 -316.872906) (xy 77.981204 -316.919587) (xy 77.958333 -316.963164) (xy 77.928768 -317.002508)
			(xy 77.893275 -317.0366) (xy 77.852772 -317.064556) (xy 77.80831 -317.085654) (xy 77.761039 -317.099346)
			(xy 77.712184 -317.105278) (xy 77.663009 -317.103297) (xy 77.61479 -317.093453) (xy 77.568774 -317.076001)
			(xy 77.526153 -317.051394) (xy 77.488032 -317.020269) (xy 77.455397 -316.983432) (xy 77.429094 -316.941836)
			(xy 77.409803 -316.89656) (xy 77.398026 -316.848776) (xy 77.394066 -316.799722) (xy 76.105258 -316.799722)
			(xy 76.104763 -316.824329) (xy 76.096868 -316.872906) (xy 76.081284 -316.919587) (xy 76.058413 -316.963164)
			(xy 76.028848 -317.002508) (xy 75.993355 -317.0366) (xy 75.952852 -317.064556) (xy 75.90839 -317.085654)
			(xy 75.861119 -317.099346) (xy 75.812264 -317.105278) (xy 75.763089 -317.103297) (xy 75.71487 -317.093453)
			(xy 75.668854 -317.076001) (xy 75.626233 -317.051394) (xy 75.588112 -317.020269) (xy 75.555477 -316.983432)
			(xy 75.529174 -316.941836) (xy 75.509883 -316.89656) (xy 75.498106 -316.848776) (xy 75.494146 -316.799722)
			(xy 74.205084 -316.799722) (xy 74.204589 -316.824329) (xy 74.196694 -316.872906) (xy 74.18111 -316.919587)
			(xy 74.158239 -316.963164) (xy 74.128674 -317.002508) (xy 74.093181 -317.0366) (xy 74.052678 -317.064556)
			(xy 74.008216 -317.085654) (xy 73.960945 -317.099346) (xy 73.91209 -317.105278) (xy 73.862915 -317.103297)
			(xy 73.814696 -317.093453) (xy 73.76868 -317.076001) (xy 73.726059 -317.051394) (xy 73.687938 -317.020269)
			(xy 73.655303 -316.983432) (xy 73.629 -316.941836) (xy 73.609709 -316.89656) (xy 73.597932 -316.848776)
			(xy 73.593972 -316.799722) (xy 64.70523 -316.799722) (xy 64.704735 -316.824329) (xy 64.69684 -316.872906)
			(xy 64.681256 -316.919587) (xy 64.658385 -316.963164) (xy 64.62882 -317.002508) (xy 64.593327 -317.0366)
			(xy 64.552824 -317.064556) (xy 64.508362 -317.085654) (xy 64.461091 -317.099346) (xy 64.412236 -317.105278)
			(xy 64.363061 -317.103297) (xy 64.314842 -317.093453) (xy 64.268826 -317.076001) (xy 64.226205 -317.051394)
			(xy 64.188084 -317.020269) (xy 64.155449 -316.983432) (xy 64.129146 -316.941836) (xy 64.109855 -316.89656)
			(xy 64.098078 -316.848776) (xy 64.094118 -316.799722) (xy 62.805056 -316.799722) (xy 62.804561 -316.824329)
			(xy 62.796666 -316.872906) (xy 62.781082 -316.919587) (xy 62.758211 -316.963164) (xy 62.728646 -317.002508)
			(xy 62.693153 -317.0366) (xy 62.65265 -317.064556) (xy 62.608188 -317.085654) (xy 62.560917 -317.099346)
			(xy 62.512062 -317.105278) (xy 62.462887 -317.103297) (xy 62.414668 -317.093453) (xy 62.368652 -317.076001)
			(xy 62.326031 -317.051394) (xy 62.28791 -317.020269) (xy 62.255275 -316.983432) (xy 62.228972 -316.941836)
			(xy 62.209681 -316.89656) (xy 62.197904 -316.848776) (xy 62.193944 -316.799722) (xy 60.905136 -316.799722)
			(xy 60.904641 -316.824329) (xy 60.896746 -316.872906) (xy 60.881162 -316.919587) (xy 60.858291 -316.963164)
			(xy 60.828726 -317.002508) (xy 60.793233 -317.0366) (xy 60.75273 -317.064556) (xy 60.708268 -317.085654)
			(xy 60.660997 -317.099346) (xy 60.612142 -317.105278) (xy 60.562967 -317.103297) (xy 60.514748 -317.093453)
			(xy 60.468732 -317.076001) (xy 60.426111 -317.051394) (xy 60.38799 -317.020269) (xy 60.355355 -316.983432)
			(xy 60.329052 -316.941836) (xy 60.309761 -316.89656) (xy 60.297984 -316.848776) (xy 60.294024 -316.799722)
			(xy 59.005216 -316.799722) (xy 59.004721 -316.824329) (xy 58.996826 -316.872906) (xy 58.981242 -316.919587)
			(xy 58.958371 -316.963164) (xy 58.928806 -317.002508) (xy 58.893313 -317.0366) (xy 58.85281 -317.064556)
			(xy 58.808348 -317.085654) (xy 58.761077 -317.099346) (xy 58.712222 -317.105278) (xy 58.663047 -317.103297)
			(xy 58.614828 -317.093453) (xy 58.568812 -317.076001) (xy 58.526191 -317.051394) (xy 58.48807 -317.020269)
			(xy 58.455435 -316.983432) (xy 58.429132 -316.941836) (xy 58.409841 -316.89656) (xy 58.398064 -316.848776)
			(xy 58.394104 -316.799722) (xy 57.105296 -316.799722) (xy 57.104801 -316.824329) (xy 57.096906 -316.872906)
			(xy 57.081322 -316.919587) (xy 57.058451 -316.963164) (xy 57.028886 -317.002508) (xy 56.993393 -317.0366)
			(xy 56.95289 -317.064556) (xy 56.908428 -317.085654) (xy 56.861157 -317.099346) (xy 56.812302 -317.105278)
			(xy 56.763127 -317.103297) (xy 56.714908 -317.093453) (xy 56.668892 -317.076001) (xy 56.626271 -317.051394)
			(xy 56.58815 -317.020269) (xy 56.555515 -316.983432) (xy 56.529212 -316.941836) (xy 56.509921 -316.89656)
			(xy 56.498144 -316.848776) (xy 56.494184 -316.799722) (xy 55.205122 -316.799722) (xy 55.204627 -316.824329)
			(xy 55.196732 -316.872906) (xy 55.181148 -316.919587) (xy 55.158277 -316.963164) (xy 55.128712 -317.002508)
			(xy 55.093219 -317.0366) (xy 55.052716 -317.064556) (xy 55.008254 -317.085654) (xy 54.960983 -317.099346)
			(xy 54.912128 -317.105278) (xy 54.862953 -317.103297) (xy 54.814734 -317.093453) (xy 54.768718 -317.076001)
			(xy 54.726097 -317.051394) (xy 54.687976 -317.020269) (xy 54.655341 -316.983432) (xy 54.629038 -316.941836)
			(xy 54.609747 -316.89656) (xy 54.59797 -316.848776) (xy 54.59401 -316.799722) (xy 53.305202 -316.799722)
			(xy 53.304707 -316.824329) (xy 53.296812 -316.872906) (xy 53.281228 -316.919587) (xy 53.258357 -316.963164)
			(xy 53.228792 -317.002508) (xy 53.193299 -317.0366) (xy 53.152796 -317.064556) (xy 53.108334 -317.085654)
			(xy 53.061063 -317.099346) (xy 53.012208 -317.105278) (xy 52.963033 -317.103297) (xy 52.914814 -317.093453)
			(xy 52.868798 -317.076001) (xy 52.826177 -317.051394) (xy 52.788056 -317.020269) (xy 52.755421 -316.983432)
			(xy 52.729118 -316.941836) (xy 52.709827 -316.89656) (xy 52.69805 -316.848776) (xy 52.69409 -316.799722)
			(xy 51.405282 -316.799722) (xy 51.404787 -316.824329) (xy 51.396892 -316.872906) (xy 51.381308 -316.919587)
			(xy 51.358437 -316.963164) (xy 51.328872 -317.002508) (xy 51.293379 -317.0366) (xy 51.252876 -317.064556)
			(xy 51.208414 -317.085654) (xy 51.161143 -317.099346) (xy 51.112288 -317.105278) (xy 51.063113 -317.103297)
			(xy 51.014894 -317.093453) (xy 50.968878 -317.076001) (xy 50.926257 -317.051394) (xy 50.888136 -317.020269)
			(xy 50.855501 -316.983432) (xy 50.829198 -316.941836) (xy 50.809907 -316.89656) (xy 50.79813 -316.848776)
			(xy 50.79417 -316.799722) (xy 0.508 -316.799722) (xy 0.508 -317.749936) (xy 51.74413 -317.749936)
			(xy 51.74809 -317.700882) (xy 51.759867 -317.653098) (xy 51.779158 -317.607822) (xy 51.805461 -317.566226)
			(xy 51.838096 -317.529389) (xy 51.876217 -317.498264) (xy 51.918838 -317.473657) (xy 51.964854 -317.456205)
			(xy 52.013073 -317.446361) (xy 52.062248 -317.44438) (xy 52.111103 -317.450312) (xy 52.158374 -317.464004)
			(xy 52.202836 -317.485102) (xy 52.243339 -317.513058) (xy 52.278832 -317.54715) (xy 52.308397 -317.586494)
			(xy 52.331268 -317.630071) (xy 52.346852 -317.676752) (xy 52.354747 -317.725329) (xy 52.355242 -317.749936)
			(xy 53.64405 -317.749936) (xy 53.64801 -317.700882) (xy 53.659787 -317.653098) (xy 53.679078 -317.607822)
			(xy 53.705381 -317.566226) (xy 53.738016 -317.529389) (xy 53.776137 -317.498264) (xy 53.818758 -317.473657)
			(xy 53.864774 -317.456205) (xy 53.912993 -317.446361) (xy 53.962168 -317.44438) (xy 54.011023 -317.450312)
			(xy 54.058294 -317.464004) (xy 54.102756 -317.485102) (xy 54.143259 -317.513058) (xy 54.178752 -317.54715)
			(xy 54.208317 -317.586494) (xy 54.231188 -317.630071) (xy 54.246772 -317.676752) (xy 54.254667 -317.725329)
			(xy 54.255162 -317.749936) (xy 55.54397 -317.749936) (xy 55.54793 -317.700882) (xy 55.559707 -317.653098)
			(xy 55.578998 -317.607822) (xy 55.605301 -317.566226) (xy 55.637936 -317.529389) (xy 55.676057 -317.498264)
			(xy 55.718678 -317.473657) (xy 55.764694 -317.456205) (xy 55.812913 -317.446361) (xy 55.862088 -317.44438)
			(xy 55.910943 -317.450312) (xy 55.958214 -317.464004) (xy 56.002676 -317.485102) (xy 56.043179 -317.513058)
			(xy 56.078672 -317.54715) (xy 56.108237 -317.586494) (xy 56.131108 -317.630071) (xy 56.146692 -317.676752)
			(xy 56.154587 -317.725329) (xy 56.155082 -317.749936) (xy 57.444144 -317.749936) (xy 57.448104 -317.700882)
			(xy 57.459881 -317.653098) (xy 57.479172 -317.607822) (xy 57.505475 -317.566226) (xy 57.53811 -317.529389)
			(xy 57.576231 -317.498264) (xy 57.618852 -317.473657) (xy 57.664868 -317.456205) (xy 57.713087 -317.446361)
			(xy 57.762262 -317.44438) (xy 57.811117 -317.450312) (xy 57.858388 -317.464004) (xy 57.90285 -317.485102)
			(xy 57.943353 -317.513058) (xy 57.978846 -317.54715) (xy 58.008411 -317.586494) (xy 58.031282 -317.630071)
			(xy 58.046866 -317.676752) (xy 58.054761 -317.725329) (xy 58.055256 -317.749936) (xy 59.344064 -317.749936)
			(xy 59.348024 -317.700882) (xy 59.359801 -317.653098) (xy 59.379092 -317.607822) (xy 59.405395 -317.566226)
			(xy 59.43803 -317.529389) (xy 59.476151 -317.498264) (xy 59.518772 -317.473657) (xy 59.564788 -317.456205)
			(xy 59.613007 -317.446361) (xy 59.662182 -317.44438) (xy 59.711037 -317.450312) (xy 59.758308 -317.464004)
			(xy 59.80277 -317.485102) (xy 59.843273 -317.513058) (xy 59.878766 -317.54715) (xy 59.908331 -317.586494)
			(xy 59.931202 -317.630071) (xy 59.946786 -317.676752) (xy 59.954681 -317.725329) (xy 59.955176 -317.749936)
			(xy 61.243984 -317.749936) (xy 61.247944 -317.700882) (xy 61.259721 -317.653098) (xy 61.279012 -317.607822)
			(xy 61.305315 -317.566226) (xy 61.33795 -317.529389) (xy 61.376071 -317.498264) (xy 61.418692 -317.473657)
			(xy 61.464708 -317.456205) (xy 61.512927 -317.446361) (xy 61.562102 -317.44438) (xy 61.610957 -317.450312)
			(xy 61.658228 -317.464004) (xy 61.70269 -317.485102) (xy 61.743193 -317.513058) (xy 61.778686 -317.54715)
			(xy 61.808251 -317.586494) (xy 61.831122 -317.630071) (xy 61.846706 -317.676752) (xy 61.854601 -317.725329)
			(xy 61.855096 -317.749936) (xy 63.144158 -317.749936) (xy 63.148118 -317.700882) (xy 63.159895 -317.653098)
			(xy 63.179186 -317.607822) (xy 63.205489 -317.566226) (xy 63.238124 -317.529389) (xy 63.276245 -317.498264)
			(xy 63.318866 -317.473657) (xy 63.364882 -317.456205) (xy 63.413101 -317.446361) (xy 63.462276 -317.44438)
			(xy 63.511131 -317.450312) (xy 63.558402 -317.464004) (xy 63.602864 -317.485102) (xy 63.643367 -317.513058)
			(xy 63.67886 -317.54715) (xy 63.708425 -317.586494) (xy 63.731296 -317.630071) (xy 63.74688 -317.676752)
			(xy 63.754775 -317.725329) (xy 63.75527 -317.749936) (xy 65.044078 -317.749936) (xy 65.048038 -317.700882)
			(xy 65.059815 -317.653098) (xy 65.079106 -317.607822) (xy 65.105409 -317.566226) (xy 65.138044 -317.529389)
			(xy 65.176165 -317.498264) (xy 65.218786 -317.473657) (xy 65.264802 -317.456205) (xy 65.313021 -317.446361)
			(xy 65.362196 -317.44438) (xy 65.411051 -317.450312) (xy 65.458322 -317.464004) (xy 65.502784 -317.485102)
			(xy 65.543287 -317.513058) (xy 65.57878 -317.54715) (xy 65.608345 -317.586494) (xy 65.631216 -317.630071)
			(xy 65.6468 -317.676752) (xy 65.654695 -317.725329) (xy 65.65519 -317.749936) (xy 74.544186 -317.749936)
			(xy 74.548146 -317.700882) (xy 74.559923 -317.653098) (xy 74.579214 -317.607822) (xy 74.605517 -317.566226)
			(xy 74.638152 -317.529389) (xy 74.676273 -317.498264) (xy 74.718894 -317.473657) (xy 74.76491 -317.456205)
			(xy 74.813129 -317.446361) (xy 74.862304 -317.44438) (xy 74.911159 -317.450312) (xy 74.95843 -317.464004)
			(xy 75.002892 -317.485102) (xy 75.043395 -317.513058) (xy 75.078888 -317.54715) (xy 75.108453 -317.586494)
			(xy 75.131324 -317.630071) (xy 75.146908 -317.676752) (xy 75.154803 -317.725329) (xy 75.155298 -317.749936)
			(xy 76.444106 -317.749936) (xy 76.448066 -317.700882) (xy 76.459843 -317.653098) (xy 76.479134 -317.607822)
			(xy 76.505437 -317.566226) (xy 76.538072 -317.529389) (xy 76.576193 -317.498264) (xy 76.618814 -317.473657)
			(xy 76.66483 -317.456205) (xy 76.713049 -317.446361) (xy 76.762224 -317.44438) (xy 76.811079 -317.450312)
			(xy 76.85835 -317.464004) (xy 76.902812 -317.485102) (xy 76.943315 -317.513058) (xy 76.978808 -317.54715)
			(xy 77.008373 -317.586494) (xy 77.031244 -317.630071) (xy 77.046828 -317.676752) (xy 77.054723 -317.725329)
			(xy 77.055218 -317.749936) (xy 78.344026 -317.749936) (xy 78.347986 -317.700882) (xy 78.359763 -317.653098)
			(xy 78.379054 -317.607822) (xy 78.405357 -317.566226) (xy 78.437992 -317.529389) (xy 78.476113 -317.498264)
			(xy 78.518734 -317.473657) (xy 78.56475 -317.456205) (xy 78.612969 -317.446361) (xy 78.662144 -317.44438)
			(xy 78.710999 -317.450312) (xy 78.75827 -317.464004) (xy 78.802732 -317.485102) (xy 78.843235 -317.513058)
			(xy 78.878728 -317.54715) (xy 78.908293 -317.586494) (xy 78.931164 -317.630071) (xy 78.946748 -317.676752)
			(xy 78.954643 -317.725329) (xy 78.955138 -317.749936) (xy 80.243946 -317.749936) (xy 80.247906 -317.700882)
			(xy 80.259683 -317.653098) (xy 80.278974 -317.607822) (xy 80.305277 -317.566226) (xy 80.337912 -317.529389)
			(xy 80.376033 -317.498264) (xy 80.418654 -317.473657) (xy 80.46467 -317.456205) (xy 80.512889 -317.446361)
			(xy 80.562064 -317.44438) (xy 80.610919 -317.450312) (xy 80.65819 -317.464004) (xy 80.702652 -317.485102)
			(xy 80.743155 -317.513058) (xy 80.778648 -317.54715) (xy 80.808213 -317.586494) (xy 80.831084 -317.630071)
			(xy 80.846668 -317.676752) (xy 80.854563 -317.725329) (xy 80.855058 -317.749936) (xy 154.54428 -317.749936)
			(xy 154.54824 -317.700882) (xy 154.560017 -317.653098) (xy 154.579308 -317.607822) (xy 154.605611 -317.566226)
			(xy 154.638246 -317.529389) (xy 154.676367 -317.498264) (xy 154.718988 -317.473657) (xy 154.765004 -317.456205)
			(xy 154.813223 -317.446361) (xy 154.862398 -317.44438) (xy 154.911253 -317.450312) (xy 154.958524 -317.464004)
			(xy 155.002986 -317.485102) (xy 155.043489 -317.513058) (xy 155.078982 -317.54715) (xy 155.108547 -317.586494)
			(xy 155.131418 -317.630071) (xy 155.147002 -317.676752) (xy 155.154897 -317.725329) (xy 155.155392 -317.749936)
			(xy 156.4442 -317.749936) (xy 156.44816 -317.700882) (xy 156.459937 -317.653098) (xy 156.479228 -317.607822)
			(xy 156.505531 -317.566226) (xy 156.538166 -317.529389) (xy 156.576287 -317.498264) (xy 156.618908 -317.473657)
			(xy 156.664924 -317.456205) (xy 156.713143 -317.446361) (xy 156.762318 -317.44438) (xy 156.811173 -317.450312)
			(xy 156.858444 -317.464004) (xy 156.902906 -317.485102) (xy 156.943409 -317.513058) (xy 156.978902 -317.54715)
			(xy 157.008467 -317.586494) (xy 157.031338 -317.630071) (xy 157.046922 -317.676752) (xy 157.054817 -317.725329)
			(xy 157.055312 -317.749936) (xy 158.34412 -317.749936) (xy 158.34808 -317.700882) (xy 158.359857 -317.653098)
			(xy 158.379148 -317.607822) (xy 158.405451 -317.566226) (xy 158.438086 -317.529389) (xy 158.476207 -317.498264)
			(xy 158.518828 -317.473657) (xy 158.564844 -317.456205) (xy 158.613063 -317.446361) (xy 158.662238 -317.44438)
			(xy 158.711093 -317.450312) (xy 158.758364 -317.464004) (xy 158.802826 -317.485102) (xy 158.843329 -317.513058)
			(xy 158.878822 -317.54715) (xy 158.908387 -317.586494) (xy 158.931258 -317.630071) (xy 158.946842 -317.676752)
			(xy 158.954737 -317.725329) (xy 158.955232 -317.749936) (xy 160.24404 -317.749936) (xy 160.248 -317.700882)
			(xy 160.259777 -317.653098) (xy 160.279068 -317.607822) (xy 160.305371 -317.566226) (xy 160.338006 -317.529389)
			(xy 160.376127 -317.498264) (xy 160.418748 -317.473657) (xy 160.464764 -317.456205) (xy 160.512983 -317.446361)
			(xy 160.562158 -317.44438) (xy 160.611013 -317.450312) (xy 160.658284 -317.464004) (xy 160.702746 -317.485102)
			(xy 160.743249 -317.513058) (xy 160.778742 -317.54715) (xy 160.808307 -317.586494) (xy 160.831178 -317.630071)
			(xy 160.846762 -317.676752) (xy 160.854657 -317.725329) (xy 160.855152 -317.749936) (xy 162.144214 -317.749936)
			(xy 162.148174 -317.700882) (xy 162.159951 -317.653098) (xy 162.179242 -317.607822) (xy 162.205545 -317.566226)
			(xy 162.23818 -317.529389) (xy 162.276301 -317.498264) (xy 162.318922 -317.473657) (xy 162.364938 -317.456205)
			(xy 162.413157 -317.446361) (xy 162.462332 -317.44438) (xy 162.511187 -317.450312) (xy 162.558458 -317.464004)
			(xy 162.60292 -317.485102) (xy 162.643423 -317.513058) (xy 162.678916 -317.54715) (xy 162.708481 -317.586494)
			(xy 162.731352 -317.630071) (xy 162.746936 -317.676752) (xy 162.754831 -317.725329) (xy 162.755326 -317.749936)
			(xy 164.044134 -317.749936) (xy 164.048094 -317.700882) (xy 164.059871 -317.653098) (xy 164.079162 -317.607822)
			(xy 164.105465 -317.566226) (xy 164.1381 -317.529389) (xy 164.176221 -317.498264) (xy 164.218842 -317.473657)
			(xy 164.264858 -317.456205) (xy 164.313077 -317.446361) (xy 164.362252 -317.44438) (xy 164.411107 -317.450312)
			(xy 164.458378 -317.464004) (xy 164.50284 -317.485102) (xy 164.543343 -317.513058) (xy 164.578836 -317.54715)
			(xy 164.608401 -317.586494) (xy 164.631272 -317.630071) (xy 164.646856 -317.676752) (xy 164.654751 -317.725329)
			(xy 164.655246 -317.749936) (xy 165.944054 -317.749936) (xy 165.948014 -317.700882) (xy 165.959791 -317.653098)
			(xy 165.979082 -317.607822) (xy 166.005385 -317.566226) (xy 166.03802 -317.529389) (xy 166.076141 -317.498264)
			(xy 166.118762 -317.473657) (xy 166.164778 -317.456205) (xy 166.212997 -317.446361) (xy 166.262172 -317.44438)
			(xy 166.311027 -317.450312) (xy 166.358298 -317.464004) (xy 166.40276 -317.485102) (xy 166.443263 -317.513058)
			(xy 166.478756 -317.54715) (xy 166.508321 -317.586494) (xy 166.531192 -317.630071) (xy 166.546776 -317.676752)
			(xy 166.554671 -317.725329) (xy 166.555166 -317.749936) (xy 183.044096 -317.749936) (xy 183.048056 -317.700882)
			(xy 183.059833 -317.653098) (xy 183.079124 -317.607822) (xy 183.105427 -317.566226) (xy 183.138062 -317.529389)
			(xy 183.176183 -317.498264) (xy 183.218804 -317.473657) (xy 183.26482 -317.456205) (xy 183.313039 -317.446361)
			(xy 183.362214 -317.44438) (xy 183.411069 -317.450312) (xy 183.45834 -317.464004) (xy 183.502802 -317.485102)
			(xy 183.543305 -317.513058) (xy 183.578798 -317.54715) (xy 183.608363 -317.586494) (xy 183.631234 -317.630071)
			(xy 183.646818 -317.676752) (xy 183.654713 -317.725329) (xy 183.655208 -317.749936) (xy 184.94427 -317.749936)
			(xy 184.94823 -317.700882) (xy 184.960007 -317.653098) (xy 184.979298 -317.607822) (xy 185.005601 -317.566226)
			(xy 185.038236 -317.529389) (xy 185.076357 -317.498264) (xy 185.118978 -317.473657) (xy 185.164994 -317.456205)
			(xy 185.213213 -317.446361) (xy 185.262388 -317.44438) (xy 185.311243 -317.450312) (xy 185.358514 -317.464004)
			(xy 185.402976 -317.485102) (xy 185.443479 -317.513058) (xy 185.478972 -317.54715) (xy 185.508537 -317.586494)
			(xy 185.531408 -317.630071) (xy 185.546992 -317.676752) (xy 185.554887 -317.725329) (xy 185.555382 -317.749936)
			(xy 186.84419 -317.749936) (xy 186.84815 -317.700882) (xy 186.859927 -317.653098) (xy 186.879218 -317.607822)
			(xy 186.905521 -317.566226) (xy 186.938156 -317.529389) (xy 186.976277 -317.498264) (xy 187.018898 -317.473657)
			(xy 187.064914 -317.456205) (xy 187.113133 -317.446361) (xy 187.162308 -317.44438) (xy 187.211163 -317.450312)
			(xy 187.258434 -317.464004) (xy 187.302896 -317.485102) (xy 187.343399 -317.513058) (xy 187.378892 -317.54715)
			(xy 187.408457 -317.586494) (xy 187.431328 -317.630071) (xy 187.446912 -317.676752) (xy 187.454807 -317.725329)
			(xy 187.455302 -317.749936) (xy 188.74411 -317.749936) (xy 188.74807 -317.700882) (xy 188.759847 -317.653098)
			(xy 188.779138 -317.607822) (xy 188.805441 -317.566226) (xy 188.838076 -317.529389) (xy 188.876197 -317.498264)
			(xy 188.918818 -317.473657) (xy 188.964834 -317.456205) (xy 189.013053 -317.446361) (xy 189.062228 -317.44438)
			(xy 189.111083 -317.450312) (xy 189.158354 -317.464004) (xy 189.202816 -317.485102) (xy 189.243319 -317.513058)
			(xy 189.278812 -317.54715) (xy 189.308377 -317.586494) (xy 189.331248 -317.630071) (xy 189.346832 -317.676752)
			(xy 189.354727 -317.725329) (xy 189.355222 -317.749936) (xy 283.944072 -317.749936) (xy 283.948032 -317.700882)
			(xy 283.959809 -317.653098) (xy 283.9791 -317.607822) (xy 284.005403 -317.566226) (xy 284.038038 -317.529389)
			(xy 284.076159 -317.498264) (xy 284.11878 -317.473657) (xy 284.164796 -317.456205) (xy 284.213015 -317.446361)
			(xy 284.26219 -317.44438) (xy 284.311045 -317.450312) (xy 284.358316 -317.464004) (xy 284.402778 -317.485102)
			(xy 284.443281 -317.513058) (xy 284.478774 -317.54715) (xy 284.508339 -317.586494) (xy 284.53121 -317.630071)
			(xy 284.546794 -317.676752) (xy 284.554689 -317.725329) (xy 284.555184 -317.749936) (xy 285.843992 -317.749936)
			(xy 285.847952 -317.700882) (xy 285.859729 -317.653098) (xy 285.87902 -317.607822) (xy 285.905323 -317.566226)
			(xy 285.937958 -317.529389) (xy 285.976079 -317.498264) (xy 286.0187 -317.473657) (xy 286.064716 -317.456205)
			(xy 286.112935 -317.446361) (xy 286.16211 -317.44438) (xy 286.210965 -317.450312) (xy 286.258236 -317.464004)
			(xy 286.302698 -317.485102) (xy 286.343201 -317.513058) (xy 286.378694 -317.54715) (xy 286.408259 -317.586494)
			(xy 286.43113 -317.630071) (xy 286.446714 -317.676752) (xy 286.454609 -317.725329) (xy 286.455104 -317.749936)
			(xy 287.743912 -317.749936) (xy 287.747872 -317.700882) (xy 287.759649 -317.653098) (xy 287.77894 -317.607822)
			(xy 287.805243 -317.566226) (xy 287.837878 -317.529389) (xy 287.875999 -317.498264) (xy 287.91862 -317.473657)
			(xy 287.964636 -317.456205) (xy 288.012855 -317.446361) (xy 288.06203 -317.44438) (xy 288.110885 -317.450312)
			(xy 288.158156 -317.464004) (xy 288.202618 -317.485102) (xy 288.243121 -317.513058) (xy 288.278614 -317.54715)
			(xy 288.308179 -317.586494) (xy 288.33105 -317.630071) (xy 288.346634 -317.676752) (xy 288.354529 -317.725329)
			(xy 288.355024 -317.749936) (xy 289.644086 -317.749936) (xy 289.648046 -317.700882) (xy 289.659823 -317.653098)
			(xy 289.679114 -317.607822) (xy 289.705417 -317.566226) (xy 289.738052 -317.529389) (xy 289.776173 -317.498264)
			(xy 289.818794 -317.473657) (xy 289.86481 -317.456205) (xy 289.913029 -317.446361) (xy 289.962204 -317.44438)
			(xy 290.011059 -317.450312) (xy 290.05833 -317.464004) (xy 290.102792 -317.485102) (xy 290.143295 -317.513058)
			(xy 290.178788 -317.54715) (xy 290.208353 -317.586494) (xy 290.231224 -317.630071) (xy 290.246808 -317.676752)
			(xy 290.254703 -317.725329) (xy 290.255198 -317.749936) (xy 291.544006 -317.749936) (xy 291.547966 -317.700882)
			(xy 291.559743 -317.653098) (xy 291.579034 -317.607822) (xy 291.605337 -317.566226) (xy 291.637972 -317.529389)
			(xy 291.676093 -317.498264) (xy 291.718714 -317.473657) (xy 291.76473 -317.456205) (xy 291.812949 -317.446361)
			(xy 291.862124 -317.44438) (xy 291.910979 -317.450312) (xy 291.95825 -317.464004) (xy 292.002712 -317.485102)
			(xy 292.043215 -317.513058) (xy 292.078708 -317.54715) (xy 292.108273 -317.586494) (xy 292.131144 -317.630071)
			(xy 292.146728 -317.676752) (xy 292.154623 -317.725329) (xy 292.155118 -317.749936) (xy 293.443926 -317.749936)
			(xy 293.447886 -317.700882) (xy 293.459663 -317.653098) (xy 293.478954 -317.607822) (xy 293.505257 -317.566226)
			(xy 293.537892 -317.529389) (xy 293.576013 -317.498264) (xy 293.618634 -317.473657) (xy 293.66465 -317.456205)
			(xy 293.712869 -317.446361) (xy 293.762044 -317.44438) (xy 293.810899 -317.450312) (xy 293.85817 -317.464004)
			(xy 293.902632 -317.485102) (xy 293.943135 -317.513058) (xy 293.978628 -317.54715) (xy 294.008193 -317.586494)
			(xy 294.031064 -317.630071) (xy 294.046648 -317.676752) (xy 294.054543 -317.725329) (xy 294.055038 -317.749936)
			(xy 295.3441 -317.749936) (xy 295.34806 -317.700882) (xy 295.359837 -317.653098) (xy 295.379128 -317.607822)
			(xy 295.405431 -317.566226) (xy 295.438066 -317.529389) (xy 295.476187 -317.498264) (xy 295.518808 -317.473657)
			(xy 295.564824 -317.456205) (xy 295.613043 -317.446361) (xy 295.662218 -317.44438) (xy 295.711073 -317.450312)
			(xy 295.758344 -317.464004) (xy 295.802806 -317.485102) (xy 295.843309 -317.513058) (xy 295.878802 -317.54715)
			(xy 295.908367 -317.586494) (xy 295.931238 -317.630071) (xy 295.946822 -317.676752) (xy 295.954717 -317.725329)
			(xy 295.955212 -317.749936) (xy 297.24402 -317.749936) (xy 297.24798 -317.700882) (xy 297.259757 -317.653098)
			(xy 297.279048 -317.607822) (xy 297.305351 -317.566226) (xy 297.337986 -317.529389) (xy 297.376107 -317.498264)
			(xy 297.418728 -317.473657) (xy 297.464744 -317.456205) (xy 297.512963 -317.446361) (xy 297.562138 -317.44438)
			(xy 297.610993 -317.450312) (xy 297.658264 -317.464004) (xy 297.702726 -317.485102) (xy 297.743229 -317.513058)
			(xy 297.778722 -317.54715) (xy 297.808287 -317.586494) (xy 297.831158 -317.630071) (xy 297.846742 -317.676752)
			(xy 297.854637 -317.725329) (xy 297.855132 -317.749936) (xy 306.744128 -317.749936) (xy 306.748088 -317.700882)
			(xy 306.759865 -317.653098) (xy 306.779156 -317.607822) (xy 306.805459 -317.566226) (xy 306.838094 -317.529389)
			(xy 306.876215 -317.498264) (xy 306.918836 -317.473657) (xy 306.964852 -317.456205) (xy 307.013071 -317.446361)
			(xy 307.062246 -317.44438) (xy 307.111101 -317.450312) (xy 307.158372 -317.464004) (xy 307.202834 -317.485102)
			(xy 307.243337 -317.513058) (xy 307.27883 -317.54715) (xy 307.308395 -317.586494) (xy 307.331266 -317.630071)
			(xy 307.34685 -317.676752) (xy 307.354745 -317.725329) (xy 307.35524 -317.749936) (xy 308.644048 -317.749936)
			(xy 308.648008 -317.700882) (xy 308.659785 -317.653098) (xy 308.679076 -317.607822) (xy 308.705379 -317.566226)
			(xy 308.738014 -317.529389) (xy 308.776135 -317.498264) (xy 308.818756 -317.473657) (xy 308.864772 -317.456205)
			(xy 308.912991 -317.446361) (xy 308.962166 -317.44438) (xy 309.011021 -317.450312) (xy 309.058292 -317.464004)
			(xy 309.102754 -317.485102) (xy 309.143257 -317.513058) (xy 309.17875 -317.54715) (xy 309.208315 -317.586494)
			(xy 309.231186 -317.630071) (xy 309.24677 -317.676752) (xy 309.254665 -317.725329) (xy 309.25516 -317.749936)
			(xy 310.543968 -317.749936) (xy 310.547928 -317.700882) (xy 310.559705 -317.653098) (xy 310.578996 -317.607822)
			(xy 310.605299 -317.566226) (xy 310.637934 -317.529389) (xy 310.676055 -317.498264) (xy 310.718676 -317.473657)
			(xy 310.764692 -317.456205) (xy 310.812911 -317.446361) (xy 310.862086 -317.44438) (xy 310.910941 -317.450312)
			(xy 310.958212 -317.464004) (xy 311.002674 -317.485102) (xy 311.043177 -317.513058) (xy 311.07867 -317.54715)
			(xy 311.108235 -317.586494) (xy 311.131106 -317.630071) (xy 311.14669 -317.676752) (xy 311.154585 -317.725329)
			(xy 311.15508 -317.749936) (xy 312.443888 -317.749936) (xy 312.447848 -317.700882) (xy 312.459625 -317.653098)
			(xy 312.478916 -317.607822) (xy 312.505219 -317.566226) (xy 312.537854 -317.529389) (xy 312.575975 -317.498264)
			(xy 312.618596 -317.473657) (xy 312.664612 -317.456205) (xy 312.712831 -317.446361) (xy 312.762006 -317.44438)
			(xy 312.810861 -317.450312) (xy 312.858132 -317.464004) (xy 312.902594 -317.485102) (xy 312.943097 -317.513058)
			(xy 312.97859 -317.54715) (xy 313.008155 -317.586494) (xy 313.031026 -317.630071) (xy 313.04661 -317.676752)
			(xy 313.054505 -317.725329) (xy 313.055 -317.749936) (xy 386.744222 -317.749936) (xy 386.748182 -317.700882)
			(xy 386.759959 -317.653098) (xy 386.77925 -317.607822) (xy 386.805553 -317.566226) (xy 386.838188 -317.529389)
			(xy 386.876309 -317.498264) (xy 386.91893 -317.473657) (xy 386.964946 -317.456205) (xy 387.013165 -317.446361)
			(xy 387.06234 -317.44438) (xy 387.111195 -317.450312) (xy 387.158466 -317.464004) (xy 387.202928 -317.485102)
			(xy 387.243431 -317.513058) (xy 387.278924 -317.54715) (xy 387.308489 -317.586494) (xy 387.33136 -317.630071)
			(xy 387.346944 -317.676752) (xy 387.354839 -317.725329) (xy 387.355334 -317.749936) (xy 388.644142 -317.749936)
			(xy 388.648102 -317.700882) (xy 388.659879 -317.653098) (xy 388.67917 -317.607822) (xy 388.705473 -317.566226)
			(xy 388.738108 -317.529389) (xy 388.776229 -317.498264) (xy 388.81885 -317.473657) (xy 388.864866 -317.456205)
			(xy 388.913085 -317.446361) (xy 388.96226 -317.44438) (xy 389.011115 -317.450312) (xy 389.058386 -317.464004)
			(xy 389.102848 -317.485102) (xy 389.143351 -317.513058) (xy 389.178844 -317.54715) (xy 389.208409 -317.586494)
			(xy 389.23128 -317.630071) (xy 389.246864 -317.676752) (xy 389.254759 -317.725329) (xy 389.255254 -317.749936)
			(xy 390.544062 -317.749936) (xy 390.548022 -317.700882) (xy 390.559799 -317.653098) (xy 390.57909 -317.607822)
			(xy 390.605393 -317.566226) (xy 390.638028 -317.529389) (xy 390.676149 -317.498264) (xy 390.71877 -317.473657)
			(xy 390.764786 -317.456205) (xy 390.813005 -317.446361) (xy 390.86218 -317.44438) (xy 390.911035 -317.450312)
			(xy 390.958306 -317.464004) (xy 391.002768 -317.485102) (xy 391.043271 -317.513058) (xy 391.078764 -317.54715)
			(xy 391.108329 -317.586494) (xy 391.1312 -317.630071) (xy 391.146784 -317.676752) (xy 391.154679 -317.725329)
			(xy 391.155174 -317.749936) (xy 392.443982 -317.749936) (xy 392.447942 -317.700882) (xy 392.459719 -317.653098)
			(xy 392.47901 -317.607822) (xy 392.505313 -317.566226) (xy 392.537948 -317.529389) (xy 392.576069 -317.498264)
			(xy 392.61869 -317.473657) (xy 392.664706 -317.456205) (xy 392.712925 -317.446361) (xy 392.7621 -317.44438)
			(xy 392.810955 -317.450312) (xy 392.858226 -317.464004) (xy 392.902688 -317.485102) (xy 392.943191 -317.513058)
			(xy 392.978684 -317.54715) (xy 393.008249 -317.586494) (xy 393.03112 -317.630071) (xy 393.046704 -317.676752)
			(xy 393.054599 -317.725329) (xy 393.055094 -317.749936) (xy 394.344156 -317.749936) (xy 394.348116 -317.700882)
			(xy 394.359893 -317.653098) (xy 394.379184 -317.607822) (xy 394.405487 -317.566226) (xy 394.438122 -317.529389)
			(xy 394.476243 -317.498264) (xy 394.518864 -317.473657) (xy 394.56488 -317.456205) (xy 394.613099 -317.446361)
			(xy 394.662274 -317.44438) (xy 394.711129 -317.450312) (xy 394.7584 -317.464004) (xy 394.802862 -317.485102)
			(xy 394.843365 -317.513058) (xy 394.878858 -317.54715) (xy 394.908423 -317.586494) (xy 394.931294 -317.630071)
			(xy 394.946878 -317.676752) (xy 394.954773 -317.725329) (xy 394.955268 -317.749936) (xy 396.244076 -317.749936)
			(xy 396.248036 -317.700882) (xy 396.259813 -317.653098) (xy 396.279104 -317.607822) (xy 396.305407 -317.566226)
			(xy 396.338042 -317.529389) (xy 396.376163 -317.498264) (xy 396.418784 -317.473657) (xy 396.4648 -317.456205)
			(xy 396.513019 -317.446361) (xy 396.562194 -317.44438) (xy 396.611049 -317.450312) (xy 396.65832 -317.464004)
			(xy 396.702782 -317.485102) (xy 396.743285 -317.513058) (xy 396.778778 -317.54715) (xy 396.808343 -317.586494)
			(xy 396.831214 -317.630071) (xy 396.846798 -317.676752) (xy 396.854693 -317.725329) (xy 396.855188 -317.749936)
			(xy 398.143996 -317.749936) (xy 398.147956 -317.700882) (xy 398.159733 -317.653098) (xy 398.179024 -317.607822)
			(xy 398.205327 -317.566226) (xy 398.237962 -317.529389) (xy 398.276083 -317.498264) (xy 398.318704 -317.473657)
			(xy 398.36472 -317.456205) (xy 398.412939 -317.446361) (xy 398.462114 -317.44438) (xy 398.510969 -317.450312)
			(xy 398.55824 -317.464004) (xy 398.602702 -317.485102) (xy 398.643205 -317.513058) (xy 398.678698 -317.54715)
			(xy 398.708263 -317.586494) (xy 398.731134 -317.630071) (xy 398.746718 -317.676752) (xy 398.754613 -317.725329)
			(xy 398.755108 -317.749936) (xy 415.244038 -317.749936) (xy 415.247998 -317.700882) (xy 415.259775 -317.653098)
			(xy 415.279066 -317.607822) (xy 415.305369 -317.566226) (xy 415.338004 -317.529389) (xy 415.376125 -317.498264)
			(xy 415.418746 -317.473657) (xy 415.464762 -317.456205) (xy 415.512981 -317.446361) (xy 415.562156 -317.44438)
			(xy 415.611011 -317.450312) (xy 415.658282 -317.464004) (xy 415.702744 -317.485102) (xy 415.743247 -317.513058)
			(xy 415.77874 -317.54715) (xy 415.808305 -317.586494) (xy 415.831176 -317.630071) (xy 415.84676 -317.676752)
			(xy 415.854655 -317.725329) (xy 415.85515 -317.749936) (xy 417.144212 -317.749936) (xy 417.148172 -317.700882)
			(xy 417.159949 -317.653098) (xy 417.17924 -317.607822) (xy 417.205543 -317.566226) (xy 417.238178 -317.529389)
			(xy 417.276299 -317.498264) (xy 417.31892 -317.473657) (xy 417.364936 -317.456205) (xy 417.413155 -317.446361)
			(xy 417.46233 -317.44438) (xy 417.511185 -317.450312) (xy 417.558456 -317.464004) (xy 417.602918 -317.485102)
			(xy 417.643421 -317.513058) (xy 417.678914 -317.54715) (xy 417.708479 -317.586494) (xy 417.73135 -317.630071)
			(xy 417.746934 -317.676752) (xy 417.754829 -317.725329) (xy 417.755324 -317.749936) (xy 419.044132 -317.749936)
			(xy 419.048092 -317.700882) (xy 419.059869 -317.653098) (xy 419.07916 -317.607822) (xy 419.105463 -317.566226)
			(xy 419.138098 -317.529389) (xy 419.176219 -317.498264) (xy 419.21884 -317.473657) (xy 419.264856 -317.456205)
			(xy 419.313075 -317.446361) (xy 419.36225 -317.44438) (xy 419.411105 -317.450312) (xy 419.458376 -317.464004)
			(xy 419.502838 -317.485102) (xy 419.543341 -317.513058) (xy 419.578834 -317.54715) (xy 419.608399 -317.586494)
			(xy 419.63127 -317.630071) (xy 419.646854 -317.676752) (xy 419.654749 -317.725329) (xy 419.655244 -317.749936)
			(xy 420.944052 -317.749936) (xy 420.948012 -317.700882) (xy 420.959789 -317.653098) (xy 420.97908 -317.607822)
			(xy 421.005383 -317.566226) (xy 421.038018 -317.529389) (xy 421.076139 -317.498264) (xy 421.11876 -317.473657)
			(xy 421.164776 -317.456205) (xy 421.212995 -317.446361) (xy 421.26217 -317.44438) (xy 421.311025 -317.450312)
			(xy 421.358296 -317.464004) (xy 421.402758 -317.485102) (xy 421.443261 -317.513058) (xy 421.478754 -317.54715)
			(xy 421.508319 -317.586494) (xy 421.53119 -317.630071) (xy 421.546774 -317.676752) (xy 421.554669 -317.725329)
			(xy 421.555164 -317.749936) (xy 421.554669 -317.774543) (xy 421.546774 -317.82312) (xy 421.53119 -317.869801)
			(xy 421.508319 -317.913378) (xy 421.478754 -317.952722) (xy 421.443261 -317.986814) (xy 421.402758 -318.01477)
			(xy 421.358296 -318.035868) (xy 421.311025 -318.04956) (xy 421.26217 -318.055492) (xy 421.212995 -318.053511)
			(xy 421.164776 -318.043667) (xy 421.11876 -318.026215) (xy 421.076139 -318.001608) (xy 421.038018 -317.970483)
			(xy 421.005383 -317.933646) (xy 420.97908 -317.89205) (xy 420.959789 -317.846774) (xy 420.948012 -317.79899)
			(xy 420.944052 -317.749936) (xy 419.655244 -317.749936) (xy 419.654749 -317.774543) (xy 419.646854 -317.82312)
			(xy 419.63127 -317.869801) (xy 419.608399 -317.913378) (xy 419.578834 -317.952722) (xy 419.543341 -317.986814)
			(xy 419.502838 -318.01477) (xy 419.458376 -318.035868) (xy 419.411105 -318.04956) (xy 419.36225 -318.055492)
			(xy 419.313075 -318.053511) (xy 419.264856 -318.043667) (xy 419.21884 -318.026215) (xy 419.176219 -318.001608)
			(xy 419.138098 -317.970483) (xy 419.105463 -317.933646) (xy 419.07916 -317.89205) (xy 419.059869 -317.846774)
			(xy 419.048092 -317.79899) (xy 419.044132 -317.749936) (xy 417.755324 -317.749936) (xy 417.754829 -317.774543)
			(xy 417.746934 -317.82312) (xy 417.73135 -317.869801) (xy 417.708479 -317.913378) (xy 417.678914 -317.952722)
			(xy 417.643421 -317.986814) (xy 417.602918 -318.01477) (xy 417.558456 -318.035868) (xy 417.511185 -318.04956)
			(xy 417.46233 -318.055492) (xy 417.413155 -318.053511) (xy 417.364936 -318.043667) (xy 417.31892 -318.026215)
			(xy 417.276299 -318.001608) (xy 417.238178 -317.970483) (xy 417.205543 -317.933646) (xy 417.17924 -317.89205)
			(xy 417.159949 -317.846774) (xy 417.148172 -317.79899) (xy 417.144212 -317.749936) (xy 415.85515 -317.749936)
			(xy 415.854655 -317.774543) (xy 415.84676 -317.82312) (xy 415.831176 -317.869801) (xy 415.808305 -317.913378)
			(xy 415.77874 -317.952722) (xy 415.743247 -317.986814) (xy 415.702744 -318.01477) (xy 415.658282 -318.035868)
			(xy 415.611011 -318.04956) (xy 415.562156 -318.055492) (xy 415.512981 -318.053511) (xy 415.464762 -318.043667)
			(xy 415.418746 -318.026215) (xy 415.376125 -318.001608) (xy 415.338004 -317.970483) (xy 415.305369 -317.933646)
			(xy 415.279066 -317.89205) (xy 415.259775 -317.846774) (xy 415.247998 -317.79899) (xy 415.244038 -317.749936)
			(xy 398.755108 -317.749936) (xy 398.754613 -317.774543) (xy 398.746718 -317.82312) (xy 398.731134 -317.869801)
			(xy 398.708263 -317.913378) (xy 398.678698 -317.952722) (xy 398.643205 -317.986814) (xy 398.602702 -318.01477)
			(xy 398.55824 -318.035868) (xy 398.510969 -318.04956) (xy 398.462114 -318.055492) (xy 398.412939 -318.053511)
			(xy 398.36472 -318.043667) (xy 398.318704 -318.026215) (xy 398.276083 -318.001608) (xy 398.237962 -317.970483)
			(xy 398.205327 -317.933646) (xy 398.179024 -317.89205) (xy 398.159733 -317.846774) (xy 398.147956 -317.79899)
			(xy 398.143996 -317.749936) (xy 396.855188 -317.749936) (xy 396.854693 -317.774543) (xy 396.846798 -317.82312)
			(xy 396.831214 -317.869801) (xy 396.808343 -317.913378) (xy 396.778778 -317.952722) (xy 396.743285 -317.986814)
			(xy 396.702782 -318.01477) (xy 396.65832 -318.035868) (xy 396.611049 -318.04956) (xy 396.562194 -318.055492)
			(xy 396.513019 -318.053511) (xy 396.4648 -318.043667) (xy 396.418784 -318.026215) (xy 396.376163 -318.001608)
			(xy 396.338042 -317.970483) (xy 396.305407 -317.933646) (xy 396.279104 -317.89205) (xy 396.259813 -317.846774)
			(xy 396.248036 -317.79899) (xy 396.244076 -317.749936) (xy 394.955268 -317.749936) (xy 394.954773 -317.774543)
			(xy 394.946878 -317.82312) (xy 394.931294 -317.869801) (xy 394.908423 -317.913378) (xy 394.878858 -317.952722)
			(xy 394.843365 -317.986814) (xy 394.802862 -318.01477) (xy 394.7584 -318.035868) (xy 394.711129 -318.04956)
			(xy 394.662274 -318.055492) (xy 394.613099 -318.053511) (xy 394.56488 -318.043667) (xy 394.518864 -318.026215)
			(xy 394.476243 -318.001608) (xy 394.438122 -317.970483) (xy 394.405487 -317.933646) (xy 394.379184 -317.89205)
			(xy 394.359893 -317.846774) (xy 394.348116 -317.79899) (xy 394.344156 -317.749936) (xy 393.055094 -317.749936)
			(xy 393.054599 -317.774543) (xy 393.046704 -317.82312) (xy 393.03112 -317.869801) (xy 393.008249 -317.913378)
			(xy 392.978684 -317.952722) (xy 392.943191 -317.986814) (xy 392.902688 -318.01477) (xy 392.858226 -318.035868)
			(xy 392.810955 -318.04956) (xy 392.7621 -318.055492) (xy 392.712925 -318.053511) (xy 392.664706 -318.043667)
			(xy 392.61869 -318.026215) (xy 392.576069 -318.001608) (xy 392.537948 -317.970483) (xy 392.505313 -317.933646)
			(xy 392.47901 -317.89205) (xy 392.459719 -317.846774) (xy 392.447942 -317.79899) (xy 392.443982 -317.749936)
			(xy 391.155174 -317.749936) (xy 391.154679 -317.774543) (xy 391.146784 -317.82312) (xy 391.1312 -317.869801)
			(xy 391.108329 -317.913378) (xy 391.078764 -317.952722) (xy 391.043271 -317.986814) (xy 391.002768 -318.01477)
			(xy 390.958306 -318.035868) (xy 390.911035 -318.04956) (xy 390.86218 -318.055492) (xy 390.813005 -318.053511)
			(xy 390.764786 -318.043667) (xy 390.71877 -318.026215) (xy 390.676149 -318.001608) (xy 390.638028 -317.970483)
			(xy 390.605393 -317.933646) (xy 390.57909 -317.89205) (xy 390.559799 -317.846774) (xy 390.548022 -317.79899)
			(xy 390.544062 -317.749936) (xy 389.255254 -317.749936) (xy 389.254759 -317.774543) (xy 389.246864 -317.82312)
			(xy 389.23128 -317.869801) (xy 389.208409 -317.913378) (xy 389.178844 -317.952722) (xy 389.143351 -317.986814)
			(xy 389.102848 -318.01477) (xy 389.058386 -318.035868) (xy 389.011115 -318.04956) (xy 388.96226 -318.055492)
			(xy 388.913085 -318.053511) (xy 388.864866 -318.043667) (xy 388.81885 -318.026215) (xy 388.776229 -318.001608)
			(xy 388.738108 -317.970483) (xy 388.705473 -317.933646) (xy 388.67917 -317.89205) (xy 388.659879 -317.846774)
			(xy 388.648102 -317.79899) (xy 388.644142 -317.749936) (xy 387.355334 -317.749936) (xy 387.354839 -317.774543)
			(xy 387.346944 -317.82312) (xy 387.33136 -317.869801) (xy 387.308489 -317.913378) (xy 387.278924 -317.952722)
			(xy 387.243431 -317.986814) (xy 387.202928 -318.01477) (xy 387.158466 -318.035868) (xy 387.111195 -318.04956)
			(xy 387.06234 -318.055492) (xy 387.013165 -318.053511) (xy 386.964946 -318.043667) (xy 386.91893 -318.026215)
			(xy 386.876309 -318.001608) (xy 386.838188 -317.970483) (xy 386.805553 -317.933646) (xy 386.77925 -317.89205)
			(xy 386.759959 -317.846774) (xy 386.748182 -317.79899) (xy 386.744222 -317.749936) (xy 313.055 -317.749936)
			(xy 313.054505 -317.774543) (xy 313.04661 -317.82312) (xy 313.031026 -317.869801) (xy 313.008155 -317.913378)
			(xy 312.97859 -317.952722) (xy 312.943097 -317.986814) (xy 312.902594 -318.01477) (xy 312.858132 -318.035868)
			(xy 312.810861 -318.04956) (xy 312.762006 -318.055492) (xy 312.712831 -318.053511) (xy 312.664612 -318.043667)
			(xy 312.618596 -318.026215) (xy 312.575975 -318.001608) (xy 312.537854 -317.970483) (xy 312.505219 -317.933646)
			(xy 312.478916 -317.89205) (xy 312.459625 -317.846774) (xy 312.447848 -317.79899) (xy 312.443888 -317.749936)
			(xy 311.15508 -317.749936) (xy 311.154585 -317.774543) (xy 311.14669 -317.82312) (xy 311.131106 -317.869801)
			(xy 311.108235 -317.913378) (xy 311.07867 -317.952722) (xy 311.043177 -317.986814) (xy 311.002674 -318.01477)
			(xy 310.958212 -318.035868) (xy 310.910941 -318.04956) (xy 310.862086 -318.055492) (xy 310.812911 -318.053511)
			(xy 310.764692 -318.043667) (xy 310.718676 -318.026215) (xy 310.676055 -318.001608) (xy 310.637934 -317.970483)
			(xy 310.605299 -317.933646) (xy 310.578996 -317.89205) (xy 310.559705 -317.846774) (xy 310.547928 -317.79899)
			(xy 310.543968 -317.749936) (xy 309.25516 -317.749936) (xy 309.254665 -317.774543) (xy 309.24677 -317.82312)
			(xy 309.231186 -317.869801) (xy 309.208315 -317.913378) (xy 309.17875 -317.952722) (xy 309.143257 -317.986814)
			(xy 309.102754 -318.01477) (xy 309.058292 -318.035868) (xy 309.011021 -318.04956) (xy 308.962166 -318.055492)
			(xy 308.912991 -318.053511) (xy 308.864772 -318.043667) (xy 308.818756 -318.026215) (xy 308.776135 -318.001608)
			(xy 308.738014 -317.970483) (xy 308.705379 -317.933646) (xy 308.679076 -317.89205) (xy 308.659785 -317.846774)
			(xy 308.648008 -317.79899) (xy 308.644048 -317.749936) (xy 307.35524 -317.749936) (xy 307.354745 -317.774543)
			(xy 307.34685 -317.82312) (xy 307.331266 -317.869801) (xy 307.308395 -317.913378) (xy 307.27883 -317.952722)
			(xy 307.243337 -317.986814) (xy 307.202834 -318.01477) (xy 307.158372 -318.035868) (xy 307.111101 -318.04956)
			(xy 307.062246 -318.055492) (xy 307.013071 -318.053511) (xy 306.964852 -318.043667) (xy 306.918836 -318.026215)
			(xy 306.876215 -318.001608) (xy 306.838094 -317.970483) (xy 306.805459 -317.933646) (xy 306.779156 -317.89205)
			(xy 306.759865 -317.846774) (xy 306.748088 -317.79899) (xy 306.744128 -317.749936) (xy 297.855132 -317.749936)
			(xy 297.854637 -317.774543) (xy 297.846742 -317.82312) (xy 297.831158 -317.869801) (xy 297.808287 -317.913378)
			(xy 297.778722 -317.952722) (xy 297.743229 -317.986814) (xy 297.702726 -318.01477) (xy 297.658264 -318.035868)
			(xy 297.610993 -318.04956) (xy 297.562138 -318.055492) (xy 297.512963 -318.053511) (xy 297.464744 -318.043667)
			(xy 297.418728 -318.026215) (xy 297.376107 -318.001608) (xy 297.337986 -317.970483) (xy 297.305351 -317.933646)
			(xy 297.279048 -317.89205) (xy 297.259757 -317.846774) (xy 297.24798 -317.79899) (xy 297.24402 -317.749936)
			(xy 295.955212 -317.749936) (xy 295.954717 -317.774543) (xy 295.946822 -317.82312) (xy 295.931238 -317.869801)
			(xy 295.908367 -317.913378) (xy 295.878802 -317.952722) (xy 295.843309 -317.986814) (xy 295.802806 -318.01477)
			(xy 295.758344 -318.035868) (xy 295.711073 -318.04956) (xy 295.662218 -318.055492) (xy 295.613043 -318.053511)
			(xy 295.564824 -318.043667) (xy 295.518808 -318.026215) (xy 295.476187 -318.001608) (xy 295.438066 -317.970483)
			(xy 295.405431 -317.933646) (xy 295.379128 -317.89205) (xy 295.359837 -317.846774) (xy 295.34806 -317.79899)
			(xy 295.3441 -317.749936) (xy 294.055038 -317.749936) (xy 294.054543 -317.774543) (xy 294.046648 -317.82312)
			(xy 294.031064 -317.869801) (xy 294.008193 -317.913378) (xy 293.978628 -317.952722) (xy 293.943135 -317.986814)
			(xy 293.902632 -318.01477) (xy 293.85817 -318.035868) (xy 293.810899 -318.04956) (xy 293.762044 -318.055492)
			(xy 293.712869 -318.053511) (xy 293.66465 -318.043667) (xy 293.618634 -318.026215) (xy 293.576013 -318.001608)
			(xy 293.537892 -317.970483) (xy 293.505257 -317.933646) (xy 293.478954 -317.89205) (xy 293.459663 -317.846774)
			(xy 293.447886 -317.79899) (xy 293.443926 -317.749936) (xy 292.155118 -317.749936) (xy 292.154623 -317.774543)
			(xy 292.146728 -317.82312) (xy 292.131144 -317.869801) (xy 292.108273 -317.913378) (xy 292.078708 -317.952722)
			(xy 292.043215 -317.986814) (xy 292.002712 -318.01477) (xy 291.95825 -318.035868) (xy 291.910979 -318.04956)
			(xy 291.862124 -318.055492) (xy 291.812949 -318.053511) (xy 291.76473 -318.043667) (xy 291.718714 -318.026215)
			(xy 291.676093 -318.001608) (xy 291.637972 -317.970483) (xy 291.605337 -317.933646) (xy 291.579034 -317.89205)
			(xy 291.559743 -317.846774) (xy 291.547966 -317.79899) (xy 291.544006 -317.749936) (xy 290.255198 -317.749936)
			(xy 290.254703 -317.774543) (xy 290.246808 -317.82312) (xy 290.231224 -317.869801) (xy 290.208353 -317.913378)
			(xy 290.178788 -317.952722) (xy 290.143295 -317.986814) (xy 290.102792 -318.01477) (xy 290.05833 -318.035868)
			(xy 290.011059 -318.04956) (xy 289.962204 -318.055492) (xy 289.913029 -318.053511) (xy 289.86481 -318.043667)
			(xy 289.818794 -318.026215) (xy 289.776173 -318.001608) (xy 289.738052 -317.970483) (xy 289.705417 -317.933646)
			(xy 289.679114 -317.89205) (xy 289.659823 -317.846774) (xy 289.648046 -317.79899) (xy 289.644086 -317.749936)
			(xy 288.355024 -317.749936) (xy 288.354529 -317.774543) (xy 288.346634 -317.82312) (xy 288.33105 -317.869801)
			(xy 288.308179 -317.913378) (xy 288.278614 -317.952722) (xy 288.243121 -317.986814) (xy 288.202618 -318.01477)
			(xy 288.158156 -318.035868) (xy 288.110885 -318.04956) (xy 288.06203 -318.055492) (xy 288.012855 -318.053511)
			(xy 287.964636 -318.043667) (xy 287.91862 -318.026215) (xy 287.875999 -318.001608) (xy 287.837878 -317.970483)
			(xy 287.805243 -317.933646) (xy 287.77894 -317.89205) (xy 287.759649 -317.846774) (xy 287.747872 -317.79899)
			(xy 287.743912 -317.749936) (xy 286.455104 -317.749936) (xy 286.454609 -317.774543) (xy 286.446714 -317.82312)
			(xy 286.43113 -317.869801) (xy 286.408259 -317.913378) (xy 286.378694 -317.952722) (xy 286.343201 -317.986814)
			(xy 286.302698 -318.01477) (xy 286.258236 -318.035868) (xy 286.210965 -318.04956) (xy 286.16211 -318.055492)
			(xy 286.112935 -318.053511) (xy 286.064716 -318.043667) (xy 286.0187 -318.026215) (xy 285.976079 -318.001608)
			(xy 285.937958 -317.970483) (xy 285.905323 -317.933646) (xy 285.87902 -317.89205) (xy 285.859729 -317.846774)
			(xy 285.847952 -317.79899) (xy 285.843992 -317.749936) (xy 284.555184 -317.749936) (xy 284.554689 -317.774543)
			(xy 284.546794 -317.82312) (xy 284.53121 -317.869801) (xy 284.508339 -317.913378) (xy 284.478774 -317.952722)
			(xy 284.443281 -317.986814) (xy 284.402778 -318.01477) (xy 284.358316 -318.035868) (xy 284.311045 -318.04956)
			(xy 284.26219 -318.055492) (xy 284.213015 -318.053511) (xy 284.164796 -318.043667) (xy 284.11878 -318.026215)
			(xy 284.076159 -318.001608) (xy 284.038038 -317.970483) (xy 284.005403 -317.933646) (xy 283.9791 -317.89205)
			(xy 283.959809 -317.846774) (xy 283.948032 -317.79899) (xy 283.944072 -317.749936) (xy 189.355222 -317.749936)
			(xy 189.354727 -317.774543) (xy 189.346832 -317.82312) (xy 189.331248 -317.869801) (xy 189.308377 -317.913378)
			(xy 189.278812 -317.952722) (xy 189.243319 -317.986814) (xy 189.202816 -318.01477) (xy 189.158354 -318.035868)
			(xy 189.111083 -318.04956) (xy 189.062228 -318.055492) (xy 189.013053 -318.053511) (xy 188.964834 -318.043667)
			(xy 188.918818 -318.026215) (xy 188.876197 -318.001608) (xy 188.838076 -317.970483) (xy 188.805441 -317.933646)
			(xy 188.779138 -317.89205) (xy 188.759847 -317.846774) (xy 188.74807 -317.79899) (xy 188.74411 -317.749936)
			(xy 187.455302 -317.749936) (xy 187.454807 -317.774543) (xy 187.446912 -317.82312) (xy 187.431328 -317.869801)
			(xy 187.408457 -317.913378) (xy 187.378892 -317.952722) (xy 187.343399 -317.986814) (xy 187.302896 -318.01477)
			(xy 187.258434 -318.035868) (xy 187.211163 -318.04956) (xy 187.162308 -318.055492) (xy 187.113133 -318.053511)
			(xy 187.064914 -318.043667) (xy 187.018898 -318.026215) (xy 186.976277 -318.001608) (xy 186.938156 -317.970483)
			(xy 186.905521 -317.933646) (xy 186.879218 -317.89205) (xy 186.859927 -317.846774) (xy 186.84815 -317.79899)
			(xy 186.84419 -317.749936) (xy 185.555382 -317.749936) (xy 185.554887 -317.774543) (xy 185.546992 -317.82312)
			(xy 185.531408 -317.869801) (xy 185.508537 -317.913378) (xy 185.478972 -317.952722) (xy 185.443479 -317.986814)
			(xy 185.402976 -318.01477) (xy 185.358514 -318.035868) (xy 185.311243 -318.04956) (xy 185.262388 -318.055492)
			(xy 185.213213 -318.053511) (xy 185.164994 -318.043667) (xy 185.118978 -318.026215) (xy 185.076357 -318.001608)
			(xy 185.038236 -317.970483) (xy 185.005601 -317.933646) (xy 184.979298 -317.89205) (xy 184.960007 -317.846774)
			(xy 184.94823 -317.79899) (xy 184.94427 -317.749936) (xy 183.655208 -317.749936) (xy 183.654713 -317.774543)
			(xy 183.646818 -317.82312) (xy 183.631234 -317.869801) (xy 183.608363 -317.913378) (xy 183.578798 -317.952722)
			(xy 183.543305 -317.986814) (xy 183.502802 -318.01477) (xy 183.45834 -318.035868) (xy 183.411069 -318.04956)
			(xy 183.362214 -318.055492) (xy 183.313039 -318.053511) (xy 183.26482 -318.043667) (xy 183.218804 -318.026215)
			(xy 183.176183 -318.001608) (xy 183.138062 -317.970483) (xy 183.105427 -317.933646) (xy 183.079124 -317.89205)
			(xy 183.059833 -317.846774) (xy 183.048056 -317.79899) (xy 183.044096 -317.749936) (xy 166.555166 -317.749936)
			(xy 166.554671 -317.774543) (xy 166.546776 -317.82312) (xy 166.531192 -317.869801) (xy 166.508321 -317.913378)
			(xy 166.478756 -317.952722) (xy 166.443263 -317.986814) (xy 166.40276 -318.01477) (xy 166.358298 -318.035868)
			(xy 166.311027 -318.04956) (xy 166.262172 -318.055492) (xy 166.212997 -318.053511) (xy 166.164778 -318.043667)
			(xy 166.118762 -318.026215) (xy 166.076141 -318.001608) (xy 166.03802 -317.970483) (xy 166.005385 -317.933646)
			(xy 165.979082 -317.89205) (xy 165.959791 -317.846774) (xy 165.948014 -317.79899) (xy 165.944054 -317.749936)
			(xy 164.655246 -317.749936) (xy 164.654751 -317.774543) (xy 164.646856 -317.82312) (xy 164.631272 -317.869801)
			(xy 164.608401 -317.913378) (xy 164.578836 -317.952722) (xy 164.543343 -317.986814) (xy 164.50284 -318.01477)
			(xy 164.458378 -318.035868) (xy 164.411107 -318.04956) (xy 164.362252 -318.055492) (xy 164.313077 -318.053511)
			(xy 164.264858 -318.043667) (xy 164.218842 -318.026215) (xy 164.176221 -318.001608) (xy 164.1381 -317.970483)
			(xy 164.105465 -317.933646) (xy 164.079162 -317.89205) (xy 164.059871 -317.846774) (xy 164.048094 -317.79899)
			(xy 164.044134 -317.749936) (xy 162.755326 -317.749936) (xy 162.754831 -317.774543) (xy 162.746936 -317.82312)
			(xy 162.731352 -317.869801) (xy 162.708481 -317.913378) (xy 162.678916 -317.952722) (xy 162.643423 -317.986814)
			(xy 162.60292 -318.01477) (xy 162.558458 -318.035868) (xy 162.511187 -318.04956) (xy 162.462332 -318.055492)
			(xy 162.413157 -318.053511) (xy 162.364938 -318.043667) (xy 162.318922 -318.026215) (xy 162.276301 -318.001608)
			(xy 162.23818 -317.970483) (xy 162.205545 -317.933646) (xy 162.179242 -317.89205) (xy 162.159951 -317.846774)
			(xy 162.148174 -317.79899) (xy 162.144214 -317.749936) (xy 160.855152 -317.749936) (xy 160.854657 -317.774543)
			(xy 160.846762 -317.82312) (xy 160.831178 -317.869801) (xy 160.808307 -317.913378) (xy 160.778742 -317.952722)
			(xy 160.743249 -317.986814) (xy 160.702746 -318.01477) (xy 160.658284 -318.035868) (xy 160.611013 -318.04956)
			(xy 160.562158 -318.055492) (xy 160.512983 -318.053511) (xy 160.464764 -318.043667) (xy 160.418748 -318.026215)
			(xy 160.376127 -318.001608) (xy 160.338006 -317.970483) (xy 160.305371 -317.933646) (xy 160.279068 -317.89205)
			(xy 160.259777 -317.846774) (xy 160.248 -317.79899) (xy 160.24404 -317.749936) (xy 158.955232 -317.749936)
			(xy 158.954737 -317.774543) (xy 158.946842 -317.82312) (xy 158.931258 -317.869801) (xy 158.908387 -317.913378)
			(xy 158.878822 -317.952722) (xy 158.843329 -317.986814) (xy 158.802826 -318.01477) (xy 158.758364 -318.035868)
			(xy 158.711093 -318.04956) (xy 158.662238 -318.055492) (xy 158.613063 -318.053511) (xy 158.564844 -318.043667)
			(xy 158.518828 -318.026215) (xy 158.476207 -318.001608) (xy 158.438086 -317.970483) (xy 158.405451 -317.933646)
			(xy 158.379148 -317.89205) (xy 158.359857 -317.846774) (xy 158.34808 -317.79899) (xy 158.34412 -317.749936)
			(xy 157.055312 -317.749936) (xy 157.054817 -317.774543) (xy 157.046922 -317.82312) (xy 157.031338 -317.869801)
			(xy 157.008467 -317.913378) (xy 156.978902 -317.952722) (xy 156.943409 -317.986814) (xy 156.902906 -318.01477)
			(xy 156.858444 -318.035868) (xy 156.811173 -318.04956) (xy 156.762318 -318.055492) (xy 156.713143 -318.053511)
			(xy 156.664924 -318.043667) (xy 156.618908 -318.026215) (xy 156.576287 -318.001608) (xy 156.538166 -317.970483)
			(xy 156.505531 -317.933646) (xy 156.479228 -317.89205) (xy 156.459937 -317.846774) (xy 156.44816 -317.79899)
			(xy 156.4442 -317.749936) (xy 155.155392 -317.749936) (xy 155.154897 -317.774543) (xy 155.147002 -317.82312)
			(xy 155.131418 -317.869801) (xy 155.108547 -317.913378) (xy 155.078982 -317.952722) (xy 155.043489 -317.986814)
			(xy 155.002986 -318.01477) (xy 154.958524 -318.035868) (xy 154.911253 -318.04956) (xy 154.862398 -318.055492)
			(xy 154.813223 -318.053511) (xy 154.765004 -318.043667) (xy 154.718988 -318.026215) (xy 154.676367 -318.001608)
			(xy 154.638246 -317.970483) (xy 154.605611 -317.933646) (xy 154.579308 -317.89205) (xy 154.560017 -317.846774)
			(xy 154.54824 -317.79899) (xy 154.54428 -317.749936) (xy 80.855058 -317.749936) (xy 80.854563 -317.774543)
			(xy 80.846668 -317.82312) (xy 80.831084 -317.869801) (xy 80.808213 -317.913378) (xy 80.778648 -317.952722)
			(xy 80.743155 -317.986814) (xy 80.702652 -318.01477) (xy 80.65819 -318.035868) (xy 80.610919 -318.04956)
			(xy 80.562064 -318.055492) (xy 80.512889 -318.053511) (xy 80.46467 -318.043667) (xy 80.418654 -318.026215)
			(xy 80.376033 -318.001608) (xy 80.337912 -317.970483) (xy 80.305277 -317.933646) (xy 80.278974 -317.89205)
			(xy 80.259683 -317.846774) (xy 80.247906 -317.79899) (xy 80.243946 -317.749936) (xy 78.955138 -317.749936)
			(xy 78.954643 -317.774543) (xy 78.946748 -317.82312) (xy 78.931164 -317.869801) (xy 78.908293 -317.913378)
			(xy 78.878728 -317.952722) (xy 78.843235 -317.986814) (xy 78.802732 -318.01477) (xy 78.75827 -318.035868)
			(xy 78.710999 -318.04956) (xy 78.662144 -318.055492) (xy 78.612969 -318.053511) (xy 78.56475 -318.043667)
			(xy 78.518734 -318.026215) (xy 78.476113 -318.001608) (xy 78.437992 -317.970483) (xy 78.405357 -317.933646)
			(xy 78.379054 -317.89205) (xy 78.359763 -317.846774) (xy 78.347986 -317.79899) (xy 78.344026 -317.749936)
			(xy 77.055218 -317.749936) (xy 77.054723 -317.774543) (xy 77.046828 -317.82312) (xy 77.031244 -317.869801)
			(xy 77.008373 -317.913378) (xy 76.978808 -317.952722) (xy 76.943315 -317.986814) (xy 76.902812 -318.01477)
			(xy 76.85835 -318.035868) (xy 76.811079 -318.04956) (xy 76.762224 -318.055492) (xy 76.713049 -318.053511)
			(xy 76.66483 -318.043667) (xy 76.618814 -318.026215) (xy 76.576193 -318.001608) (xy 76.538072 -317.970483)
			(xy 76.505437 -317.933646) (xy 76.479134 -317.89205) (xy 76.459843 -317.846774) (xy 76.448066 -317.79899)
			(xy 76.444106 -317.749936) (xy 75.155298 -317.749936) (xy 75.154803 -317.774543) (xy 75.146908 -317.82312)
			(xy 75.131324 -317.869801) (xy 75.108453 -317.913378) (xy 75.078888 -317.952722) (xy 75.043395 -317.986814)
			(xy 75.002892 -318.01477) (xy 74.95843 -318.035868) (xy 74.911159 -318.04956) (xy 74.862304 -318.055492)
			(xy 74.813129 -318.053511) (xy 74.76491 -318.043667) (xy 74.718894 -318.026215) (xy 74.676273 -318.001608)
			(xy 74.638152 -317.970483) (xy 74.605517 -317.933646) (xy 74.579214 -317.89205) (xy 74.559923 -317.846774)
			(xy 74.548146 -317.79899) (xy 74.544186 -317.749936) (xy 65.65519 -317.749936) (xy 65.654695 -317.774543)
			(xy 65.6468 -317.82312) (xy 65.631216 -317.869801) (xy 65.608345 -317.913378) (xy 65.57878 -317.952722)
			(xy 65.543287 -317.986814) (xy 65.502784 -318.01477) (xy 65.458322 -318.035868) (xy 65.411051 -318.04956)
			(xy 65.362196 -318.055492) (xy 65.313021 -318.053511) (xy 65.264802 -318.043667) (xy 65.218786 -318.026215)
			(xy 65.176165 -318.001608) (xy 65.138044 -317.970483) (xy 65.105409 -317.933646) (xy 65.079106 -317.89205)
			(xy 65.059815 -317.846774) (xy 65.048038 -317.79899) (xy 65.044078 -317.749936) (xy 63.75527 -317.749936)
			(xy 63.754775 -317.774543) (xy 63.74688 -317.82312) (xy 63.731296 -317.869801) (xy 63.708425 -317.913378)
			(xy 63.67886 -317.952722) (xy 63.643367 -317.986814) (xy 63.602864 -318.01477) (xy 63.558402 -318.035868)
			(xy 63.511131 -318.04956) (xy 63.462276 -318.055492) (xy 63.413101 -318.053511) (xy 63.364882 -318.043667)
			(xy 63.318866 -318.026215) (xy 63.276245 -318.001608) (xy 63.238124 -317.970483) (xy 63.205489 -317.933646)
			(xy 63.179186 -317.89205) (xy 63.159895 -317.846774) (xy 63.148118 -317.79899) (xy 63.144158 -317.749936)
			(xy 61.855096 -317.749936) (xy 61.854601 -317.774543) (xy 61.846706 -317.82312) (xy 61.831122 -317.869801)
			(xy 61.808251 -317.913378) (xy 61.778686 -317.952722) (xy 61.743193 -317.986814) (xy 61.70269 -318.01477)
			(xy 61.658228 -318.035868) (xy 61.610957 -318.04956) (xy 61.562102 -318.055492) (xy 61.512927 -318.053511)
			(xy 61.464708 -318.043667) (xy 61.418692 -318.026215) (xy 61.376071 -318.001608) (xy 61.33795 -317.970483)
			(xy 61.305315 -317.933646) (xy 61.279012 -317.89205) (xy 61.259721 -317.846774) (xy 61.247944 -317.79899)
			(xy 61.243984 -317.749936) (xy 59.955176 -317.749936) (xy 59.954681 -317.774543) (xy 59.946786 -317.82312)
			(xy 59.931202 -317.869801) (xy 59.908331 -317.913378) (xy 59.878766 -317.952722) (xy 59.843273 -317.986814)
			(xy 59.80277 -318.01477) (xy 59.758308 -318.035868) (xy 59.711037 -318.04956) (xy 59.662182 -318.055492)
			(xy 59.613007 -318.053511) (xy 59.564788 -318.043667) (xy 59.518772 -318.026215) (xy 59.476151 -318.001608)
			(xy 59.43803 -317.970483) (xy 59.405395 -317.933646) (xy 59.379092 -317.89205) (xy 59.359801 -317.846774)
			(xy 59.348024 -317.79899) (xy 59.344064 -317.749936) (xy 58.055256 -317.749936) (xy 58.054761 -317.774543)
			(xy 58.046866 -317.82312) (xy 58.031282 -317.869801) (xy 58.008411 -317.913378) (xy 57.978846 -317.952722)
			(xy 57.943353 -317.986814) (xy 57.90285 -318.01477) (xy 57.858388 -318.035868) (xy 57.811117 -318.04956)
			(xy 57.762262 -318.055492) (xy 57.713087 -318.053511) (xy 57.664868 -318.043667) (xy 57.618852 -318.026215)
			(xy 57.576231 -318.001608) (xy 57.53811 -317.970483) (xy 57.505475 -317.933646) (xy 57.479172 -317.89205)
			(xy 57.459881 -317.846774) (xy 57.448104 -317.79899) (xy 57.444144 -317.749936) (xy 56.155082 -317.749936)
			(xy 56.154587 -317.774543) (xy 56.146692 -317.82312) (xy 56.131108 -317.869801) (xy 56.108237 -317.913378)
			(xy 56.078672 -317.952722) (xy 56.043179 -317.986814) (xy 56.002676 -318.01477) (xy 55.958214 -318.035868)
			(xy 55.910943 -318.04956) (xy 55.862088 -318.055492) (xy 55.812913 -318.053511) (xy 55.764694 -318.043667)
			(xy 55.718678 -318.026215) (xy 55.676057 -318.001608) (xy 55.637936 -317.970483) (xy 55.605301 -317.933646)
			(xy 55.578998 -317.89205) (xy 55.559707 -317.846774) (xy 55.54793 -317.79899) (xy 55.54397 -317.749936)
			(xy 54.255162 -317.749936) (xy 54.254667 -317.774543) (xy 54.246772 -317.82312) (xy 54.231188 -317.869801)
			(xy 54.208317 -317.913378) (xy 54.178752 -317.952722) (xy 54.143259 -317.986814) (xy 54.102756 -318.01477)
			(xy 54.058294 -318.035868) (xy 54.011023 -318.04956) (xy 53.962168 -318.055492) (xy 53.912993 -318.053511)
			(xy 53.864774 -318.043667) (xy 53.818758 -318.026215) (xy 53.776137 -318.001608) (xy 53.738016 -317.970483)
			(xy 53.705381 -317.933646) (xy 53.679078 -317.89205) (xy 53.659787 -317.846774) (xy 53.64801 -317.79899)
			(xy 53.64405 -317.749936) (xy 52.355242 -317.749936) (xy 52.354747 -317.774543) (xy 52.346852 -317.82312)
			(xy 52.331268 -317.869801) (xy 52.308397 -317.913378) (xy 52.278832 -317.952722) (xy 52.243339 -317.986814)
			(xy 52.202836 -318.01477) (xy 52.158374 -318.035868) (xy 52.111103 -318.04956) (xy 52.062248 -318.055492)
			(xy 52.013073 -318.053511) (xy 51.964854 -318.043667) (xy 51.918838 -318.026215) (xy 51.876217 -318.001608)
			(xy 51.838096 -317.970483) (xy 51.805461 -317.933646) (xy 51.779158 -317.89205) (xy 51.759867 -317.846774)
			(xy 51.74809 -317.79899) (xy 51.74413 -317.749936) (xy 0.508 -317.749936) (xy 0.508 -320.900044)
			(xy 26.882353 -320.900044) (xy 26.886342 -320.751504) (xy 26.898299 -320.603391) (xy 26.918189 -320.456134)
			(xy 26.945954 -320.310158) (xy 26.981515 -320.165881) (xy 27.024769 -320.023722) (xy 27.075591 -319.884089)
			(xy 27.133835 -319.747386) (xy 27.199333 -319.614006) (xy 27.271896 -319.484334) (xy 27.351314 -319.358744)
			(xy 27.437359 -319.237597) (xy 27.529783 -319.121244) (xy 27.628319 -319.01002) (xy 27.732683 -318.904245)
			(xy 27.842575 -318.804225) (xy 27.957676 -318.710247) (xy 28.077656 -318.622583) (xy 28.202169 -318.541486)
			(xy 28.330855 -318.467189) (xy 28.463344 -318.399907) (xy 28.599253 -318.339833) (xy 28.738191 -318.287141)
			(xy 28.879757 -318.241982) (xy 29.023543 -318.204487) (xy 29.169134 -318.174765) (xy 29.31611 -318.1529)
			(xy 29.464049 -318.138956) (xy 29.612522 -318.132972) (xy 29.761103 -318.134967) (xy 29.909362 -318.144935)
			(xy 30.056873 -318.162846) (xy 30.203209 -318.188649) (xy 30.34795 -318.222269) (xy 30.490677 -318.263611)
			(xy 30.63098 -318.312554) (xy 30.768453 -318.368957) (xy 30.9027 -318.432658) (xy 31.033335 -318.503474)
			(xy 31.15998 -318.581199) (xy 31.28227 -318.66561) (xy 31.326643 -318.699896) (xy 51.74413 -318.699896)
			(xy 51.74809 -318.650842) (xy 51.759867 -318.603058) (xy 51.779158 -318.557782) (xy 51.805461 -318.516186)
			(xy 51.838096 -318.479349) (xy 51.876217 -318.448224) (xy 51.918838 -318.423617) (xy 51.964854 -318.406165)
			(xy 52.013073 -318.396321) (xy 52.062248 -318.39434) (xy 52.111103 -318.400272) (xy 52.158374 -318.413964)
			(xy 52.202836 -318.435062) (xy 52.243339 -318.463018) (xy 52.278832 -318.49711) (xy 52.308397 -318.536454)
			(xy 52.331268 -318.580031) (xy 52.346852 -318.626712) (xy 52.354747 -318.675289) (xy 52.355242 -318.699896)
			(xy 53.64405 -318.699896) (xy 53.64801 -318.650842) (xy 53.659787 -318.603058) (xy 53.679078 -318.557782)
			(xy 53.705381 -318.516186) (xy 53.738016 -318.479349) (xy 53.776137 -318.448224) (xy 53.818758 -318.423617)
			(xy 53.864774 -318.406165) (xy 53.912993 -318.396321) (xy 53.962168 -318.39434) (xy 54.011023 -318.400272)
			(xy 54.058294 -318.413964) (xy 54.102756 -318.435062) (xy 54.143259 -318.463018) (xy 54.178752 -318.49711)
			(xy 54.208317 -318.536454) (xy 54.231188 -318.580031) (xy 54.246772 -318.626712) (xy 54.254667 -318.675289)
			(xy 54.255162 -318.699896) (xy 55.54397 -318.699896) (xy 55.54793 -318.650842) (xy 55.559707 -318.603058)
			(xy 55.578998 -318.557782) (xy 55.605301 -318.516186) (xy 55.637936 -318.479349) (xy 55.676057 -318.448224)
			(xy 55.718678 -318.423617) (xy 55.764694 -318.406165) (xy 55.812913 -318.396321) (xy 55.862088 -318.39434)
			(xy 55.910943 -318.400272) (xy 55.958214 -318.413964) (xy 56.002676 -318.435062) (xy 56.043179 -318.463018)
			(xy 56.078672 -318.49711) (xy 56.108237 -318.536454) (xy 56.131108 -318.580031) (xy 56.146692 -318.626712)
			(xy 56.154587 -318.675289) (xy 56.155082 -318.699896) (xy 57.444144 -318.699896) (xy 57.448104 -318.650842)
			(xy 57.459881 -318.603058) (xy 57.479172 -318.557782) (xy 57.505475 -318.516186) (xy 57.53811 -318.479349)
			(xy 57.576231 -318.448224) (xy 57.618852 -318.423617) (xy 57.664868 -318.406165) (xy 57.713087 -318.396321)
			(xy 57.762262 -318.39434) (xy 57.811117 -318.400272) (xy 57.858388 -318.413964) (xy 57.90285 -318.435062)
			(xy 57.943353 -318.463018) (xy 57.978846 -318.49711) (xy 58.008411 -318.536454) (xy 58.031282 -318.580031)
			(xy 58.046866 -318.626712) (xy 58.054761 -318.675289) (xy 58.055256 -318.699896) (xy 59.344064 -318.699896)
			(xy 59.348024 -318.650842) (xy 59.359801 -318.603058) (xy 59.379092 -318.557782) (xy 59.405395 -318.516186)
			(xy 59.43803 -318.479349) (xy 59.476151 -318.448224) (xy 59.518772 -318.423617) (xy 59.564788 -318.406165)
			(xy 59.613007 -318.396321) (xy 59.662182 -318.39434) (xy 59.711037 -318.400272) (xy 59.758308 -318.413964)
			(xy 59.80277 -318.435062) (xy 59.843273 -318.463018) (xy 59.878766 -318.49711) (xy 59.908331 -318.536454)
			(xy 59.931202 -318.580031) (xy 59.946786 -318.626712) (xy 59.954681 -318.675289) (xy 59.955176 -318.699896)
			(xy 61.243984 -318.699896) (xy 61.247944 -318.650842) (xy 61.259721 -318.603058) (xy 61.279012 -318.557782)
			(xy 61.305315 -318.516186) (xy 61.33795 -318.479349) (xy 61.376071 -318.448224) (xy 61.418692 -318.423617)
			(xy 61.464708 -318.406165) (xy 61.512927 -318.396321) (xy 61.562102 -318.39434) (xy 61.610957 -318.400272)
			(xy 61.658228 -318.413964) (xy 61.70269 -318.435062) (xy 61.743193 -318.463018) (xy 61.778686 -318.49711)
			(xy 61.808251 -318.536454) (xy 61.831122 -318.580031) (xy 61.846706 -318.626712) (xy 61.854601 -318.675289)
			(xy 61.855096 -318.699896) (xy 63.144158 -318.699896) (xy 63.148118 -318.650842) (xy 63.159895 -318.603058)
			(xy 63.179186 -318.557782) (xy 63.205489 -318.516186) (xy 63.238124 -318.479349) (xy 63.276245 -318.448224)
			(xy 63.318866 -318.423617) (xy 63.364882 -318.406165) (xy 63.413101 -318.396321) (xy 63.462276 -318.39434)
			(xy 63.511131 -318.400272) (xy 63.558402 -318.413964) (xy 63.602864 -318.435062) (xy 63.643367 -318.463018)
			(xy 63.67886 -318.49711) (xy 63.708425 -318.536454) (xy 63.731296 -318.580031) (xy 63.74688 -318.626712)
			(xy 63.754775 -318.675289) (xy 63.75527 -318.699896) (xy 65.044078 -318.699896) (xy 65.048038 -318.650842)
			(xy 65.059815 -318.603058) (xy 65.079106 -318.557782) (xy 65.105409 -318.516186) (xy 65.138044 -318.479349)
			(xy 65.176165 -318.448224) (xy 65.218786 -318.423617) (xy 65.264802 -318.406165) (xy 65.313021 -318.396321)
			(xy 65.362196 -318.39434) (xy 65.411051 -318.400272) (xy 65.458322 -318.413964) (xy 65.502784 -318.435062)
			(xy 65.543287 -318.463018) (xy 65.57878 -318.49711) (xy 65.608345 -318.536454) (xy 65.631216 -318.580031)
			(xy 65.6468 -318.626712) (xy 65.654695 -318.675289) (xy 65.65519 -318.699896) (xy 74.544186 -318.699896)
			(xy 74.548146 -318.650842) (xy 74.559923 -318.603058) (xy 74.579214 -318.557782) (xy 74.605517 -318.516186)
			(xy 74.638152 -318.479349) (xy 74.676273 -318.448224) (xy 74.718894 -318.423617) (xy 74.76491 -318.406165)
			(xy 74.813129 -318.396321) (xy 74.862304 -318.39434) (xy 74.911159 -318.400272) (xy 74.95843 -318.413964)
			(xy 75.002892 -318.435062) (xy 75.043395 -318.463018) (xy 75.078888 -318.49711) (xy 75.108453 -318.536454)
			(xy 75.131324 -318.580031) (xy 75.146908 -318.626712) (xy 75.154803 -318.675289) (xy 75.155298 -318.699896)
			(xy 76.444106 -318.699896) (xy 76.448066 -318.650842) (xy 76.459843 -318.603058) (xy 76.479134 -318.557782)
			(xy 76.505437 -318.516186) (xy 76.538072 -318.479349) (xy 76.576193 -318.448224) (xy 76.618814 -318.423617)
			(xy 76.66483 -318.406165) (xy 76.713049 -318.396321) (xy 76.762224 -318.39434) (xy 76.811079 -318.400272)
			(xy 76.85835 -318.413964) (xy 76.902812 -318.435062) (xy 76.943315 -318.463018) (xy 76.978808 -318.49711)
			(xy 77.008373 -318.536454) (xy 77.031244 -318.580031) (xy 77.046828 -318.626712) (xy 77.054723 -318.675289)
			(xy 77.055218 -318.699896) (xy 78.344026 -318.699896) (xy 78.347986 -318.650842) (xy 78.359763 -318.603058)
			(xy 78.379054 -318.557782) (xy 78.405357 -318.516186) (xy 78.437992 -318.479349) (xy 78.476113 -318.448224)
			(xy 78.518734 -318.423617) (xy 78.56475 -318.406165) (xy 78.612969 -318.396321) (xy 78.662144 -318.39434)
			(xy 78.710999 -318.400272) (xy 78.75827 -318.413964) (xy 78.802732 -318.435062) (xy 78.843235 -318.463018)
			(xy 78.878728 -318.49711) (xy 78.908293 -318.536454) (xy 78.931164 -318.580031) (xy 78.946748 -318.626712)
			(xy 78.954643 -318.675289) (xy 78.955138 -318.699896) (xy 80.243946 -318.699896) (xy 80.247906 -318.650842)
			(xy 80.259683 -318.603058) (xy 80.278974 -318.557782) (xy 80.305277 -318.516186) (xy 80.337912 -318.479349)
			(xy 80.376033 -318.448224) (xy 80.418654 -318.423617) (xy 80.46467 -318.406165) (xy 80.512889 -318.396321)
			(xy 80.562064 -318.39434) (xy 80.610919 -318.400272) (xy 80.65819 -318.413964) (xy 80.702652 -318.435062)
			(xy 80.743155 -318.463018) (xy 80.778648 -318.49711) (xy 80.808213 -318.536454) (xy 80.831084 -318.580031)
			(xy 80.846668 -318.626712) (xy 80.854563 -318.675289) (xy 80.855058 -318.699896) (xy 80.854563 -318.724503)
			(xy 80.846668 -318.77308) (xy 80.831084 -318.819761) (xy 80.808213 -318.863338) (xy 80.778648 -318.902682)
			(xy 80.743155 -318.936774) (xy 80.702652 -318.96473) (xy 80.65819 -318.985828) (xy 80.610919 -318.99952)
			(xy 80.562064 -319.005452) (xy 80.512889 -319.003471) (xy 80.46467 -318.993627) (xy 80.418654 -318.976175)
			(xy 80.376033 -318.951568) (xy 80.337912 -318.920443) (xy 80.305277 -318.883606) (xy 80.278974 -318.84201)
			(xy 80.259683 -318.796734) (xy 80.247906 -318.74895) (xy 80.243946 -318.699896) (xy 78.955138 -318.699896)
			(xy 78.954643 -318.724503) (xy 78.946748 -318.77308) (xy 78.931164 -318.819761) (xy 78.908293 -318.863338)
			(xy 78.878728 -318.902682) (xy 78.843235 -318.936774) (xy 78.802732 -318.96473) (xy 78.75827 -318.985828)
			(xy 78.710999 -318.99952) (xy 78.662144 -319.005452) (xy 78.612969 -319.003471) (xy 78.56475 -318.993627)
			(xy 78.518734 -318.976175) (xy 78.476113 -318.951568) (xy 78.437992 -318.920443) (xy 78.405357 -318.883606)
			(xy 78.379054 -318.84201) (xy 78.359763 -318.796734) (xy 78.347986 -318.74895) (xy 78.344026 -318.699896)
			(xy 77.055218 -318.699896) (xy 77.054723 -318.724503) (xy 77.046828 -318.77308) (xy 77.031244 -318.819761)
			(xy 77.008373 -318.863338) (xy 76.978808 -318.902682) (xy 76.943315 -318.936774) (xy 76.902812 -318.96473)
			(xy 76.85835 -318.985828) (xy 76.811079 -318.99952) (xy 76.762224 -319.005452) (xy 76.713049 -319.003471)
			(xy 76.66483 -318.993627) (xy 76.618814 -318.976175) (xy 76.576193 -318.951568) (xy 76.538072 -318.920443)
			(xy 76.505437 -318.883606) (xy 76.479134 -318.84201) (xy 76.459843 -318.796734) (xy 76.448066 -318.74895)
			(xy 76.444106 -318.699896) (xy 75.155298 -318.699896) (xy 75.154803 -318.724503) (xy 75.146908 -318.77308)
			(xy 75.131324 -318.819761) (xy 75.108453 -318.863338) (xy 75.078888 -318.902682) (xy 75.043395 -318.936774)
			(xy 75.002892 -318.96473) (xy 74.95843 -318.985828) (xy 74.911159 -318.99952) (xy 74.862304 -319.005452)
			(xy 74.813129 -319.003471) (xy 74.76491 -318.993627) (xy 74.718894 -318.976175) (xy 74.676273 -318.951568)
			(xy 74.638152 -318.920443) (xy 74.605517 -318.883606) (xy 74.579214 -318.84201) (xy 74.559923 -318.796734)
			(xy 74.548146 -318.74895) (xy 74.544186 -318.699896) (xy 65.65519 -318.699896) (xy 65.654695 -318.724503)
			(xy 65.6468 -318.77308) (xy 65.631216 -318.819761) (xy 65.608345 -318.863338) (xy 65.57878 -318.902682)
			(xy 65.543287 -318.936774) (xy 65.502784 -318.96473) (xy 65.458322 -318.985828) (xy 65.411051 -318.99952)
			(xy 65.362196 -319.005452) (xy 65.313021 -319.003471) (xy 65.264802 -318.993627) (xy 65.218786 -318.976175)
			(xy 65.176165 -318.951568) (xy 65.138044 -318.920443) (xy 65.105409 -318.883606) (xy 65.079106 -318.84201)
			(xy 65.059815 -318.796734) (xy 65.048038 -318.74895) (xy 65.044078 -318.699896) (xy 63.75527 -318.699896)
			(xy 63.754775 -318.724503) (xy 63.74688 -318.77308) (xy 63.731296 -318.819761) (xy 63.708425 -318.863338)
			(xy 63.67886 -318.902682) (xy 63.643367 -318.936774) (xy 63.602864 -318.96473) (xy 63.558402 -318.985828)
			(xy 63.511131 -318.99952) (xy 63.462276 -319.005452) (xy 63.413101 -319.003471) (xy 63.364882 -318.993627)
			(xy 63.318866 -318.976175) (xy 63.276245 -318.951568) (xy 63.238124 -318.920443) (xy 63.205489 -318.883606)
			(xy 63.179186 -318.84201) (xy 63.159895 -318.796734) (xy 63.148118 -318.74895) (xy 63.144158 -318.699896)
			(xy 61.855096 -318.699896) (xy 61.854601 -318.724503) (xy 61.846706 -318.77308) (xy 61.831122 -318.819761)
			(xy 61.808251 -318.863338) (xy 61.778686 -318.902682) (xy 61.743193 -318.936774) (xy 61.70269 -318.96473)
			(xy 61.658228 -318.985828) (xy 61.610957 -318.99952) (xy 61.562102 -319.005452) (xy 61.512927 -319.003471)
			(xy 61.464708 -318.993627) (xy 61.418692 -318.976175) (xy 61.376071 -318.951568) (xy 61.33795 -318.920443)
			(xy 61.305315 -318.883606) (xy 61.279012 -318.84201) (xy 61.259721 -318.796734) (xy 61.247944 -318.74895)
			(xy 61.243984 -318.699896) (xy 59.955176 -318.699896) (xy 59.954681 -318.724503) (xy 59.946786 -318.77308)
			(xy 59.931202 -318.819761) (xy 59.908331 -318.863338) (xy 59.878766 -318.902682) (xy 59.843273 -318.936774)
			(xy 59.80277 -318.96473) (xy 59.758308 -318.985828) (xy 59.711037 -318.99952) (xy 59.662182 -319.005452)
			(xy 59.613007 -319.003471) (xy 59.564788 -318.993627) (xy 59.518772 -318.976175) (xy 59.476151 -318.951568)
			(xy 59.43803 -318.920443) (xy 59.405395 -318.883606) (xy 59.379092 -318.84201) (xy 59.359801 -318.796734)
			(xy 59.348024 -318.74895) (xy 59.344064 -318.699896) (xy 58.055256 -318.699896) (xy 58.054761 -318.724503)
			(xy 58.046866 -318.77308) (xy 58.031282 -318.819761) (xy 58.008411 -318.863338) (xy 57.978846 -318.902682)
			(xy 57.943353 -318.936774) (xy 57.90285 -318.96473) (xy 57.858388 -318.985828) (xy 57.811117 -318.99952)
			(xy 57.762262 -319.005452) (xy 57.713087 -319.003471) (xy 57.664868 -318.993627) (xy 57.618852 -318.976175)
			(xy 57.576231 -318.951568) (xy 57.53811 -318.920443) (xy 57.505475 -318.883606) (xy 57.479172 -318.84201)
			(xy 57.459881 -318.796734) (xy 57.448104 -318.74895) (xy 57.444144 -318.699896) (xy 56.155082 -318.699896)
			(xy 56.154587 -318.724503) (xy 56.146692 -318.77308) (xy 56.131108 -318.819761) (xy 56.108237 -318.863338)
			(xy 56.078672 -318.902682) (xy 56.043179 -318.936774) (xy 56.002676 -318.96473) (xy 55.958214 -318.985828)
			(xy 55.910943 -318.99952) (xy 55.862088 -319.005452) (xy 55.812913 -319.003471) (xy 55.764694 -318.993627)
			(xy 55.718678 -318.976175) (xy 55.676057 -318.951568) (xy 55.637936 -318.920443) (xy 55.605301 -318.883606)
			(xy 55.578998 -318.84201) (xy 55.559707 -318.796734) (xy 55.54793 -318.74895) (xy 55.54397 -318.699896)
			(xy 54.255162 -318.699896) (xy 54.254667 -318.724503) (xy 54.246772 -318.77308) (xy 54.231188 -318.819761)
			(xy 54.208317 -318.863338) (xy 54.178752 -318.902682) (xy 54.143259 -318.936774) (xy 54.102756 -318.96473)
			(xy 54.058294 -318.985828) (xy 54.011023 -318.99952) (xy 53.962168 -319.005452) (xy 53.912993 -319.003471)
			(xy 53.864774 -318.993627) (xy 53.818758 -318.976175) (xy 53.776137 -318.951568) (xy 53.738016 -318.920443)
			(xy 53.705381 -318.883606) (xy 53.679078 -318.84201) (xy 53.659787 -318.796734) (xy 53.64801 -318.74895)
			(xy 53.64405 -318.699896) (xy 52.355242 -318.699896) (xy 52.354747 -318.724503) (xy 52.346852 -318.77308)
			(xy 52.331268 -318.819761) (xy 52.308397 -318.863338) (xy 52.278832 -318.902682) (xy 52.243339 -318.936774)
			(xy 52.202836 -318.96473) (xy 52.158374 -318.985828) (xy 52.111103 -318.99952) (xy 52.062248 -319.005452)
			(xy 52.013073 -319.003471) (xy 51.964854 -318.993627) (xy 51.918838 -318.976175) (xy 51.876217 -318.951568)
			(xy 51.838096 -318.920443) (xy 51.805461 -318.883606) (xy 51.779158 -318.84201) (xy 51.759867 -318.796734)
			(xy 51.74809 -318.74895) (xy 51.74413 -318.699896) (xy 31.326643 -318.699896) (xy 31.399853 -318.756463)
			(xy 31.51239 -318.853497) (xy 31.619557 -318.956432) (xy 31.721044 -319.064971) (xy 31.816558 -319.1788)
			(xy 31.905825 -319.297593) (xy 31.988586 -319.421005) (xy 32.064604 -319.548683) (xy 32.133659 -319.680256)
			(xy 32.195552 -319.815347) (xy 32.250105 -319.953564) (xy 32.29716 -320.094511) (xy 32.336582 -320.237781)
			(xy 32.368256 -320.38296) (xy 32.392092 -320.529629) (xy 32.408021 -320.677367) (xy 32.415997 -320.825747)
			(xy 32.416496 -320.900044) (xy 86.882487 -320.900044) (xy 86.886476 -320.751504) (xy 86.898433 -320.603391)
			(xy 86.918323 -320.456134) (xy 86.946088 -320.310158) (xy 86.981649 -320.165881) (xy 87.024903 -320.023722)
			(xy 87.075725 -319.884089) (xy 87.133969 -319.747386) (xy 87.199467 -319.614006) (xy 87.27203 -319.484334)
			(xy 87.351448 -319.358744) (xy 87.437493 -319.237597) (xy 87.529917 -319.121244) (xy 87.628453 -319.01002)
			(xy 87.732817 -318.904245) (xy 87.842709 -318.804225) (xy 87.95781 -318.710247) (xy 88.07779 -318.622583)
			(xy 88.202303 -318.541486) (xy 88.330989 -318.467189) (xy 88.463478 -318.399907) (xy 88.599387 -318.339833)
			(xy 88.738325 -318.287141) (xy 88.879891 -318.241982) (xy 89.023677 -318.204487) (xy 89.169268 -318.174765)
			(xy 89.316244 -318.1529) (xy 89.464183 -318.138956) (xy 89.612656 -318.132972) (xy 89.761237 -318.134967)
			(xy 89.909496 -318.144935) (xy 90.057007 -318.162846) (xy 90.203343 -318.188649) (xy 90.348084 -318.222269)
			(xy 90.490811 -318.263611) (xy 90.631114 -318.312554) (xy 90.768587 -318.368957) (xy 90.902834 -318.432658)
			(xy 91.033469 -318.503474) (xy 91.160114 -318.581199) (xy 91.282404 -318.66561) (xy 91.399987 -318.756463)
			(xy 91.512524 -318.853497) (xy 91.619691 -318.956432) (xy 91.721178 -319.064971) (xy 91.816692 -319.1788)
			(xy 91.905959 -319.297593) (xy 91.98872 -319.421005) (xy 92.064738 -319.548683) (xy 92.133793 -319.680256)
			(xy 92.195686 -319.815347) (xy 92.250239 -319.953564) (xy 92.297294 -320.094511) (xy 92.336716 -320.237781)
			(xy 92.36839 -320.38296) (xy 92.392226 -320.529629) (xy 92.408155 -320.677367) (xy 92.416131 -320.825747)
			(xy 92.41663 -320.900044) (xy 142.982451 -320.900044) (xy 142.98644 -320.751504) (xy 142.998397 -320.603391)
			(xy 143.018287 -320.456134) (xy 143.046052 -320.310158) (xy 143.081613 -320.165881) (xy 143.124867 -320.023722)
			(xy 143.175689 -319.884089) (xy 143.233933 -319.747386) (xy 143.299431 -319.614006) (xy 143.371994 -319.484334)
			(xy 143.451412 -319.358744) (xy 143.537457 -319.237597) (xy 143.629881 -319.121244) (xy 143.728417 -319.01002)
			(xy 143.832781 -318.904245) (xy 143.942673 -318.804225) (xy 144.057774 -318.710247) (xy 144.177754 -318.622583)
			(xy 144.302267 -318.541486) (xy 144.430953 -318.467189) (xy 144.563442 -318.399907) (xy 144.699351 -318.339833)
			(xy 144.838289 -318.287141) (xy 144.979855 -318.241982) (xy 145.123641 -318.204487) (xy 145.269232 -318.174765)
			(xy 145.416208 -318.1529) (xy 145.564147 -318.138956) (xy 145.71262 -318.132972) (xy 145.861201 -318.134967)
			(xy 146.00946 -318.144935) (xy 146.156971 -318.162846) (xy 146.303307 -318.188649) (xy 146.448048 -318.222269)
			(xy 146.590775 -318.263611) (xy 146.731078 -318.312554) (xy 146.868551 -318.368957) (xy 147.002798 -318.432658)
			(xy 147.133433 -318.503474) (xy 147.260078 -318.581199) (xy 147.382368 -318.66561) (xy 147.426741 -318.699896)
			(xy 154.54428 -318.699896) (xy 154.54824 -318.650842) (xy 154.560017 -318.603058) (xy 154.579308 -318.557782)
			(xy 154.605611 -318.516186) (xy 154.638246 -318.479349) (xy 154.676367 -318.448224) (xy 154.718988 -318.423617)
			(xy 154.765004 -318.406165) (xy 154.813223 -318.396321) (xy 154.862398 -318.39434) (xy 154.911253 -318.400272)
			(xy 154.958524 -318.413964) (xy 155.002986 -318.435062) (xy 155.043489 -318.463018) (xy 155.078982 -318.49711)
			(xy 155.108547 -318.536454) (xy 155.131418 -318.580031) (xy 155.147002 -318.626712) (xy 155.154897 -318.675289)
			(xy 155.155392 -318.699896) (xy 156.4442 -318.699896) (xy 156.44816 -318.650842) (xy 156.459937 -318.603058)
			(xy 156.479228 -318.557782) (xy 156.505531 -318.516186) (xy 156.538166 -318.479349) (xy 156.576287 -318.448224)
			(xy 156.618908 -318.423617) (xy 156.664924 -318.406165) (xy 156.713143 -318.396321) (xy 156.762318 -318.39434)
			(xy 156.811173 -318.400272) (xy 156.858444 -318.413964) (xy 156.902906 -318.435062) (xy 156.943409 -318.463018)
			(xy 156.978902 -318.49711) (xy 157.008467 -318.536454) (xy 157.031338 -318.580031) (xy 157.046922 -318.626712)
			(xy 157.054817 -318.675289) (xy 157.055312 -318.699896) (xy 158.34412 -318.699896) (xy 158.34808 -318.650842)
			(xy 158.359857 -318.603058) (xy 158.379148 -318.557782) (xy 158.405451 -318.516186) (xy 158.438086 -318.479349)
			(xy 158.476207 -318.448224) (xy 158.518828 -318.423617) (xy 158.564844 -318.406165) (xy 158.613063 -318.396321)
			(xy 158.662238 -318.39434) (xy 158.711093 -318.400272) (xy 158.758364 -318.413964) (xy 158.802826 -318.435062)
			(xy 158.843329 -318.463018) (xy 158.878822 -318.49711) (xy 158.908387 -318.536454) (xy 158.931258 -318.580031)
			(xy 158.946842 -318.626712) (xy 158.954737 -318.675289) (xy 158.955232 -318.699896) (xy 160.24404 -318.699896)
			(xy 160.248 -318.650842) (xy 160.259777 -318.603058) (xy 160.279068 -318.557782) (xy 160.305371 -318.516186)
			(xy 160.338006 -318.479349) (xy 160.376127 -318.448224) (xy 160.418748 -318.423617) (xy 160.464764 -318.406165)
			(xy 160.512983 -318.396321) (xy 160.562158 -318.39434) (xy 160.611013 -318.400272) (xy 160.658284 -318.413964)
			(xy 160.702746 -318.435062) (xy 160.743249 -318.463018) (xy 160.778742 -318.49711) (xy 160.808307 -318.536454)
			(xy 160.831178 -318.580031) (xy 160.846762 -318.626712) (xy 160.854657 -318.675289) (xy 160.855152 -318.699896)
			(xy 162.144214 -318.699896) (xy 162.148174 -318.650842) (xy 162.159951 -318.603058) (xy 162.179242 -318.557782)
			(xy 162.205545 -318.516186) (xy 162.23818 -318.479349) (xy 162.276301 -318.448224) (xy 162.318922 -318.423617)
			(xy 162.364938 -318.406165) (xy 162.413157 -318.396321) (xy 162.462332 -318.39434) (xy 162.511187 -318.400272)
			(xy 162.558458 -318.413964) (xy 162.60292 -318.435062) (xy 162.643423 -318.463018) (xy 162.678916 -318.49711)
			(xy 162.708481 -318.536454) (xy 162.731352 -318.580031) (xy 162.746936 -318.626712) (xy 162.754831 -318.675289)
			(xy 162.755326 -318.699896) (xy 164.044134 -318.699896) (xy 164.048094 -318.650842) (xy 164.059871 -318.603058)
			(xy 164.079162 -318.557782) (xy 164.105465 -318.516186) (xy 164.1381 -318.479349) (xy 164.176221 -318.448224)
			(xy 164.218842 -318.423617) (xy 164.264858 -318.406165) (xy 164.313077 -318.396321) (xy 164.362252 -318.39434)
			(xy 164.411107 -318.400272) (xy 164.458378 -318.413964) (xy 164.50284 -318.435062) (xy 164.543343 -318.463018)
			(xy 164.578836 -318.49711) (xy 164.608401 -318.536454) (xy 164.631272 -318.580031) (xy 164.646856 -318.626712)
			(xy 164.654751 -318.675289) (xy 164.655246 -318.699896) (xy 165.944054 -318.699896) (xy 165.948014 -318.650842)
			(xy 165.959791 -318.603058) (xy 165.979082 -318.557782) (xy 166.005385 -318.516186) (xy 166.03802 -318.479349)
			(xy 166.076141 -318.448224) (xy 166.118762 -318.423617) (xy 166.164778 -318.406165) (xy 166.212997 -318.396321)
			(xy 166.262172 -318.39434) (xy 166.311027 -318.400272) (xy 166.358298 -318.413964) (xy 166.40276 -318.435062)
			(xy 166.443263 -318.463018) (xy 166.478756 -318.49711) (xy 166.508321 -318.536454) (xy 166.531192 -318.580031)
			(xy 166.546776 -318.626712) (xy 166.554671 -318.675289) (xy 166.555166 -318.699896) (xy 183.044096 -318.699896)
			(xy 183.048056 -318.650842) (xy 183.059833 -318.603058) (xy 183.079124 -318.557782) (xy 183.105427 -318.516186)
			(xy 183.138062 -318.479349) (xy 183.176183 -318.448224) (xy 183.218804 -318.423617) (xy 183.26482 -318.406165)
			(xy 183.313039 -318.396321) (xy 183.362214 -318.39434) (xy 183.411069 -318.400272) (xy 183.45834 -318.413964)
			(xy 183.502802 -318.435062) (xy 183.543305 -318.463018) (xy 183.578798 -318.49711) (xy 183.608363 -318.536454)
			(xy 183.631234 -318.580031) (xy 183.646818 -318.626712) (xy 183.654713 -318.675289) (xy 183.655208 -318.699896)
			(xy 184.94427 -318.699896) (xy 184.94823 -318.650842) (xy 184.960007 -318.603058) (xy 184.979298 -318.557782)
			(xy 185.005601 -318.516186) (xy 185.038236 -318.479349) (xy 185.076357 -318.448224) (xy 185.118978 -318.423617)
			(xy 185.164994 -318.406165) (xy 185.213213 -318.396321) (xy 185.262388 -318.39434) (xy 185.311243 -318.400272)
			(xy 185.358514 -318.413964) (xy 185.402976 -318.435062) (xy 185.443479 -318.463018) (xy 185.478972 -318.49711)
			(xy 185.508537 -318.536454) (xy 185.531408 -318.580031) (xy 185.546992 -318.626712) (xy 185.554887 -318.675289)
			(xy 185.555382 -318.699896) (xy 186.84419 -318.699896) (xy 186.84815 -318.650842) (xy 186.859927 -318.603058)
			(xy 186.879218 -318.557782) (xy 186.905521 -318.516186) (xy 186.938156 -318.479349) (xy 186.976277 -318.448224)
			(xy 187.018898 -318.423617) (xy 187.064914 -318.406165) (xy 187.113133 -318.396321) (xy 187.162308 -318.39434)
			(xy 187.211163 -318.400272) (xy 187.258434 -318.413964) (xy 187.302896 -318.435062) (xy 187.343399 -318.463018)
			(xy 187.378892 -318.49711) (xy 187.408457 -318.536454) (xy 187.431328 -318.580031) (xy 187.446912 -318.626712)
			(xy 187.454807 -318.675289) (xy 187.455302 -318.699896) (xy 188.74411 -318.699896) (xy 188.74807 -318.650842)
			(xy 188.759847 -318.603058) (xy 188.779138 -318.557782) (xy 188.805441 -318.516186) (xy 188.838076 -318.479349)
			(xy 188.876197 -318.448224) (xy 188.918818 -318.423617) (xy 188.964834 -318.406165) (xy 189.013053 -318.396321)
			(xy 189.062228 -318.39434) (xy 189.111083 -318.400272) (xy 189.158354 -318.413964) (xy 189.202816 -318.435062)
			(xy 189.243319 -318.463018) (xy 189.278812 -318.49711) (xy 189.308377 -318.536454) (xy 189.331248 -318.580031)
			(xy 189.346832 -318.626712) (xy 189.354727 -318.675289) (xy 189.355222 -318.699896) (xy 189.354727 -318.724503)
			(xy 189.346832 -318.77308) (xy 189.331248 -318.819761) (xy 189.308377 -318.863338) (xy 189.278812 -318.902682)
			(xy 189.243319 -318.936774) (xy 189.202816 -318.96473) (xy 189.158354 -318.985828) (xy 189.111083 -318.99952)
			(xy 189.062228 -319.005452) (xy 189.013053 -319.003471) (xy 188.964834 -318.993627) (xy 188.918818 -318.976175)
			(xy 188.876197 -318.951568) (xy 188.838076 -318.920443) (xy 188.805441 -318.883606) (xy 188.779138 -318.84201)
			(xy 188.759847 -318.796734) (xy 188.74807 -318.74895) (xy 188.74411 -318.699896) (xy 187.455302 -318.699896)
			(xy 187.454807 -318.724503) (xy 187.446912 -318.77308) (xy 187.431328 -318.819761) (xy 187.408457 -318.863338)
			(xy 187.378892 -318.902682) (xy 187.343399 -318.936774) (xy 187.302896 -318.96473) (xy 187.258434 -318.985828)
			(xy 187.211163 -318.99952) (xy 187.162308 -319.005452) (xy 187.113133 -319.003471) (xy 187.064914 -318.993627)
			(xy 187.018898 -318.976175) (xy 186.976277 -318.951568) (xy 186.938156 -318.920443) (xy 186.905521 -318.883606)
			(xy 186.879218 -318.84201) (xy 186.859927 -318.796734) (xy 186.84815 -318.74895) (xy 186.84419 -318.699896)
			(xy 185.555382 -318.699896) (xy 185.554887 -318.724503) (xy 185.546992 -318.77308) (xy 185.531408 -318.819761)
			(xy 185.508537 -318.863338) (xy 185.478972 -318.902682) (xy 185.443479 -318.936774) (xy 185.402976 -318.96473)
			(xy 185.358514 -318.985828) (xy 185.311243 -318.99952) (xy 185.262388 -319.005452) (xy 185.213213 -319.003471)
			(xy 185.164994 -318.993627) (xy 185.118978 -318.976175) (xy 185.076357 -318.951568) (xy 185.038236 -318.920443)
			(xy 185.005601 -318.883606) (xy 184.979298 -318.84201) (xy 184.960007 -318.796734) (xy 184.94823 -318.74895)
			(xy 184.94427 -318.699896) (xy 183.655208 -318.699896) (xy 183.654713 -318.724503) (xy 183.646818 -318.77308)
			(xy 183.631234 -318.819761) (xy 183.608363 -318.863338) (xy 183.578798 -318.902682) (xy 183.543305 -318.936774)
			(xy 183.502802 -318.96473) (xy 183.45834 -318.985828) (xy 183.411069 -318.99952) (xy 183.362214 -319.005452)
			(xy 183.313039 -319.003471) (xy 183.26482 -318.993627) (xy 183.218804 -318.976175) (xy 183.176183 -318.951568)
			(xy 183.138062 -318.920443) (xy 183.105427 -318.883606) (xy 183.079124 -318.84201) (xy 183.059833 -318.796734)
			(xy 183.048056 -318.74895) (xy 183.044096 -318.699896) (xy 166.555166 -318.699896) (xy 166.554671 -318.724503)
			(xy 166.546776 -318.77308) (xy 166.531192 -318.819761) (xy 166.508321 -318.863338) (xy 166.478756 -318.902682)
			(xy 166.443263 -318.936774) (xy 166.40276 -318.96473) (xy 166.358298 -318.985828) (xy 166.311027 -318.99952)
			(xy 166.262172 -319.005452) (xy 166.212997 -319.003471) (xy 166.164778 -318.993627) (xy 166.118762 -318.976175)
			(xy 166.076141 -318.951568) (xy 166.03802 -318.920443) (xy 166.005385 -318.883606) (xy 165.979082 -318.84201)
			(xy 165.959791 -318.796734) (xy 165.948014 -318.74895) (xy 165.944054 -318.699896) (xy 164.655246 -318.699896)
			(xy 164.654751 -318.724503) (xy 164.646856 -318.77308) (xy 164.631272 -318.819761) (xy 164.608401 -318.863338)
			(xy 164.578836 -318.902682) (xy 164.543343 -318.936774) (xy 164.50284 -318.96473) (xy 164.458378 -318.985828)
			(xy 164.411107 -318.99952) (xy 164.362252 -319.005452) (xy 164.313077 -319.003471) (xy 164.264858 -318.993627)
			(xy 164.218842 -318.976175) (xy 164.176221 -318.951568) (xy 164.1381 -318.920443) (xy 164.105465 -318.883606)
			(xy 164.079162 -318.84201) (xy 164.059871 -318.796734) (xy 164.048094 -318.74895) (xy 164.044134 -318.699896)
			(xy 162.755326 -318.699896) (xy 162.754831 -318.724503) (xy 162.746936 -318.77308) (xy 162.731352 -318.819761)
			(xy 162.708481 -318.863338) (xy 162.678916 -318.902682) (xy 162.643423 -318.936774) (xy 162.60292 -318.96473)
			(xy 162.558458 -318.985828) (xy 162.511187 -318.99952) (xy 162.462332 -319.005452) (xy 162.413157 -319.003471)
			(xy 162.364938 -318.993627) (xy 162.318922 -318.976175) (xy 162.276301 -318.951568) (xy 162.23818 -318.920443)
			(xy 162.205545 -318.883606) (xy 162.179242 -318.84201) (xy 162.159951 -318.796734) (xy 162.148174 -318.74895)
			(xy 162.144214 -318.699896) (xy 160.855152 -318.699896) (xy 160.854657 -318.724503) (xy 160.846762 -318.77308)
			(xy 160.831178 -318.819761) (xy 160.808307 -318.863338) (xy 160.778742 -318.902682) (xy 160.743249 -318.936774)
			(xy 160.702746 -318.96473) (xy 160.658284 -318.985828) (xy 160.611013 -318.99952) (xy 160.562158 -319.005452)
			(xy 160.512983 -319.003471) (xy 160.464764 -318.993627) (xy 160.418748 -318.976175) (xy 160.376127 -318.951568)
			(xy 160.338006 -318.920443) (xy 160.305371 -318.883606) (xy 160.279068 -318.84201) (xy 160.259777 -318.796734)
			(xy 160.248 -318.74895) (xy 160.24404 -318.699896) (xy 158.955232 -318.699896) (xy 158.954737 -318.724503)
			(xy 158.946842 -318.77308) (xy 158.931258 -318.819761) (xy 158.908387 -318.863338) (xy 158.878822 -318.902682)
			(xy 158.843329 -318.936774) (xy 158.802826 -318.96473) (xy 158.758364 -318.985828) (xy 158.711093 -318.99952)
			(xy 158.662238 -319.005452) (xy 158.613063 -319.003471) (xy 158.564844 -318.993627) (xy 158.518828 -318.976175)
			(xy 158.476207 -318.951568) (xy 158.438086 -318.920443) (xy 158.405451 -318.883606) (xy 158.379148 -318.84201)
			(xy 158.359857 -318.796734) (xy 158.34808 -318.74895) (xy 158.34412 -318.699896) (xy 157.055312 -318.699896)
			(xy 157.054817 -318.724503) (xy 157.046922 -318.77308) (xy 157.031338 -318.819761) (xy 157.008467 -318.863338)
			(xy 156.978902 -318.902682) (xy 156.943409 -318.936774) (xy 156.902906 -318.96473) (xy 156.858444 -318.985828)
			(xy 156.811173 -318.99952) (xy 156.762318 -319.005452) (xy 156.713143 -319.003471) (xy 156.664924 -318.993627)
			(xy 156.618908 -318.976175) (xy 156.576287 -318.951568) (xy 156.538166 -318.920443) (xy 156.505531 -318.883606)
			(xy 156.479228 -318.84201) (xy 156.459937 -318.796734) (xy 156.44816 -318.74895) (xy 156.4442 -318.699896)
			(xy 155.155392 -318.699896) (xy 155.154897 -318.724503) (xy 155.147002 -318.77308) (xy 155.131418 -318.819761)
			(xy 155.108547 -318.863338) (xy 155.078982 -318.902682) (xy 155.043489 -318.936774) (xy 155.002986 -318.96473)
			(xy 154.958524 -318.985828) (xy 154.911253 -318.99952) (xy 154.862398 -319.005452) (xy 154.813223 -319.003471)
			(xy 154.765004 -318.993627) (xy 154.718988 -318.976175) (xy 154.676367 -318.951568) (xy 154.638246 -318.920443)
			(xy 154.605611 -318.883606) (xy 154.579308 -318.84201) (xy 154.560017 -318.796734) (xy 154.54824 -318.74895)
			(xy 154.54428 -318.699896) (xy 147.426741 -318.699896) (xy 147.499951 -318.756463) (xy 147.612488 -318.853497)
			(xy 147.719655 -318.956432) (xy 147.821142 -319.064971) (xy 147.916656 -319.1788) (xy 148.005923 -319.297593)
			(xy 148.088684 -319.421005) (xy 148.164702 -319.548683) (xy 148.233757 -319.680256) (xy 148.29565 -319.815347)
			(xy 148.350203 -319.953564) (xy 148.397258 -320.094511) (xy 148.43668 -320.237781) (xy 148.468354 -320.38296)
			(xy 148.49219 -320.529629) (xy 148.508119 -320.677367) (xy 148.516095 -320.825747) (xy 148.516594 -320.900044)
			(xy 202.982331 -320.900044) (xy 202.98632 -320.751504) (xy 202.998277 -320.603391) (xy 203.018167 -320.456134)
			(xy 203.045932 -320.310158) (xy 203.081493 -320.165881) (xy 203.124747 -320.023722) (xy 203.175569 -319.884089)
			(xy 203.233813 -319.747386) (xy 203.299311 -319.614006) (xy 203.371874 -319.484334) (xy 203.451292 -319.358744)
			(xy 203.537337 -319.237597) (xy 203.629761 -319.121244) (xy 203.728297 -319.01002) (xy 203.832661 -318.904245)
			(xy 203.942553 -318.804225) (xy 204.057654 -318.710247) (xy 204.177634 -318.622583) (xy 204.302147 -318.541486)
			(xy 204.430833 -318.467189) (xy 204.563322 -318.399907) (xy 204.699231 -318.339833) (xy 204.838169 -318.287141)
			(xy 204.979735 -318.241982) (xy 205.123521 -318.204487) (xy 205.269112 -318.174765) (xy 205.416088 -318.1529)
			(xy 205.564027 -318.138956) (xy 205.7125 -318.132972) (xy 205.861081 -318.134967) (xy 206.00934 -318.144935)
			(xy 206.156851 -318.162846) (xy 206.303187 -318.188649) (xy 206.447928 -318.222269) (xy 206.590655 -318.263611)
			(xy 206.730958 -318.312554) (xy 206.868431 -318.368957) (xy 207.002678 -318.432658) (xy 207.133313 -318.503474)
			(xy 207.259958 -318.581199) (xy 207.382248 -318.66561) (xy 207.499831 -318.756463) (xy 207.612368 -318.853497)
			(xy 207.719535 -318.956432) (xy 207.821022 -319.064971) (xy 207.916536 -319.1788) (xy 208.005803 -319.297593)
			(xy 208.088564 -319.421005) (xy 208.164582 -319.548683) (xy 208.233637 -319.680256) (xy 208.29553 -319.815347)
			(xy 208.350083 -319.953564) (xy 208.397138 -320.094511) (xy 208.43656 -320.237781) (xy 208.468234 -320.38296)
			(xy 208.49207 -320.529629) (xy 208.507999 -320.677367) (xy 208.515975 -320.825747) (xy 208.516474 -320.900044)
			(xy 259.082549 -320.900044) (xy 259.086538 -320.751504) (xy 259.098495 -320.603391) (xy 259.118385 -320.456134)
			(xy 259.14615 -320.310158) (xy 259.181711 -320.165881) (xy 259.224965 -320.023722) (xy 259.275787 -319.884089)
			(xy 259.334031 -319.747386) (xy 259.399529 -319.614006) (xy 259.472092 -319.484334) (xy 259.55151 -319.358744)
			(xy 259.637555 -319.237597) (xy 259.729979 -319.121244) (xy 259.828515 -319.01002) (xy 259.932879 -318.904245)
			(xy 260.042771 -318.804225) (xy 260.157872 -318.710247) (xy 260.277852 -318.622583) (xy 260.402365 -318.541486)
			(xy 260.531051 -318.467189) (xy 260.66354 -318.399907) (xy 260.799449 -318.339833) (xy 260.938387 -318.287141)
			(xy 261.079953 -318.241982) (xy 261.223739 -318.204487) (xy 261.36933 -318.174765) (xy 261.516306 -318.1529)
			(xy 261.664245 -318.138956) (xy 261.812718 -318.132972) (xy 261.961299 -318.134967) (xy 262.109558 -318.144935)
			(xy 262.257069 -318.162846) (xy 262.403405 -318.188649) (xy 262.548146 -318.222269) (xy 262.690873 -318.263611)
			(xy 262.831176 -318.312554) (xy 262.968649 -318.368957) (xy 263.102896 -318.432658) (xy 263.233531 -318.503474)
			(xy 263.360176 -318.581199) (xy 263.482466 -318.66561) (xy 263.526839 -318.699896) (xy 283.944072 -318.699896)
			(xy 283.948032 -318.650842) (xy 283.959809 -318.603058) (xy 283.9791 -318.557782) (xy 284.005403 -318.516186)
			(xy 284.038038 -318.479349) (xy 284.076159 -318.448224) (xy 284.11878 -318.423617) (xy 284.164796 -318.406165)
			(xy 284.213015 -318.396321) (xy 284.26219 -318.39434) (xy 284.311045 -318.400272) (xy 284.358316 -318.413964)
			(xy 284.402778 -318.435062) (xy 284.443281 -318.463018) (xy 284.478774 -318.49711) (xy 284.508339 -318.536454)
			(xy 284.53121 -318.580031) (xy 284.546794 -318.626712) (xy 284.554689 -318.675289) (xy 284.555184 -318.699896)
			(xy 285.843992 -318.699896) (xy 285.847952 -318.650842) (xy 285.859729 -318.603058) (xy 285.87902 -318.557782)
			(xy 285.905323 -318.516186) (xy 285.937958 -318.479349) (xy 285.976079 -318.448224) (xy 286.0187 -318.423617)
			(xy 286.064716 -318.406165) (xy 286.112935 -318.396321) (xy 286.16211 -318.39434) (xy 286.210965 -318.400272)
			(xy 286.258236 -318.413964) (xy 286.302698 -318.435062) (xy 286.343201 -318.463018) (xy 286.378694 -318.49711)
			(xy 286.408259 -318.536454) (xy 286.43113 -318.580031) (xy 286.446714 -318.626712) (xy 286.454609 -318.675289)
			(xy 286.455104 -318.699896) (xy 287.743912 -318.699896) (xy 287.747872 -318.650842) (xy 287.759649 -318.603058)
			(xy 287.77894 -318.557782) (xy 287.805243 -318.516186) (xy 287.837878 -318.479349) (xy 287.875999 -318.448224)
			(xy 287.91862 -318.423617) (xy 287.964636 -318.406165) (xy 288.012855 -318.396321) (xy 288.06203 -318.39434)
			(xy 288.110885 -318.400272) (xy 288.158156 -318.413964) (xy 288.202618 -318.435062) (xy 288.243121 -318.463018)
			(xy 288.278614 -318.49711) (xy 288.308179 -318.536454) (xy 288.33105 -318.580031) (xy 288.346634 -318.626712)
			(xy 288.354529 -318.675289) (xy 288.355024 -318.699896) (xy 289.644086 -318.699896) (xy 289.648046 -318.650842)
			(xy 289.659823 -318.603058) (xy 289.679114 -318.557782) (xy 289.705417 -318.516186) (xy 289.738052 -318.479349)
			(xy 289.776173 -318.448224) (xy 289.818794 -318.423617) (xy 289.86481 -318.406165) (xy 289.913029 -318.396321)
			(xy 289.962204 -318.39434) (xy 290.011059 -318.400272) (xy 290.05833 -318.413964) (xy 290.102792 -318.435062)
			(xy 290.143295 -318.463018) (xy 290.178788 -318.49711) (xy 290.208353 -318.536454) (xy 290.231224 -318.580031)
			(xy 290.246808 -318.626712) (xy 290.254703 -318.675289) (xy 290.255198 -318.699896) (xy 291.544006 -318.699896)
			(xy 291.547966 -318.650842) (xy 291.559743 -318.603058) (xy 291.579034 -318.557782) (xy 291.605337 -318.516186)
			(xy 291.637972 -318.479349) (xy 291.676093 -318.448224) (xy 291.718714 -318.423617) (xy 291.76473 -318.406165)
			(xy 291.812949 -318.396321) (xy 291.862124 -318.39434) (xy 291.910979 -318.400272) (xy 291.95825 -318.413964)
			(xy 292.002712 -318.435062) (xy 292.043215 -318.463018) (xy 292.078708 -318.49711) (xy 292.108273 -318.536454)
			(xy 292.131144 -318.580031) (xy 292.146728 -318.626712) (xy 292.154623 -318.675289) (xy 292.155118 -318.699896)
			(xy 293.443926 -318.699896) (xy 293.447886 -318.650842) (xy 293.459663 -318.603058) (xy 293.478954 -318.557782)
			(xy 293.505257 -318.516186) (xy 293.537892 -318.479349) (xy 293.576013 -318.448224) (xy 293.618634 -318.423617)
			(xy 293.66465 -318.406165) (xy 293.712869 -318.396321) (xy 293.762044 -318.39434) (xy 293.810899 -318.400272)
			(xy 293.85817 -318.413964) (xy 293.902632 -318.435062) (xy 293.943135 -318.463018) (xy 293.978628 -318.49711)
			(xy 294.008193 -318.536454) (xy 294.031064 -318.580031) (xy 294.046648 -318.626712) (xy 294.054543 -318.675289)
			(xy 294.055038 -318.699896) (xy 295.3441 -318.699896) (xy 295.34806 -318.650842) (xy 295.359837 -318.603058)
			(xy 295.379128 -318.557782) (xy 295.405431 -318.516186) (xy 295.438066 -318.479349) (xy 295.476187 -318.448224)
			(xy 295.518808 -318.423617) (xy 295.564824 -318.406165) (xy 295.613043 -318.396321) (xy 295.662218 -318.39434)
			(xy 295.711073 -318.400272) (xy 295.758344 -318.413964) (xy 295.802806 -318.435062) (xy 295.843309 -318.463018)
			(xy 295.878802 -318.49711) (xy 295.908367 -318.536454) (xy 295.931238 -318.580031) (xy 295.946822 -318.626712)
			(xy 295.954717 -318.675289) (xy 295.955212 -318.699896) (xy 297.24402 -318.699896) (xy 297.24798 -318.650842)
			(xy 297.259757 -318.603058) (xy 297.279048 -318.557782) (xy 297.305351 -318.516186) (xy 297.337986 -318.479349)
			(xy 297.376107 -318.448224) (xy 297.418728 -318.423617) (xy 297.464744 -318.406165) (xy 297.512963 -318.396321)
			(xy 297.562138 -318.39434) (xy 297.610993 -318.400272) (xy 297.658264 -318.413964) (xy 297.702726 -318.435062)
			(xy 297.743229 -318.463018) (xy 297.778722 -318.49711) (xy 297.808287 -318.536454) (xy 297.831158 -318.580031)
			(xy 297.846742 -318.626712) (xy 297.854637 -318.675289) (xy 297.855132 -318.699896) (xy 306.744128 -318.699896)
			(xy 306.748088 -318.650842) (xy 306.759865 -318.603058) (xy 306.779156 -318.557782) (xy 306.805459 -318.516186)
			(xy 306.838094 -318.479349) (xy 306.876215 -318.448224) (xy 306.918836 -318.423617) (xy 306.964852 -318.406165)
			(xy 307.013071 -318.396321) (xy 307.062246 -318.39434) (xy 307.111101 -318.400272) (xy 307.158372 -318.413964)
			(xy 307.202834 -318.435062) (xy 307.243337 -318.463018) (xy 307.27883 -318.49711) (xy 307.308395 -318.536454)
			(xy 307.331266 -318.580031) (xy 307.34685 -318.626712) (xy 307.354745 -318.675289) (xy 307.35524 -318.699896)
			(xy 308.644048 -318.699896) (xy 308.648008 -318.650842) (xy 308.659785 -318.603058) (xy 308.679076 -318.557782)
			(xy 308.705379 -318.516186) (xy 308.738014 -318.479349) (xy 308.776135 -318.448224) (xy 308.818756 -318.423617)
			(xy 308.864772 -318.406165) (xy 308.912991 -318.396321) (xy 308.962166 -318.39434) (xy 309.011021 -318.400272)
			(xy 309.058292 -318.413964) (xy 309.102754 -318.435062) (xy 309.143257 -318.463018) (xy 309.17875 -318.49711)
			(xy 309.208315 -318.536454) (xy 309.231186 -318.580031) (xy 309.24677 -318.626712) (xy 309.254665 -318.675289)
			(xy 309.25516 -318.699896) (xy 310.543968 -318.699896) (xy 310.547928 -318.650842) (xy 310.559705 -318.603058)
			(xy 310.578996 -318.557782) (xy 310.605299 -318.516186) (xy 310.637934 -318.479349) (xy 310.676055 -318.448224)
			(xy 310.718676 -318.423617) (xy 310.764692 -318.406165) (xy 310.812911 -318.396321) (xy 310.862086 -318.39434)
			(xy 310.910941 -318.400272) (xy 310.958212 -318.413964) (xy 311.002674 -318.435062) (xy 311.043177 -318.463018)
			(xy 311.07867 -318.49711) (xy 311.108235 -318.536454) (xy 311.131106 -318.580031) (xy 311.14669 -318.626712)
			(xy 311.154585 -318.675289) (xy 311.15508 -318.699896) (xy 312.443888 -318.699896) (xy 312.447848 -318.650842)
			(xy 312.459625 -318.603058) (xy 312.478916 -318.557782) (xy 312.505219 -318.516186) (xy 312.537854 -318.479349)
			(xy 312.575975 -318.448224) (xy 312.618596 -318.423617) (xy 312.664612 -318.406165) (xy 312.712831 -318.396321)
			(xy 312.762006 -318.39434) (xy 312.810861 -318.400272) (xy 312.858132 -318.413964) (xy 312.902594 -318.435062)
			(xy 312.943097 -318.463018) (xy 312.97859 -318.49711) (xy 313.008155 -318.536454) (xy 313.031026 -318.580031)
			(xy 313.04661 -318.626712) (xy 313.054505 -318.675289) (xy 313.055 -318.699896) (xy 313.054505 -318.724503)
			(xy 313.04661 -318.77308) (xy 313.031026 -318.819761) (xy 313.008155 -318.863338) (xy 312.97859 -318.902682)
			(xy 312.943097 -318.936774) (xy 312.902594 -318.96473) (xy 312.858132 -318.985828) (xy 312.810861 -318.99952)
			(xy 312.762006 -319.005452) (xy 312.712831 -319.003471) (xy 312.664612 -318.993627) (xy 312.618596 -318.976175)
			(xy 312.575975 -318.951568) (xy 312.537854 -318.920443) (xy 312.505219 -318.883606) (xy 312.478916 -318.84201)
			(xy 312.459625 -318.796734) (xy 312.447848 -318.74895) (xy 312.443888 -318.699896) (xy 311.15508 -318.699896)
			(xy 311.154585 -318.724503) (xy 311.14669 -318.77308) (xy 311.131106 -318.819761) (xy 311.108235 -318.863338)
			(xy 311.07867 -318.902682) (xy 311.043177 -318.936774) (xy 311.002674 -318.96473) (xy 310.958212 -318.985828)
			(xy 310.910941 -318.99952) (xy 310.862086 -319.005452) (xy 310.812911 -319.003471) (xy 310.764692 -318.993627)
			(xy 310.718676 -318.976175) (xy 310.676055 -318.951568) (xy 310.637934 -318.920443) (xy 310.605299 -318.883606)
			(xy 310.578996 -318.84201) (xy 310.559705 -318.796734) (xy 310.547928 -318.74895) (xy 310.543968 -318.699896)
			(xy 309.25516 -318.699896) (xy 309.254665 -318.724503) (xy 309.24677 -318.77308) (xy 309.231186 -318.819761)
			(xy 309.208315 -318.863338) (xy 309.17875 -318.902682) (xy 309.143257 -318.936774) (xy 309.102754 -318.96473)
			(xy 309.058292 -318.985828) (xy 309.011021 -318.99952) (xy 308.962166 -319.005452) (xy 308.912991 -319.003471)
			(xy 308.864772 -318.993627) (xy 308.818756 -318.976175) (xy 308.776135 -318.951568) (xy 308.738014 -318.920443)
			(xy 308.705379 -318.883606) (xy 308.679076 -318.84201) (xy 308.659785 -318.796734) (xy 308.648008 -318.74895)
			(xy 308.644048 -318.699896) (xy 307.35524 -318.699896) (xy 307.354745 -318.724503) (xy 307.34685 -318.77308)
			(xy 307.331266 -318.819761) (xy 307.308395 -318.863338) (xy 307.27883 -318.902682) (xy 307.243337 -318.936774)
			(xy 307.202834 -318.96473) (xy 307.158372 -318.985828) (xy 307.111101 -318.99952) (xy 307.062246 -319.005452)
			(xy 307.013071 -319.003471) (xy 306.964852 -318.993627) (xy 306.918836 -318.976175) (xy 306.876215 -318.951568)
			(xy 306.838094 -318.920443) (xy 306.805459 -318.883606) (xy 306.779156 -318.84201) (xy 306.759865 -318.796734)
			(xy 306.748088 -318.74895) (xy 306.744128 -318.699896) (xy 297.855132 -318.699896) (xy 297.854637 -318.724503)
			(xy 297.846742 -318.77308) (xy 297.831158 -318.819761) (xy 297.808287 -318.863338) (xy 297.778722 -318.902682)
			(xy 297.743229 -318.936774) (xy 297.702726 -318.96473) (xy 297.658264 -318.985828) (xy 297.610993 -318.99952)
			(xy 297.562138 -319.005452) (xy 297.512963 -319.003471) (xy 297.464744 -318.993627) (xy 297.418728 -318.976175)
			(xy 297.376107 -318.951568) (xy 297.337986 -318.920443) (xy 297.305351 -318.883606) (xy 297.279048 -318.84201)
			(xy 297.259757 -318.796734) (xy 297.24798 -318.74895) (xy 297.24402 -318.699896) (xy 295.955212 -318.699896)
			(xy 295.954717 -318.724503) (xy 295.946822 -318.77308) (xy 295.931238 -318.819761) (xy 295.908367 -318.863338)
			(xy 295.878802 -318.902682) (xy 295.843309 -318.936774) (xy 295.802806 -318.96473) (xy 295.758344 -318.985828)
			(xy 295.711073 -318.99952) (xy 295.662218 -319.005452) (xy 295.613043 -319.003471) (xy 295.564824 -318.993627)
			(xy 295.518808 -318.976175) (xy 295.476187 -318.951568) (xy 295.438066 -318.920443) (xy 295.405431 -318.883606)
			(xy 295.379128 -318.84201) (xy 295.359837 -318.796734) (xy 295.34806 -318.74895) (xy 295.3441 -318.699896)
			(xy 294.055038 -318.699896) (xy 294.054543 -318.724503) (xy 294.046648 -318.77308) (xy 294.031064 -318.819761)
			(xy 294.008193 -318.863338) (xy 293.978628 -318.902682) (xy 293.943135 -318.936774) (xy 293.902632 -318.96473)
			(xy 293.85817 -318.985828) (xy 293.810899 -318.99952) (xy 293.762044 -319.005452) (xy 293.712869 -319.003471)
			(xy 293.66465 -318.993627) (xy 293.618634 -318.976175) (xy 293.576013 -318.951568) (xy 293.537892 -318.920443)
			(xy 293.505257 -318.883606) (xy 293.478954 -318.84201) (xy 293.459663 -318.796734) (xy 293.447886 -318.74895)
			(xy 293.443926 -318.699896) (xy 292.155118 -318.699896) (xy 292.154623 -318.724503) (xy 292.146728 -318.77308)
			(xy 292.131144 -318.819761) (xy 292.108273 -318.863338) (xy 292.078708 -318.902682) (xy 292.043215 -318.936774)
			(xy 292.002712 -318.96473) (xy 291.95825 -318.985828) (xy 291.910979 -318.99952) (xy 291.862124 -319.005452)
			(xy 291.812949 -319.003471) (xy 291.76473 -318.993627) (xy 291.718714 -318.976175) (xy 291.676093 -318.951568)
			(xy 291.637972 -318.920443) (xy 291.605337 -318.883606) (xy 291.579034 -318.84201) (xy 291.559743 -318.796734)
			(xy 291.547966 -318.74895) (xy 291.544006 -318.699896) (xy 290.255198 -318.699896) (xy 290.254703 -318.724503)
			(xy 290.246808 -318.77308) (xy 290.231224 -318.819761) (xy 290.208353 -318.863338) (xy 290.178788 -318.902682)
			(xy 290.143295 -318.936774) (xy 290.102792 -318.96473) (xy 290.05833 -318.985828) (xy 290.011059 -318.99952)
			(xy 289.962204 -319.005452) (xy 289.913029 -319.003471) (xy 289.86481 -318.993627) (xy 289.818794 -318.976175)
			(xy 289.776173 -318.951568) (xy 289.738052 -318.920443) (xy 289.705417 -318.883606) (xy 289.679114 -318.84201)
			(xy 289.659823 -318.796734) (xy 289.648046 -318.74895) (xy 289.644086 -318.699896) (xy 288.355024 -318.699896)
			(xy 288.354529 -318.724503) (xy 288.346634 -318.77308) (xy 288.33105 -318.819761) (xy 288.308179 -318.863338)
			(xy 288.278614 -318.902682) (xy 288.243121 -318.936774) (xy 288.202618 -318.96473) (xy 288.158156 -318.985828)
			(xy 288.110885 -318.99952) (xy 288.06203 -319.005452) (xy 288.012855 -319.003471) (xy 287.964636 -318.993627)
			(xy 287.91862 -318.976175) (xy 287.875999 -318.951568) (xy 287.837878 -318.920443) (xy 287.805243 -318.883606)
			(xy 287.77894 -318.84201) (xy 287.759649 -318.796734) (xy 287.747872 -318.74895) (xy 287.743912 -318.699896)
			(xy 286.455104 -318.699896) (xy 286.454609 -318.724503) (xy 286.446714 -318.77308) (xy 286.43113 -318.819761)
			(xy 286.408259 -318.863338) (xy 286.378694 -318.902682) (xy 286.343201 -318.936774) (xy 286.302698 -318.96473)
			(xy 286.258236 -318.985828) (xy 286.210965 -318.99952) (xy 286.16211 -319.005452) (xy 286.112935 -319.003471)
			(xy 286.064716 -318.993627) (xy 286.0187 -318.976175) (xy 285.976079 -318.951568) (xy 285.937958 -318.920443)
			(xy 285.905323 -318.883606) (xy 285.87902 -318.84201) (xy 285.859729 -318.796734) (xy 285.847952 -318.74895)
			(xy 285.843992 -318.699896) (xy 284.555184 -318.699896) (xy 284.554689 -318.724503) (xy 284.546794 -318.77308)
			(xy 284.53121 -318.819761) (xy 284.508339 -318.863338) (xy 284.478774 -318.902682) (xy 284.443281 -318.936774)
			(xy 284.402778 -318.96473) (xy 284.358316 -318.985828) (xy 284.311045 -318.99952) (xy 284.26219 -319.005452)
			(xy 284.213015 -319.003471) (xy 284.164796 -318.993627) (xy 284.11878 -318.976175) (xy 284.076159 -318.951568)
			(xy 284.038038 -318.920443) (xy 284.005403 -318.883606) (xy 283.9791 -318.84201) (xy 283.959809 -318.796734)
			(xy 283.948032 -318.74895) (xy 283.944072 -318.699896) (xy 263.526839 -318.699896) (xy 263.600049 -318.756463)
			(xy 263.712586 -318.853497) (xy 263.819753 -318.956432) (xy 263.92124 -319.064971) (xy 264.016754 -319.1788)
			(xy 264.106021 -319.297593) (xy 264.188782 -319.421005) (xy 264.2648 -319.548683) (xy 264.333855 -319.680256)
			(xy 264.395748 -319.815347) (xy 264.450301 -319.953564) (xy 264.497356 -320.094511) (xy 264.536778 -320.237781)
			(xy 264.568452 -320.38296) (xy 264.592288 -320.529629) (xy 264.608217 -320.677367) (xy 264.616193 -320.825747)
			(xy 264.616692 -320.900044) (xy 319.082429 -320.900044) (xy 319.086418 -320.751504) (xy 319.098375 -320.603391)
			(xy 319.118265 -320.456134) (xy 319.14603 -320.310158) (xy 319.181591 -320.165881) (xy 319.224845 -320.023722)
			(xy 319.275667 -319.884089) (xy 319.333911 -319.747386) (xy 319.399409 -319.614006) (xy 319.471972 -319.484334)
			(xy 319.55139 -319.358744) (xy 319.637435 -319.237597) (xy 319.729859 -319.121244) (xy 319.828395 -319.01002)
			(xy 319.932759 -318.904245) (xy 320.042651 -318.804225) (xy 320.157752 -318.710247) (xy 320.277732 -318.622583)
			(xy 320.402245 -318.541486) (xy 320.530931 -318.467189) (xy 320.66342 -318.399907) (xy 320.799329 -318.339833)
			(xy 320.938267 -318.287141) (xy 321.079833 -318.241982) (xy 321.223619 -318.204487) (xy 321.36921 -318.174765)
			(xy 321.516186 -318.1529) (xy 321.664125 -318.138956) (xy 321.812598 -318.132972) (xy 321.961179 -318.134967)
			(xy 322.109438 -318.144935) (xy 322.256949 -318.162846) (xy 322.403285 -318.188649) (xy 322.548026 -318.222269)
			(xy 322.690753 -318.263611) (xy 322.831056 -318.312554) (xy 322.968529 -318.368957) (xy 323.102776 -318.432658)
			(xy 323.233411 -318.503474) (xy 323.360056 -318.581199) (xy 323.482346 -318.66561) (xy 323.599929 -318.756463)
			(xy 323.712466 -318.853497) (xy 323.819633 -318.956432) (xy 323.92112 -319.064971) (xy 324.016634 -319.1788)
			(xy 324.105901 -319.297593) (xy 324.188662 -319.421005) (xy 324.26468 -319.548683) (xy 324.333735 -319.680256)
			(xy 324.395628 -319.815347) (xy 324.450181 -319.953564) (xy 324.497236 -320.094511) (xy 324.536658 -320.237781)
			(xy 324.568332 -320.38296) (xy 324.592168 -320.529629) (xy 324.608097 -320.677367) (xy 324.616073 -320.825747)
			(xy 324.616572 -320.900044) (xy 375.182393 -320.900044) (xy 375.186382 -320.751504) (xy 375.198339 -320.603391)
			(xy 375.218229 -320.456134) (xy 375.245994 -320.310158) (xy 375.281555 -320.165881) (xy 375.324809 -320.023722)
			(xy 375.375631 -319.884089) (xy 375.433875 -319.747386) (xy 375.499373 -319.614006) (xy 375.571936 -319.484334)
			(xy 375.651354 -319.358744) (xy 375.737399 -319.237597) (xy 375.829823 -319.121244) (xy 375.928359 -319.01002)
			(xy 376.032723 -318.904245) (xy 376.142615 -318.804225) (xy 376.257716 -318.710247) (xy 376.377696 -318.622583)
			(xy 376.502209 -318.541486) (xy 376.630895 -318.467189) (xy 376.763384 -318.399907) (xy 376.899293 -318.339833)
			(xy 377.038231 -318.287141) (xy 377.179797 -318.241982) (xy 377.323583 -318.204487) (xy 377.469174 -318.174765)
			(xy 377.61615 -318.1529) (xy 377.764089 -318.138956) (xy 377.912562 -318.132972) (xy 378.061143 -318.134967)
			(xy 378.209402 -318.144935) (xy 378.356913 -318.162846) (xy 378.503249 -318.188649) (xy 378.64799 -318.222269)
			(xy 378.790717 -318.263611) (xy 378.93102 -318.312554) (xy 379.068493 -318.368957) (xy 379.20274 -318.432658)
			(xy 379.333375 -318.503474) (xy 379.46002 -318.581199) (xy 379.58231 -318.66561) (xy 379.626683 -318.699896)
			(xy 386.744222 -318.699896) (xy 386.748182 -318.650842) (xy 386.759959 -318.603058) (xy 386.77925 -318.557782)
			(xy 386.805553 -318.516186) (xy 386.838188 -318.479349) (xy 386.876309 -318.448224) (xy 386.91893 -318.423617)
			(xy 386.964946 -318.406165) (xy 387.013165 -318.396321) (xy 387.06234 -318.39434) (xy 387.111195 -318.400272)
			(xy 387.158466 -318.413964) (xy 387.202928 -318.435062) (xy 387.243431 -318.463018) (xy 387.278924 -318.49711)
			(xy 387.308489 -318.536454) (xy 387.33136 -318.580031) (xy 387.346944 -318.626712) (xy 387.354839 -318.675289)
			(xy 387.355334 -318.699896) (xy 388.644142 -318.699896) (xy 388.648102 -318.650842) (xy 388.659879 -318.603058)
			(xy 388.67917 -318.557782) (xy 388.705473 -318.516186) (xy 388.738108 -318.479349) (xy 388.776229 -318.448224)
			(xy 388.81885 -318.423617) (xy 388.864866 -318.406165) (xy 388.913085 -318.396321) (xy 388.96226 -318.39434)
			(xy 389.011115 -318.400272) (xy 389.058386 -318.413964) (xy 389.102848 -318.435062) (xy 389.143351 -318.463018)
			(xy 389.178844 -318.49711) (xy 389.208409 -318.536454) (xy 389.23128 -318.580031) (xy 389.246864 -318.626712)
			(xy 389.254759 -318.675289) (xy 389.255254 -318.699896) (xy 390.544062 -318.699896) (xy 390.548022 -318.650842)
			(xy 390.559799 -318.603058) (xy 390.57909 -318.557782) (xy 390.605393 -318.516186) (xy 390.638028 -318.479349)
			(xy 390.676149 -318.448224) (xy 390.71877 -318.423617) (xy 390.764786 -318.406165) (xy 390.813005 -318.396321)
			(xy 390.86218 -318.39434) (xy 390.911035 -318.400272) (xy 390.958306 -318.413964) (xy 391.002768 -318.435062)
			(xy 391.043271 -318.463018) (xy 391.078764 -318.49711) (xy 391.108329 -318.536454) (xy 391.1312 -318.580031)
			(xy 391.146784 -318.626712) (xy 391.154679 -318.675289) (xy 391.155174 -318.699896) (xy 392.443982 -318.699896)
			(xy 392.447942 -318.650842) (xy 392.459719 -318.603058) (xy 392.47901 -318.557782) (xy 392.505313 -318.516186)
			(xy 392.537948 -318.479349) (xy 392.576069 -318.448224) (xy 392.61869 -318.423617) (xy 392.664706 -318.406165)
			(xy 392.712925 -318.396321) (xy 392.7621 -318.39434) (xy 392.810955 -318.400272) (xy 392.858226 -318.413964)
			(xy 392.902688 -318.435062) (xy 392.943191 -318.463018) (xy 392.978684 -318.49711) (xy 393.008249 -318.536454)
			(xy 393.03112 -318.580031) (xy 393.046704 -318.626712) (xy 393.054599 -318.675289) (xy 393.055094 -318.699896)
			(xy 394.344156 -318.699896) (xy 394.348116 -318.650842) (xy 394.359893 -318.603058) (xy 394.379184 -318.557782)
			(xy 394.405487 -318.516186) (xy 394.438122 -318.479349) (xy 394.476243 -318.448224) (xy 394.518864 -318.423617)
			(xy 394.56488 -318.406165) (xy 394.613099 -318.396321) (xy 394.662274 -318.39434) (xy 394.711129 -318.400272)
			(xy 394.7584 -318.413964) (xy 394.802862 -318.435062) (xy 394.843365 -318.463018) (xy 394.878858 -318.49711)
			(xy 394.908423 -318.536454) (xy 394.931294 -318.580031) (xy 394.946878 -318.626712) (xy 394.954773 -318.675289)
			(xy 394.955268 -318.699896) (xy 396.244076 -318.699896) (xy 396.248036 -318.650842) (xy 396.259813 -318.603058)
			(xy 396.279104 -318.557782) (xy 396.305407 -318.516186) (xy 396.338042 -318.479349) (xy 396.376163 -318.448224)
			(xy 396.418784 -318.423617) (xy 396.4648 -318.406165) (xy 396.513019 -318.396321) (xy 396.562194 -318.39434)
			(xy 396.611049 -318.400272) (xy 396.65832 -318.413964) (xy 396.702782 -318.435062) (xy 396.743285 -318.463018)
			(xy 396.778778 -318.49711) (xy 396.808343 -318.536454) (xy 396.831214 -318.580031) (xy 396.846798 -318.626712)
			(xy 396.854693 -318.675289) (xy 396.855188 -318.699896) (xy 398.143996 -318.699896) (xy 398.147956 -318.650842)
			(xy 398.159733 -318.603058) (xy 398.179024 -318.557782) (xy 398.205327 -318.516186) (xy 398.237962 -318.479349)
			(xy 398.276083 -318.448224) (xy 398.318704 -318.423617) (xy 398.36472 -318.406165) (xy 398.412939 -318.396321)
			(xy 398.462114 -318.39434) (xy 398.510969 -318.400272) (xy 398.55824 -318.413964) (xy 398.602702 -318.435062)
			(xy 398.643205 -318.463018) (xy 398.678698 -318.49711) (xy 398.708263 -318.536454) (xy 398.731134 -318.580031)
			(xy 398.746718 -318.626712) (xy 398.754613 -318.675289) (xy 398.755108 -318.699896) (xy 415.244038 -318.699896)
			(xy 415.247998 -318.650842) (xy 415.259775 -318.603058) (xy 415.279066 -318.557782) (xy 415.305369 -318.516186)
			(xy 415.338004 -318.479349) (xy 415.376125 -318.448224) (xy 415.418746 -318.423617) (xy 415.464762 -318.406165)
			(xy 415.512981 -318.396321) (xy 415.562156 -318.39434) (xy 415.611011 -318.400272) (xy 415.658282 -318.413964)
			(xy 415.702744 -318.435062) (xy 415.743247 -318.463018) (xy 415.77874 -318.49711) (xy 415.808305 -318.536454)
			(xy 415.831176 -318.580031) (xy 415.84676 -318.626712) (xy 415.854655 -318.675289) (xy 415.85515 -318.699896)
			(xy 417.144212 -318.699896) (xy 417.148172 -318.650842) (xy 417.159949 -318.603058) (xy 417.17924 -318.557782)
			(xy 417.205543 -318.516186) (xy 417.238178 -318.479349) (xy 417.276299 -318.448224) (xy 417.31892 -318.423617)
			(xy 417.364936 -318.406165) (xy 417.413155 -318.396321) (xy 417.46233 -318.39434) (xy 417.511185 -318.400272)
			(xy 417.558456 -318.413964) (xy 417.602918 -318.435062) (xy 417.643421 -318.463018) (xy 417.678914 -318.49711)
			(xy 417.708479 -318.536454) (xy 417.73135 -318.580031) (xy 417.746934 -318.626712) (xy 417.754829 -318.675289)
			(xy 417.755324 -318.699896) (xy 419.044132 -318.699896) (xy 419.048092 -318.650842) (xy 419.059869 -318.603058)
			(xy 419.07916 -318.557782) (xy 419.105463 -318.516186) (xy 419.138098 -318.479349) (xy 419.176219 -318.448224)
			(xy 419.21884 -318.423617) (xy 419.264856 -318.406165) (xy 419.313075 -318.396321) (xy 419.36225 -318.39434)
			(xy 419.411105 -318.400272) (xy 419.458376 -318.413964) (xy 419.502838 -318.435062) (xy 419.543341 -318.463018)
			(xy 419.578834 -318.49711) (xy 419.608399 -318.536454) (xy 419.63127 -318.580031) (xy 419.646854 -318.626712)
			(xy 419.654749 -318.675289) (xy 419.655244 -318.699896) (xy 420.944052 -318.699896) (xy 420.948012 -318.650842)
			(xy 420.959789 -318.603058) (xy 420.97908 -318.557782) (xy 421.005383 -318.516186) (xy 421.038018 -318.479349)
			(xy 421.076139 -318.448224) (xy 421.11876 -318.423617) (xy 421.164776 -318.406165) (xy 421.212995 -318.396321)
			(xy 421.26217 -318.39434) (xy 421.311025 -318.400272) (xy 421.358296 -318.413964) (xy 421.402758 -318.435062)
			(xy 421.443261 -318.463018) (xy 421.478754 -318.49711) (xy 421.508319 -318.536454) (xy 421.53119 -318.580031)
			(xy 421.546774 -318.626712) (xy 421.554669 -318.675289) (xy 421.555164 -318.699896) (xy 421.554669 -318.724503)
			(xy 421.546774 -318.77308) (xy 421.53119 -318.819761) (xy 421.508319 -318.863338) (xy 421.478754 -318.902682)
			(xy 421.443261 -318.936774) (xy 421.402758 -318.96473) (xy 421.358296 -318.985828) (xy 421.311025 -318.99952)
			(xy 421.26217 -319.005452) (xy 421.212995 -319.003471) (xy 421.164776 -318.993627) (xy 421.11876 -318.976175)
			(xy 421.076139 -318.951568) (xy 421.038018 -318.920443) (xy 421.005383 -318.883606) (xy 420.97908 -318.84201)
			(xy 420.959789 -318.796734) (xy 420.948012 -318.74895) (xy 420.944052 -318.699896) (xy 419.655244 -318.699896)
			(xy 419.654749 -318.724503) (xy 419.646854 -318.77308) (xy 419.63127 -318.819761) (xy 419.608399 -318.863338)
			(xy 419.578834 -318.902682) (xy 419.543341 -318.936774) (xy 419.502838 -318.96473) (xy 419.458376 -318.985828)
			(xy 419.411105 -318.99952) (xy 419.36225 -319.005452) (xy 419.313075 -319.003471) (xy 419.264856 -318.993627)
			(xy 419.21884 -318.976175) (xy 419.176219 -318.951568) (xy 419.138098 -318.920443) (xy 419.105463 -318.883606)
			(xy 419.07916 -318.84201) (xy 419.059869 -318.796734) (xy 419.048092 -318.74895) (xy 419.044132 -318.699896)
			(xy 417.755324 -318.699896) (xy 417.754829 -318.724503) (xy 417.746934 -318.77308) (xy 417.73135 -318.819761)
			(xy 417.708479 -318.863338) (xy 417.678914 -318.902682) (xy 417.643421 -318.936774) (xy 417.602918 -318.96473)
			(xy 417.558456 -318.985828) (xy 417.511185 -318.99952) (xy 417.46233 -319.005452) (xy 417.413155 -319.003471)
			(xy 417.364936 -318.993627) (xy 417.31892 -318.976175) (xy 417.276299 -318.951568) (xy 417.238178 -318.920443)
			(xy 417.205543 -318.883606) (xy 417.17924 -318.84201) (xy 417.159949 -318.796734) (xy 417.148172 -318.74895)
			(xy 417.144212 -318.699896) (xy 415.85515 -318.699896) (xy 415.854655 -318.724503) (xy 415.84676 -318.77308)
			(xy 415.831176 -318.819761) (xy 415.808305 -318.863338) (xy 415.77874 -318.902682) (xy 415.743247 -318.936774)
			(xy 415.702744 -318.96473) (xy 415.658282 -318.985828) (xy 415.611011 -318.99952) (xy 415.562156 -319.005452)
			(xy 415.512981 -319.003471) (xy 415.464762 -318.993627) (xy 415.418746 -318.976175) (xy 415.376125 -318.951568)
			(xy 415.338004 -318.920443) (xy 415.305369 -318.883606) (xy 415.279066 -318.84201) (xy 415.259775 -318.796734)
			(xy 415.247998 -318.74895) (xy 415.244038 -318.699896) (xy 398.755108 -318.699896) (xy 398.754613 -318.724503)
			(xy 398.746718 -318.77308) (xy 398.731134 -318.819761) (xy 398.708263 -318.863338) (xy 398.678698 -318.902682)
			(xy 398.643205 -318.936774) (xy 398.602702 -318.96473) (xy 398.55824 -318.985828) (xy 398.510969 -318.99952)
			(xy 398.462114 -319.005452) (xy 398.412939 -319.003471) (xy 398.36472 -318.993627) (xy 398.318704 -318.976175)
			(xy 398.276083 -318.951568) (xy 398.237962 -318.920443) (xy 398.205327 -318.883606) (xy 398.179024 -318.84201)
			(xy 398.159733 -318.796734) (xy 398.147956 -318.74895) (xy 398.143996 -318.699896) (xy 396.855188 -318.699896)
			(xy 396.854693 -318.724503) (xy 396.846798 -318.77308) (xy 396.831214 -318.819761) (xy 396.808343 -318.863338)
			(xy 396.778778 -318.902682) (xy 396.743285 -318.936774) (xy 396.702782 -318.96473) (xy 396.65832 -318.985828)
			(xy 396.611049 -318.99952) (xy 396.562194 -319.005452) (xy 396.513019 -319.003471) (xy 396.4648 -318.993627)
			(xy 396.418784 -318.976175) (xy 396.376163 -318.951568) (xy 396.338042 -318.920443) (xy 396.305407 -318.883606)
			(xy 396.279104 -318.84201) (xy 396.259813 -318.796734) (xy 396.248036 -318.74895) (xy 396.244076 -318.699896)
			(xy 394.955268 -318.699896) (xy 394.954773 -318.724503) (xy 394.946878 -318.77308) (xy 394.931294 -318.819761)
			(xy 394.908423 -318.863338) (xy 394.878858 -318.902682) (xy 394.843365 -318.936774) (xy 394.802862 -318.96473)
			(xy 394.7584 -318.985828) (xy 394.711129 -318.99952) (xy 394.662274 -319.005452) (xy 394.613099 -319.003471)
			(xy 394.56488 -318.993627) (xy 394.518864 -318.976175) (xy 394.476243 -318.951568) (xy 394.438122 -318.920443)
			(xy 394.405487 -318.883606) (xy 394.379184 -318.84201) (xy 394.359893 -318.796734) (xy 394.348116 -318.74895)
			(xy 394.344156 -318.699896) (xy 393.055094 -318.699896) (xy 393.054599 -318.724503) (xy 393.046704 -318.77308)
			(xy 393.03112 -318.819761) (xy 393.008249 -318.863338) (xy 392.978684 -318.902682) (xy 392.943191 -318.936774)
			(xy 392.902688 -318.96473) (xy 392.858226 -318.985828) (xy 392.810955 -318.99952) (xy 392.7621 -319.005452)
			(xy 392.712925 -319.003471) (xy 392.664706 -318.993627) (xy 392.61869 -318.976175) (xy 392.576069 -318.951568)
			(xy 392.537948 -318.920443) (xy 392.505313 -318.883606) (xy 392.47901 -318.84201) (xy 392.459719 -318.796734)
			(xy 392.447942 -318.74895) (xy 392.443982 -318.699896) (xy 391.155174 -318.699896) (xy 391.154679 -318.724503)
			(xy 391.146784 -318.77308) (xy 391.1312 -318.819761) (xy 391.108329 -318.863338) (xy 391.078764 -318.902682)
			(xy 391.043271 -318.936774) (xy 391.002768 -318.96473) (xy 390.958306 -318.985828) (xy 390.911035 -318.99952)
			(xy 390.86218 -319.005452) (xy 390.813005 -319.003471) (xy 390.764786 -318.993627) (xy 390.71877 -318.976175)
			(xy 390.676149 -318.951568) (xy 390.638028 -318.920443) (xy 390.605393 -318.883606) (xy 390.57909 -318.84201)
			(xy 390.559799 -318.796734) (xy 390.548022 -318.74895) (xy 390.544062 -318.699896) (xy 389.255254 -318.699896)
			(xy 389.254759 -318.724503) (xy 389.246864 -318.77308) (xy 389.23128 -318.819761) (xy 389.208409 -318.863338)
			(xy 389.178844 -318.902682) (xy 389.143351 -318.936774) (xy 389.102848 -318.96473) (xy 389.058386 -318.985828)
			(xy 389.011115 -318.99952) (xy 388.96226 -319.005452) (xy 388.913085 -319.003471) (xy 388.864866 -318.993627)
			(xy 388.81885 -318.976175) (xy 388.776229 -318.951568) (xy 388.738108 -318.920443) (xy 388.705473 -318.883606)
			(xy 388.67917 -318.84201) (xy 388.659879 -318.796734) (xy 388.648102 -318.74895) (xy 388.644142 -318.699896)
			(xy 387.355334 -318.699896) (xy 387.354839 -318.724503) (xy 387.346944 -318.77308) (xy 387.33136 -318.819761)
			(xy 387.308489 -318.863338) (xy 387.278924 -318.902682) (xy 387.243431 -318.936774) (xy 387.202928 -318.96473)
			(xy 387.158466 -318.985828) (xy 387.111195 -318.99952) (xy 387.06234 -319.005452) (xy 387.013165 -319.003471)
			(xy 386.964946 -318.993627) (xy 386.91893 -318.976175) (xy 386.876309 -318.951568) (xy 386.838188 -318.920443)
			(xy 386.805553 -318.883606) (xy 386.77925 -318.84201) (xy 386.759959 -318.796734) (xy 386.748182 -318.74895)
			(xy 386.744222 -318.699896) (xy 379.626683 -318.699896) (xy 379.699893 -318.756463) (xy 379.81243 -318.853497)
			(xy 379.919597 -318.956432) (xy 380.021084 -319.064971) (xy 380.116598 -319.1788) (xy 380.205865 -319.297593)
			(xy 380.288626 -319.421005) (xy 380.364644 -319.548683) (xy 380.433699 -319.680256) (xy 380.495592 -319.815347)
			(xy 380.550145 -319.953564) (xy 380.5972 -320.094511) (xy 380.636622 -320.237781) (xy 380.668296 -320.38296)
			(xy 380.692132 -320.529629) (xy 380.708061 -320.677367) (xy 380.716037 -320.825747) (xy 380.716536 -320.900044)
			(xy 435.182527 -320.900044) (xy 435.186516 -320.751504) (xy 435.198473 -320.603391) (xy 435.218363 -320.456134)
			(xy 435.246128 -320.310158) (xy 435.281689 -320.165881) (xy 435.324943 -320.023722) (xy 435.375765 -319.884089)
			(xy 435.434009 -319.747386) (xy 435.499507 -319.614006) (xy 435.57207 -319.484334) (xy 435.651488 -319.358744)
			(xy 435.737533 -319.237597) (xy 435.829957 -319.121244) (xy 435.928493 -319.01002) (xy 436.032857 -318.904245)
			(xy 436.142749 -318.804225) (xy 436.25785 -318.710247) (xy 436.37783 -318.622583) (xy 436.502343 -318.541486)
			(xy 436.631029 -318.467189) (xy 436.763518 -318.399907) (xy 436.899427 -318.339833) (xy 437.038365 -318.287141)
			(xy 437.179931 -318.241982) (xy 437.323717 -318.204487) (xy 437.469308 -318.174765) (xy 437.616284 -318.1529)
			(xy 437.764223 -318.138956) (xy 437.912696 -318.132972) (xy 438.061277 -318.134967) (xy 438.209536 -318.144935)
			(xy 438.357047 -318.162846) (xy 438.503383 -318.188649) (xy 438.648124 -318.222269) (xy 438.790851 -318.263611)
			(xy 438.931154 -318.312554) (xy 439.068627 -318.368957) (xy 439.202874 -318.432658) (xy 439.333509 -318.503474)
			(xy 439.460154 -318.581199) (xy 439.582444 -318.66561) (xy 439.700027 -318.756463) (xy 439.812564 -318.853497)
			(xy 439.919731 -318.956432) (xy 440.021218 -319.064971) (xy 440.116732 -319.1788) (xy 440.205999 -319.297593)
			(xy 440.28876 -319.421005) (xy 440.364778 -319.548683) (xy 440.433833 -319.680256) (xy 440.495726 -319.815347)
			(xy 440.550279 -319.953564) (xy 440.597334 -320.094511) (xy 440.636756 -320.237781) (xy 440.66843 -320.38296)
			(xy 440.692266 -320.529629) (xy 440.708195 -320.677367) (xy 440.716171 -320.825747) (xy 440.71667 -320.900044)
			(xy 440.716171 -320.974341) (xy 440.708195 -321.122721) (xy 440.692266 -321.270459) (xy 440.66843 -321.417128)
			(xy 440.636756 -321.562307) (xy 440.597334 -321.705577) (xy 440.550279 -321.846524) (xy 440.495726 -321.984741)
			(xy 440.433833 -322.119832) (xy 440.364778 -322.251405) (xy 440.28876 -322.379083) (xy 440.205999 -322.502495)
			(xy 440.116732 -322.621288) (xy 440.021218 -322.735117) (xy 439.919731 -322.843656) (xy 439.812564 -322.946591)
			(xy 439.700027 -323.043625) (xy 439.582444 -323.134478) (xy 439.460154 -323.218889) (xy 439.333509 -323.296614)
			(xy 439.202874 -323.36743) (xy 439.068627 -323.431131) (xy 438.931154 -323.487534) (xy 438.790851 -323.536477)
			(xy 438.648124 -323.577819) (xy 438.503383 -323.611439) (xy 438.357047 -323.637242) (xy 438.209536 -323.655153)
			(xy 438.061277 -323.665121) (xy 437.912696 -323.667116) (xy 437.764223 -323.661132) (xy 437.616284 -323.647188)
			(xy 437.469308 -323.625323) (xy 437.323717 -323.595601) (xy 437.179931 -323.558106) (xy 437.038365 -323.512947)
			(xy 436.899427 -323.460255) (xy 436.763518 -323.400181) (xy 436.631029 -323.332899) (xy 436.502343 -323.258602)
			(xy 436.37783 -323.177505) (xy 436.25785 -323.089841) (xy 436.142749 -322.995863) (xy 436.032857 -322.895843)
			(xy 435.928493 -322.790068) (xy 435.829957 -322.678844) (xy 435.737533 -322.562491) (xy 435.651488 -322.441344)
			(xy 435.57207 -322.315754) (xy 435.499507 -322.186082) (xy 435.434009 -322.052702) (xy 435.375765 -321.915999)
			(xy 435.324943 -321.776366) (xy 435.281689 -321.634207) (xy 435.246128 -321.48993) (xy 435.218363 -321.343954)
			(xy 435.198473 -321.196697) (xy 435.186516 -321.048584) (xy 435.182527 -320.900044) (xy 380.716536 -320.900044)
			(xy 380.716037 -320.974341) (xy 380.708061 -321.122721) (xy 380.692132 -321.270459) (xy 380.668296 -321.417128)
			(xy 380.636622 -321.562307) (xy 380.5972 -321.705577) (xy 380.550145 -321.846524) (xy 380.495592 -321.984741)
			(xy 380.433699 -322.119832) (xy 380.364644 -322.251405) (xy 380.288626 -322.379083) (xy 380.205865 -322.502495)
			(xy 380.116598 -322.621288) (xy 380.021084 -322.735117) (xy 379.919597 -322.843656) (xy 379.81243 -322.946591)
			(xy 379.699893 -323.043625) (xy 379.58231 -323.134478) (xy 379.46002 -323.218889) (xy 379.333375 -323.296614)
			(xy 379.20274 -323.36743) (xy 379.068493 -323.431131) (xy 378.93102 -323.487534) (xy 378.790717 -323.536477)
			(xy 378.64799 -323.577819) (xy 378.503249 -323.611439) (xy 378.356913 -323.637242) (xy 378.209402 -323.655153)
			(xy 378.061143 -323.665121) (xy 377.912562 -323.667116) (xy 377.764089 -323.661132) (xy 377.61615 -323.647188)
			(xy 377.469174 -323.625323) (xy 377.323583 -323.595601) (xy 377.179797 -323.558106) (xy 377.038231 -323.512947)
			(xy 376.899293 -323.460255) (xy 376.763384 -323.400181) (xy 376.630895 -323.332899) (xy 376.502209 -323.258602)
			(xy 376.377696 -323.177505) (xy 376.257716 -323.089841) (xy 376.142615 -322.995863) (xy 376.032723 -322.895843)
			(xy 375.928359 -322.790068) (xy 375.829823 -322.678844) (xy 375.737399 -322.562491) (xy 375.651354 -322.441344)
			(xy 375.571936 -322.315754) (xy 375.499373 -322.186082) (xy 375.433875 -322.052702) (xy 375.375631 -321.915999)
			(xy 375.324809 -321.776366) (xy 375.281555 -321.634207) (xy 375.245994 -321.48993) (xy 375.218229 -321.343954)
			(xy 375.198339 -321.196697) (xy 375.186382 -321.048584) (xy 375.182393 -320.900044) (xy 324.616572 -320.900044)
			(xy 324.616073 -320.974341) (xy 324.608097 -321.122721) (xy 324.592168 -321.270459) (xy 324.568332 -321.417128)
			(xy 324.536658 -321.562307) (xy 324.497236 -321.705577) (xy 324.450181 -321.846524) (xy 324.395628 -321.984741)
			(xy 324.333735 -322.119832) (xy 324.26468 -322.251405) (xy 324.188662 -322.379083) (xy 324.105901 -322.502495)
			(xy 324.016634 -322.621288) (xy 323.92112 -322.735117) (xy 323.819633 -322.843656) (xy 323.712466 -322.946591)
			(xy 323.599929 -323.043625) (xy 323.482346 -323.134478) (xy 323.360056 -323.218889) (xy 323.233411 -323.296614)
			(xy 323.102776 -323.36743) (xy 322.968529 -323.431131) (xy 322.831056 -323.487534) (xy 322.690753 -323.536477)
			(xy 322.548026 -323.577819) (xy 322.403285 -323.611439) (xy 322.256949 -323.637242) (xy 322.109438 -323.655153)
			(xy 321.961179 -323.665121) (xy 321.812598 -323.667116) (xy 321.664125 -323.661132) (xy 321.516186 -323.647188)
			(xy 321.36921 -323.625323) (xy 321.223619 -323.595601) (xy 321.079833 -323.558106) (xy 320.938267 -323.512947)
			(xy 320.799329 -323.460255) (xy 320.66342 -323.400181) (xy 320.530931 -323.332899) (xy 320.402245 -323.258602)
			(xy 320.277732 -323.177505) (xy 320.157752 -323.089841) (xy 320.042651 -322.995863) (xy 319.932759 -322.895843)
			(xy 319.828395 -322.790068) (xy 319.729859 -322.678844) (xy 319.637435 -322.562491) (xy 319.55139 -322.441344)
			(xy 319.471972 -322.315754) (xy 319.399409 -322.186082) (xy 319.333911 -322.052702) (xy 319.275667 -321.915999)
			(xy 319.224845 -321.776366) (xy 319.181591 -321.634207) (xy 319.14603 -321.48993) (xy 319.118265 -321.343954)
			(xy 319.098375 -321.196697) (xy 319.086418 -321.048584) (xy 319.082429 -320.900044) (xy 264.616692 -320.900044)
			(xy 264.616193 -320.974341) (xy 264.608217 -321.122721) (xy 264.592288 -321.270459) (xy 264.568452 -321.417128)
			(xy 264.536778 -321.562307) (xy 264.497356 -321.705577) (xy 264.450301 -321.846524) (xy 264.395748 -321.984741)
			(xy 264.333855 -322.119832) (xy 264.2648 -322.251405) (xy 264.188782 -322.379083) (xy 264.106021 -322.502495)
			(xy 264.016754 -322.621288) (xy 263.92124 -322.735117) (xy 263.819753 -322.843656) (xy 263.712586 -322.946591)
			(xy 263.600049 -323.043625) (xy 263.482466 -323.134478) (xy 263.360176 -323.218889) (xy 263.233531 -323.296614)
			(xy 263.102896 -323.36743) (xy 262.968649 -323.431131) (xy 262.831176 -323.487534) (xy 262.690873 -323.536477)
			(xy 262.548146 -323.577819) (xy 262.403405 -323.611439) (xy 262.257069 -323.637242) (xy 262.109558 -323.655153)
			(xy 261.961299 -323.665121) (xy 261.812718 -323.667116) (xy 261.664245 -323.661132) (xy 261.516306 -323.647188)
			(xy 261.36933 -323.625323) (xy 261.223739 -323.595601) (xy 261.079953 -323.558106) (xy 260.938387 -323.512947)
			(xy 260.799449 -323.460255) (xy 260.66354 -323.400181) (xy 260.531051 -323.332899) (xy 260.402365 -323.258602)
			(xy 260.277852 -323.177505) (xy 260.157872 -323.089841) (xy 260.042771 -322.995863) (xy 259.932879 -322.895843)
			(xy 259.828515 -322.790068) (xy 259.729979 -322.678844) (xy 259.637555 -322.562491) (xy 259.55151 -322.441344)
			(xy 259.472092 -322.315754) (xy 259.399529 -322.186082) (xy 259.334031 -322.052702) (xy 259.275787 -321.915999)
			(xy 259.224965 -321.776366) (xy 259.181711 -321.634207) (xy 259.14615 -321.48993) (xy 259.118385 -321.343954)
			(xy 259.098495 -321.196697) (xy 259.086538 -321.048584) (xy 259.082549 -320.900044) (xy 208.516474 -320.900044)
			(xy 208.515975 -320.974341) (xy 208.507999 -321.122721) (xy 208.49207 -321.270459) (xy 208.468234 -321.417128)
			(xy 208.43656 -321.562307) (xy 208.397138 -321.705577) (xy 208.350083 -321.846524) (xy 208.29553 -321.984741)
			(xy 208.233637 -322.119832) (xy 208.164582 -322.251405) (xy 208.088564 -322.379083) (xy 208.005803 -322.502495)
			(xy 207.916536 -322.621288) (xy 207.821022 -322.735117) (xy 207.719535 -322.843656) (xy 207.612368 -322.946591)
			(xy 207.499831 -323.043625) (xy 207.382248 -323.134478) (xy 207.259958 -323.218889) (xy 207.133313 -323.296614)
			(xy 207.002678 -323.36743) (xy 206.868431 -323.431131) (xy 206.730958 -323.487534) (xy 206.590655 -323.536477)
			(xy 206.447928 -323.577819) (xy 206.303187 -323.611439) (xy 206.156851 -323.637242) (xy 206.00934 -323.655153)
			(xy 205.861081 -323.665121) (xy 205.7125 -323.667116) (xy 205.564027 -323.661132) (xy 205.416088 -323.647188)
			(xy 205.269112 -323.625323) (xy 205.123521 -323.595601) (xy 204.979735 -323.558106) (xy 204.838169 -323.512947)
			(xy 204.699231 -323.460255) (xy 204.563322 -323.400181) (xy 204.430833 -323.332899) (xy 204.302147 -323.258602)
			(xy 204.177634 -323.177505) (xy 204.057654 -323.089841) (xy 203.942553 -322.995863) (xy 203.832661 -322.895843)
			(xy 203.728297 -322.790068) (xy 203.629761 -322.678844) (xy 203.537337 -322.562491) (xy 203.451292 -322.441344)
			(xy 203.371874 -322.315754) (xy 203.299311 -322.186082) (xy 203.233813 -322.052702) (xy 203.175569 -321.915999)
			(xy 203.124747 -321.776366) (xy 203.081493 -321.634207) (xy 203.045932 -321.48993) (xy 203.018167 -321.343954)
			(xy 202.998277 -321.196697) (xy 202.98632 -321.048584) (xy 202.982331 -320.900044) (xy 148.516594 -320.900044)
			(xy 148.516095 -320.974341) (xy 148.508119 -321.122721) (xy 148.49219 -321.270459) (xy 148.468354 -321.417128)
			(xy 148.43668 -321.562307) (xy 148.397258 -321.705577) (xy 148.350203 -321.846524) (xy 148.29565 -321.984741)
			(xy 148.233757 -322.119832) (xy 148.164702 -322.251405) (xy 148.088684 -322.379083) (xy 148.005923 -322.502495)
			(xy 147.916656 -322.621288) (xy 147.821142 -322.735117) (xy 147.719655 -322.843656) (xy 147.612488 -322.946591)
			(xy 147.499951 -323.043625) (xy 147.382368 -323.134478) (xy 147.260078 -323.218889) (xy 147.133433 -323.296614)
			(xy 147.002798 -323.36743) (xy 146.868551 -323.431131) (xy 146.731078 -323.487534) (xy 146.590775 -323.536477)
			(xy 146.448048 -323.577819) (xy 146.303307 -323.611439) (xy 146.156971 -323.637242) (xy 146.00946 -323.655153)
			(xy 145.861201 -323.665121) (xy 145.71262 -323.667116) (xy 145.564147 -323.661132) (xy 145.416208 -323.647188)
			(xy 145.269232 -323.625323) (xy 145.123641 -323.595601) (xy 144.979855 -323.558106) (xy 144.838289 -323.512947)
			(xy 144.699351 -323.460255) (xy 144.563442 -323.400181) (xy 144.430953 -323.332899) (xy 144.302267 -323.258602)
			(xy 144.177754 -323.177505) (xy 144.057774 -323.089841) (xy 143.942673 -322.995863) (xy 143.832781 -322.895843)
			(xy 143.728417 -322.790068) (xy 143.629881 -322.678844) (xy 143.537457 -322.562491) (xy 143.451412 -322.441344)
			(xy 143.371994 -322.315754) (xy 143.299431 -322.186082) (xy 143.233933 -322.052702) (xy 143.175689 -321.915999)
			(xy 143.124867 -321.776366) (xy 143.081613 -321.634207) (xy 143.046052 -321.48993) (xy 143.018287 -321.343954)
			(xy 142.998397 -321.196697) (xy 142.98644 -321.048584) (xy 142.982451 -320.900044) (xy 92.41663 -320.900044)
			(xy 92.416131 -320.974341) (xy 92.408155 -321.122721) (xy 92.392226 -321.270459) (xy 92.36839 -321.417128)
			(xy 92.336716 -321.562307) (xy 92.297294 -321.705577) (xy 92.250239 -321.846524) (xy 92.195686 -321.984741)
			(xy 92.133793 -322.119832) (xy 92.064738 -322.251405) (xy 91.98872 -322.379083) (xy 91.905959 -322.502495)
			(xy 91.816692 -322.621288) (xy 91.721178 -322.735117) (xy 91.619691 -322.843656) (xy 91.512524 -322.946591)
			(xy 91.399987 -323.043625) (xy 91.282404 -323.134478) (xy 91.160114 -323.218889) (xy 91.033469 -323.296614)
			(xy 90.902834 -323.36743) (xy 90.768587 -323.431131) (xy 90.631114 -323.487534) (xy 90.490811 -323.536477)
			(xy 90.348084 -323.577819) (xy 90.203343 -323.611439) (xy 90.057007 -323.637242) (xy 89.909496 -323.655153)
			(xy 89.761237 -323.665121) (xy 89.612656 -323.667116) (xy 89.464183 -323.661132) (xy 89.316244 -323.647188)
			(xy 89.169268 -323.625323) (xy 89.023677 -323.595601) (xy 88.879891 -323.558106) (xy 88.738325 -323.512947)
			(xy 88.599387 -323.460255) (xy 88.463478 -323.400181) (xy 88.330989 -323.332899) (xy 88.202303 -323.258602)
			(xy 88.07779 -323.177505) (xy 87.95781 -323.089841) (xy 87.842709 -322.995863) (xy 87.732817 -322.895843)
			(xy 87.628453 -322.790068) (xy 87.529917 -322.678844) (xy 87.437493 -322.562491) (xy 87.351448 -322.441344)
			(xy 87.27203 -322.315754) (xy 87.199467 -322.186082) (xy 87.133969 -322.052702) (xy 87.075725 -321.915999)
			(xy 87.024903 -321.776366) (xy 86.981649 -321.634207) (xy 86.946088 -321.48993) (xy 86.918323 -321.343954)
			(xy 86.898433 -321.196697) (xy 86.886476 -321.048584) (xy 86.882487 -320.900044) (xy 32.416496 -320.900044)
			(xy 32.415997 -320.974341) (xy 32.408021 -321.122721) (xy 32.392092 -321.270459) (xy 32.368256 -321.417128)
			(xy 32.336582 -321.562307) (xy 32.29716 -321.705577) (xy 32.250105 -321.846524) (xy 32.195552 -321.984741)
			(xy 32.133659 -322.119832) (xy 32.064604 -322.251405) (xy 31.988586 -322.379083) (xy 31.905825 -322.502495)
			(xy 31.816558 -322.621288) (xy 31.721044 -322.735117) (xy 31.619557 -322.843656) (xy 31.51239 -322.946591)
			(xy 31.399853 -323.043625) (xy 31.28227 -323.134478) (xy 31.15998 -323.218889) (xy 31.033335 -323.296614)
			(xy 30.9027 -323.36743) (xy 30.768453 -323.431131) (xy 30.63098 -323.487534) (xy 30.490677 -323.536477)
			(xy 30.34795 -323.577819) (xy 30.203209 -323.611439) (xy 30.056873 -323.637242) (xy 29.909362 -323.655153)
			(xy 29.761103 -323.665121) (xy 29.612522 -323.667116) (xy 29.464049 -323.661132) (xy 29.31611 -323.647188)
			(xy 29.169134 -323.625323) (xy 29.023543 -323.595601) (xy 28.879757 -323.558106) (xy 28.738191 -323.512947)
			(xy 28.599253 -323.460255) (xy 28.463344 -323.400181) (xy 28.330855 -323.332899) (xy 28.202169 -323.258602)
			(xy 28.077656 -323.177505) (xy 27.957676 -323.089841) (xy 27.842575 -322.995863) (xy 27.732683 -322.895843)
			(xy 27.628319 -322.790068) (xy 27.529783 -322.678844) (xy 27.437359 -322.562491) (xy 27.351314 -322.441344)
			(xy 27.271896 -322.315754) (xy 27.199333 -322.186082) (xy 27.133835 -322.052702) (xy 27.075591 -321.915999)
			(xy 27.024769 -321.776366) (xy 26.981515 -321.634207) (xy 26.945954 -321.48993) (xy 26.918189 -321.343954)
			(xy 26.898299 -321.196697) (xy 26.886342 -321.048584) (xy 26.882353 -320.900044) (xy 0.508 -320.900044)
			(xy 0.508 -330.416662) (xy 97.355152 -330.416662) (xy 97.355152 -329.553062) (xy 97.355642 -329.523078)
			(xy 97.36347 -329.463622) (xy 97.378991 -329.405697) (xy 97.40194 -329.350293) (xy 97.431924 -329.298359)
			(xy 97.46843 -329.250783) (xy 97.510835 -329.208378) (xy 97.558411 -329.171872) (xy 97.610345 -329.141888)
			(xy 97.665749 -329.118939) (xy 97.723674 -329.103418) (xy 97.78313 -329.09559) (xy 97.843098 -329.09559)
			(xy 97.902554 -329.103418) (xy 97.960479 -329.118939) (xy 98.015883 -329.141888) (xy 98.067817 -329.171872)
			(xy 98.115393 -329.208378) (xy 98.157798 -329.250783) (xy 98.194304 -329.298359) (xy 98.224288 -329.350293)
			(xy 98.247237 -329.405697) (xy 98.262758 -329.463622) (xy 98.270586 -329.523078) (xy 98.271076 -329.553062)
			(xy 98.271076 -330.416662) (xy 98.270586 -330.446646) (xy 98.262758 -330.506102) (xy 98.247237 -330.564027)
			(xy 98.224288 -330.619431) (xy 98.194304 -330.671365) (xy 98.157798 -330.718941) (xy 98.115393 -330.761346)
			(xy 98.067817 -330.797852) (xy 98.015883 -330.827836) (xy 97.960479 -330.850785) (xy 97.902554 -330.866306)
			(xy 97.843098 -330.874134) (xy 97.78313 -330.874134) (xy 97.723674 -330.866306) (xy 97.665749 -330.850785)
			(xy 97.610345 -330.827836) (xy 97.558411 -330.797852) (xy 97.510835 -330.761346) (xy 97.46843 -330.718941)
			(xy 97.431924 -330.671365) (xy 97.40194 -330.619431) (xy 97.378991 -330.564027) (xy 97.36347 -330.506102)
			(xy 97.355642 -330.446646) (xy 97.355152 -330.416662) (xy 0.508 -330.416662) (xy 0.508 -331.53223)
			(xy 114.955828 -331.53223) (xy 114.955828 -330.66863) (xy 114.956318 -330.638646) (xy 114.964146 -330.57919)
			(xy 114.979667 -330.521265) (xy 115.002616 -330.465861) (xy 115.0326 -330.413927) (xy 115.069106 -330.366351)
			(xy 115.111511 -330.323946) (xy 115.159087 -330.28744) (xy 115.211021 -330.257456) (xy 115.266425 -330.234507)
			(xy 115.32435 -330.218986) (xy 115.383806 -330.211158) (xy 115.443774 -330.211158) (xy 115.50323 -330.218986)
			(xy 115.561155 -330.234507) (xy 115.616559 -330.257456) (xy 115.668493 -330.28744) (xy 115.716069 -330.323946)
			(xy 115.758474 -330.366351) (xy 115.79498 -330.413927) (xy 115.824964 -330.465861) (xy 115.847913 -330.521265)
			(xy 115.863434 -330.57919) (xy 115.871262 -330.638646) (xy 115.871752 -330.66863) (xy 115.871752 -331.53223)
			(xy 115.871262 -331.562214) (xy 115.863434 -331.62167) (xy 115.847913 -331.679595) (xy 115.824964 -331.734999)
			(xy 115.79498 -331.786933) (xy 115.758474 -331.834509) (xy 115.716069 -331.876914) (xy 115.668493 -331.91342)
			(xy 115.616559 -331.943404) (xy 115.561155 -331.966353) (xy 115.50323 -331.981874) (xy 115.443774 -331.989702)
			(xy 115.383806 -331.989702) (xy 115.32435 -331.981874) (xy 115.266425 -331.966353) (xy 115.211021 -331.943404)
			(xy 115.159087 -331.91342) (xy 115.111511 -331.876914) (xy 115.069106 -331.834509) (xy 115.0326 -331.786933)
			(xy 115.002616 -331.734999) (xy 114.979667 -331.679595) (xy 114.964146 -331.62167) (xy 114.956318 -331.562214)
			(xy 114.955828 -331.53223) (xy 0.508 -331.53223) (xy 0.508 -333.950056) (xy 93.5736 -333.950056)
			(xy 93.5736 -333.086456) (xy 93.57409 -333.056488) (xy 93.581913 -332.997066) (xy 93.597426 -332.939173)
			(xy 93.620362 -332.8838) (xy 93.650329 -332.831894) (xy 93.686816 -332.784344) (xy 93.729196 -332.741964)
			(xy 93.776746 -332.705477) (xy 93.828652 -332.67551) (xy 93.884025 -332.652574) (xy 93.941918 -332.637061)
			(xy 94.00134 -332.629238) (xy 94.061276 -332.629238) (xy 94.120698 -332.637061) (xy 94.178591 -332.652574)
			(xy 94.233964 -332.67551) (xy 94.28587 -332.705477) (xy 94.33342 -332.741964) (xy 94.3758 -332.784344)
			(xy 94.412287 -332.831894) (xy 94.442254 -332.8838) (xy 94.46519 -332.939173) (xy 94.46736 -332.947271)
			(xy 365.368753 -332.947271) (xy 365.368753 -332.887329) (xy 365.376578 -332.827899) (xy 365.392093 -332.77)
			(xy 365.415033 -332.71462) (xy 365.445006 -332.66271) (xy 365.481498 -332.615155) (xy 365.523886 -332.572772)
			(xy 365.571443 -332.536283) (xy 365.623356 -332.506315) (xy 365.678737 -332.48338) (xy 365.736639 -332.46787)
			(xy 365.796069 -332.460051) (xy 365.82604 -332.459584) (xy 366.68964 -332.459584) (xy 366.719605 -332.460093)
			(xy 366.779023 -332.46792) (xy 366.836911 -332.483435) (xy 366.892278 -332.506374) (xy 366.944178 -332.536342)
			(xy 366.991723 -332.572828) (xy 367.034098 -332.615207) (xy 367.07058 -332.662755) (xy 367.100544 -332.714658)
			(xy 367.123478 -332.770027) (xy 367.138988 -332.827916) (xy 367.14681 -332.887335) (xy 367.14681 -332.947265)
			(xy 367.138988 -333.006684) (xy 367.123478 -333.064573) (xy 367.100544 -333.119942) (xy 367.07058 -333.171845)
			(xy 367.034098 -333.219393) (xy 366.991723 -333.261772) (xy 366.944178 -333.298258) (xy 366.892278 -333.328226)
			(xy 366.836911 -333.351165) (xy 366.779023 -333.36668) (xy 366.719605 -333.374507) (xy 366.68964 -333.375)
			(xy 365.82604 -333.375) (xy 365.796069 -333.374549) (xy 365.736639 -333.36673) (xy 365.678737 -333.35122)
			(xy 365.623356 -333.328285) (xy 365.571443 -333.298317) (xy 365.523886 -333.261828) (xy 365.481498 -333.219445)
			(xy 365.445006 -333.17189) (xy 365.415033 -333.11998) (xy 365.392093 -333.0646) (xy 365.376578 -333.006701)
			(xy 365.368753 -332.947271) (xy 94.46736 -332.947271) (xy 94.480703 -332.997066) (xy 94.488526 -333.056488)
			(xy 94.489016 -333.086456) (xy 94.489016 -333.950056) (xy 94.488526 -333.980024) (xy 94.480703 -334.039446)
			(xy 94.46519 -334.097339) (xy 94.442254 -334.152712) (xy 94.412287 -334.204618) (xy 94.3758 -334.252168)
			(xy 94.33342 -334.294548) (xy 94.28587 -334.331035) (xy 94.233964 -334.361002) (xy 94.178591 -334.383938)
			(xy 94.120698 -334.399451) (xy 94.061276 -334.407274) (xy 94.00134 -334.407274) (xy 93.941918 -334.399451)
			(xy 93.884025 -334.383938) (xy 93.828652 -334.361002) (xy 93.776746 -334.331035) (xy 93.729196 -334.294548)
			(xy 93.686816 -334.252168) (xy 93.650329 -334.204618) (xy 93.620362 -334.152712) (xy 93.597426 -334.097339)
			(xy 93.581913 -334.039446) (xy 93.57409 -333.980024) (xy 93.5736 -333.950056) (xy 0.508 -333.950056)
			(xy 0.508 -337.266026) (xy 234.403392 -337.266026) (xy 234.403392 -336.402426) (xy 234.403882 -336.372458)
			(xy 234.411705 -336.313036) (xy 234.427218 -336.255143) (xy 234.450154 -336.19977) (xy 234.480121 -336.147864)
			(xy 234.516608 -336.100314) (xy 234.558988 -336.057934) (xy 234.606538 -336.021447) (xy 234.658444 -335.99148)
			(xy 234.713817 -335.968544) (xy 234.77171 -335.953031) (xy 234.831132 -335.945208) (xy 234.891068 -335.945208)
			(xy 234.95049 -335.953031) (xy 235.008383 -335.968544) (xy 235.063756 -335.99148) (xy 235.115662 -336.021447)
			(xy 235.163212 -336.057934) (xy 235.205592 -336.100314) (xy 235.242079 -336.147864) (xy 235.272046 -336.19977)
			(xy 235.294982 -336.255143) (xy 235.310495 -336.313036) (xy 235.318318 -336.372458) (xy 235.318808 -336.402426)
			(xy 235.318808 -337.266026) (xy 235.318318 -337.295994) (xy 235.310495 -337.355416) (xy 235.294982 -337.413309)
			(xy 235.272046 -337.468682) (xy 235.242079 -337.520588) (xy 235.205592 -337.568138) (xy 235.163212 -337.610518)
			(xy 235.115662 -337.647005) (xy 235.063756 -337.676972) (xy 235.008383 -337.699908) (xy 234.95049 -337.715421)
			(xy 234.891068 -337.723244) (xy 234.831132 -337.723244) (xy 234.77171 -337.715421) (xy 234.713817 -337.699908)
			(xy 234.658444 -337.676972) (xy 234.606538 -337.647005) (xy 234.558988 -337.610518) (xy 234.516608 -337.568138)
			(xy 234.480121 -337.520588) (xy 234.450154 -337.468682) (xy 234.427218 -337.413309) (xy 234.411705 -337.355416)
			(xy 234.403882 -337.295994) (xy 234.403392 -337.266026) (xy 0.508 -337.266026) (xy 0.508 -342.466769)
			(xy 18.951172 -342.466769) (xy 18.951172 -342.412231) (xy 18.958934 -342.358247) (xy 18.974299 -342.305917)
			(xy 18.996956 -342.256307) (xy 19.026441 -342.210426) (xy 19.062157 -342.169208) (xy 19.103374 -342.133493)
			(xy 19.149255 -342.104007) (xy 19.198865 -342.08135) (xy 19.251195 -342.065985) (xy 19.305179 -342.058223)
			(xy 19.332448 -342.057736) (xy 20.196048 -342.057736) (xy 20.223319 -342.058203) (xy 20.277306 -342.065965)
			(xy 20.329638 -342.081331) (xy 20.379252 -342.103989) (xy 20.425135 -342.133476) (xy 20.466355 -342.169193)
			(xy 20.502073 -342.210413) (xy 20.53156 -342.256297) (xy 20.554218 -342.30591) (xy 20.569584 -342.358242)
			(xy 20.577347 -342.412229) (xy 20.577347 -342.466771) (xy 20.577347 -342.466772) (xy 22.0601 -342.466772)
			(xy 22.0601 -342.412228) (xy 22.067862 -342.358241) (xy 22.083229 -342.305907) (xy 22.105887 -342.256293)
			(xy 22.135375 -342.210409) (xy 22.171094 -342.169188) (xy 22.212315 -342.133471) (xy 22.2582 -342.103983)
			(xy 22.307815 -342.081326) (xy 22.360148 -342.06596) (xy 22.414136 -342.058199) (xy 22.441408 -342.057736)
			(xy 23.305008 -342.057736) (xy 23.332277 -342.058227) (xy 23.386259 -342.06599) (xy 23.438588 -342.081355)
			(xy 23.488197 -342.104012) (xy 23.534076 -342.133498) (xy 23.575293 -342.169213) (xy 23.611007 -342.21043)
			(xy 23.640492 -342.256311) (xy 23.663147 -342.30592) (xy 23.678512 -342.358249) (xy 23.686274 -342.412231)
			(xy 23.686274 -342.466768) (xy 25.169122 -342.466768) (xy 25.169122 -342.412232) (xy 25.176883 -342.358251)
			(xy 25.192247 -342.305924) (xy 25.214901 -342.256315) (xy 25.244384 -342.210436) (xy 25.280096 -342.169219)
			(xy 25.32131 -342.133503) (xy 25.367187 -342.104016) (xy 25.416794 -342.081358) (xy 25.46912 -342.06599)
			(xy 25.5231 -342.058225) (xy 25.550368 -342.057736) (xy 26.413968 -342.057736) (xy 26.44124 -342.058201)
			(xy 26.49523 -342.06596) (xy 26.547567 -342.081323) (xy 26.597184 -342.103979) (xy 26.643071 -342.133465)
			(xy 26.684295 -342.169183) (xy 26.720015 -342.210403) (xy 26.749506 -342.256288) (xy 26.772166 -342.305903)
			(xy 26.787533 -342.358238) (xy 26.795296 -342.412228) (xy 26.795296 -342.466772) (xy 28.278 -342.466772)
			(xy 28.278 -342.412228) (xy 28.285762 -342.358238) (xy 28.30113 -342.305903) (xy 28.32379 -342.256288)
			(xy 28.35328 -342.210402) (xy 28.389001 -342.169181) (xy 28.430225 -342.133464) (xy 28.476112 -342.103977)
			(xy 28.525729 -342.08132) (xy 28.578065 -342.065957) (xy 28.632056 -342.058198) (xy 28.659328 -342.057736)
			(xy 29.522928 -342.057736) (xy 29.550196 -342.058228) (xy 29.604176 -342.065993) (xy 29.656502 -342.081361)
			(xy 29.706109 -342.104019) (xy 29.751986 -342.133505) (xy 29.7932 -342.16922) (xy 29.828912 -342.210437)
			(xy 29.858395 -342.256316) (xy 29.881049 -342.305924) (xy 29.896413 -342.358251) (xy 29.904174 -342.412232)
			(xy 29.904174 -342.466768) (xy 29.904174 -342.466769) (xy 31.387022 -342.466769) (xy 31.387022 -342.412231)
			(xy 31.394784 -342.358248) (xy 31.410149 -342.305919) (xy 31.432804 -342.25631) (xy 31.462289 -342.210429)
			(xy 31.498003 -342.169212) (xy 31.53922 -342.133496) (xy 31.585099 -342.10401) (xy 31.634708 -342.081353)
			(xy 31.687036 -342.065986) (xy 31.741019 -342.058223) (xy 31.768288 -342.057736) (xy 32.631888 -342.057736)
			(xy 32.659159 -342.058203) (xy 32.713147 -342.065963) (xy 32.765481 -342.081329) (xy 32.815096 -342.103985)
			(xy 32.86098 -342.133472) (xy 32.902202 -342.16919) (xy 32.93792 -342.21041) (xy 32.967409 -342.256294)
			(xy 32.990067 -342.305908) (xy 33.005434 -342.358241) (xy 33.013196 -342.412229) (xy 33.013196 -342.466771)
			(xy 33.013196 -342.466773) (xy 34.4959 -342.466773) (xy 34.4959 -342.412227) (xy 34.503663 -342.358235)
			(xy 34.519032 -342.305899) (xy 34.541693 -342.256282) (xy 34.571185 -342.210396) (xy 34.606908 -342.169174)
			(xy 34.648134 -342.133456) (xy 34.694024 -342.10397) (xy 34.743644 -342.081315) (xy 34.795982 -342.065953)
			(xy 34.849975 -342.058196) (xy 34.877248 -342.057736) (xy 35.740848 -342.057736) (xy 35.768115 -342.05823)
			(xy 35.822093 -342.065997) (xy 35.874417 -342.081366) (xy 35.92402 -342.104025) (xy 35.969895 -342.133512)
			(xy 36.011107 -342.169227) (xy 36.046817 -342.210443) (xy 36.076298 -342.256322) (xy 36.098951 -342.305928)
			(xy 36.114313 -342.358254) (xy 36.122074 -342.412233) (xy 36.122074 -342.466767) (xy 36.122073 -342.466772)
			(xy 37.6049 -342.466772) (xy 37.6049 -342.412228) (xy 37.612662 -342.358241) (xy 37.628029 -342.305907)
			(xy 37.650687 -342.256293) (xy 37.680175 -342.210409) (xy 37.715894 -342.169188) (xy 37.757115 -342.133471)
			(xy 37.803 -342.103983) (xy 37.852615 -342.081326) (xy 37.904948 -342.06596) (xy 37.958936 -342.058199)
			(xy 37.986208 -342.057736) (xy 38.849808 -342.057736) (xy 38.877077 -342.058227) (xy 38.931059 -342.06599)
			(xy 38.983388 -342.081355) (xy 39.032997 -342.104012) (xy 39.078876 -342.133498) (xy 39.120093 -342.169213)
			(xy 39.155807 -342.21043) (xy 39.185292 -342.256311) (xy 39.207947 -342.30592) (xy 39.223312 -342.358249)
			(xy 39.231074 -342.412231) (xy 39.231074 -342.466768) (xy 40.713922 -342.466768) (xy 40.713922 -342.412232)
			(xy 40.721683 -342.358251) (xy 40.737047 -342.305924) (xy 40.759701 -342.256315) (xy 40.789184 -342.210436)
			(xy 40.824896 -342.169219) (xy 40.86611 -342.133503) (xy 40.911987 -342.104016) (xy 40.961594 -342.081358)
			(xy 41.01392 -342.06599) (xy 41.0679 -342.058225) (xy 41.095168 -342.057736) (xy 41.958768 -342.057736)
			(xy 41.98604 -342.058201) (xy 42.04003 -342.06596) (xy 42.092367 -342.081323) (xy 42.141984 -342.103979)
			(xy 42.187871 -342.133465) (xy 42.229095 -342.169183) (xy 42.264815 -342.210403) (xy 42.294306 -342.256288)
			(xy 42.316966 -342.305903) (xy 42.332333 -342.358238) (xy 42.340096 -342.412228) (xy 42.340096 -342.466772)
			(xy 43.8228 -342.466772) (xy 43.8228 -342.412228) (xy 43.830562 -342.358238) (xy 43.84593 -342.305903)
			(xy 43.86859 -342.256288) (xy 43.89808 -342.210402) (xy 43.933801 -342.169181) (xy 43.975025 -342.133464)
			(xy 44.020912 -342.103977) (xy 44.070529 -342.08132) (xy 44.122865 -342.065957) (xy 44.176856 -342.058198)
			(xy 44.204128 -342.057736) (xy 45.067728 -342.057736) (xy 45.094996 -342.058228) (xy 45.148976 -342.065993)
			(xy 45.201302 -342.081361) (xy 45.250909 -342.104019) (xy 45.296786 -342.133505) (xy 45.338 -342.16922)
			(xy 45.373712 -342.210437) (xy 45.403195 -342.256316) (xy 45.425849 -342.305924) (xy 45.441213 -342.358251)
			(xy 45.448974 -342.412232) (xy 45.448974 -342.466768) (xy 45.448974 -342.466769) (xy 46.931822 -342.466769)
			(xy 46.931822 -342.412231) (xy 46.939584 -342.358248) (xy 46.954949 -342.305919) (xy 46.977604 -342.25631)
			(xy 47.007089 -342.210429) (xy 47.042803 -342.169212) (xy 47.08402 -342.133496) (xy 47.129899 -342.10401)
			(xy 47.179508 -342.081353) (xy 47.231836 -342.065986) (xy 47.285819 -342.058223) (xy 47.313088 -342.057736)
			(xy 48.176688 -342.057736) (xy 48.203959 -342.058203) (xy 48.257947 -342.065963) (xy 48.310281 -342.081329)
			(xy 48.359896 -342.103985) (xy 48.40578 -342.133472) (xy 48.447002 -342.16919) (xy 48.48272 -342.21041)
			(xy 48.512209 -342.256294) (xy 48.534867 -342.305908) (xy 48.550234 -342.358241) (xy 48.557996 -342.412229)
			(xy 48.557996 -342.466771) (xy 48.557996 -342.466773) (xy 50.0407 -342.466773) (xy 50.0407 -342.412227)
			(xy 50.048463 -342.358235) (xy 50.063832 -342.305899) (xy 50.086493 -342.256282) (xy 50.115985 -342.210396)
			(xy 50.151708 -342.169174) (xy 50.192934 -342.133456) (xy 50.238824 -342.10397) (xy 50.288444 -342.081315)
			(xy 50.340782 -342.065953) (xy 50.394775 -342.058196) (xy 50.422048 -342.057736) (xy 51.285648 -342.057736)
			(xy 51.312915 -342.05823) (xy 51.366893 -342.065997) (xy 51.419217 -342.081366) (xy 51.46882 -342.104025)
			(xy 51.514695 -342.133512) (xy 51.555907 -342.169227) (xy 51.591617 -342.210443) (xy 51.621098 -342.256322)
			(xy 51.643751 -342.305928) (xy 51.659113 -342.358254) (xy 51.666874 -342.412233) (xy 51.666874 -342.466767)
			(xy 51.666873 -342.466773) (xy 60.9909 -342.466773) (xy 60.9909 -342.412227) (xy 60.998663 -342.358236)
			(xy 61.014031 -342.3059) (xy 61.036692 -342.256284) (xy 61.066184 -342.210398) (xy 61.101906 -342.169176)
			(xy 61.143131 -342.133459) (xy 61.18902 -342.103972) (xy 61.238639 -342.081317) (xy 61.290977 -342.065954)
			(xy 61.344969 -342.058197) (xy 61.372242 -342.057736) (xy 62.235842 -342.057736) (xy 62.263109 -342.058229)
			(xy 62.317088 -342.065996) (xy 62.369412 -342.081365) (xy 62.419017 -342.104023) (xy 62.464892 -342.13351)
			(xy 62.506105 -342.169225) (xy 62.541815 -342.210441) (xy 62.571297 -342.25632) (xy 62.59395 -342.305927)
			(xy 62.609313 -342.358253) (xy 62.617074 -342.412233) (xy 62.617074 -342.466767) (xy 62.617073 -342.466771)
			(xy 64.099899 -342.466771) (xy 64.099899 -342.412229) (xy 64.107662 -342.358241) (xy 64.123028 -342.305908)
			(xy 64.145686 -342.256295) (xy 64.175174 -342.210411) (xy 64.210892 -342.16919) (xy 64.252112 -342.133473)
			(xy 64.297997 -342.103985) (xy 64.34761 -342.081327) (xy 64.399943 -342.065961) (xy 64.453931 -342.058199)
			(xy 64.481202 -342.057736) (xy 65.344802 -342.057736) (xy 65.372071 -342.058227) (xy 65.426054 -342.065988)
			(xy 65.478383 -342.081354) (xy 65.527993 -342.10401) (xy 65.573873 -342.133496) (xy 65.615091 -342.169211)
			(xy 65.650805 -342.210428) (xy 65.680291 -342.256309) (xy 65.702947 -342.305919) (xy 65.718312 -342.358248)
			(xy 65.726074 -342.412231) (xy 65.726074 -342.466768) (xy 67.208922 -342.466768) (xy 67.208922 -342.412232)
			(xy 67.216683 -342.358252) (xy 67.232047 -342.305925) (xy 67.2547 -342.256317) (xy 67.284183 -342.210438)
			(xy 67.319894 -342.169221) (xy 67.361107 -342.133505) (xy 67.406984 -342.104018) (xy 67.456589 -342.08136)
			(xy 67.508914 -342.065991) (xy 67.562894 -342.058225) (xy 67.590162 -342.057736) (xy 68.453762 -342.057736)
			(xy 68.481035 -342.058201) (xy 68.535025 -342.065959) (xy 68.587362 -342.081321) (xy 68.63698 -342.103977)
			(xy 68.682868 -342.133463) (xy 68.724093 -342.16918) (xy 68.759814 -342.210401) (xy 68.789305 -342.256287)
			(xy 68.811965 -342.305902) (xy 68.827333 -342.358237) (xy 68.835096 -342.412227) (xy 68.835096 -342.466772)
			(xy 70.3178 -342.466772) (xy 70.3178 -342.412228) (xy 70.325562 -342.358239) (xy 70.34093 -342.305904)
			(xy 70.363589 -342.256289) (xy 70.393079 -342.210404) (xy 70.428799 -342.169183) (xy 70.470022 -342.133466)
			(xy 70.515909 -342.103979) (xy 70.565525 -342.081322) (xy 70.61786 -342.065958) (xy 70.67185 -342.058198)
			(xy 70.699122 -342.057736) (xy 71.562722 -342.057736) (xy 71.58999 -342.058228) (xy 71.643971 -342.065992)
			(xy 71.696298 -342.081359) (xy 71.745905 -342.104017) (xy 71.791783 -342.133503) (xy 71.832998 -342.169218)
			(xy 71.86871 -342.210435) (xy 71.898194 -342.256314) (xy 71.920848 -342.305923) (xy 71.936213 -342.35825)
			(xy 71.943974 -342.412232) (xy 71.943974 -342.466768) (xy 71.943974 -342.466769) (xy 73.426822 -342.466769)
			(xy 73.426822 -342.412231) (xy 73.434584 -342.358249) (xy 73.449948 -342.305921) (xy 73.472603 -342.256311)
			(xy 73.502087 -342.210431) (xy 73.537801 -342.169214) (xy 73.579017 -342.133498) (xy 73.624896 -342.104012)
			(xy 73.674504 -342.081354) (xy 73.726831 -342.065987) (xy 73.780813 -342.058224) (xy 73.808082 -342.057736)
			(xy 74.671682 -342.057736) (xy 74.698954 -342.058202) (xy 74.752942 -342.065962) (xy 74.805277 -342.081327)
			(xy 74.854892 -342.103983) (xy 74.900778 -342.13347) (xy 74.942 -342.169188) (xy 74.977719 -342.210408)
			(xy 75.007208 -342.256292) (xy 75.029867 -342.305906) (xy 75.045234 -342.35824) (xy 75.052996 -342.412228)
			(xy 75.052996 -342.466772) (xy 75.052996 -342.466773) (xy 76.5357 -342.466773) (xy 76.5357 -342.412227)
			(xy 76.543463 -342.358236) (xy 76.558831 -342.3059) (xy 76.581492 -342.256284) (xy 76.610984 -342.210398)
			(xy 76.646706 -342.169176) (xy 76.687931 -342.133459) (xy 76.73382 -342.103972) (xy 76.783439 -342.081317)
			(xy 76.835777 -342.065954) (xy 76.889769 -342.058197) (xy 76.917042 -342.057736) (xy 77.780642 -342.057736)
			(xy 77.807909 -342.058229) (xy 77.861888 -342.065996) (xy 77.914212 -342.081365) (xy 77.963817 -342.104023)
			(xy 78.009692 -342.13351) (xy 78.050905 -342.169225) (xy 78.086615 -342.210441) (xy 78.116097 -342.25632)
			(xy 78.13875 -342.305927) (xy 78.154113 -342.358253) (xy 78.161874 -342.412233) (xy 78.161874 -342.466767)
			(xy 78.161873 -342.466771) (xy 79.644699 -342.466771) (xy 79.644699 -342.412229) (xy 79.652462 -342.358241)
			(xy 79.667828 -342.305908) (xy 79.690486 -342.256295) (xy 79.719974 -342.210411) (xy 79.755692 -342.16919)
			(xy 79.796912 -342.133473) (xy 79.842797 -342.103985) (xy 79.89241 -342.081327) (xy 79.944743 -342.065961)
			(xy 79.998731 -342.058199) (xy 80.026002 -342.057736) (xy 80.889602 -342.057736) (xy 80.916871 -342.058227)
			(xy 80.970854 -342.065988) (xy 81.023183 -342.081354) (xy 81.072793 -342.10401) (xy 81.118673 -342.133496)
			(xy 81.159891 -342.169211) (xy 81.195605 -342.210428) (xy 81.225091 -342.256309) (xy 81.247747 -342.305919)
			(xy 81.263112 -342.358248) (xy 81.270874 -342.412231) (xy 81.270874 -342.466768) (xy 82.753722 -342.466768)
			(xy 82.753722 -342.412232) (xy 82.761483 -342.358252) (xy 82.776847 -342.305925) (xy 82.7995 -342.256317)
			(xy 82.828983 -342.210438) (xy 82.864694 -342.169221) (xy 82.905907 -342.133505) (xy 82.951784 -342.104018)
			(xy 83.001389 -342.08136) (xy 83.053714 -342.065991) (xy 83.107694 -342.058225) (xy 83.134962 -342.057736)
			(xy 83.998562 -342.057736) (xy 84.025835 -342.058201) (xy 84.079825 -342.065959) (xy 84.132162 -342.081321)
			(xy 84.18178 -342.103977) (xy 84.227668 -342.133463) (xy 84.268893 -342.16918) (xy 84.304614 -342.210401)
			(xy 84.334105 -342.256287) (xy 84.356765 -342.305902) (xy 84.372133 -342.358237) (xy 84.379896 -342.412227)
			(xy 84.379896 -342.466772) (xy 85.8626 -342.466772) (xy 85.8626 -342.412228) (xy 85.870362 -342.358239)
			(xy 85.88573 -342.305904) (xy 85.908389 -342.256289) (xy 85.937879 -342.210404) (xy 85.973599 -342.169183)
			(xy 86.014822 -342.133466) (xy 86.060709 -342.103979) (xy 86.110325 -342.081322) (xy 86.16266 -342.065958)
			(xy 86.21665 -342.058198) (xy 86.243922 -342.057736) (xy 87.107522 -342.057736) (xy 87.13479 -342.058228)
			(xy 87.188771 -342.065992) (xy 87.241098 -342.081359) (xy 87.290705 -342.104017) (xy 87.336583 -342.133503)
			(xy 87.377798 -342.169218) (xy 87.41351 -342.210435) (xy 87.442994 -342.256314) (xy 87.465648 -342.305923)
			(xy 87.481013 -342.35825) (xy 87.488774 -342.412232) (xy 87.488774 -342.466768) (xy 87.488774 -342.466769)
			(xy 88.971622 -342.466769) (xy 88.971622 -342.412231) (xy 88.979384 -342.358249) (xy 88.994748 -342.305921)
			(xy 89.017403 -342.256311) (xy 89.046887 -342.210431) (xy 89.082601 -342.169214) (xy 89.123817 -342.133498)
			(xy 89.169696 -342.104012) (xy 89.219304 -342.081354) (xy 89.271631 -342.065987) (xy 89.325613 -342.058224)
			(xy 89.352882 -342.057736) (xy 90.216482 -342.057736) (xy 90.243754 -342.058202) (xy 90.297742 -342.065962)
			(xy 90.350077 -342.081327) (xy 90.399692 -342.103983) (xy 90.445578 -342.13347) (xy 90.4868 -342.169188)
			(xy 90.522519 -342.210408) (xy 90.552008 -342.256292) (xy 90.574667 -342.305906) (xy 90.590034 -342.35824)
			(xy 90.597796 -342.412228) (xy 90.597796 -342.466772) (xy 90.597796 -342.466773) (xy 92.0805 -342.466773)
			(xy 92.0805 -342.412227) (xy 92.088263 -342.358236) (xy 92.103631 -342.3059) (xy 92.126292 -342.256284)
			(xy 92.155784 -342.210398) (xy 92.191506 -342.169176) (xy 92.232731 -342.133459) (xy 92.27862 -342.103972)
			(xy 92.328239 -342.081317) (xy 92.380577 -342.065954) (xy 92.434569 -342.058197) (xy 92.461842 -342.057736)
			(xy 93.325442 -342.057736) (xy 93.352709 -342.058229) (xy 93.406688 -342.065996) (xy 93.459012 -342.081365)
			(xy 93.508617 -342.104023) (xy 93.554492 -342.13351) (xy 93.595705 -342.169225) (xy 93.631415 -342.210441)
			(xy 93.660897 -342.25632) (xy 93.68355 -342.305927) (xy 93.698913 -342.358253) (xy 93.706674 -342.412233)
			(xy 93.706674 -342.466767) (xy 93.698913 -342.520747) (xy 93.68355 -342.573073) (xy 93.660897 -342.62268)
			(xy 93.631415 -342.668559) (xy 93.60914 -342.694268) (xy 102.35157 -342.694268) (xy 102.35157 -342.634332)
			(xy 102.359393 -342.574909) (xy 102.374905 -342.517016) (xy 102.397841 -342.461642) (xy 102.427809 -342.409736)
			(xy 102.464294 -342.362185) (xy 102.506675 -342.319804) (xy 102.554224 -342.283316) (xy 102.60613 -342.253347)
			(xy 102.661502 -342.23041) (xy 102.719395 -342.214896) (xy 102.778818 -342.207071) (xy 102.808786 -342.20658)
			(xy 103.672386 -342.20658) (xy 103.702355 -342.207072) (xy 103.76178 -342.214894) (xy 103.819676 -342.230405)
			(xy 103.875051 -342.253341) (xy 103.926959 -342.283309) (xy 103.974512 -342.319796) (xy 104.016895 -342.362178)
			(xy 104.053383 -342.409729) (xy 104.083352 -342.461636) (xy 104.085479 -342.466772) (xy 111.4808 -342.466772)
			(xy 111.4808 -342.412228) (xy 111.488562 -342.358241) (xy 111.503929 -342.305907) (xy 111.526587 -342.256293)
			(xy 111.556075 -342.210409) (xy 111.591794 -342.169188) (xy 111.633015 -342.133471) (xy 111.6789 -342.103983)
			(xy 111.728515 -342.081326) (xy 111.780848 -342.06596) (xy 111.834836 -342.058199) (xy 111.862108 -342.057736)
			(xy 112.725708 -342.057736) (xy 112.752977 -342.058227) (xy 112.806959 -342.06599) (xy 112.859288 -342.081355)
			(xy 112.908897 -342.104012) (xy 112.954776 -342.133498) (xy 112.995993 -342.169213) (xy 113.031707 -342.21043)
			(xy 113.061192 -342.256311) (xy 113.083847 -342.30592) (xy 113.099212 -342.358249) (xy 113.106974 -342.412231)
			(xy 113.106974 -342.466768) (xy 114.589822 -342.466768) (xy 114.589822 -342.412232) (xy 114.597583 -342.358251)
			(xy 114.612947 -342.305924) (xy 114.635601 -342.256315) (xy 114.665084 -342.210436) (xy 114.700796 -342.169219)
			(xy 114.74201 -342.133503) (xy 114.787887 -342.104016) (xy 114.837494 -342.081358) (xy 114.88982 -342.06599)
			(xy 114.9438 -342.058225) (xy 114.971068 -342.057736) (xy 115.834668 -342.057736) (xy 115.86194 -342.058201)
			(xy 115.91593 -342.06596) (xy 115.968267 -342.081323) (xy 116.017884 -342.103979) (xy 116.063771 -342.133465)
			(xy 116.104995 -342.169183) (xy 116.140715 -342.210403) (xy 116.170206 -342.256288) (xy 116.192866 -342.305903)
			(xy 116.208233 -342.358238) (xy 116.215996 -342.412228) (xy 116.215996 -342.466772) (xy 117.6987 -342.466772)
			(xy 117.6987 -342.412228) (xy 117.706462 -342.358238) (xy 117.72183 -342.305903) (xy 117.74449 -342.256288)
			(xy 117.77398 -342.210402) (xy 117.809701 -342.169181) (xy 117.850925 -342.133464) (xy 117.896812 -342.103977)
			(xy 117.946429 -342.08132) (xy 117.998765 -342.065957) (xy 118.052756 -342.058198) (xy 118.080028 -342.057736)
			(xy 118.943628 -342.057736) (xy 118.970896 -342.058228) (xy 119.024876 -342.065993) (xy 119.077202 -342.081361)
			(xy 119.126809 -342.104019) (xy 119.172686 -342.133505) (xy 119.2139 -342.16922) (xy 119.249612 -342.210437)
			(xy 119.279095 -342.256316) (xy 119.301749 -342.305924) (xy 119.317113 -342.358251) (xy 119.324874 -342.412232)
			(xy 119.324874 -342.466768) (xy 119.324874 -342.466769) (xy 120.807722 -342.466769) (xy 120.807722 -342.412231)
			(xy 120.815484 -342.358248) (xy 120.830849 -342.305919) (xy 120.853504 -342.25631) (xy 120.882989 -342.210429)
			(xy 120.918703 -342.169212) (xy 120.95992 -342.133496) (xy 121.005799 -342.10401) (xy 121.055408 -342.081353)
			(xy 121.107736 -342.065986) (xy 121.161719 -342.058223) (xy 121.188988 -342.057736) (xy 122.052588 -342.057736)
			(xy 122.079859 -342.058203) (xy 122.133847 -342.065963) (xy 122.186181 -342.081329) (xy 122.235796 -342.103985)
			(xy 122.28168 -342.133472) (xy 122.322902 -342.16919) (xy 122.35862 -342.21041) (xy 122.388109 -342.256294)
			(xy 122.410767 -342.305908) (xy 122.426134 -342.358241) (xy 122.433896 -342.412229) (xy 122.433896 -342.466771)
			(xy 122.433896 -342.466773) (xy 123.9166 -342.466773) (xy 123.9166 -342.412227) (xy 123.924363 -342.358235)
			(xy 123.939732 -342.305899) (xy 123.962393 -342.256282) (xy 123.991885 -342.210396) (xy 124.027608 -342.169174)
			(xy 124.068834 -342.133456) (xy 124.114724 -342.10397) (xy 124.164344 -342.081315) (xy 124.216682 -342.065953)
			(xy 124.270675 -342.058196) (xy 124.297948 -342.057736) (xy 125.161548 -342.057736) (xy 125.188815 -342.05823)
			(xy 125.242793 -342.065997) (xy 125.295117 -342.081366) (xy 125.34472 -342.104025) (xy 125.390595 -342.133512)
			(xy 125.431807 -342.169227) (xy 125.467517 -342.210443) (xy 125.496998 -342.256322) (xy 125.519651 -342.305928)
			(xy 125.535013 -342.358254) (xy 125.542774 -342.412233) (xy 125.542774 -342.466767) (xy 125.542773 -342.466772)
			(xy 127.0256 -342.466772) (xy 127.0256 -342.412228) (xy 127.033362 -342.358241) (xy 127.048729 -342.305907)
			(xy 127.071387 -342.256293) (xy 127.100875 -342.210409) (xy 127.136594 -342.169188) (xy 127.177815 -342.133471)
			(xy 127.2237 -342.103983) (xy 127.273315 -342.081326) (xy 127.325648 -342.06596) (xy 127.379636 -342.058199)
			(xy 127.406908 -342.057736) (xy 128.270508 -342.057736) (xy 128.297777 -342.058227) (xy 128.351759 -342.06599)
			(xy 128.404088 -342.081355) (xy 128.453697 -342.104012) (xy 128.499576 -342.133498) (xy 128.540793 -342.169213)
			(xy 128.576507 -342.21043) (xy 128.605992 -342.256311) (xy 128.628647 -342.30592) (xy 128.644012 -342.358249)
			(xy 128.651774 -342.412231) (xy 128.651774 -342.466768) (xy 130.134622 -342.466768) (xy 130.134622 -342.412232)
			(xy 130.142383 -342.358251) (xy 130.157747 -342.305924) (xy 130.180401 -342.256315) (xy 130.209884 -342.210436)
			(xy 130.245596 -342.169219) (xy 130.28681 -342.133503) (xy 130.332687 -342.104016) (xy 130.382294 -342.081358)
			(xy 130.43462 -342.06599) (xy 130.4886 -342.058225) (xy 130.515868 -342.057736) (xy 131.379468 -342.057736)
			(xy 131.40674 -342.058201) (xy 131.46073 -342.06596) (xy 131.513067 -342.081323) (xy 131.562684 -342.103979)
			(xy 131.608571 -342.133465) (xy 131.649795 -342.169183) (xy 131.685515 -342.210403) (xy 131.715006 -342.256288)
			(xy 131.737666 -342.305903) (xy 131.753033 -342.358238) (xy 131.760796 -342.412228) (xy 131.760796 -342.466772)
			(xy 133.2435 -342.466772) (xy 133.2435 -342.412228) (xy 133.251262 -342.358238) (xy 133.26663 -342.305903)
			(xy 133.28929 -342.256288) (xy 133.31878 -342.210402) (xy 133.354501 -342.169181) (xy 133.395725 -342.133464)
			(xy 133.441612 -342.103977) (xy 133.491229 -342.08132) (xy 133.543565 -342.065957) (xy 133.597556 -342.058198)
			(xy 133.624828 -342.057736) (xy 134.488428 -342.057736) (xy 134.515696 -342.058228) (xy 134.569676 -342.065993)
			(xy 134.622002 -342.081361) (xy 134.671609 -342.104019) (xy 134.717486 -342.133505) (xy 134.7587 -342.16922)
			(xy 134.794412 -342.210437) (xy 134.823895 -342.256316) (xy 134.846549 -342.305924) (xy 134.861913 -342.358251)
			(xy 134.869674 -342.412232) (xy 134.869674 -342.466768) (xy 134.869674 -342.466769) (xy 136.352522 -342.466769)
			(xy 136.352522 -342.412231) (xy 136.360284 -342.358248) (xy 136.375649 -342.305919) (xy 136.398304 -342.25631)
			(xy 136.427789 -342.210429) (xy 136.463503 -342.169212) (xy 136.50472 -342.133496) (xy 136.550599 -342.10401)
			(xy 136.600208 -342.081353) (xy 136.652536 -342.065986) (xy 136.706519 -342.058223) (xy 136.733788 -342.057736)
			(xy 137.597388 -342.057736) (xy 137.624659 -342.058203) (xy 137.678647 -342.065963) (xy 137.730981 -342.081329)
			(xy 137.780596 -342.103985) (xy 137.82648 -342.133472) (xy 137.867702 -342.16919) (xy 137.90342 -342.21041)
			(xy 137.932909 -342.256294) (xy 137.955567 -342.305908) (xy 137.970934 -342.358241) (xy 137.978696 -342.412229)
			(xy 137.978696 -342.466771) (xy 137.978696 -342.466773) (xy 139.4614 -342.466773) (xy 139.4614 -342.412227)
			(xy 139.469163 -342.358235) (xy 139.484532 -342.305899) (xy 139.507193 -342.256282) (xy 139.536685 -342.210396)
			(xy 139.572408 -342.169174) (xy 139.613634 -342.133456) (xy 139.659524 -342.10397) (xy 139.709144 -342.081315)
			(xy 139.761482 -342.065953) (xy 139.815475 -342.058196) (xy 139.842748 -342.057736) (xy 140.706348 -342.057736)
			(xy 140.733615 -342.05823) (xy 140.787593 -342.065997) (xy 140.839917 -342.081366) (xy 140.88952 -342.104025)
			(xy 140.935395 -342.133512) (xy 140.976607 -342.169227) (xy 141.012317 -342.210443) (xy 141.041798 -342.256322)
			(xy 141.064451 -342.305928) (xy 141.079813 -342.358254) (xy 141.087574 -342.412233) (xy 141.087574 -342.466767)
			(xy 141.087573 -342.466772) (xy 142.5704 -342.466772) (xy 142.5704 -342.412228) (xy 142.578162 -342.358241)
			(xy 142.593529 -342.305907) (xy 142.616187 -342.256293) (xy 142.645675 -342.210409) (xy 142.681394 -342.169188)
			(xy 142.722615 -342.133471) (xy 142.7685 -342.103983) (xy 142.818115 -342.081326) (xy 142.870448 -342.06596)
			(xy 142.924436 -342.058199) (xy 142.951708 -342.057736) (xy 143.815308 -342.057736) (xy 143.842577 -342.058227)
			(xy 143.896559 -342.06599) (xy 143.948888 -342.081355) (xy 143.998497 -342.104012) (xy 144.044376 -342.133498)
			(xy 144.085593 -342.169213) (xy 144.121307 -342.21043) (xy 144.150792 -342.256311) (xy 144.173447 -342.30592)
			(xy 144.188812 -342.358249) (xy 144.196574 -342.412231) (xy 144.196574 -342.466768) (xy 164.913822 -342.466768)
			(xy 164.913822 -342.412232) (xy 164.921583 -342.35825) (xy 164.936947 -342.305923) (xy 164.959602 -342.256314)
			(xy 164.989085 -342.210434) (xy 165.024797 -342.169217) (xy 165.066012 -342.133502) (xy 165.11189 -342.104015)
			(xy 165.161496 -342.081357) (xy 165.213823 -342.065989) (xy 165.267804 -342.058224) (xy 165.295072 -342.057736)
			(xy 166.158672 -342.057736) (xy 166.185944 -342.058202) (xy 166.239934 -342.06596) (xy 166.29227 -342.081324)
			(xy 166.341886 -342.10398) (xy 166.387773 -342.133467) (xy 166.428996 -342.169184) (xy 166.464716 -342.210405)
			(xy 166.494207 -342.256289) (xy 166.516866 -342.305904) (xy 166.532234 -342.358239) (xy 166.539996 -342.412228)
			(xy 166.539996 -342.466772) (xy 166.539996 -342.466773) (xy 168.0227 -342.466773) (xy 168.0227 -342.412227)
			(xy 168.030463 -342.358237) (xy 168.045831 -342.305902) (xy 168.068491 -342.256286) (xy 168.097981 -342.210401)
			(xy 168.133702 -342.16918) (xy 168.174927 -342.133462) (xy 168.220815 -342.103975) (xy 168.270432 -342.081319)
			(xy 168.322769 -342.065956) (xy 168.376759 -342.058197) (xy 168.404032 -342.057736) (xy 169.267632 -342.057736)
			(xy 169.2949 -342.058229) (xy 169.34888 -342.065994) (xy 169.401205 -342.081362) (xy 169.450811 -342.10402)
			(xy 169.496688 -342.133506) (xy 169.537901 -342.169222) (xy 169.573613 -342.210438) (xy 169.603095 -342.256317)
			(xy 169.625749 -342.305925) (xy 169.641113 -342.358252) (xy 169.648874 -342.412232) (xy 169.648874 -342.466768)
			(xy 169.648874 -342.466769) (xy 171.131722 -342.466769) (xy 171.131722 -342.412231) (xy 171.139484 -342.358248)
			(xy 171.154849 -342.305918) (xy 171.177505 -342.256309) (xy 171.20699 -342.210428) (xy 171.242705 -342.16921)
			(xy 171.283921 -342.133495) (xy 171.329802 -342.104009) (xy 171.379411 -342.081352) (xy 171.43174 -342.065986)
			(xy 171.485723 -342.058223) (xy 171.512992 -342.057736) (xy 172.376592 -342.057736) (xy 172.403863 -342.058203)
			(xy 172.457851 -342.065964) (xy 172.510184 -342.08133) (xy 172.559798 -342.103987) (xy 172.605682 -342.133474)
			(xy 172.646903 -342.169191) (xy 172.682621 -342.210411) (xy 172.71211 -342.256295) (xy 172.734768 -342.305908)
			(xy 172.750134 -342.358241) (xy 172.757896 -342.412229) (xy 172.757896 -342.466767) (xy 174.240722 -342.466767)
			(xy 174.240722 -342.412233) (xy 174.248483 -342.358253) (xy 174.263846 -342.305927) (xy 174.286499 -342.25632)
			(xy 174.31598 -342.210441) (xy 174.35169 -342.169224) (xy 174.392902 -342.133509) (xy 174.438778 -342.104022)
			(xy 174.488382 -342.081363) (xy 174.540706 -342.065993) (xy 174.594685 -342.058226) (xy 174.621952 -342.057736)
			(xy 175.485552 -342.057736) (xy 175.512825 -342.0582) (xy 175.566817 -342.065957) (xy 175.619155 -342.081319)
			(xy 175.668774 -342.103974) (xy 175.714663 -342.13346) (xy 175.755889 -342.169177) (xy 175.791612 -342.210398)
			(xy 175.821103 -342.256284) (xy 175.843764 -342.3059) (xy 175.859133 -342.358236) (xy 175.866896 -342.412227)
			(xy 175.866896 -342.466772) (xy 177.3496 -342.466772) (xy 177.3496 -342.412228) (xy 177.357362 -342.35824)
			(xy 177.372729 -342.305906) (xy 177.395388 -342.256292) (xy 177.424876 -342.210407) (xy 177.460595 -342.169187)
			(xy 177.501817 -342.133469) (xy 177.547703 -342.103982) (xy 177.597317 -342.081325) (xy 177.649652 -342.065959)
			(xy 177.70364 -342.058199) (xy 177.730912 -342.057736) (xy 178.594512 -342.057736) (xy 178.621781 -342.058227)
			(xy 178.675763 -342.06599) (xy 178.728091 -342.081357) (xy 178.777699 -342.104013) (xy 178.823578 -342.133499)
			(xy 178.864794 -342.169214) (xy 178.900508 -342.210432) (xy 178.929992 -342.256312) (xy 178.952648 -342.305921)
			(xy 178.968012 -342.358249) (xy 178.975774 -342.412231) (xy 178.975774 -342.466768) (xy 180.458622 -342.466768)
			(xy 180.458622 -342.412232) (xy 180.466383 -342.35825) (xy 180.481747 -342.305923) (xy 180.504402 -342.256314)
			(xy 180.533885 -342.210434) (xy 180.569597 -342.169217) (xy 180.610812 -342.133502) (xy 180.65669 -342.104015)
			(xy 180.706296 -342.081357) (xy 180.758623 -342.065989) (xy 180.812604 -342.058224) (xy 180.839872 -342.057736)
			(xy 181.703472 -342.057736) (xy 181.730744 -342.058202) (xy 181.784734 -342.06596) (xy 181.83707 -342.081324)
			(xy 181.886686 -342.10398) (xy 181.932573 -342.133467) (xy 181.973796 -342.169184) (xy 182.009516 -342.210405)
			(xy 182.039007 -342.256289) (xy 182.061666 -342.305904) (xy 182.077034 -342.358239) (xy 182.084796 -342.412228)
			(xy 182.084796 -342.466772) (xy 182.084796 -342.466773) (xy 183.5675 -342.466773) (xy 183.5675 -342.412227)
			(xy 183.575263 -342.358237) (xy 183.590631 -342.305902) (xy 183.613291 -342.256286) (xy 183.642781 -342.210401)
			(xy 183.678502 -342.16918) (xy 183.719727 -342.133462) (xy 183.765615 -342.103975) (xy 183.815232 -342.081319)
			(xy 183.867569 -342.065956) (xy 183.921559 -342.058197) (xy 183.948832 -342.057736) (xy 184.812432 -342.057736)
			(xy 184.8397 -342.058229) (xy 184.89368 -342.065994) (xy 184.946005 -342.081362) (xy 184.995611 -342.10402)
			(xy 185.041488 -342.133506) (xy 185.082701 -342.169222) (xy 185.118413 -342.210438) (xy 185.147895 -342.256317)
			(xy 185.170549 -342.305925) (xy 185.185913 -342.358252) (xy 185.193674 -342.412232) (xy 185.193674 -342.466768)
			(xy 185.193674 -342.466769) (xy 186.676522 -342.466769) (xy 186.676522 -342.412231) (xy 186.684284 -342.358248)
			(xy 186.699649 -342.305918) (xy 186.722305 -342.256309) (xy 186.75179 -342.210428) (xy 186.787505 -342.16921)
			(xy 186.828721 -342.133495) (xy 186.874602 -342.104009) (xy 186.924211 -342.081352) (xy 186.97654 -342.065986)
			(xy 187.030523 -342.058223) (xy 187.057792 -342.057736) (xy 187.921392 -342.057736) (xy 187.948663 -342.058203)
			(xy 188.002651 -342.065964) (xy 188.054984 -342.08133) (xy 188.104598 -342.103987) (xy 188.150482 -342.133474)
			(xy 188.191703 -342.169191) (xy 188.227421 -342.210411) (xy 188.25691 -342.256295) (xy 188.279568 -342.305908)
			(xy 188.294934 -342.358241) (xy 188.302696 -342.412229) (xy 188.302696 -342.466767) (xy 189.785522 -342.466767)
			(xy 189.785522 -342.412233) (xy 189.793283 -342.358253) (xy 189.808646 -342.305927) (xy 189.831299 -342.25632)
			(xy 189.86078 -342.210441) (xy 189.89649 -342.169224) (xy 189.937702 -342.133509) (xy 189.983578 -342.104022)
			(xy 190.033182 -342.081363) (xy 190.085506 -342.065993) (xy 190.139485 -342.058226) (xy 190.166752 -342.057736)
			(xy 191.030352 -342.057736) (xy 191.057625 -342.0582) (xy 191.111617 -342.065957) (xy 191.163955 -342.081319)
			(xy 191.213574 -342.103974) (xy 191.259463 -342.13346) (xy 191.300689 -342.169177) (xy 191.336412 -342.210398)
			(xy 191.365903 -342.256284) (xy 191.388564 -342.3059) (xy 191.403933 -342.358236) (xy 191.411696 -342.412227)
			(xy 191.411696 -342.466772) (xy 192.8944 -342.466772) (xy 192.8944 -342.412228) (xy 192.902162 -342.35824)
			(xy 192.917529 -342.305906) (xy 192.940188 -342.256292) (xy 192.969676 -342.210407) (xy 193.005395 -342.169187)
			(xy 193.046617 -342.133469) (xy 193.092503 -342.103982) (xy 193.142117 -342.081325) (xy 193.194452 -342.065959)
			(xy 193.24844 -342.058199) (xy 193.275712 -342.057736) (xy 194.139312 -342.057736) (xy 194.166581 -342.058227)
			(xy 194.220563 -342.06599) (xy 194.272891 -342.081357) (xy 194.322499 -342.104013) (xy 194.368378 -342.133499)
			(xy 194.409594 -342.169214) (xy 194.445308 -342.210432) (xy 194.474792 -342.256312) (xy 194.497448 -342.305921)
			(xy 194.512812 -342.358249) (xy 194.520574 -342.412231) (xy 194.520574 -342.466768) (xy 196.003422 -342.466768)
			(xy 196.003422 -342.412232) (xy 196.011183 -342.35825) (xy 196.026547 -342.305923) (xy 196.049202 -342.256314)
			(xy 196.078685 -342.210434) (xy 196.114397 -342.169217) (xy 196.155612 -342.133502) (xy 196.20149 -342.104015)
			(xy 196.251096 -342.081357) (xy 196.303423 -342.065989) (xy 196.357404 -342.058224) (xy 196.384672 -342.057736)
			(xy 197.248272 -342.057736) (xy 197.275544 -342.058202) (xy 197.28821 -342.060022) (xy 255.91262 -342.060022)
			(xy 255.91262 -341.196422) (xy 255.91311 -341.166438) (xy 255.920938 -341.106982) (xy 255.936459 -341.049057)
			(xy 255.959408 -340.993653) (xy 255.989392 -340.941719) (xy 256.025898 -340.894143) (xy 256.068303 -340.851738)
			(xy 256.115879 -340.815232) (xy 256.167813 -340.785248) (xy 256.223217 -340.762299) (xy 256.281142 -340.746778)
			(xy 256.340598 -340.73895) (xy 256.400566 -340.73895) (xy 256.460022 -340.746778) (xy 256.517947 -340.762299)
			(xy 256.573351 -340.785248) (xy 256.625285 -340.815232) (xy 256.672861 -340.851738) (xy 256.715266 -340.894143)
			(xy 256.751772 -340.941719) (xy 256.781756 -340.993653) (xy 256.804705 -341.049057) (xy 256.820226 -341.106982)
			(xy 256.828054 -341.166438) (xy 256.828544 -341.196422) (xy 256.828544 -342.060022) (xy 256.828054 -342.090006)
			(xy 256.820226 -342.149462) (xy 256.804705 -342.207387) (xy 256.781756 -342.262791) (xy 256.751772 -342.314725)
			(xy 256.715266 -342.362301) (xy 256.672861 -342.404706) (xy 256.625285 -342.441212) (xy 256.581015 -342.466771)
			(xy 267.515799 -342.466771) (xy 267.515799 -342.412229) (xy 267.523562 -342.358241) (xy 267.538928 -342.305908)
			(xy 267.561586 -342.256295) (xy 267.591074 -342.210411) (xy 267.626792 -342.16919) (xy 267.668012 -342.133473)
			(xy 267.713897 -342.103985) (xy 267.76351 -342.081327) (xy 267.815843 -342.065961) (xy 267.869831 -342.058199)
			(xy 267.897102 -342.057736) (xy 268.760702 -342.057736) (xy 268.787971 -342.058227) (xy 268.841954 -342.065988)
			(xy 268.894283 -342.081354) (xy 268.943893 -342.10401) (xy 268.989773 -342.133496) (xy 269.030991 -342.169211)
			(xy 269.066705 -342.210428) (xy 269.096191 -342.256309) (xy 269.118847 -342.305919) (xy 269.134212 -342.358248)
			(xy 269.141974 -342.412231) (xy 269.141974 -342.466768) (xy 270.624822 -342.466768) (xy 270.624822 -342.412232)
			(xy 270.632583 -342.358252) (xy 270.647947 -342.305925) (xy 270.6706 -342.256317) (xy 270.700083 -342.210438)
			(xy 270.735794 -342.169221) (xy 270.777007 -342.133505) (xy 270.822884 -342.104018) (xy 270.872489 -342.08136)
			(xy 270.924814 -342.065991) (xy 270.978794 -342.058225) (xy 271.006062 -342.057736) (xy 271.869662 -342.057736)
			(xy 271.896935 -342.058201) (xy 271.950925 -342.065959) (xy 272.003262 -342.081321) (xy 272.05288 -342.103977)
			(xy 272.098768 -342.133463) (xy 272.139993 -342.16918) (xy 272.175714 -342.210401) (xy 272.205205 -342.256287)
			(xy 272.227865 -342.305902) (xy 272.243233 -342.358237) (xy 272.250996 -342.412227) (xy 272.250996 -342.466772)
			(xy 273.7337 -342.466772) (xy 273.7337 -342.412228) (xy 273.741462 -342.358239) (xy 273.75683 -342.305904)
			(xy 273.779489 -342.256289) (xy 273.808979 -342.210404) (xy 273.844699 -342.169183) (xy 273.885922 -342.133466)
			(xy 273.931809 -342.103979) (xy 273.981425 -342.081322) (xy 274.03376 -342.065958) (xy 274.08775 -342.058198)
			(xy 274.115022 -342.057736) (xy 274.978622 -342.057736) (xy 275.00589 -342.058228) (xy 275.059871 -342.065992)
			(xy 275.112198 -342.081359) (xy 275.161805 -342.104017) (xy 275.207683 -342.133503) (xy 275.248898 -342.169218)
			(xy 275.28461 -342.210435) (xy 275.314094 -342.256314) (xy 275.336748 -342.305923) (xy 275.352113 -342.35825)
			(xy 275.359874 -342.412232) (xy 275.359874 -342.466768) (xy 275.359874 -342.466769) (xy 276.842722 -342.466769)
			(xy 276.842722 -342.412231) (xy 276.850484 -342.358249) (xy 276.865848 -342.305921) (xy 276.888503 -342.256311)
			(xy 276.917987 -342.210431) (xy 276.953701 -342.169214) (xy 276.994917 -342.133498) (xy 277.040796 -342.104012)
			(xy 277.090404 -342.081354) (xy 277.142731 -342.065987) (xy 277.196713 -342.058224) (xy 277.223982 -342.057736)
			(xy 278.087582 -342.057736) (xy 278.114854 -342.058202) (xy 278.168842 -342.065962) (xy 278.221177 -342.081327)
			(xy 278.270792 -342.103983) (xy 278.316678 -342.13347) (xy 278.3579 -342.169188) (xy 278.393619 -342.210408)
			(xy 278.423108 -342.256292) (xy 278.445767 -342.305906) (xy 278.461134 -342.35824) (xy 278.468896 -342.412228)
			(xy 278.468896 -342.466772) (xy 278.468896 -342.466773) (xy 279.9516 -342.466773) (xy 279.9516 -342.412227)
			(xy 279.959363 -342.358236) (xy 279.974731 -342.3059) (xy 279.997392 -342.256284) (xy 280.026884 -342.210398)
			(xy 280.062606 -342.169176) (xy 280.103831 -342.133459) (xy 280.14972 -342.103972) (xy 280.199339 -342.081317)
			(xy 280.251677 -342.065954) (xy 280.305669 -342.058197) (xy 280.332942 -342.057736) (xy 281.196542 -342.057736)
			(xy 281.223809 -342.058229) (xy 281.277788 -342.065996) (xy 281.330112 -342.081365) (xy 281.379717 -342.104023)
			(xy 281.425592 -342.13351) (xy 281.466805 -342.169225) (xy 281.502515 -342.210441) (xy 281.531997 -342.25632)
			(xy 281.55465 -342.305927) (xy 281.570013 -342.358253) (xy 281.577774 -342.412233) (xy 281.577774 -342.466767)
			(xy 281.577773 -342.466771) (xy 283.060599 -342.466771) (xy 283.060599 -342.412229) (xy 283.068362 -342.358241)
			(xy 283.083728 -342.305908) (xy 283.106386 -342.256295) (xy 283.135874 -342.210411) (xy 283.171592 -342.16919)
			(xy 283.212812 -342.133473) (xy 283.258697 -342.103985) (xy 283.30831 -342.081327) (xy 283.360643 -342.065961)
			(xy 283.414631 -342.058199) (xy 283.441902 -342.057736) (xy 284.305502 -342.057736) (xy 284.332771 -342.058227)
			(xy 284.386754 -342.065988) (xy 284.439083 -342.081354) (xy 284.488693 -342.10401) (xy 284.534573 -342.133496)
			(xy 284.575791 -342.169211) (xy 284.611505 -342.210428) (xy 284.640991 -342.256309) (xy 284.663647 -342.305919)
			(xy 284.679012 -342.358248) (xy 284.686774 -342.412231) (xy 284.686774 -342.466768) (xy 286.169622 -342.466768)
			(xy 286.169622 -342.412232) (xy 286.177383 -342.358252) (xy 286.192747 -342.305925) (xy 286.2154 -342.256317)
			(xy 286.244883 -342.210438) (xy 286.280594 -342.169221) (xy 286.321807 -342.133505) (xy 286.367684 -342.104018)
			(xy 286.417289 -342.08136) (xy 286.469614 -342.065991) (xy 286.523594 -342.058225) (xy 286.550862 -342.057736)
			(xy 287.414462 -342.057736) (xy 287.441735 -342.058201) (xy 287.495725 -342.065959) (xy 287.548062 -342.081321)
			(xy 287.59768 -342.103977) (xy 287.643568 -342.133463) (xy 287.684793 -342.16918) (xy 287.720514 -342.210401)
			(xy 287.750005 -342.256287) (xy 287.772665 -342.305902) (xy 287.788033 -342.358237) (xy 287.795796 -342.412227)
			(xy 287.795796 -342.466772) (xy 289.2785 -342.466772) (xy 289.2785 -342.412228) (xy 289.286262 -342.358239)
			(xy 289.30163 -342.305904) (xy 289.324289 -342.256289) (xy 289.353779 -342.210404) (xy 289.389499 -342.169183)
			(xy 289.430722 -342.133466) (xy 289.476609 -342.103979) (xy 289.526225 -342.081322) (xy 289.57856 -342.065958)
			(xy 289.63255 -342.058198) (xy 289.659822 -342.057736) (xy 290.523422 -342.057736) (xy 290.55069 -342.058228)
			(xy 290.604671 -342.065992) (xy 290.656998 -342.081359) (xy 290.706605 -342.104017) (xy 290.752483 -342.133503)
			(xy 290.793698 -342.169218) (xy 290.82941 -342.210435) (xy 290.858894 -342.256314) (xy 290.881548 -342.305923)
			(xy 290.896913 -342.35825) (xy 290.904674 -342.412232) (xy 290.904674 -342.466768) (xy 290.904674 -342.466769)
			(xy 292.387522 -342.466769) (xy 292.387522 -342.412231) (xy 292.395284 -342.358249) (xy 292.410648 -342.305921)
			(xy 292.433303 -342.256311) (xy 292.462787 -342.210431) (xy 292.498501 -342.169214) (xy 292.539717 -342.133498)
			(xy 292.585596 -342.104012) (xy 292.635204 -342.081354) (xy 292.687531 -342.065987) (xy 292.741513 -342.058224)
			(xy 292.768782 -342.057736) (xy 293.632382 -342.057736) (xy 293.659654 -342.058202) (xy 293.713642 -342.065962)
			(xy 293.765977 -342.081327) (xy 293.815592 -342.103983) (xy 293.861478 -342.13347) (xy 293.9027 -342.169188)
			(xy 293.938419 -342.210408) (xy 293.967908 -342.256292) (xy 293.990567 -342.305906) (xy 294.005934 -342.35824)
			(xy 294.013696 -342.412228) (xy 294.013696 -342.466772) (xy 294.013696 -342.466773) (xy 295.4964 -342.466773)
			(xy 295.4964 -342.412227) (xy 295.504163 -342.358236) (xy 295.519531 -342.3059) (xy 295.542192 -342.256284)
			(xy 295.571684 -342.210398) (xy 295.607406 -342.169176) (xy 295.648631 -342.133459) (xy 295.69452 -342.103972)
			(xy 295.744139 -342.081317) (xy 295.796477 -342.065954) (xy 295.850469 -342.058197) (xy 295.877742 -342.057736)
			(xy 296.741342 -342.057736) (xy 296.768609 -342.058229) (xy 296.822588 -342.065996) (xy 296.874912 -342.081365)
			(xy 296.924517 -342.104023) (xy 296.970392 -342.13351) (xy 297.011605 -342.169225) (xy 297.047315 -342.210441)
			(xy 297.076797 -342.25632) (xy 297.09945 -342.305927) (xy 297.114813 -342.358253) (xy 297.122574 -342.412233)
			(xy 297.122574 -342.466767) (xy 297.122573 -342.466771) (xy 298.605399 -342.466771) (xy 298.605399 -342.412229)
			(xy 298.613162 -342.358241) (xy 298.628528 -342.305908) (xy 298.651186 -342.256295) (xy 298.680674 -342.210411)
			(xy 298.716392 -342.16919) (xy 298.757612 -342.133473) (xy 298.803497 -342.103985) (xy 298.85311 -342.081327)
			(xy 298.905443 -342.065961) (xy 298.959431 -342.058199) (xy 298.986702 -342.057736) (xy 299.850302 -342.057736)
			(xy 299.877571 -342.058227) (xy 299.931554 -342.065988) (xy 299.983883 -342.081354) (xy 300.033493 -342.10401)
			(xy 300.079373 -342.133496) (xy 300.120591 -342.169211) (xy 300.156305 -342.210428) (xy 300.185791 -342.256309)
			(xy 300.208447 -342.305919) (xy 300.223812 -342.358248) (xy 300.231574 -342.412231) (xy 300.231574 -342.466769)
			(xy 300.231574 -342.466771) (xy 312.1215 -342.466771) (xy 312.1215 -342.412229) (xy 312.129262 -342.358241)
			(xy 312.144628 -342.305908) (xy 312.167286 -342.256294) (xy 312.196774 -342.21041) (xy 312.232493 -342.16919)
			(xy 312.273713 -342.133472) (xy 312.319598 -342.103984) (xy 312.369212 -342.081327) (xy 312.421545 -342.065961)
			(xy 312.475533 -342.058199) (xy 312.502804 -342.057736) (xy 313.366404 -342.057736) (xy 313.393673 -342.058227)
			(xy 313.447656 -342.065989) (xy 313.499985 -342.081354) (xy 313.549594 -342.104011) (xy 313.595474 -342.133497)
			(xy 313.636691 -342.169212) (xy 313.672406 -342.210429) (xy 313.701891 -342.256309) (xy 313.724547 -342.305919)
			(xy 313.739912 -342.358248) (xy 313.747674 -342.412231) (xy 313.747674 -342.466768) (xy 315.230522 -342.466768)
			(xy 315.230522 -342.412232) (xy 315.238283 -342.358251) (xy 315.253647 -342.305924) (xy 315.2763 -342.256316)
			(xy 315.305783 -342.210437) (xy 315.341495 -342.16922) (xy 315.382708 -342.133505) (xy 315.428585 -342.104018)
			(xy 315.478191 -342.081359) (xy 315.530516 -342.065991) (xy 315.584496 -342.058225) (xy 315.611764 -342.057736)
			(xy 316.475364 -342.057736) (xy 316.502637 -342.058201) (xy 316.556627 -342.065959) (xy 316.608964 -342.081322)
			(xy 316.658581 -342.103977) (xy 316.704469 -342.133464) (xy 316.745693 -342.169181) (xy 316.781414 -342.210402)
			(xy 316.810905 -342.256287) (xy 316.833565 -342.305902) (xy 316.848933 -342.358238) (xy 316.856696 -342.412228)
			(xy 316.856696 -342.466772) (xy 318.3394 -342.466772) (xy 318.3394 -342.412228) (xy 318.347162 -342.358239)
			(xy 318.36253 -342.305904) (xy 318.385189 -342.256289) (xy 318.414679 -342.210404) (xy 318.4504 -342.169183)
			(xy 318.491623 -342.133465) (xy 318.53751 -342.103978) (xy 318.587126 -342.081322) (xy 318.639462 -342.065957)
			(xy 318.693452 -342.058198) (xy 318.720724 -342.057736) (xy 319.584324 -342.057736) (xy 319.611592 -342.058228)
			(xy 319.665573 -342.065992) (xy 319.717899 -342.08136) (xy 319.767506 -342.104017) (xy 319.813384 -342.133504)
			(xy 319.854598 -342.169219) (xy 319.890311 -342.210435) (xy 319.919794 -342.256315) (xy 319.942449 -342.305923)
			(xy 319.957813 -342.358251) (xy 319.965574 -342.412232) (xy 319.965574 -342.466768) (xy 319.965574 -342.466769)
			(xy 321.448422 -342.466769) (xy 321.448422 -342.412231) (xy 321.456184 -342.358249) (xy 321.471548 -342.30592)
			(xy 321.494203 -342.256311) (xy 321.523688 -342.21043) (xy 321.559402 -342.169213) (xy 321.600618 -342.133498)
			(xy 321.646497 -342.104011) (xy 321.696105 -342.081354) (xy 321.748433 -342.065987) (xy 321.802415 -342.058224)
			(xy 321.829684 -342.057736) (xy 322.693284 -342.057736) (xy 322.720556 -342.058202) (xy 322.774544 -342.065963)
			(xy 322.826878 -342.081327) (xy 322.876493 -342.103984) (xy 322.922379 -342.133471) (xy 322.9636 -342.169188)
			(xy 322.999319 -342.210409) (xy 323.028808 -342.256293) (xy 323.051467 -342.305907) (xy 323.066834 -342.35824)
			(xy 323.074596 -342.412228) (xy 323.074596 -342.466772) (xy 323.074596 -342.466773) (xy 324.5573 -342.466773)
			(xy 324.5573 -342.412227) (xy 324.565063 -342.358236) (xy 324.580432 -342.305899) (xy 324.603092 -342.256283)
			(xy 324.632584 -342.210397) (xy 324.668307 -342.169176) (xy 324.709532 -342.133458) (xy 324.755422 -342.103971)
			(xy 324.805041 -342.081316) (xy 324.857379 -342.065954) (xy 324.911371 -342.058196) (xy 324.938644 -342.057736)
			(xy 325.802244 -342.057736) (xy 325.829511 -342.058229) (xy 325.88349 -342.065996) (xy 325.935814 -342.081365)
			(xy 325.985418 -342.104024) (xy 326.031293 -342.133511) (xy 326.072505 -342.169226) (xy 326.108216 -342.210442)
			(xy 326.137697 -342.256321) (xy 326.16035 -342.305928) (xy 326.175713 -342.358253) (xy 326.183474 -342.412233)
			(xy 326.183474 -342.466767) (xy 326.183473 -342.466771) (xy 327.6663 -342.466771) (xy 327.6663 -342.412229)
			(xy 327.674062 -342.358241) (xy 327.689428 -342.305908) (xy 327.712086 -342.256294) (xy 327.741574 -342.21041)
			(xy 327.777293 -342.16919) (xy 327.818513 -342.133472) (xy 327.864398 -342.103984) (xy 327.914012 -342.081327)
			(xy 327.966345 -342.065961) (xy 328.020333 -342.058199) (xy 328.047604 -342.057736) (xy 328.911204 -342.057736)
			(xy 328.938473 -342.058227) (xy 328.992456 -342.065989) (xy 329.044785 -342.081354) (xy 329.094394 -342.104011)
			(xy 329.140274 -342.133497) (xy 329.181491 -342.169212) (xy 329.217206 -342.210429) (xy 329.246691 -342.256309)
			(xy 329.269347 -342.305919) (xy 329.284712 -342.358248) (xy 329.292474 -342.412231) (xy 329.292474 -342.466768)
			(xy 330.775322 -342.466768) (xy 330.775322 -342.412232) (xy 330.783083 -342.358251) (xy 330.798447 -342.305924)
			(xy 330.8211 -342.256316) (xy 330.850583 -342.210437) (xy 330.886295 -342.16922) (xy 330.927508 -342.133505)
			(xy 330.973385 -342.104018) (xy 331.022991 -342.081359) (xy 331.075316 -342.065991) (xy 331.129296 -342.058225)
			(xy 331.156564 -342.057736) (xy 332.020164 -342.057736) (xy 332.047437 -342.058201) (xy 332.101427 -342.065959)
			(xy 332.153764 -342.081322) (xy 332.203381 -342.103977) (xy 332.249269 -342.133464) (xy 332.290493 -342.169181)
			(xy 332.326214 -342.210402) (xy 332.355705 -342.256287) (xy 332.378365 -342.305902) (xy 332.393733 -342.358238)
			(xy 332.401496 -342.412228) (xy 332.401496 -342.466772) (xy 333.8842 -342.466772) (xy 333.8842 -342.412228)
			(xy 333.891962 -342.358239) (xy 333.90733 -342.305904) (xy 333.929989 -342.256289) (xy 333.959479 -342.210404)
			(xy 333.9952 -342.169183) (xy 334.036423 -342.133465) (xy 334.08231 -342.103978) (xy 334.131926 -342.081322)
			(xy 334.184262 -342.065957) (xy 334.238252 -342.058198) (xy 334.265524 -342.057736) (xy 335.129124 -342.057736)
			(xy 335.156392 -342.058228) (xy 335.210373 -342.065992) (xy 335.262699 -342.08136) (xy 335.312306 -342.104017)
			(xy 335.358184 -342.133504) (xy 335.399398 -342.169219) (xy 335.435111 -342.210435) (xy 335.464594 -342.256315)
			(xy 335.487249 -342.305923) (xy 335.502613 -342.358251) (xy 335.510374 -342.412232) (xy 335.510374 -342.466768)
			(xy 335.510374 -342.466769) (xy 336.993222 -342.466769) (xy 336.993222 -342.412231) (xy 337.000984 -342.358249)
			(xy 337.016348 -342.30592) (xy 337.039003 -342.256311) (xy 337.068488 -342.21043) (xy 337.104202 -342.169213)
			(xy 337.145418 -342.133498) (xy 337.191297 -342.104011) (xy 337.240905 -342.081354) (xy 337.293233 -342.065987)
			(xy 337.347215 -342.058224) (xy 337.374484 -342.057736) (xy 338.238084 -342.057736) (xy 338.265356 -342.058202)
			(xy 338.319344 -342.065963) (xy 338.371678 -342.081327) (xy 338.421293 -342.103984) (xy 338.467179 -342.133471)
			(xy 338.5084 -342.169188) (xy 338.544119 -342.210409) (xy 338.573608 -342.256293) (xy 338.596267 -342.305907)
			(xy 338.611634 -342.35824) (xy 338.619396 -342.412228) (xy 338.619396 -342.466772) (xy 338.619396 -342.466773)
			(xy 340.1021 -342.466773) (xy 340.1021 -342.412227) (xy 340.109863 -342.358236) (xy 340.125232 -342.305899)
			(xy 340.147892 -342.256283) (xy 340.177384 -342.210397) (xy 340.213107 -342.169176) (xy 340.254332 -342.133458)
			(xy 340.300222 -342.103971) (xy 340.349841 -342.081316) (xy 340.402179 -342.065954) (xy 340.456171 -342.058196)
			(xy 340.483444 -342.057736) (xy 341.347044 -342.057736) (xy 341.374311 -342.058229) (xy 341.42829 -342.065996)
			(xy 341.480614 -342.081365) (xy 341.530218 -342.104024) (xy 341.576093 -342.133511) (xy 341.617305 -342.169226)
			(xy 341.653016 -342.210442) (xy 341.682497 -342.256321) (xy 341.70515 -342.305928) (xy 341.720513 -342.358253)
			(xy 341.728274 -342.412233) (xy 341.728274 -342.466767) (xy 341.728273 -342.466771) (xy 343.2111 -342.466771)
			(xy 343.2111 -342.412229) (xy 343.218862 -342.358241) (xy 343.234228 -342.305908) (xy 343.256886 -342.256294)
			(xy 343.286374 -342.21041) (xy 343.322093 -342.16919) (xy 343.363313 -342.133472) (xy 343.409198 -342.103984)
			(xy 343.458812 -342.081327) (xy 343.511145 -342.065961) (xy 343.565133 -342.058199) (xy 343.592404 -342.057736)
			(xy 344.456004 -342.057736) (xy 344.483273 -342.058227) (xy 344.537256 -342.065989) (xy 344.589585 -342.081354)
			(xy 344.639194 -342.104011) (xy 344.685074 -342.133497) (xy 344.726291 -342.169212) (xy 344.762006 -342.210429)
			(xy 344.791491 -342.256309) (xy 344.814147 -342.305919) (xy 344.829512 -342.358248) (xy 344.837274 -342.412231)
			(xy 344.837274 -342.466769) (xy 370.806722 -342.466769) (xy 370.806722 -342.412231) (xy 370.814484 -342.358249)
			(xy 370.829848 -342.305921) (xy 370.852503 -342.256312) (xy 370.881987 -342.210432) (xy 370.9177 -342.169214)
			(xy 370.958916 -342.133499) (xy 371.004794 -342.104012) (xy 371.054402 -342.081355) (xy 371.10673 -342.065988)
			(xy 371.160711 -342.058224) (xy 371.18798 -342.057736) (xy 372.05158 -342.057736) (xy 372.078852 -342.058202)
			(xy 372.132841 -342.065962) (xy 372.185175 -342.081326) (xy 372.234791 -342.103983) (xy 372.280677 -342.13347)
			(xy 372.321899 -342.169187) (xy 372.357618 -342.210407) (xy 372.387108 -342.256292) (xy 372.409767 -342.305906)
			(xy 372.425134 -342.35824) (xy 372.432896 -342.412228) (xy 372.432896 -342.466772) (xy 372.432896 -342.466773)
			(xy 373.9156 -342.466773) (xy 373.9156 -342.412227) (xy 373.923363 -342.358236) (xy 373.938731 -342.3059)
			(xy 373.961392 -342.256284) (xy 373.990883 -342.210398) (xy 374.026605 -342.169177) (xy 374.06783 -342.133459)
			(xy 374.113719 -342.103973) (xy 374.163338 -342.081317) (xy 374.215676 -342.065954) (xy 374.269667 -342.058197)
			(xy 374.29694 -342.057736) (xy 375.16054 -342.057736) (xy 375.187807 -342.058229) (xy 375.241786 -342.065995)
			(xy 375.294111 -342.081364) (xy 375.343716 -342.104022) (xy 375.389591 -342.133509) (xy 375.430804 -342.169224)
			(xy 375.466515 -342.210441) (xy 375.495997 -342.256319) (xy 375.51865 -342.305927) (xy 375.534013 -342.358253)
			(xy 375.541774 -342.412233) (xy 375.541774 -342.466767) (xy 375.541774 -342.46677) (xy 377.024622 -342.46677)
			(xy 377.024622 -342.41223) (xy 377.032384 -342.358247) (xy 377.04775 -342.305917) (xy 377.070406 -342.256306)
			(xy 377.099892 -342.210425) (xy 377.135607 -342.169207) (xy 377.176825 -342.133492) (xy 377.222706 -342.104006)
			(xy 377.272317 -342.08135) (xy 377.324647 -342.065984) (xy 377.37863 -342.058222) (xy 377.4059 -342.057736)
			(xy 378.2695 -342.057736) (xy 378.296769 -342.058226) (xy 378.350753 -342.065988) (xy 378.403082 -342.081353)
			(xy 378.452692 -342.104009) (xy 378.498572 -342.133495) (xy 378.53979 -342.16921) (xy 378.575505 -342.210428)
			(xy 378.604991 -342.256308) (xy 378.627647 -342.305918) (xy 378.643012 -342.358247) (xy 378.650774 -342.412231)
			(xy 378.650774 -342.466768) (xy 380.133622 -342.466768) (xy 380.133622 -342.412232) (xy 380.141383 -342.358252)
			(xy 380.156746 -342.305925) (xy 380.1794 -342.256318) (xy 380.208882 -342.210438) (xy 380.244593 -342.169222)
			(xy 380.285806 -342.133506) (xy 380.331682 -342.104019) (xy 380.381288 -342.08136) (xy 380.433613 -342.065991)
			(xy 380.487592 -342.058225) (xy 380.51486 -342.057736) (xy 381.37846 -342.057736) (xy 381.405733 -342.058201)
			(xy 381.459724 -342.065958) (xy 381.512061 -342.081321) (xy 381.561679 -342.103976) (xy 381.607567 -342.133463)
			(xy 381.648792 -342.16918) (xy 381.684513 -342.210401) (xy 381.714005 -342.256286) (xy 381.736665 -342.305902)
			(xy 381.752033 -342.358237) (xy 381.759796 -342.412227) (xy 381.759796 -342.466772) (xy 383.2425 -342.466772)
			(xy 383.2425 -342.412228) (xy 383.250262 -342.358239) (xy 383.26563 -342.305904) (xy 383.288289 -342.25629)
			(xy 383.317778 -342.210405) (xy 383.353498 -342.169184) (xy 383.394721 -342.133466) (xy 383.440607 -342.103979)
			(xy 383.490223 -342.081323) (xy 383.542559 -342.065958) (xy 383.596548 -342.058198) (xy 383.62382 -342.057736)
			(xy 384.48742 -342.057736) (xy 384.514688 -342.058228) (xy 384.568669 -342.065992) (xy 384.620996 -342.081359)
			(xy 384.670604 -342.104016) (xy 384.716482 -342.133502) (xy 384.757697 -342.169217) (xy 384.79341 -342.210434)
			(xy 384.822894 -342.256314) (xy 384.845548 -342.305922) (xy 384.860913 -342.35825) (xy 384.868674 -342.412232)
			(xy 384.868674 -342.466768) (xy 384.868674 -342.466769) (xy 386.351522 -342.466769) (xy 386.351522 -342.412231)
			(xy 386.359284 -342.358249) (xy 386.374648 -342.305921) (xy 386.397303 -342.256312) (xy 386.426787 -342.210432)
			(xy 386.4625 -342.169214) (xy 386.503716 -342.133499) (xy 386.549594 -342.104012) (xy 386.599202 -342.081355)
			(xy 386.65153 -342.065988) (xy 386.705511 -342.058224) (xy 386.73278 -342.057736) (xy 387.59638 -342.057736)
			(xy 387.623652 -342.058202) (xy 387.677641 -342.065962) (xy 387.729975 -342.081326) (xy 387.779591 -342.103983)
			(xy 387.825477 -342.13347) (xy 387.866699 -342.169187) (xy 387.902418 -342.210407) (xy 387.931908 -342.256292)
			(xy 387.954567 -342.305906) (xy 387.969934 -342.35824) (xy 387.977696 -342.412228) (xy 387.977696 -342.466772)
			(xy 387.977696 -342.466773) (xy 389.4604 -342.466773) (xy 389.4604 -342.412227) (xy 389.468163 -342.358236)
			(xy 389.483531 -342.3059) (xy 389.506192 -342.256284) (xy 389.535683 -342.210398) (xy 389.571405 -342.169177)
			(xy 389.61263 -342.133459) (xy 389.658519 -342.103973) (xy 389.708138 -342.081317) (xy 389.760476 -342.065954)
			(xy 389.814467 -342.058197) (xy 389.84174 -342.057736) (xy 390.70534 -342.057736) (xy 390.732607 -342.058229)
			(xy 390.786586 -342.065995) (xy 390.838911 -342.081364) (xy 390.888516 -342.104022) (xy 390.934391 -342.133509)
			(xy 390.975604 -342.169224) (xy 391.011315 -342.210441) (xy 391.040797 -342.256319) (xy 391.06345 -342.305927)
			(xy 391.078813 -342.358253) (xy 391.086574 -342.412233) (xy 391.086574 -342.466767) (xy 391.086574 -342.46677)
			(xy 392.569422 -342.46677) (xy 392.569422 -342.41223) (xy 392.577184 -342.358247) (xy 392.59255 -342.305917)
			(xy 392.615206 -342.256306) (xy 392.644692 -342.210425) (xy 392.680407 -342.169207) (xy 392.721625 -342.133492)
			(xy 392.767506 -342.104006) (xy 392.817117 -342.08135) (xy 392.869447 -342.065984) (xy 392.92343 -342.058222)
			(xy 392.9507 -342.057736) (xy 393.8143 -342.057736) (xy 393.841569 -342.058226) (xy 393.895553 -342.065988)
			(xy 393.947882 -342.081353) (xy 393.997492 -342.104009) (xy 394.043372 -342.133495) (xy 394.08459 -342.16921)
			(xy 394.120305 -342.210428) (xy 394.149791 -342.256308) (xy 394.172447 -342.305918) (xy 394.187812 -342.358247)
			(xy 394.195574 -342.412231) (xy 394.195574 -342.466768) (xy 395.678422 -342.466768) (xy 395.678422 -342.412232)
			(xy 395.686183 -342.358252) (xy 395.701546 -342.305925) (xy 395.7242 -342.256318) (xy 395.753682 -342.210438)
			(xy 395.789393 -342.169222) (xy 395.830606 -342.133506) (xy 395.876482 -342.104019) (xy 395.926088 -342.08136)
			(xy 395.978413 -342.065991) (xy 396.032392 -342.058225) (xy 396.05966 -342.057736) (xy 396.92326 -342.057736)
			(xy 396.950533 -342.058201) (xy 397.004524 -342.065958) (xy 397.056861 -342.081321) (xy 397.106479 -342.103976)
			(xy 397.152367 -342.133463) (xy 397.193592 -342.16918) (xy 397.229313 -342.210401) (xy 397.258805 -342.256286)
			(xy 397.281465 -342.305902) (xy 397.296833 -342.358237) (xy 397.304596 -342.412227) (xy 397.304596 -342.466772)
			(xy 398.7873 -342.466772) (xy 398.7873 -342.412228) (xy 398.795062 -342.358239) (xy 398.81043 -342.305904)
			(xy 398.833089 -342.25629) (xy 398.862578 -342.210405) (xy 398.898298 -342.169184) (xy 398.939521 -342.133466)
			(xy 398.985407 -342.103979) (xy 399.035023 -342.081323) (xy 399.087359 -342.065958) (xy 399.141348 -342.058198)
			(xy 399.16862 -342.057736) (xy 400.03222 -342.057736) (xy 400.059488 -342.058228) (xy 400.113469 -342.065992)
			(xy 400.165796 -342.081359) (xy 400.215404 -342.104016) (xy 400.261282 -342.133502) (xy 400.302497 -342.169217)
			(xy 400.33821 -342.210434) (xy 400.367694 -342.256314) (xy 400.390348 -342.305922) (xy 400.405713 -342.35825)
			(xy 400.413474 -342.412232) (xy 400.413474 -342.466768) (xy 400.413474 -342.466769) (xy 401.896322 -342.466769)
			(xy 401.896322 -342.412231) (xy 401.904084 -342.358249) (xy 401.919448 -342.305921) (xy 401.942103 -342.256312)
			(xy 401.971587 -342.210432) (xy 402.0073 -342.169214) (xy 402.048516 -342.133499) (xy 402.094394 -342.104012)
			(xy 402.144002 -342.081355) (xy 402.19633 -342.065988) (xy 402.250311 -342.058224) (xy 402.27758 -342.057736)
			(xy 403.14118 -342.057736) (xy 403.168452 -342.058202) (xy 403.222441 -342.065962) (xy 403.274775 -342.081326)
			(xy 403.324391 -342.103983) (xy 403.370277 -342.13347) (xy 403.411499 -342.169187) (xy 403.447218 -342.210407)
			(xy 403.476708 -342.256292) (xy 403.499367 -342.305906) (xy 403.514734 -342.35824) (xy 403.522496 -342.412228)
			(xy 403.522496 -342.466769) (xy 408.913822 -342.466769) (xy 408.913822 -342.412231) (xy 408.921584 -342.358248)
			(xy 408.936949 -342.305918) (xy 408.959605 -342.256309) (xy 408.98909 -342.210428) (xy 409.024805 -342.16921)
			(xy 409.066021 -342.133495) (xy 409.111902 -342.104009) (xy 409.161511 -342.081352) (xy 409.21384 -342.065986)
			(xy 409.267823 -342.058223) (xy 409.295092 -342.057736) (xy 410.158692 -342.057736) (xy 410.185963 -342.058203)
			(xy 410.239951 -342.065964) (xy 410.292284 -342.08133) (xy 410.341898 -342.103987) (xy 410.387782 -342.133474)
			(xy 410.429003 -342.169191) (xy 410.464721 -342.210411) (xy 410.49421 -342.256295) (xy 410.516868 -342.305908)
			(xy 410.532234 -342.358241) (xy 410.539996 -342.412229) (xy 410.539996 -342.466767) (xy 412.022822 -342.466767)
			(xy 412.022822 -342.412233) (xy 412.030583 -342.358253) (xy 412.045946 -342.305927) (xy 412.068599 -342.25632)
			(xy 412.09808 -342.210441) (xy 412.13379 -342.169224) (xy 412.175002 -342.133509) (xy 412.220878 -342.104022)
			(xy 412.270482 -342.081363) (xy 412.322806 -342.065993) (xy 412.376785 -342.058226) (xy 412.404052 -342.057736)
			(xy 413.267652 -342.057736) (xy 413.294925 -342.0582) (xy 413.348917 -342.065957) (xy 413.401255 -342.081319)
			(xy 413.450874 -342.103974) (xy 413.496763 -342.13346) (xy 413.537989 -342.169177) (xy 413.573712 -342.210398)
			(xy 413.603203 -342.256284) (xy 413.625864 -342.3059) (xy 413.641233 -342.358236) (xy 413.648996 -342.412227)
			(xy 413.648996 -342.466772) (xy 415.1317 -342.466772) (xy 415.1317 -342.412228) (xy 415.139462 -342.35824)
			(xy 415.154829 -342.305906) (xy 415.177488 -342.256292) (xy 415.206976 -342.210407) (xy 415.242695 -342.169187)
			(xy 415.283917 -342.133469) (xy 415.329803 -342.103982) (xy 415.379417 -342.081325) (xy 415.431752 -342.065959)
			(xy 415.48574 -342.058199) (xy 415.513012 -342.057736) (xy 416.376612 -342.057736) (xy 416.403881 -342.058227)
			(xy 416.457863 -342.06599) (xy 416.510191 -342.081357) (xy 416.559799 -342.104013) (xy 416.605678 -342.133499)
			(xy 416.646894 -342.169214) (xy 416.682608 -342.210432) (xy 416.712092 -342.256312) (xy 416.734748 -342.305921)
			(xy 416.750112 -342.358249) (xy 416.757874 -342.412231) (xy 416.757874 -342.466768) (xy 418.240722 -342.466768)
			(xy 418.240722 -342.412232) (xy 418.248483 -342.35825) (xy 418.263847 -342.305923) (xy 418.286502 -342.256314)
			(xy 418.315985 -342.210434) (xy 418.351697 -342.169217) (xy 418.392912 -342.133502) (xy 418.43879 -342.104015)
			(xy 418.488396 -342.081357) (xy 418.540723 -342.065989) (xy 418.594704 -342.058224) (xy 418.621972 -342.057736)
			(xy 419.485572 -342.057736) (xy 419.512844 -342.058202) (xy 419.566834 -342.06596) (xy 419.61917 -342.081324)
			(xy 419.668786 -342.10398) (xy 419.714673 -342.133467) (xy 419.755896 -342.169184) (xy 419.791616 -342.210405)
			(xy 419.821107 -342.256289) (xy 419.843766 -342.305904) (xy 419.859134 -342.358239) (xy 419.866896 -342.412228)
			(xy 419.866896 -342.466772) (xy 419.866896 -342.466773) (xy 421.3496 -342.466773) (xy 421.3496 -342.412227)
			(xy 421.357363 -342.358237) (xy 421.372731 -342.305902) (xy 421.395391 -342.256286) (xy 421.424881 -342.210401)
			(xy 421.460602 -342.16918) (xy 421.501827 -342.133462) (xy 421.547715 -342.103975) (xy 421.597332 -342.081319)
			(xy 421.649669 -342.065956) (xy 421.703659 -342.058197) (xy 421.730932 -342.057736) (xy 422.594532 -342.057736)
			(xy 422.6218 -342.058229) (xy 422.67578 -342.065994) (xy 422.728105 -342.081362) (xy 422.777711 -342.10402)
			(xy 422.823588 -342.133506) (xy 422.864801 -342.169222) (xy 422.900513 -342.210438) (xy 422.929995 -342.256317)
			(xy 422.952649 -342.305925) (xy 422.968013 -342.358252) (xy 422.975774 -342.412232) (xy 422.975774 -342.466768)
			(xy 422.975774 -342.466769) (xy 424.458622 -342.466769) (xy 424.458622 -342.412231) (xy 424.466384 -342.358248)
			(xy 424.481749 -342.305918) (xy 424.504405 -342.256309) (xy 424.53389 -342.210428) (xy 424.569605 -342.16921)
			(xy 424.610821 -342.133495) (xy 424.656702 -342.104009) (xy 424.706311 -342.081352) (xy 424.75864 -342.065986)
			(xy 424.812623 -342.058223) (xy 424.839892 -342.057736) (xy 425.703492 -342.057736) (xy 425.730763 -342.058203)
			(xy 425.784751 -342.065964) (xy 425.837084 -342.08133) (xy 425.886698 -342.103987) (xy 425.932582 -342.133474)
			(xy 425.973803 -342.169191) (xy 426.009521 -342.210411) (xy 426.03901 -342.256295) (xy 426.061668 -342.305908)
			(xy 426.077034 -342.358241) (xy 426.084796 -342.412229) (xy 426.084796 -342.466767) (xy 427.567622 -342.466767)
			(xy 427.567622 -342.412233) (xy 427.575383 -342.358253) (xy 427.590746 -342.305927) (xy 427.613399 -342.25632)
			(xy 427.64288 -342.210441) (xy 427.67859 -342.169224) (xy 427.719802 -342.133509) (xy 427.765678 -342.104022)
			(xy 427.815282 -342.081363) (xy 427.867606 -342.065993) (xy 427.921585 -342.058226) (xy 427.948852 -342.057736)
			(xy 428.812452 -342.057736) (xy 428.839725 -342.0582) (xy 428.893717 -342.065957) (xy 428.946055 -342.081319)
			(xy 428.995674 -342.103974) (xy 429.041563 -342.13346) (xy 429.082789 -342.169177) (xy 429.118512 -342.210398)
			(xy 429.148003 -342.256284) (xy 429.170664 -342.3059) (xy 429.186033 -342.358236) (xy 429.193796 -342.412227)
			(xy 429.193796 -342.466772) (xy 430.6765 -342.466772) (xy 430.6765 -342.412228) (xy 430.684262 -342.35824)
			(xy 430.699629 -342.305906) (xy 430.722288 -342.256292) (xy 430.751776 -342.210407) (xy 430.787495 -342.169187)
			(xy 430.828717 -342.133469) (xy 430.874603 -342.103982) (xy 430.924217 -342.081325) (xy 430.976552 -342.065959)
			(xy 431.03054 -342.058199) (xy 431.057812 -342.057736) (xy 431.921412 -342.057736) (xy 431.948681 -342.058227)
			(xy 432.002663 -342.06599) (xy 432.054991 -342.081357) (xy 432.104599 -342.104013) (xy 432.150478 -342.133499)
			(xy 432.191694 -342.169214) (xy 432.227408 -342.210432) (xy 432.256892 -342.256312) (xy 432.279548 -342.305921)
			(xy 432.294912 -342.358249) (xy 432.302674 -342.412231) (xy 432.302674 -342.466768) (xy 433.785522 -342.466768)
			(xy 433.785522 -342.412232) (xy 433.793283 -342.35825) (xy 433.808647 -342.305923) (xy 433.831302 -342.256314)
			(xy 433.860785 -342.210434) (xy 433.896497 -342.169217) (xy 433.937712 -342.133502) (xy 433.98359 -342.104015)
			(xy 434.033196 -342.081357) (xy 434.085523 -342.065989) (xy 434.139504 -342.058224) (xy 434.166772 -342.057736)
			(xy 435.030372 -342.057736) (xy 435.057644 -342.058202) (xy 435.111634 -342.06596) (xy 435.16397 -342.081324)
			(xy 435.213586 -342.10398) (xy 435.259473 -342.133467) (xy 435.300696 -342.169184) (xy 435.336416 -342.210405)
			(xy 435.365907 -342.256289) (xy 435.388566 -342.305904) (xy 435.403934 -342.358239) (xy 435.411696 -342.412228)
			(xy 435.411696 -342.466772) (xy 435.411696 -342.466773) (xy 436.8944 -342.466773) (xy 436.8944 -342.412227)
			(xy 436.902163 -342.358237) (xy 436.917531 -342.305902) (xy 436.940191 -342.256286) (xy 436.969681 -342.210401)
			(xy 437.005402 -342.16918) (xy 437.046627 -342.133462) (xy 437.092515 -342.103975) (xy 437.142132 -342.081319)
			(xy 437.194469 -342.065956) (xy 437.248459 -342.058197) (xy 437.275732 -342.057736) (xy 438.139332 -342.057736)
			(xy 438.1666 -342.058229) (xy 438.22058 -342.065994) (xy 438.272905 -342.081362) (xy 438.322511 -342.10402)
			(xy 438.368388 -342.133506) (xy 438.409601 -342.169222) (xy 438.445313 -342.210438) (xy 438.474795 -342.256317)
			(xy 438.497449 -342.305925) (xy 438.512813 -342.358252) (xy 438.520574 -342.412232) (xy 438.520574 -342.466768)
			(xy 438.520574 -342.466769) (xy 440.003422 -342.466769) (xy 440.003422 -342.412231) (xy 440.011184 -342.358248)
			(xy 440.026549 -342.305918) (xy 440.049205 -342.256309) (xy 440.07869 -342.210428) (xy 440.114405 -342.16921)
			(xy 440.155621 -342.133495) (xy 440.201502 -342.104009) (xy 440.251111 -342.081352) (xy 440.30344 -342.065986)
			(xy 440.357423 -342.058223) (xy 440.384692 -342.057736) (xy 441.248292 -342.057736) (xy 441.275563 -342.058203)
			(xy 441.329551 -342.065964) (xy 441.381884 -342.08133) (xy 441.431498 -342.103987) (xy 441.477382 -342.133474)
			(xy 441.518603 -342.169191) (xy 441.554321 -342.210411) (xy 441.58381 -342.256295) (xy 441.606468 -342.305908)
			(xy 441.621834 -342.358241) (xy 441.629596 -342.412229) (xy 441.629596 -342.466771) (xy 441.621834 -342.520759)
			(xy 441.606468 -342.573092) (xy 441.58381 -342.622705) (xy 441.554321 -342.668589) (xy 441.518603 -342.709809)
			(xy 441.477382 -342.745526) (xy 441.431498 -342.775013) (xy 441.381884 -342.79767) (xy 441.329551 -342.813036)
			(xy 441.275563 -342.820797) (xy 441.248292 -342.82126) (xy 440.384692 -342.82126) (xy 440.357423 -342.820777)
			(xy 440.30344 -342.813014) (xy 440.251111 -342.797648) (xy 440.201502 -342.774991) (xy 440.155621 -342.745505)
			(xy 440.114405 -342.70979) (xy 440.07869 -342.668572) (xy 440.049205 -342.622691) (xy 440.026549 -342.573082)
			(xy 440.011184 -342.520752) (xy 440.003422 -342.466769) (xy 438.520574 -342.466769) (xy 438.512813 -342.520748)
			(xy 438.497449 -342.573075) (xy 438.474795 -342.622683) (xy 438.445313 -342.668562) (xy 438.409601 -342.709778)
			(xy 438.368388 -342.745494) (xy 438.322511 -342.77498) (xy 438.272905 -342.797638) (xy 438.22058 -342.813006)
			(xy 438.1666 -342.820771) (xy 438.139332 -342.82126) (xy 437.275732 -342.82126) (xy 437.248459 -342.820803)
			(xy 437.194469 -342.813044) (xy 437.142132 -342.797681) (xy 437.092515 -342.775025) (xy 437.046627 -342.745538)
			(xy 437.005402 -342.70982) (xy 436.969681 -342.668599) (xy 436.940191 -342.622714) (xy 436.917531 -342.573098)
			(xy 436.902163 -342.520763) (xy 436.8944 -342.466773) (xy 435.411696 -342.466773) (xy 435.403934 -342.520761)
			(xy 435.388566 -342.573096) (xy 435.365907 -342.622711) (xy 435.336416 -342.668595) (xy 435.300696 -342.709816)
			(xy 435.259473 -342.745533) (xy 435.213586 -342.77502) (xy 435.16397 -342.797676) (xy 435.111634 -342.81304)
			(xy 435.057644 -342.820798) (xy 435.030372 -342.82126) (xy 434.166772 -342.82126) (xy 434.139504 -342.820776)
			(xy 434.085523 -342.813011) (xy 434.033196 -342.797643) (xy 433.98359 -342.774985) (xy 433.937712 -342.745498)
			(xy 433.896497 -342.709783) (xy 433.860785 -342.668566) (xy 433.831302 -342.622686) (xy 433.808647 -342.573077)
			(xy 433.793283 -342.52075) (xy 433.785522 -342.466768) (xy 432.302674 -342.466768) (xy 432.302674 -342.466769)
			(xy 432.294912 -342.520751) (xy 432.279548 -342.573079) (xy 432.256892 -342.622688) (xy 432.227408 -342.668568)
			(xy 432.191694 -342.709786) (xy 432.150478 -342.745501) (xy 432.104599 -342.774987) (xy 432.054991 -342.797643)
			(xy 432.002663 -342.81301) (xy 431.948681 -342.820773) (xy 431.921412 -342.82126) (xy 431.057812 -342.82126)
			(xy 431.03054 -342.820801) (xy 430.976552 -342.813041) (xy 430.924217 -342.797675) (xy 430.874603 -342.775018)
			(xy 430.828717 -342.745531) (xy 430.787495 -342.709813) (xy 430.751776 -342.668593) (xy 430.722288 -342.622708)
			(xy 430.699629 -342.573094) (xy 430.684262 -342.52076) (xy 430.6765 -342.466772) (xy 429.193796 -342.466772)
			(xy 429.193796 -342.466773) (xy 429.186033 -342.520764) (xy 429.170664 -342.5731) (xy 429.148003 -342.622716)
			(xy 429.118512 -342.668602) (xy 429.082789 -342.709823) (xy 429.041563 -342.74554) (xy 428.995674 -342.775026)
			(xy 428.946055 -342.797681) (xy 428.893717 -342.813043) (xy 428.839725 -342.8208) (xy 428.812452 -342.82126)
			(xy 427.948852 -342.82126) (xy 427.921585 -342.820774) (xy 427.867606 -342.813007) (xy 427.815282 -342.797637)
			(xy 427.765678 -342.774978) (xy 427.719802 -342.745491) (xy 427.67859 -342.709776) (xy 427.64288 -342.668559)
			(xy 427.613399 -342.62268) (xy 427.590746 -342.573073) (xy 427.575383 -342.520747) (xy 427.567622 -342.466767)
			(xy 426.084796 -342.466767) (xy 426.084796 -342.466771) (xy 426.077034 -342.520759) (xy 426.061668 -342.573092)
			(xy 426.03901 -342.622705) (xy 426.009521 -342.668589) (xy 425.973803 -342.709809) (xy 425.932582 -342.745526)
			(xy 425.886698 -342.775013) (xy 425.837084 -342.79767) (xy 425.784751 -342.813036) (xy 425.730763 -342.820797)
			(xy 425.703492 -342.82126) (xy 424.839892 -342.82126) (xy 424.812623 -342.820777) (xy 424.75864 -342.813014)
			(xy 424.706311 -342.797648) (xy 424.656702 -342.774991) (xy 424.610821 -342.745505) (xy 424.569605 -342.70979)
			(xy 424.53389 -342.668572) (xy 424.504405 -342.622691) (xy 424.481749 -342.573082) (xy 424.466384 -342.520752)
			(xy 424.458622 -342.466769) (xy 422.975774 -342.466769) (xy 422.968013 -342.520748) (xy 422.952649 -342.573075)
			(xy 422.929995 -342.622683) (xy 422.900513 -342.668562) (xy 422.864801 -342.709778) (xy 422.823588 -342.745494)
			(xy 422.777711 -342.77498) (xy 422.728105 -342.797638) (xy 422.67578 -342.813006) (xy 422.6218 -342.820771)
			(xy 422.594532 -342.82126) (xy 421.730932 -342.82126) (xy 421.703659 -342.820803) (xy 421.649669 -342.813044)
			(xy 421.597332 -342.797681) (xy 421.547715 -342.775025) (xy 421.501827 -342.745538) (xy 421.460602 -342.70982)
			(xy 421.424881 -342.668599) (xy 421.395391 -342.622714) (xy 421.372731 -342.573098) (xy 421.357363 -342.520763)
			(xy 421.3496 -342.466773) (xy 419.866896 -342.466773) (xy 419.859134 -342.520761) (xy 419.843766 -342.573096)
			(xy 419.821107 -342.622711) (xy 419.791616 -342.668595) (xy 419.755896 -342.709816) (xy 419.714673 -342.745533)
			(xy 419.668786 -342.77502) (xy 419.61917 -342.797676) (xy 419.566834 -342.81304) (xy 419.512844 -342.820798)
			(xy 419.485572 -342.82126) (xy 418.621972 -342.82126) (xy 418.594704 -342.820776) (xy 418.540723 -342.813011)
			(xy 418.488396 -342.797643) (xy 418.43879 -342.774985) (xy 418.392912 -342.745498) (xy 418.351697 -342.709783)
			(xy 418.315985 -342.668566) (xy 418.286502 -342.622686) (xy 418.263847 -342.573077) (xy 418.248483 -342.52075)
			(xy 418.240722 -342.466768) (xy 416.757874 -342.466768) (xy 416.757874 -342.466769) (xy 416.750112 -342.520751)
			(xy 416.734748 -342.573079) (xy 416.712092 -342.622688) (xy 416.682608 -342.668568) (xy 416.646894 -342.709786)
			(xy 416.605678 -342.745501) (xy 416.559799 -342.774987) (xy 416.510191 -342.797643) (xy 416.457863 -342.81301)
			(xy 416.403881 -342.820773) (xy 416.376612 -342.82126) (xy 415.513012 -342.82126) (xy 415.48574 -342.820801)
			(xy 415.431752 -342.813041) (xy 415.379417 -342.797675) (xy 415.329803 -342.775018) (xy 415.283917 -342.745531)
			(xy 415.242695 -342.709813) (xy 415.206976 -342.668593) (xy 415.177488 -342.622708) (xy 415.154829 -342.573094)
			(xy 415.139462 -342.52076) (xy 415.1317 -342.466772) (xy 413.648996 -342.466772) (xy 413.648996 -342.466773)
			(xy 413.641233 -342.520764) (xy 413.625864 -342.5731) (xy 413.603203 -342.622716) (xy 413.573712 -342.668602)
			(xy 413.537989 -342.709823) (xy 413.496763 -342.74554) (xy 413.450874 -342.775026) (xy 413.401255 -342.797681)
			(xy 413.348917 -342.813043) (xy 413.294925 -342.8208) (xy 413.267652 -342.82126) (xy 412.404052 -342.82126)
			(xy 412.376785 -342.820774) (xy 412.322806 -342.813007) (xy 412.270482 -342.797637) (xy 412.220878 -342.774978)
			(xy 412.175002 -342.745491) (xy 412.13379 -342.709776) (xy 412.09808 -342.668559) (xy 412.068599 -342.62268)
			(xy 412.045946 -342.573073) (xy 412.030583 -342.520747) (xy 412.022822 -342.466767) (xy 410.539996 -342.466767)
			(xy 410.539996 -342.466771) (xy 410.532234 -342.520759) (xy 410.516868 -342.573092) (xy 410.49421 -342.622705)
			(xy 410.464721 -342.668589) (xy 410.429003 -342.709809) (xy 410.387782 -342.745526) (xy 410.341898 -342.775013)
			(xy 410.292284 -342.79767) (xy 410.239951 -342.813036) (xy 410.185963 -342.820797) (xy 410.158692 -342.82126)
			(xy 409.295092 -342.82126) (xy 409.267823 -342.820777) (xy 409.21384 -342.813014) (xy 409.161511 -342.797648)
			(xy 409.111902 -342.774991) (xy 409.066021 -342.745505) (xy 409.024805 -342.70979) (xy 408.98909 -342.668572)
			(xy 408.959605 -342.622691) (xy 408.936949 -342.573082) (xy 408.921584 -342.520752) (xy 408.913822 -342.466769)
			(xy 403.522496 -342.466769) (xy 403.522496 -342.466772) (xy 403.514734 -342.52076) (xy 403.499367 -342.573094)
			(xy 403.476708 -342.622708) (xy 403.447218 -342.668593) (xy 403.411499 -342.709813) (xy 403.370277 -342.74553)
			(xy 403.324391 -342.775017) (xy 403.274775 -342.797674) (xy 403.222441 -342.813038) (xy 403.168452 -342.820798)
			(xy 403.14118 -342.82126) (xy 402.27758 -342.82126) (xy 402.250311 -342.820776) (xy 402.19633 -342.813012)
			(xy 402.144002 -342.797645) (xy 402.094394 -342.774988) (xy 402.048516 -342.745501) (xy 402.0073 -342.709786)
			(xy 401.971587 -342.668568) (xy 401.942103 -342.622688) (xy 401.919448 -342.573079) (xy 401.904084 -342.520751)
			(xy 401.896322 -342.466769) (xy 400.413474 -342.466769) (xy 400.405713 -342.52075) (xy 400.390348 -342.573078)
			(xy 400.367694 -342.622686) (xy 400.33821 -342.668566) (xy 400.302497 -342.709783) (xy 400.261282 -342.745498)
			(xy 400.215404 -342.774984) (xy 400.165796 -342.797641) (xy 400.113469 -342.813008) (xy 400.059488 -342.820772)
			(xy 400.03222 -342.82126) (xy 399.16862 -342.82126) (xy 399.141348 -342.820802) (xy 399.087359 -342.813042)
			(xy 399.035023 -342.797677) (xy 398.985407 -342.775021) (xy 398.939521 -342.745534) (xy 398.898298 -342.709816)
			(xy 398.862578 -342.668595) (xy 398.833089 -342.62271) (xy 398.81043 -342.573096) (xy 398.795062 -342.520761)
			(xy 398.7873 -342.466772) (xy 397.304596 -342.466772) (xy 397.304596 -342.466773) (xy 397.296833 -342.520763)
			(xy 397.281465 -342.573098) (xy 397.258805 -342.622714) (xy 397.229313 -342.668599) (xy 397.193592 -342.70982)
			(xy 397.152367 -342.745537) (xy 397.106479 -342.775024) (xy 397.056861 -342.797679) (xy 397.004524 -342.813042)
			(xy 396.950533 -342.820799) (xy 396.92326 -342.82126) (xy 396.05966 -342.82126) (xy 396.032392 -342.820775)
			(xy 395.978413 -342.813009) (xy 395.926088 -342.79764) (xy 395.876482 -342.774981) (xy 395.830606 -342.745494)
			(xy 395.789393 -342.709778) (xy 395.753682 -342.668562) (xy 395.7242 -342.622682) (xy 395.701546 -342.573075)
			(xy 395.686183 -342.520748) (xy 395.678422 -342.466768) (xy 394.195574 -342.466768) (xy 394.195574 -342.466769)
			(xy 394.187812 -342.520753) (xy 394.172447 -342.573082) (xy 394.149791 -342.622692) (xy 394.120305 -342.668572)
			(xy 394.08459 -342.70979) (xy 394.043372 -342.745505) (xy 393.997492 -342.774991) (xy 393.947882 -342.797647)
			(xy 393.895553 -342.813012) (xy 393.841569 -342.820774) (xy 393.8143 -342.82126) (xy 392.9507 -342.82126)
			(xy 392.92343 -342.820778) (xy 392.869447 -342.813016) (xy 392.817117 -342.79765) (xy 392.767506 -342.774994)
			(xy 392.721625 -342.745508) (xy 392.680407 -342.709793) (xy 392.644692 -342.668575) (xy 392.615206 -342.622694)
			(xy 392.59255 -342.573083) (xy 392.577184 -342.520753) (xy 392.569422 -342.46677) (xy 391.086574 -342.46677)
			(xy 391.078813 -342.520747) (xy 391.06345 -342.573073) (xy 391.040797 -342.622681) (xy 391.011315 -342.668559)
			(xy 390.975604 -342.709776) (xy 390.934391 -342.745491) (xy 390.888516 -342.774978) (xy 390.838911 -342.797636)
			(xy 390.786586 -342.813005) (xy 390.732607 -342.820771) (xy 390.70534 -342.82126) (xy 389.84174 -342.82126)
			(xy 389.814467 -342.820803) (xy 389.760476 -342.813046) (xy 389.708138 -342.797683) (xy 389.658519 -342.775027)
			(xy 389.61263 -342.745541) (xy 389.571405 -342.709823) (xy 389.535683 -342.668602) (xy 389.506192 -342.622716)
			(xy 389.483531 -342.5731) (xy 389.468163 -342.520764) (xy 389.4604 -342.466773) (xy 387.977696 -342.466773)
			(xy 387.969934 -342.52076) (xy 387.954567 -342.573094) (xy 387.931908 -342.622708) (xy 387.902418 -342.668593)
			(xy 387.866699 -342.709813) (xy 387.825477 -342.74553) (xy 387.779591 -342.775017) (xy 387.729975 -342.797674)
			(xy 387.677641 -342.813038) (xy 387.623652 -342.820798) (xy 387.59638 -342.82126) (xy 386.73278 -342.82126)
			(xy 386.705511 -342.820776) (xy 386.65153 -342.813012) (xy 386.599202 -342.797645) (xy 386.549594 -342.774988)
			(xy 386.503716 -342.745501) (xy 386.4625 -342.709786) (xy 386.426787 -342.668568) (xy 386.397303 -342.622688)
			(xy 386.374648 -342.573079) (xy 386.359284 -342.520751) (xy 386.351522 -342.466769) (xy 384.868674 -342.466769)
			(xy 384.860913 -342.52075) (xy 384.845548 -342.573078) (xy 384.822894 -342.622686) (xy 384.79341 -342.668566)
			(xy 384.757697 -342.709783) (xy 384.716482 -342.745498) (xy 384.670604 -342.774984) (xy 384.620996 -342.797641)
			(xy 384.568669 -342.813008) (xy 384.514688 -342.820772) (xy 384.48742 -342.82126) (xy 383.62382 -342.82126)
			(xy 383.596548 -342.820802) (xy 383.542559 -342.813042) (xy 383.490223 -342.797677) (xy 383.440607 -342.775021)
			(xy 383.394721 -342.745534) (xy 383.353498 -342.709816) (xy 383.317778 -342.668595) (xy 383.288289 -342.62271)
			(xy 383.26563 -342.573096) (xy 383.250262 -342.520761) (xy 383.2425 -342.466772) (xy 381.759796 -342.466772)
			(xy 381.759796 -342.466773) (xy 381.752033 -342.520763) (xy 381.736665 -342.573098) (xy 381.714005 -342.622714)
			(xy 381.684513 -342.668599) (xy 381.648792 -342.70982) (xy 381.607567 -342.745537) (xy 381.561679 -342.775024)
			(xy 381.512061 -342.797679) (xy 381.459724 -342.813042) (xy 381.405733 -342.820799) (xy 381.37846 -342.82126)
			(xy 380.51486 -342.82126) (xy 380.487592 -342.820775) (xy 380.433613 -342.813009) (xy 380.381288 -342.79764)
			(xy 380.331682 -342.774981) (xy 380.285806 -342.745494) (xy 380.244593 -342.709778) (xy 380.208882 -342.668562)
			(xy 380.1794 -342.622682) (xy 380.156746 -342.573075) (xy 380.141383 -342.520748) (xy 380.133622 -342.466768)
			(xy 378.650774 -342.466768) (xy 378.650774 -342.466769) (xy 378.643012 -342.520753) (xy 378.627647 -342.573082)
			(xy 378.604991 -342.622692) (xy 378.575505 -342.668572) (xy 378.53979 -342.70979) (xy 378.498572 -342.745505)
			(xy 378.452692 -342.774991) (xy 378.403082 -342.797647) (xy 378.350753 -342.813012) (xy 378.296769 -342.820774)
			(xy 378.2695 -342.82126) (xy 377.4059 -342.82126) (xy 377.37863 -342.820778) (xy 377.324647 -342.813016)
			(xy 377.272317 -342.79765) (xy 377.222706 -342.774994) (xy 377.176825 -342.745508) (xy 377.135607 -342.709793)
			(xy 377.099892 -342.668575) (xy 377.070406 -342.622694) (xy 377.04775 -342.573083) (xy 377.032384 -342.520753)
			(xy 377.024622 -342.46677) (xy 375.541774 -342.46677) (xy 375.534013 -342.520747) (xy 375.51865 -342.573073)
			(xy 375.495997 -342.622681) (xy 375.466515 -342.668559) (xy 375.430804 -342.709776) (xy 375.389591 -342.745491)
			(xy 375.343716 -342.774978) (xy 375.294111 -342.797636) (xy 375.241786 -342.813005) (xy 375.187807 -342.820771)
			(xy 375.16054 -342.82126) (xy 374.29694 -342.82126) (xy 374.269667 -342.820803) (xy 374.215676 -342.813046)
			(xy 374.163338 -342.797683) (xy 374.113719 -342.775027) (xy 374.06783 -342.745541) (xy 374.026605 -342.709823)
			(xy 373.990883 -342.668602) (xy 373.961392 -342.622716) (xy 373.938731 -342.5731) (xy 373.923363 -342.520764)
			(xy 373.9156 -342.466773) (xy 372.432896 -342.466773) (xy 372.425134 -342.52076) (xy 372.409767 -342.573094)
			(xy 372.387108 -342.622708) (xy 372.357618 -342.668593) (xy 372.321899 -342.709813) (xy 372.280677 -342.74553)
			(xy 372.234791 -342.775017) (xy 372.185175 -342.797674) (xy 372.132841 -342.813038) (xy 372.078852 -342.820798)
			(xy 372.05158 -342.82126) (xy 371.18798 -342.82126) (xy 371.160711 -342.820776) (xy 371.10673 -342.813012)
			(xy 371.054402 -342.797645) (xy 371.004794 -342.774988) (xy 370.958916 -342.745501) (xy 370.9177 -342.709786)
			(xy 370.881987 -342.668568) (xy 370.852503 -342.622688) (xy 370.829848 -342.573079) (xy 370.814484 -342.520751)
			(xy 370.806722 -342.466769) (xy 344.837274 -342.466769) (xy 344.829512 -342.520752) (xy 344.814147 -342.573081)
			(xy 344.791491 -342.622691) (xy 344.762006 -342.668571) (xy 344.726291 -342.709788) (xy 344.685074 -342.745503)
			(xy 344.639194 -342.774989) (xy 344.589585 -342.797646) (xy 344.537256 -342.813011) (xy 344.483273 -342.820773)
			(xy 344.456004 -342.82126) (xy 343.592404 -342.82126) (xy 343.565133 -342.820801) (xy 343.511145 -342.813039)
			(xy 343.458812 -342.797673) (xy 343.409198 -342.775016) (xy 343.363313 -342.745528) (xy 343.322093 -342.70981)
			(xy 343.286374 -342.66859) (xy 343.256886 -342.622706) (xy 343.234228 -342.573092) (xy 343.218862 -342.520759)
			(xy 343.2111 -342.466771) (xy 341.728273 -342.466771) (xy 341.720513 -342.520747) (xy 341.70515 -342.573072)
			(xy 341.682497 -342.622679) (xy 341.653016 -342.668558) (xy 341.617305 -342.709774) (xy 341.576093 -342.745489)
			(xy 341.530218 -342.774976) (xy 341.480614 -342.797635) (xy 341.42829 -342.813004) (xy 341.374311 -342.820771)
			(xy 341.347044 -342.82126) (xy 340.483444 -342.82126) (xy 340.456171 -342.820804) (xy 340.402179 -342.813046)
			(xy 340.349841 -342.797684) (xy 340.300222 -342.775029) (xy 340.254332 -342.745542) (xy 340.213107 -342.709824)
			(xy 340.177384 -342.668603) (xy 340.147892 -342.622717) (xy 340.125232 -342.573101) (xy 340.109863 -342.520764)
			(xy 340.1021 -342.466773) (xy 338.619396 -342.466773) (xy 338.611634 -342.52076) (xy 338.596267 -342.573093)
			(xy 338.573608 -342.622707) (xy 338.544119 -342.668591) (xy 338.5084 -342.709812) (xy 338.467179 -342.745529)
			(xy 338.421293 -342.775016) (xy 338.371678 -342.797673) (xy 338.319344 -342.813037) (xy 338.265356 -342.820798)
			(xy 338.238084 -342.82126) (xy 337.374484 -342.82126) (xy 337.347215 -342.820776) (xy 337.293233 -342.813013)
			(xy 337.240905 -342.797646) (xy 337.191297 -342.774989) (xy 337.145418 -342.745502) (xy 337.104202 -342.709787)
			(xy 337.068488 -342.66857) (xy 337.039003 -342.622689) (xy 337.016348 -342.57308) (xy 337.000984 -342.520751)
			(xy 336.993222 -342.466769) (xy 335.510374 -342.466769) (xy 335.502613 -342.520749) (xy 335.487249 -342.573077)
			(xy 335.464594 -342.622685) (xy 335.435111 -342.668565) (xy 335.399398 -342.709781) (xy 335.358184 -342.745496)
			(xy 335.312306 -342.774983) (xy 335.262699 -342.79764) (xy 335.210373 -342.813008) (xy 335.156392 -342.820772)
			(xy 335.129124 -342.82126) (xy 334.265524 -342.82126) (xy 334.238252 -342.820802) (xy 334.184262 -342.813043)
			(xy 334.131926 -342.797678) (xy 334.08231 -342.775022) (xy 334.036423 -342.745535) (xy 333.9952 -342.709817)
			(xy 333.959479 -342.668596) (xy 333.929989 -342.622711) (xy 333.90733 -342.573096) (xy 333.891962 -342.520761)
			(xy 333.8842 -342.466772) (xy 332.401496 -342.466772) (xy 332.393733 -342.520762) (xy 332.378365 -342.573098)
			(xy 332.355705 -342.622713) (xy 332.326214 -342.668598) (xy 332.290493 -342.709819) (xy 332.249269 -342.745536)
			(xy 332.203381 -342.775023) (xy 332.153764 -342.797678) (xy 332.101427 -342.813041) (xy 332.047437 -342.820799)
			(xy 332.020164 -342.82126) (xy 331.156564 -342.82126) (xy 331.129296 -342.820775) (xy 331.075316 -342.813009)
			(xy 331.022991 -342.797641) (xy 330.973385 -342.774982) (xy 330.927508 -342.745495) (xy 330.886295 -342.70978)
			(xy 330.850583 -342.668563) (xy 330.8211 -342.622684) (xy 330.798447 -342.573076) (xy 330.783083 -342.520749)
			(xy 330.775322 -342.466768) (xy 329.292474 -342.466768) (xy 329.292474 -342.466769) (xy 329.284712 -342.520752)
			(xy 329.269347 -342.573081) (xy 329.246691 -342.622691) (xy 329.217206 -342.668571) (xy 329.181491 -342.709788)
			(xy 329.140274 -342.745503) (xy 329.094394 -342.774989) (xy 329.044785 -342.797646) (xy 328.992456 -342.813011)
			(xy 328.938473 -342.820773) (xy 328.911204 -342.82126) (xy 328.047604 -342.82126) (xy 328.020333 -342.820801)
			(xy 327.966345 -342.813039) (xy 327.914012 -342.797673) (xy 327.864398 -342.775016) (xy 327.818513 -342.745528)
			(xy 327.777293 -342.70981) (xy 327.741574 -342.66859) (xy 327.712086 -342.622706) (xy 327.689428 -342.573092)
			(xy 327.674062 -342.520759) (xy 327.6663 -342.466771) (xy 326.183473 -342.466771) (xy 326.175713 -342.520747)
			(xy 326.16035 -342.573072) (xy 326.137697 -342.622679) (xy 326.108216 -342.668558) (xy 326.072505 -342.709774)
			(xy 326.031293 -342.745489) (xy 325.985418 -342.774976) (xy 325.935814 -342.797635) (xy 325.88349 -342.813004)
			(xy 325.829511 -342.820771) (xy 325.802244 -342.82126) (xy 324.938644 -342.82126) (xy 324.911371 -342.820804)
			(xy 324.857379 -342.813046) (xy 324.805041 -342.797684) (xy 324.755422 -342.775029) (xy 324.709532 -342.745542)
			(xy 324.668307 -342.709824) (xy 324.632584 -342.668603) (xy 324.603092 -342.622717) (xy 324.580432 -342.573101)
			(xy 324.565063 -342.520764) (xy 324.5573 -342.466773) (xy 323.074596 -342.466773) (xy 323.066834 -342.52076)
			(xy 323.051467 -342.573093) (xy 323.028808 -342.622707) (xy 322.999319 -342.668591) (xy 322.9636 -342.709812)
			(xy 322.922379 -342.745529) (xy 322.876493 -342.775016) (xy 322.826878 -342.797673) (xy 322.774544 -342.813037)
			(xy 322.720556 -342.820798) (xy 322.693284 -342.82126) (xy 321.829684 -342.82126) (xy 321.802415 -342.820776)
			(xy 321.748433 -342.813013) (xy 321.696105 -342.797646) (xy 321.646497 -342.774989) (xy 321.600618 -342.745502)
			(xy 321.559402 -342.709787) (xy 321.523688 -342.66857) (xy 321.494203 -342.622689) (xy 321.471548 -342.57308)
			(xy 321.456184 -342.520751) (xy 321.448422 -342.466769) (xy 319.965574 -342.466769) (xy 319.957813 -342.520749)
			(xy 319.942449 -342.573077) (xy 319.919794 -342.622685) (xy 319.890311 -342.668565) (xy 319.854598 -342.709781)
			(xy 319.813384 -342.745496) (xy 319.767506 -342.774983) (xy 319.717899 -342.79764) (xy 319.665573 -342.813008)
			(xy 319.611592 -342.820772) (xy 319.584324 -342.82126) (xy 318.720724 -342.82126) (xy 318.693452 -342.820802)
			(xy 318.639462 -342.813043) (xy 318.587126 -342.797678) (xy 318.53751 -342.775022) (xy 318.491623 -342.745535)
			(xy 318.4504 -342.709817) (xy 318.414679 -342.668596) (xy 318.385189 -342.622711) (xy 318.36253 -342.573096)
			(xy 318.347162 -342.520761) (xy 318.3394 -342.466772) (xy 316.856696 -342.466772) (xy 316.848933 -342.520762)
			(xy 316.833565 -342.573098) (xy 316.810905 -342.622713) (xy 316.781414 -342.668598) (xy 316.745693 -342.709819)
			(xy 316.704469 -342.745536) (xy 316.658581 -342.775023) (xy 316.608964 -342.797678) (xy 316.556627 -342.813041)
			(xy 316.502637 -342.820799) (xy 316.475364 -342.82126) (xy 315.611764 -342.82126) (xy 315.584496 -342.820775)
			(xy 315.530516 -342.813009) (xy 315.478191 -342.797641) (xy 315.428585 -342.774982) (xy 315.382708 -342.745495)
			(xy 315.341495 -342.70978) (xy 315.305783 -342.668563) (xy 315.2763 -342.622684) (xy 315.253647 -342.573076)
			(xy 315.238283 -342.520749) (xy 315.230522 -342.466768) (xy 313.747674 -342.466768) (xy 313.747674 -342.466769)
			(xy 313.739912 -342.520752) (xy 313.724547 -342.573081) (xy 313.701891 -342.622691) (xy 313.672406 -342.668571)
			(xy 313.636691 -342.709788) (xy 313.595474 -342.745503) (xy 313.549594 -342.774989) (xy 313.499985 -342.797646)
			(xy 313.447656 -342.813011) (xy 313.393673 -342.820773) (xy 313.366404 -342.82126) (xy 312.502804 -342.82126)
			(xy 312.475533 -342.820801) (xy 312.421545 -342.813039) (xy 312.369212 -342.797673) (xy 312.319598 -342.775016)
			(xy 312.273713 -342.745528) (xy 312.232493 -342.70981) (xy 312.196774 -342.66859) (xy 312.167286 -342.622706)
			(xy 312.144628 -342.573092) (xy 312.129262 -342.520759) (xy 312.1215 -342.466771) (xy 300.231574 -342.466771)
			(xy 300.223812 -342.520752) (xy 300.208447 -342.573081) (xy 300.185791 -342.622691) (xy 300.156305 -342.668572)
			(xy 300.120591 -342.709789) (xy 300.079373 -342.745504) (xy 300.033493 -342.77499) (xy 299.983883 -342.797646)
			(xy 299.931554 -342.813012) (xy 299.877571 -342.820773) (xy 299.850302 -342.82126) (xy 298.986702 -342.82126)
			(xy 298.959431 -342.820801) (xy 298.905443 -342.813039) (xy 298.85311 -342.797673) (xy 298.803497 -342.775015)
			(xy 298.757612 -342.745527) (xy 298.716392 -342.70981) (xy 298.680674 -342.668589) (xy 298.651186 -342.622705)
			(xy 298.628528 -342.573092) (xy 298.613162 -342.520759) (xy 298.605399 -342.466771) (xy 297.122573 -342.466771)
			(xy 297.114813 -342.520747) (xy 297.09945 -342.573073) (xy 297.076797 -342.62268) (xy 297.047315 -342.668559)
			(xy 297.011605 -342.709775) (xy 296.970392 -342.74549) (xy 296.924517 -342.774977) (xy 296.874912 -342.797635)
			(xy 296.822588 -342.813004) (xy 296.768609 -342.820771) (xy 296.741342 -342.82126) (xy 295.877742 -342.82126)
			(xy 295.850469 -342.820803) (xy 295.796477 -342.813046) (xy 295.744139 -342.797683) (xy 295.694521 -342.775028)
			(xy 295.648631 -342.745541) (xy 295.607406 -342.709824) (xy 295.571684 -342.668602) (xy 295.542192 -342.622716)
			(xy 295.519531 -342.5731) (xy 295.504163 -342.520764) (xy 295.4964 -342.466773) (xy 294.013696 -342.466773)
			(xy 294.005934 -342.52076) (xy 293.990567 -342.573094) (xy 293.967908 -342.622708) (xy 293.938419 -342.668592)
			(xy 293.9027 -342.709812) (xy 293.861478 -342.74553) (xy 293.815592 -342.775017) (xy 293.765977 -342.797673)
			(xy 293.713642 -342.813038) (xy 293.659654 -342.820798) (xy 293.632382 -342.82126) (xy 292.768782 -342.82126)
			(xy 292.741513 -342.820776) (xy 292.687531 -342.813013) (xy 292.635204 -342.797646) (xy 292.585596 -342.774988)
			(xy 292.539717 -342.745502) (xy 292.498501 -342.709786) (xy 292.462787 -342.668569) (xy 292.433303 -342.622689)
			(xy 292.410648 -342.573079) (xy 292.395284 -342.520751) (xy 292.387522 -342.466769) (xy 290.904674 -342.466769)
			(xy 290.896913 -342.52075) (xy 290.881548 -342.573077) (xy 290.858894 -342.622686) (xy 290.82941 -342.668565)
			(xy 290.793698 -342.709782) (xy 290.752483 -342.745497) (xy 290.706605 -342.774983) (xy 290.656998 -342.797641)
			(xy 290.604671 -342.813008) (xy 290.55069 -342.820772) (xy 290.523422 -342.82126) (xy 289.659822 -342.82126)
			(xy 289.63255 -342.820802) (xy 289.57856 -342.813042) (xy 289.526225 -342.797678) (xy 289.476609 -342.775021)
			(xy 289.430722 -342.745534) (xy 289.389499 -342.709817) (xy 289.353779 -342.668596) (xy 289.324289 -342.622711)
			(xy 289.30163 -342.573096) (xy 289.286262 -342.520761) (xy 289.2785 -342.466772) (xy 287.795796 -342.466772)
			(xy 287.795796 -342.466773) (xy 287.788033 -342.520763) (xy 287.772665 -342.573098) (xy 287.750005 -342.622713)
			(xy 287.720514 -342.668599) (xy 287.684793 -342.70982) (xy 287.643568 -342.745537) (xy 287.59768 -342.775023)
			(xy 287.548062 -342.797679) (xy 287.495725 -342.813041) (xy 287.441735 -342.820799) (xy 287.414462 -342.82126)
			(xy 286.550862 -342.82126) (xy 286.523594 -342.820775) (xy 286.469614 -342.813009) (xy 286.417289 -342.79764)
			(xy 286.367684 -342.774982) (xy 286.321807 -342.745495) (xy 286.280594 -342.709779) (xy 286.244883 -342.668562)
			(xy 286.2154 -342.622683) (xy 286.192747 -342.573075) (xy 286.177383 -342.520748) (xy 286.169622 -342.466768)
			(xy 284.686774 -342.466768) (xy 284.686774 -342.466769) (xy 284.679012 -342.520752) (xy 284.663647 -342.573081)
			(xy 284.640991 -342.622691) (xy 284.611505 -342.668572) (xy 284.575791 -342.709789) (xy 284.534573 -342.745504)
			(xy 284.488693 -342.77499) (xy 284.439083 -342.797646) (xy 284.386754 -342.813012) (xy 284.332771 -342.820773)
			(xy 284.305502 -342.82126) (xy 283.441902 -342.82126) (xy 283.414631 -342.820801) (xy 283.360643 -342.813039)
			(xy 283.30831 -342.797673) (xy 283.258697 -342.775015) (xy 283.212812 -342.745527) (xy 283.171592 -342.70981)
			(xy 283.135874 -342.668589) (xy 283.106386 -342.622705) (xy 283.083728 -342.573092) (xy 283.068362 -342.520759)
			(xy 283.060599 -342.466771) (xy 281.577773 -342.466771) (xy 281.570013 -342.520747) (xy 281.55465 -342.573073)
			(xy 281.531997 -342.62268) (xy 281.502515 -342.668559) (xy 281.466805 -342.709775) (xy 281.425592 -342.74549)
			(xy 281.379717 -342.774977) (xy 281.330112 -342.797635) (xy 281.277788 -342.813004) (xy 281.223809 -342.820771)
			(xy 281.196542 -342.82126) (xy 280.332942 -342.82126) (xy 280.305669 -342.820803) (xy 280.251677 -342.813046)
			(xy 280.199339 -342.797683) (xy 280.149721 -342.775028) (xy 280.103831 -342.745541) (xy 280.062606 -342.709824)
			(xy 280.026884 -342.668602) (xy 279.997392 -342.622716) (xy 279.974731 -342.5731) (xy 279.959363 -342.520764)
			(xy 279.9516 -342.466773) (xy 278.468896 -342.466773) (xy 278.461134 -342.52076) (xy 278.445767 -342.573094)
			(xy 278.423108 -342.622708) (xy 278.393619 -342.668592) (xy 278.3579 -342.709812) (xy 278.316678 -342.74553)
			(xy 278.270792 -342.775017) (xy 278.221177 -342.797673) (xy 278.168842 -342.813038) (xy 278.114854 -342.820798)
			(xy 278.087582 -342.82126) (xy 277.223982 -342.82126) (xy 277.196713 -342.820776) (xy 277.142731 -342.813013)
			(xy 277.090404 -342.797646) (xy 277.040796 -342.774988) (xy 276.994917 -342.745502) (xy 276.953701 -342.709786)
			(xy 276.917987 -342.668569) (xy 276.888503 -342.622689) (xy 276.865848 -342.573079) (xy 276.850484 -342.520751)
			(xy 276.842722 -342.466769) (xy 275.359874 -342.466769) (xy 275.352113 -342.52075) (xy 275.336748 -342.573077)
			(xy 275.314094 -342.622686) (xy 275.28461 -342.668565) (xy 275.248898 -342.709782) (xy 275.207683 -342.745497)
			(xy 275.161805 -342.774983) (xy 275.112198 -342.797641) (xy 275.059871 -342.813008) (xy 275.00589 -342.820772)
			(xy 274.978622 -342.82126) (xy 274.115022 -342.82126) (xy 274.08775 -342.820802) (xy 274.03376 -342.813042)
			(xy 273.981425 -342.797678) (xy 273.931809 -342.775021) (xy 273.885922 -342.745534) (xy 273.844699 -342.709817)
			(xy 273.808979 -342.668596) (xy 273.779489 -342.622711) (xy 273.75683 -342.573096) (xy 273.741462 -342.520761)
			(xy 273.7337 -342.466772) (xy 272.250996 -342.466772) (xy 272.250996 -342.466773) (xy 272.243233 -342.520763)
			(xy 272.227865 -342.573098) (xy 272.205205 -342.622713) (xy 272.175714 -342.668599) (xy 272.139993 -342.70982)
			(xy 272.098768 -342.745537) (xy 272.05288 -342.775023) (xy 272.003262 -342.797679) (xy 271.950925 -342.813041)
			(xy 271.896935 -342.820799) (xy 271.869662 -342.82126) (xy 271.006062 -342.82126) (xy 270.978794 -342.820775)
			(xy 270.924814 -342.813009) (xy 270.872489 -342.79764) (xy 270.822884 -342.774982) (xy 270.777007 -342.745495)
			(xy 270.735794 -342.709779) (xy 270.700083 -342.668562) (xy 270.6706 -342.622683) (xy 270.647947 -342.573075)
			(xy 270.632583 -342.520748) (xy 270.624822 -342.466768) (xy 269.141974 -342.466768) (xy 269.141974 -342.466769)
			(xy 269.134212 -342.520752) (xy 269.118847 -342.573081) (xy 269.096191 -342.622691) (xy 269.066705 -342.668572)
			(xy 269.030991 -342.709789) (xy 268.989773 -342.745504) (xy 268.943893 -342.77499) (xy 268.894283 -342.797646)
			(xy 268.841954 -342.813012) (xy 268.787971 -342.820773) (xy 268.760702 -342.82126) (xy 267.897102 -342.82126)
			(xy 267.869831 -342.820801) (xy 267.815843 -342.813039) (xy 267.76351 -342.797673) (xy 267.713897 -342.775015)
			(xy 267.668012 -342.745527) (xy 267.626792 -342.70981) (xy 267.591074 -342.668589) (xy 267.561586 -342.622705)
			(xy 267.538928 -342.573092) (xy 267.523562 -342.520759) (xy 267.515799 -342.466771) (xy 256.581015 -342.466771)
			(xy 256.573351 -342.471196) (xy 256.517947 -342.494145) (xy 256.460022 -342.509666) (xy 256.400566 -342.517494)
			(xy 256.340598 -342.517494) (xy 256.281142 -342.509666) (xy 256.223217 -342.494145) (xy 256.167813 -342.471196)
			(xy 256.115879 -342.441212) (xy 256.068303 -342.404706) (xy 256.025898 -342.362301) (xy 255.989392 -342.314725)
			(xy 255.959408 -342.262791) (xy 255.936459 -342.207387) (xy 255.920938 -342.149462) (xy 255.91311 -342.090006)
			(xy 255.91262 -342.060022) (xy 197.28821 -342.060022) (xy 197.329534 -342.06596) (xy 197.38187 -342.081324)
			(xy 197.431486 -342.10398) (xy 197.477373 -342.133467) (xy 197.518596 -342.169184) (xy 197.554316 -342.210405)
			(xy 197.583807 -342.256289) (xy 197.606466 -342.305904) (xy 197.621834 -342.358239) (xy 197.629596 -342.412228)
			(xy 197.629596 -342.466772) (xy 197.621834 -342.520761) (xy 197.606466 -342.573096) (xy 197.583807 -342.622711)
			(xy 197.554316 -342.668595) (xy 197.518596 -342.709816) (xy 197.477373 -342.745533) (xy 197.431486 -342.77502)
			(xy 197.38187 -342.797676) (xy 197.329534 -342.81304) (xy 197.275544 -342.820798) (xy 197.248272 -342.82126)
			(xy 196.384672 -342.82126) (xy 196.357404 -342.820776) (xy 196.303423 -342.813011) (xy 196.251096 -342.797643)
			(xy 196.20149 -342.774985) (xy 196.155612 -342.745498) (xy 196.114397 -342.709783) (xy 196.078685 -342.668566)
			(xy 196.049202 -342.622686) (xy 196.026547 -342.573077) (xy 196.011183 -342.52075) (xy 196.003422 -342.466768)
			(xy 194.520574 -342.466768) (xy 194.520574 -342.466769) (xy 194.512812 -342.520751) (xy 194.497448 -342.573079)
			(xy 194.474792 -342.622688) (xy 194.445308 -342.668568) (xy 194.409594 -342.709786) (xy 194.368378 -342.745501)
			(xy 194.322499 -342.774987) (xy 194.272891 -342.797643) (xy 194.220563 -342.81301) (xy 194.166581 -342.820773)
			(xy 194.139312 -342.82126) (xy 193.275712 -342.82126) (xy 193.24844 -342.820801) (xy 193.194452 -342.813041)
			(xy 193.142117 -342.797675) (xy 193.092503 -342.775018) (xy 193.046617 -342.745531) (xy 193.005395 -342.709813)
			(xy 192.969676 -342.668593) (xy 192.940188 -342.622708) (xy 192.917529 -342.573094) (xy 192.902162 -342.52076)
			(xy 192.8944 -342.466772) (xy 191.411696 -342.466772) (xy 191.411696 -342.466773) (xy 191.403933 -342.520764)
			(xy 191.388564 -342.5731) (xy 191.365903 -342.622716) (xy 191.336412 -342.668602) (xy 191.300689 -342.709823)
			(xy 191.259463 -342.74554) (xy 191.213574 -342.775026) (xy 191.163955 -342.797681) (xy 191.111617 -342.813043)
			(xy 191.057625 -342.8208) (xy 191.030352 -342.82126) (xy 190.166752 -342.82126) (xy 190.139485 -342.820774)
			(xy 190.085506 -342.813007) (xy 190.033182 -342.797637) (xy 189.983578 -342.774978) (xy 189.937702 -342.745491)
			(xy 189.89649 -342.709776) (xy 189.86078 -342.668559) (xy 189.831299 -342.62268) (xy 189.808646 -342.573073)
			(xy 189.793283 -342.520747) (xy 189.785522 -342.466767) (xy 188.302696 -342.466767) (xy 188.302696 -342.466771)
			(xy 188.294934 -342.520759) (xy 188.279568 -342.573092) (xy 188.25691 -342.622705) (xy 188.227421 -342.668589)
			(xy 188.191703 -342.709809) (xy 188.150482 -342.745526) (xy 188.104598 -342.775013) (xy 188.054984 -342.79767)
			(xy 188.002651 -342.813036) (xy 187.948663 -342.820797) (xy 187.921392 -342.82126) (xy 187.057792 -342.82126)
			(xy 187.030523 -342.820777) (xy 186.97654 -342.813014) (xy 186.924211 -342.797648) (xy 186.874602 -342.774991)
			(xy 186.828721 -342.745505) (xy 186.787505 -342.70979) (xy 186.75179 -342.668572) (xy 186.722305 -342.622691)
			(xy 186.699649 -342.573082) (xy 186.684284 -342.520752) (xy 186.676522 -342.466769) (xy 185.193674 -342.466769)
			(xy 185.185913 -342.520748) (xy 185.170549 -342.573075) (xy 185.147895 -342.622683) (xy 185.118413 -342.668562)
			(xy 185.082701 -342.709778) (xy 185.041488 -342.745494) (xy 184.995611 -342.77498) (xy 184.946005 -342.797638)
			(xy 184.89368 -342.813006) (xy 184.8397 -342.820771) (xy 184.812432 -342.82126) (xy 183.948832 -342.82126)
			(xy 183.921559 -342.820803) (xy 183.867569 -342.813044) (xy 183.815232 -342.797681) (xy 183.765615 -342.775025)
			(xy 183.719727 -342.745538) (xy 183.678502 -342.70982) (xy 183.642781 -342.668599) (xy 183.613291 -342.622714)
			(xy 183.590631 -342.573098) (xy 183.575263 -342.520763) (xy 183.5675 -342.466773) (xy 182.084796 -342.466773)
			(xy 182.077034 -342.520761) (xy 182.061666 -342.573096) (xy 182.039007 -342.622711) (xy 182.009516 -342.668595)
			(xy 181.973796 -342.709816) (xy 181.932573 -342.745533) (xy 181.886686 -342.77502) (xy 181.83707 -342.797676)
			(xy 181.784734 -342.81304) (xy 181.730744 -342.820798) (xy 181.703472 -342.82126) (xy 180.839872 -342.82126)
			(xy 180.812604 -342.820776) (xy 180.758623 -342.813011) (xy 180.706296 -342.797643) (xy 180.65669 -342.774985)
			(xy 180.610812 -342.745498) (xy 180.569597 -342.709783) (xy 180.533885 -342.668566) (xy 180.504402 -342.622686)
			(xy 180.481747 -342.573077) (xy 180.466383 -342.52075) (xy 180.458622 -342.466768) (xy 178.975774 -342.466768)
			(xy 178.975774 -342.466769) (xy 178.968012 -342.520751) (xy 178.952648 -342.573079) (xy 178.929992 -342.622688)
			(xy 178.900508 -342.668568) (xy 178.864794 -342.709786) (xy 178.823578 -342.745501) (xy 178.777699 -342.774987)
			(xy 178.728091 -342.797643) (xy 178.675763 -342.81301) (xy 178.621781 -342.820773) (xy 178.594512 -342.82126)
			(xy 177.730912 -342.82126) (xy 177.70364 -342.820801) (xy 177.649652 -342.813041) (xy 177.597317 -342.797675)
			(xy 177.547703 -342.775018) (xy 177.501817 -342.745531) (xy 177.460595 -342.709813) (xy 177.424876 -342.668593)
			(xy 177.395388 -342.622708) (xy 177.372729 -342.573094) (xy 177.357362 -342.52076) (xy 177.3496 -342.466772)
			(xy 175.866896 -342.466772) (xy 175.866896 -342.466773) (xy 175.859133 -342.520764) (xy 175.843764 -342.5731)
			(xy 175.821103 -342.622716) (xy 175.791612 -342.668602) (xy 175.755889 -342.709823) (xy 175.714663 -342.74554)
			(xy 175.668774 -342.775026) (xy 175.619155 -342.797681) (xy 175.566817 -342.813043) (xy 175.512825 -342.8208)
			(xy 175.485552 -342.82126) (xy 174.621952 -342.82126) (xy 174.594685 -342.820774) (xy 174.540706 -342.813007)
			(xy 174.488382 -342.797637) (xy 174.438778 -342.774978) (xy 174.392902 -342.745491) (xy 174.35169 -342.709776)
			(xy 174.31598 -342.668559) (xy 174.286499 -342.62268) (xy 174.263846 -342.573073) (xy 174.248483 -342.520747)
			(xy 174.240722 -342.466767) (xy 172.757896 -342.466767) (xy 172.757896 -342.466771) (xy 172.750134 -342.520759)
			(xy 172.734768 -342.573092) (xy 172.71211 -342.622705) (xy 172.682621 -342.668589) (xy 172.646903 -342.709809)
			(xy 172.605682 -342.745526) (xy 172.559798 -342.775013) (xy 172.510184 -342.79767) (xy 172.457851 -342.813036)
			(xy 172.403863 -342.820797) (xy 172.376592 -342.82126) (xy 171.512992 -342.82126) (xy 171.485723 -342.820777)
			(xy 171.43174 -342.813014) (xy 171.379411 -342.797648) (xy 171.329802 -342.774991) (xy 171.283921 -342.745505)
			(xy 171.242705 -342.70979) (xy 171.20699 -342.668572) (xy 171.177505 -342.622691) (xy 171.154849 -342.573082)
			(xy 171.139484 -342.520752) (xy 171.131722 -342.466769) (xy 169.648874 -342.466769) (xy 169.641113 -342.520748)
			(xy 169.625749 -342.573075) (xy 169.603095 -342.622683) (xy 169.573613 -342.668562) (xy 169.537901 -342.709778)
			(xy 169.496688 -342.745494) (xy 169.450811 -342.77498) (xy 169.401205 -342.797638) (xy 169.34888 -342.813006)
			(xy 169.2949 -342.820771) (xy 169.267632 -342.82126) (xy 168.404032 -342.82126) (xy 168.376759 -342.820803)
			(xy 168.322769 -342.813044) (xy 168.270432 -342.797681) (xy 168.220815 -342.775025) (xy 168.174927 -342.745538)
			(xy 168.133702 -342.70982) (xy 168.097981 -342.668599) (xy 168.068491 -342.622714) (xy 168.045831 -342.573098)
			(xy 168.030463 -342.520763) (xy 168.0227 -342.466773) (xy 166.539996 -342.466773) (xy 166.532234 -342.520761)
			(xy 166.516866 -342.573096) (xy 166.494207 -342.622711) (xy 166.464716 -342.668595) (xy 166.428996 -342.709816)
			(xy 166.387773 -342.745533) (xy 166.341886 -342.77502) (xy 166.29227 -342.797676) (xy 166.239934 -342.81304)
			(xy 166.185944 -342.820798) (xy 166.158672 -342.82126) (xy 165.295072 -342.82126) (xy 165.267804 -342.820776)
			(xy 165.213823 -342.813011) (xy 165.161496 -342.797643) (xy 165.11189 -342.774985) (xy 165.066012 -342.745498)
			(xy 165.024797 -342.709783) (xy 164.989085 -342.668566) (xy 164.959602 -342.622686) (xy 164.936947 -342.573077)
			(xy 164.921583 -342.52075) (xy 164.913822 -342.466768) (xy 144.196574 -342.466768) (xy 144.196574 -342.466769)
			(xy 144.188812 -342.520751) (xy 144.173447 -342.57308) (xy 144.150792 -342.622689) (xy 144.121307 -342.66857)
			(xy 144.085593 -342.709787) (xy 144.044376 -342.745502) (xy 143.998497 -342.774988) (xy 143.948888 -342.797645)
			(xy 143.896559 -342.81301) (xy 143.842577 -342.820773) (xy 143.815308 -342.82126) (xy 142.951708 -342.82126)
			(xy 142.924436 -342.820801) (xy 142.870448 -342.81304) (xy 142.818115 -342.797674) (xy 142.7685 -342.775017)
			(xy 142.722615 -342.745529) (xy 142.681394 -342.709812) (xy 142.645675 -342.668591) (xy 142.616187 -342.622707)
			(xy 142.593529 -342.573093) (xy 142.578162 -342.520759) (xy 142.5704 -342.466772) (xy 141.087573 -342.466772)
			(xy 141.079813 -342.520746) (xy 141.064451 -342.573072) (xy 141.041798 -342.622678) (xy 141.012317 -342.668557)
			(xy 140.976607 -342.709773) (xy 140.935395 -342.745488) (xy 140.88952 -342.774975) (xy 140.839917 -342.797634)
			(xy 140.787593 -342.813003) (xy 140.733615 -342.82077) (xy 140.706348 -342.82126) (xy 139.842748 -342.82126)
			(xy 139.815475 -342.820804) (xy 139.761482 -342.813047) (xy 139.709144 -342.797685) (xy 139.659524 -342.77503)
			(xy 139.613634 -342.745544) (xy 139.572408 -342.709826) (xy 139.536685 -342.668604) (xy 139.507193 -342.622718)
			(xy 139.484532 -342.573101) (xy 139.469163 -342.520765) (xy 139.4614 -342.466773) (xy 137.978696 -342.466773)
			(xy 137.970934 -342.520759) (xy 137.955567 -342.573092) (xy 137.932909 -342.622706) (xy 137.90342 -342.66859)
			(xy 137.867702 -342.70981) (xy 137.82648 -342.745528) (xy 137.780596 -342.775015) (xy 137.730981 -342.797671)
			(xy 137.678647 -342.813037) (xy 137.624659 -342.820797) (xy 137.597388 -342.82126) (xy 136.733788 -342.82126)
			(xy 136.706519 -342.820777) (xy 136.652536 -342.813014) (xy 136.600208 -342.797647) (xy 136.550599 -342.77499)
			(xy 136.50472 -342.745504) (xy 136.463503 -342.709788) (xy 136.427789 -342.668571) (xy 136.398304 -342.62269)
			(xy 136.375649 -342.573081) (xy 136.360284 -342.520752) (xy 136.352522 -342.466769) (xy 134.869674 -342.466769)
			(xy 134.861913 -342.520749) (xy 134.846549 -342.573076) (xy 134.823895 -342.622684) (xy 134.794412 -342.668563)
			(xy 134.7587 -342.70978) (xy 134.717486 -342.745495) (xy 134.671609 -342.774981) (xy 134.622002 -342.797639)
			(xy 134.569676 -342.813007) (xy 134.515696 -342.820772) (xy 134.488428 -342.82126) (xy 133.624828 -342.82126)
			(xy 133.597556 -342.820802) (xy 133.543565 -342.813043) (xy 133.491229 -342.79768) (xy 133.441612 -342.775023)
			(xy 133.395725 -342.745536) (xy 133.354501 -342.709819) (xy 133.31878 -342.668598) (xy 133.28929 -342.622712)
			(xy 133.26663 -342.573097) (xy 133.251262 -342.520762) (xy 133.2435 -342.466772) (xy 131.760796 -342.466772)
			(xy 131.753033 -342.520762) (xy 131.737666 -342.573097) (xy 131.715006 -342.622712) (xy 131.685515 -342.668597)
			(xy 131.649795 -342.709817) (xy 131.608571 -342.745535) (xy 131.562684 -342.775021) (xy 131.513067 -342.797677)
			(xy 131.46073 -342.81304) (xy 131.40674 -342.820799) (xy 131.379468 -342.82126) (xy 130.515868 -342.82126)
			(xy 130.4886 -342.820775) (xy 130.43462 -342.81301) (xy 130.382294 -342.797642) (xy 130.332687 -342.774984)
			(xy 130.28681 -342.745497) (xy 130.245596 -342.709781) (xy 130.209884 -342.668564) (xy 130.180401 -342.622685)
			(xy 130.157747 -342.573076) (xy 130.142383 -342.520749) (xy 130.134622 -342.466768) (xy 128.651774 -342.466768)
			(xy 128.651774 -342.466769) (xy 128.644012 -342.520751) (xy 128.628647 -342.57308) (xy 128.605992 -342.622689)
			(xy 128.576507 -342.66857) (xy 128.540793 -342.709787) (xy 128.499576 -342.745502) (xy 128.453697 -342.774988)
			(xy 128.404088 -342.797645) (xy 128.351759 -342.81301) (xy 128.297777 -342.820773) (xy 128.270508 -342.82126)
			(xy 127.406908 -342.82126) (xy 127.379636 -342.820801) (xy 127.325648 -342.81304) (xy 127.273315 -342.797674)
			(xy 127.2237 -342.775017) (xy 127.177815 -342.745529) (xy 127.136594 -342.709812) (xy 127.100875 -342.668591)
			(xy 127.071387 -342.622707) (xy 127.048729 -342.573093) (xy 127.033362 -342.520759) (xy 127.0256 -342.466772)
			(xy 125.542773 -342.466772) (xy 125.535013 -342.520746) (xy 125.519651 -342.573072) (xy 125.496998 -342.622678)
			(xy 125.467517 -342.668557) (xy 125.431807 -342.709773) (xy 125.390595 -342.745488) (xy 125.34472 -342.774975)
			(xy 125.295117 -342.797634) (xy 125.242793 -342.813003) (xy 125.188815 -342.82077) (xy 125.161548 -342.82126)
			(xy 124.297948 -342.82126) (xy 124.270675 -342.820804) (xy 124.216682 -342.813047) (xy 124.164344 -342.797685)
			(xy 124.114724 -342.77503) (xy 124.068834 -342.745544) (xy 124.027608 -342.709826) (xy 123.991885 -342.668604)
			(xy 123.962393 -342.622718) (xy 123.939732 -342.573101) (xy 123.924363 -342.520765) (xy 123.9166 -342.466773)
			(xy 122.433896 -342.466773) (xy 122.426134 -342.520759) (xy 122.410767 -342.573092) (xy 122.388109 -342.622706)
			(xy 122.35862 -342.66859) (xy 122.322902 -342.70981) (xy 122.28168 -342.745528) (xy 122.235796 -342.775015)
			(xy 122.186181 -342.797671) (xy 122.133847 -342.813037) (xy 122.079859 -342.820797) (xy 122.052588 -342.82126)
			(xy 121.188988 -342.82126) (xy 121.161719 -342.820777) (xy 121.107736 -342.813014) (xy 121.055408 -342.797647)
			(xy 121.005799 -342.77499) (xy 120.95992 -342.745504) (xy 120.918703 -342.709788) (xy 120.882989 -342.668571)
			(xy 120.853504 -342.62269) (xy 120.830849 -342.573081) (xy 120.815484 -342.520752) (xy 120.807722 -342.466769)
			(xy 119.324874 -342.466769) (xy 119.317113 -342.520749) (xy 119.301749 -342.573076) (xy 119.279095 -342.622684)
			(xy 119.249612 -342.668563) (xy 119.2139 -342.70978) (xy 119.172686 -342.745495) (xy 119.126809 -342.774981)
			(xy 119.077202 -342.797639) (xy 119.024876 -342.813007) (xy 118.970896 -342.820772) (xy 118.943628 -342.82126)
			(xy 118.080028 -342.82126) (xy 118.052756 -342.820802) (xy 117.998765 -342.813043) (xy 117.946429 -342.79768)
			(xy 117.896812 -342.775023) (xy 117.850925 -342.745536) (xy 117.809701 -342.709819) (xy 117.77398 -342.668598)
			(xy 117.74449 -342.622712) (xy 117.72183 -342.573097) (xy 117.706462 -342.520762) (xy 117.6987 -342.466772)
			(xy 116.215996 -342.466772) (xy 116.208233 -342.520762) (xy 116.192866 -342.573097) (xy 116.170206 -342.622712)
			(xy 116.140715 -342.668597) (xy 116.104995 -342.709817) (xy 116.063771 -342.745535) (xy 116.017884 -342.775021)
			(xy 115.968267 -342.797677) (xy 115.91593 -342.81304) (xy 115.86194 -342.820799) (xy 115.834668 -342.82126)
			(xy 114.971068 -342.82126) (xy 114.9438 -342.820775) (xy 114.88982 -342.81301) (xy 114.837494 -342.797642)
			(xy 114.787887 -342.774984) (xy 114.74201 -342.745497) (xy 114.700796 -342.709781) (xy 114.665084 -342.668564)
			(xy 114.635601 -342.622685) (xy 114.612947 -342.573076) (xy 114.597583 -342.520749) (xy 114.589822 -342.466768)
			(xy 113.106974 -342.466768) (xy 113.106974 -342.466769) (xy 113.099212 -342.520751) (xy 113.083847 -342.57308)
			(xy 113.061192 -342.622689) (xy 113.031707 -342.66857) (xy 112.995993 -342.709787) (xy 112.954776 -342.745502)
			(xy 112.908897 -342.774988) (xy 112.859288 -342.797645) (xy 112.806959 -342.81301) (xy 112.752977 -342.820773)
			(xy 112.725708 -342.82126) (xy 111.862108 -342.82126) (xy 111.834836 -342.820801) (xy 111.780848 -342.81304)
			(xy 111.728515 -342.797674) (xy 111.6789 -342.775017) (xy 111.633015 -342.745529) (xy 111.591794 -342.709812)
			(xy 111.556075 -342.668591) (xy 111.526587 -342.622707) (xy 111.503929 -342.573093) (xy 111.488562 -342.520759)
			(xy 111.4808 -342.466772) (xy 104.085479 -342.466772) (xy 104.10629 -342.517011) (xy 104.121803 -342.574906)
			(xy 104.129627 -342.634331) (xy 104.129627 -342.694269) (xy 104.121803 -342.753694) (xy 104.10629 -342.811589)
			(xy 104.083352 -342.866964) (xy 104.053383 -342.918871) (xy 104.016895 -342.966422) (xy 103.974512 -343.008804)
			(xy 103.926959 -343.045291) (xy 103.875051 -343.075259) (xy 103.819676 -343.098195) (xy 103.76178 -343.113706)
			(xy 103.702355 -343.121528) (xy 103.672386 -343.121996) (xy 102.808786 -343.121996) (xy 102.778818 -343.121529)
			(xy 102.719395 -343.113704) (xy 102.661502 -343.09819) (xy 102.60613 -343.075253) (xy 102.554224 -343.045284)
			(xy 102.506675 -343.008796) (xy 102.464294 -342.966415) (xy 102.427809 -342.918864) (xy 102.397841 -342.866958)
			(xy 102.374905 -342.811584) (xy 102.359393 -342.753691) (xy 102.35157 -342.694268) (xy 93.60914 -342.694268)
			(xy 93.595705 -342.709775) (xy 93.554492 -342.74549) (xy 93.508617 -342.774977) (xy 93.459012 -342.797635)
			(xy 93.406688 -342.813004) (xy 93.352709 -342.820771) (xy 93.325442 -342.82126) (xy 92.461842 -342.82126)
			(xy 92.434569 -342.820803) (xy 92.380577 -342.813046) (xy 92.328239 -342.797683) (xy 92.278621 -342.775028)
			(xy 92.232731 -342.745541) (xy 92.191506 -342.709824) (xy 92.155784 -342.668602) (xy 92.126292 -342.622716)
			(xy 92.103631 -342.5731) (xy 92.088263 -342.520764) (xy 92.0805 -342.466773) (xy 90.597796 -342.466773)
			(xy 90.590034 -342.52076) (xy 90.574667 -342.573094) (xy 90.552008 -342.622708) (xy 90.522519 -342.668592)
			(xy 90.4868 -342.709812) (xy 90.445578 -342.74553) (xy 90.399692 -342.775017) (xy 90.350077 -342.797673)
			(xy 90.297742 -342.813038) (xy 90.243754 -342.820798) (xy 90.216482 -342.82126) (xy 89.352882 -342.82126)
			(xy 89.325613 -342.820776) (xy 89.271631 -342.813013) (xy 89.219304 -342.797646) (xy 89.169696 -342.774988)
			(xy 89.123817 -342.745502) (xy 89.082601 -342.709786) (xy 89.046887 -342.668569) (xy 89.017403 -342.622689)
			(xy 88.994748 -342.573079) (xy 88.979384 -342.520751) (xy 88.971622 -342.466769) (xy 87.488774 -342.466769)
			(xy 87.481013 -342.52075) (xy 87.465648 -342.573077) (xy 87.442994 -342.622686) (xy 87.41351 -342.668565)
			(xy 87.377798 -342.709782) (xy 87.336583 -342.745497) (xy 87.290705 -342.774983) (xy 87.241098 -342.797641)
			(xy 87.188771 -342.813008) (xy 87.13479 -342.820772) (xy 87.107522 -342.82126) (xy 86.243922 -342.82126)
			(xy 86.21665 -342.820802) (xy 86.16266 -342.813042) (xy 86.110325 -342.797678) (xy 86.060709 -342.775021)
			(xy 86.014822 -342.745534) (xy 85.973599 -342.709817) (xy 85.937879 -342.668596) (xy 85.908389 -342.622711)
			(xy 85.88573 -342.573096) (xy 85.870362 -342.520761) (xy 85.8626 -342.466772) (xy 84.379896 -342.466772)
			(xy 84.379896 -342.466773) (xy 84.372133 -342.520763) (xy 84.356765 -342.573098) (xy 84.334105 -342.622713)
			(xy 84.304614 -342.668599) (xy 84.268893 -342.70982) (xy 84.227668 -342.745537) (xy 84.18178 -342.775023)
			(xy 84.132162 -342.797679) (xy 84.079825 -342.813041) (xy 84.025835 -342.820799) (xy 83.998562 -342.82126)
			(xy 83.134962 -342.82126) (xy 83.107694 -342.820775) (xy 83.053714 -342.813009) (xy 83.001389 -342.79764)
			(xy 82.951784 -342.774982) (xy 82.905907 -342.745495) (xy 82.864694 -342.709779) (xy 82.828983 -342.668562)
			(xy 82.7995 -342.622683) (xy 82.776847 -342.573075) (xy 82.761483 -342.520748) (xy 82.753722 -342.466768)
			(xy 81.270874 -342.466768) (xy 81.270874 -342.466769) (xy 81.263112 -342.520752) (xy 81.247747 -342.573081)
			(xy 81.225091 -342.622691) (xy 81.195605 -342.668572) (xy 81.159891 -342.709789) (xy 81.118673 -342.745504)
			(xy 81.072793 -342.77499) (xy 81.023183 -342.797646) (xy 80.970854 -342.813012) (xy 80.916871 -342.820773)
			(xy 80.889602 -342.82126) (xy 80.026002 -342.82126) (xy 79.998731 -342.820801) (xy 79.944743 -342.813039)
			(xy 79.89241 -342.797673) (xy 79.842797 -342.775015) (xy 79.796912 -342.745527) (xy 79.755692 -342.70981)
			(xy 79.719974 -342.668589) (xy 79.690486 -342.622705) (xy 79.667828 -342.573092) (xy 79.652462 -342.520759)
			(xy 79.644699 -342.466771) (xy 78.161873 -342.466771) (xy 78.154113 -342.520747) (xy 78.13875 -342.573073)
			(xy 78.116097 -342.62268) (xy 78.086615 -342.668559) (xy 78.050905 -342.709775) (xy 78.009692 -342.74549)
			(xy 77.963817 -342.774977) (xy 77.914212 -342.797635) (xy 77.861888 -342.813004) (xy 77.807909 -342.820771)
			(xy 77.780642 -342.82126) (xy 76.917042 -342.82126) (xy 76.889769 -342.820803) (xy 76.835777 -342.813046)
			(xy 76.783439 -342.797683) (xy 76.733821 -342.775028) (xy 76.687931 -342.745541) (xy 76.646706 -342.709824)
			(xy 76.610984 -342.668602) (xy 76.581492 -342.622716) (xy 76.558831 -342.5731) (xy 76.543463 -342.520764)
			(xy 76.5357 -342.466773) (xy 75.052996 -342.466773) (xy 75.045234 -342.52076) (xy 75.029867 -342.573094)
			(xy 75.007208 -342.622708) (xy 74.977719 -342.668592) (xy 74.942 -342.709812) (xy 74.900778 -342.74553)
			(xy 74.854892 -342.775017) (xy 74.805277 -342.797673) (xy 74.752942 -342.813038) (xy 74.698954 -342.820798)
			(xy 74.671682 -342.82126) (xy 73.808082 -342.82126) (xy 73.780813 -342.820776) (xy 73.726831 -342.813013)
			(xy 73.674504 -342.797646) (xy 73.624896 -342.774988) (xy 73.579017 -342.745502) (xy 73.537801 -342.709786)
			(xy 73.502087 -342.668569) (xy 73.472603 -342.622689) (xy 73.449948 -342.573079) (xy 73.434584 -342.520751)
			(xy 73.426822 -342.466769) (xy 71.943974 -342.466769) (xy 71.936213 -342.52075) (xy 71.920848 -342.573077)
			(xy 71.898194 -342.622686) (xy 71.86871 -342.668565) (xy 71.832998 -342.709782) (xy 71.791783 -342.745497)
			(xy 71.745905 -342.774983) (xy 71.696298 -342.797641) (xy 71.643971 -342.813008) (xy 71.58999 -342.820772)
			(xy 71.562722 -342.82126) (xy 70.699122 -342.82126) (xy 70.67185 -342.820802) (xy 70.61786 -342.813042)
			(xy 70.565525 -342.797678) (xy 70.515909 -342.775021) (xy 70.470022 -342.745534) (xy 70.428799 -342.709817)
			(xy 70.393079 -342.668596) (xy 70.363589 -342.622711) (xy 70.34093 -342.573096) (xy 70.325562 -342.520761)
			(xy 70.3178 -342.466772) (xy 68.835096 -342.466772) (xy 68.835096 -342.466773) (xy 68.827333 -342.520763)
			(xy 68.811965 -342.573098) (xy 68.789305 -342.622713) (xy 68.759814 -342.668599) (xy 68.724093 -342.70982)
			(xy 68.682868 -342.745537) (xy 68.63698 -342.775023) (xy 68.587362 -342.797679) (xy 68.535025 -342.813041)
			(xy 68.481035 -342.820799) (xy 68.453762 -342.82126) (xy 67.590162 -342.82126) (xy 67.562894 -342.820775)
			(xy 67.508914 -342.813009) (xy 67.456589 -342.79764) (xy 67.406984 -342.774982) (xy 67.361107 -342.745495)
			(xy 67.319894 -342.709779) (xy 67.284183 -342.668562) (xy 67.2547 -342.622683) (xy 67.232047 -342.573075)
			(xy 67.216683 -342.520748) (xy 67.208922 -342.466768) (xy 65.726074 -342.466768) (xy 65.726074 -342.466769)
			(xy 65.718312 -342.520752) (xy 65.702947 -342.573081) (xy 65.680291 -342.622691) (xy 65.650805 -342.668572)
			(xy 65.615091 -342.709789) (xy 65.573873 -342.745504) (xy 65.527993 -342.77499) (xy 65.478383 -342.797646)
			(xy 65.426054 -342.813012) (xy 65.372071 -342.820773) (xy 65.344802 -342.82126) (xy 64.481202 -342.82126)
			(xy 64.453931 -342.820801) (xy 64.399943 -342.813039) (xy 64.34761 -342.797673) (xy 64.297997 -342.775015)
			(xy 64.252112 -342.745527) (xy 64.210892 -342.70981) (xy 64.175174 -342.668589) (xy 64.145686 -342.622705)
			(xy 64.123028 -342.573092) (xy 64.107662 -342.520759) (xy 64.099899 -342.466771) (xy 62.617073 -342.466771)
			(xy 62.609313 -342.520747) (xy 62.59395 -342.573073) (xy 62.571297 -342.62268) (xy 62.541815 -342.668559)
			(xy 62.506105 -342.709775) (xy 62.464892 -342.74549) (xy 62.419017 -342.774977) (xy 62.369412 -342.797635)
			(xy 62.317088 -342.813004) (xy 62.263109 -342.820771) (xy 62.235842 -342.82126) (xy 61.372242 -342.82126)
			(xy 61.344969 -342.820803) (xy 61.290977 -342.813046) (xy 61.238639 -342.797683) (xy 61.189021 -342.775028)
			(xy 61.143131 -342.745541) (xy 61.101906 -342.709824) (xy 61.066184 -342.668602) (xy 61.036692 -342.622716)
			(xy 61.014031 -342.5731) (xy 60.998663 -342.520764) (xy 60.9909 -342.466773) (xy 51.666873 -342.466773)
			(xy 51.659113 -342.520746) (xy 51.643751 -342.573072) (xy 51.621098 -342.622678) (xy 51.591617 -342.668557)
			(xy 51.555907 -342.709773) (xy 51.514695 -342.745488) (xy 51.46882 -342.774975) (xy 51.419217 -342.797634)
			(xy 51.366893 -342.813003) (xy 51.312915 -342.82077) (xy 51.285648 -342.82126) (xy 50.422048 -342.82126)
			(xy 50.394775 -342.820804) (xy 50.340782 -342.813047) (xy 50.288444 -342.797685) (xy 50.238824 -342.77503)
			(xy 50.192934 -342.745544) (xy 50.151708 -342.709826) (xy 50.115985 -342.668604) (xy 50.086493 -342.622718)
			(xy 50.063832 -342.573101) (xy 50.048463 -342.520765) (xy 50.0407 -342.466773) (xy 48.557996 -342.466773)
			(xy 48.550234 -342.520759) (xy 48.534867 -342.573092) (xy 48.512209 -342.622706) (xy 48.48272 -342.66859)
			(xy 48.447002 -342.70981) (xy 48.40578 -342.745528) (xy 48.359896 -342.775015) (xy 48.310281 -342.797671)
			(xy 48.257947 -342.813037) (xy 48.203959 -342.820797) (xy 48.176688 -342.82126) (xy 47.313088 -342.82126)
			(xy 47.285819 -342.820777) (xy 47.231836 -342.813014) (xy 47.179508 -342.797647) (xy 47.129899 -342.77499)
			(xy 47.08402 -342.745504) (xy 47.042803 -342.709788) (xy 47.007089 -342.668571) (xy 46.977604 -342.62269)
			(xy 46.954949 -342.573081) (xy 46.939584 -342.520752) (xy 46.931822 -342.466769) (xy 45.448974 -342.466769)
			(xy 45.441213 -342.520749) (xy 45.425849 -342.573076) (xy 45.403195 -342.622684) (xy 45.373712 -342.668563)
			(xy 45.338 -342.70978) (xy 45.296786 -342.745495) (xy 45.250909 -342.774981) (xy 45.201302 -342.797639)
			(xy 45.148976 -342.813007) (xy 45.094996 -342.820772) (xy 45.067728 -342.82126) (xy 44.204128 -342.82126)
			(xy 44.176856 -342.820802) (xy 44.122865 -342.813043) (xy 44.070529 -342.79768) (xy 44.020912 -342.775023)
			(xy 43.975025 -342.745536) (xy 43.933801 -342.709819) (xy 43.89808 -342.668598) (xy 43.86859 -342.622712)
			(xy 43.84593 -342.573097) (xy 43.830562 -342.520762) (xy 43.8228 -342.466772) (xy 42.340096 -342.466772)
			(xy 42.332333 -342.520762) (xy 42.316966 -342.573097) (xy 42.294306 -342.622712) (xy 42.264815 -342.668597)
			(xy 42.229095 -342.709817) (xy 42.187871 -342.745535) (xy 42.141984 -342.775021) (xy 42.092367 -342.797677)
			(xy 42.04003 -342.81304) (xy 41.98604 -342.820799) (xy 41.958768 -342.82126) (xy 41.095168 -342.82126)
			(xy 41.0679 -342.820775) (xy 41.01392 -342.81301) (xy 40.961594 -342.797642) (xy 40.911987 -342.774984)
			(xy 40.86611 -342.745497) (xy 40.824896 -342.709781) (xy 40.789184 -342.668564) (xy 40.759701 -342.622685)
			(xy 40.737047 -342.573076) (xy 40.721683 -342.520749) (xy 40.713922 -342.466768) (xy 39.231074 -342.466768)
			(xy 39.231074 -342.466769) (xy 39.223312 -342.520751) (xy 39.207947 -342.57308) (xy 39.185292 -342.622689)
			(xy 39.155807 -342.66857) (xy 39.120093 -342.709787) (xy 39.078876 -342.745502) (xy 39.032997 -342.774988)
			(xy 38.983388 -342.797645) (xy 38.931059 -342.81301) (xy 38.877077 -342.820773) (xy 38.849808 -342.82126)
			(xy 37.986208 -342.82126) (xy 37.958936 -342.820801) (xy 37.904948 -342.81304) (xy 37.852615 -342.797674)
			(xy 37.803 -342.775017) (xy 37.757115 -342.745529) (xy 37.715894 -342.709812) (xy 37.680175 -342.668591)
			(xy 37.650687 -342.622707) (xy 37.628029 -342.573093) (xy 37.612662 -342.520759) (xy 37.6049 -342.466772)
			(xy 36.122073 -342.466772) (xy 36.114313 -342.520746) (xy 36.098951 -342.573072) (xy 36.076298 -342.622678)
			(xy 36.046817 -342.668557) (xy 36.011107 -342.709773) (xy 35.969895 -342.745488) (xy 35.92402 -342.774975)
			(xy 35.874417 -342.797634) (xy 35.822093 -342.813003) (xy 35.768115 -342.82077) (xy 35.740848 -342.82126)
			(xy 34.877248 -342.82126) (xy 34.849975 -342.820804) (xy 34.795982 -342.813047) (xy 34.743644 -342.797685)
			(xy 34.694024 -342.77503) (xy 34.648134 -342.745544) (xy 34.606908 -342.709826) (xy 34.571185 -342.668604)
			(xy 34.541693 -342.622718) (xy 34.519032 -342.573101) (xy 34.503663 -342.520765) (xy 34.4959 -342.466773)
			(xy 33.013196 -342.466773) (xy 33.005434 -342.520759) (xy 32.990067 -342.573092) (xy 32.967409 -342.622706)
			(xy 32.93792 -342.66859) (xy 32.902202 -342.70981) (xy 32.86098 -342.745528) (xy 32.815096 -342.775015)
			(xy 32.765481 -342.797671) (xy 32.713147 -342.813037) (xy 32.659159 -342.820797) (xy 32.631888 -342.82126)
			(xy 31.768288 -342.82126) (xy 31.741019 -342.820777) (xy 31.687036 -342.813014) (xy 31.634708 -342.797647)
			(xy 31.585099 -342.77499) (xy 31.53922 -342.745504) (xy 31.498003 -342.709788) (xy 31.462289 -342.668571)
			(xy 31.432804 -342.62269) (xy 31.410149 -342.573081) (xy 31.394784 -342.520752) (xy 31.387022 -342.466769)
			(xy 29.904174 -342.466769) (xy 29.896413 -342.520749) (xy 29.881049 -342.573076) (xy 29.858395 -342.622684)
			(xy 29.828912 -342.668563) (xy 29.7932 -342.70978) (xy 29.751986 -342.745495) (xy 29.706109 -342.774981)
			(xy 29.656502 -342.797639) (xy 29.604176 -342.813007) (xy 29.550196 -342.820772) (xy 29.522928 -342.82126)
			(xy 28.659328 -342.82126) (xy 28.632056 -342.820802) (xy 28.578065 -342.813043) (xy 28.525729 -342.79768)
			(xy 28.476112 -342.775023) (xy 28.430225 -342.745536) (xy 28.389001 -342.709819) (xy 28.35328 -342.668598)
			(xy 28.32379 -342.622712) (xy 28.30113 -342.573097) (xy 28.285762 -342.520762) (xy 28.278 -342.466772)
			(xy 26.795296 -342.466772) (xy 26.787533 -342.520762) (xy 26.772166 -342.573097) (xy 26.749506 -342.622712)
			(xy 26.720015 -342.668597) (xy 26.684295 -342.709817) (xy 26.643071 -342.745535) (xy 26.597184 -342.775021)
			(xy 26.547567 -342.797677) (xy 26.49523 -342.81304) (xy 26.44124 -342.820799) (xy 26.413968 -342.82126)
			(xy 25.550368 -342.82126) (xy 25.5231 -342.820775) (xy 25.46912 -342.81301) (xy 25.416794 -342.797642)
			(xy 25.367187 -342.774984) (xy 25.32131 -342.745497) (xy 25.280096 -342.709781) (xy 25.244384 -342.668564)
			(xy 25.214901 -342.622685) (xy 25.192247 -342.573076) (xy 25.176883 -342.520749) (xy 25.169122 -342.466768)
			(xy 23.686274 -342.466768) (xy 23.686274 -342.466769) (xy 23.678512 -342.520751) (xy 23.663147 -342.57308)
			(xy 23.640492 -342.622689) (xy 23.611007 -342.66857) (xy 23.575293 -342.709787) (xy 23.534076 -342.745502)
			(xy 23.488197 -342.774988) (xy 23.438588 -342.797645) (xy 23.386259 -342.81301) (xy 23.332277 -342.820773)
			(xy 23.305008 -342.82126) (xy 22.441408 -342.82126) (xy 22.414136 -342.820801) (xy 22.360148 -342.81304)
			(xy 22.307815 -342.797674) (xy 22.2582 -342.775017) (xy 22.212315 -342.745529) (xy 22.171094 -342.709812)
			(xy 22.135375 -342.668591) (xy 22.105887 -342.622707) (xy 22.083229 -342.573093) (xy 22.067862 -342.520759)
			(xy 22.0601 -342.466772) (xy 20.577347 -342.466772) (xy 20.569584 -342.520758) (xy 20.554218 -342.57309)
			(xy 20.53156 -342.622703) (xy 20.502073 -342.668587) (xy 20.466355 -342.709807) (xy 20.425135 -342.745524)
			(xy 20.379252 -342.775011) (xy 20.329638 -342.797669) (xy 20.277306 -342.813035) (xy 20.223319 -342.820797)
			(xy 20.196048 -342.82126) (xy 19.332448 -342.82126) (xy 19.305179 -342.820777) (xy 19.251195 -342.813015)
			(xy 19.198865 -342.79765) (xy 19.149255 -342.774993) (xy 19.103374 -342.745507) (xy 19.062157 -342.709792)
			(xy 19.026441 -342.668574) (xy 18.996956 -342.622693) (xy 18.974299 -342.573083) (xy 18.958934 -342.520753)
			(xy 18.951172 -342.466769) (xy 0.508 -342.466769) (xy 0.508 -345.49242) (xy 18.95117 -345.49242)
			(xy 18.95117 -345.43788) (xy 18.958932 -345.383896) (xy 18.974298 -345.331567) (xy 18.996954 -345.281956)
			(xy 19.02644 -345.236075) (xy 19.062155 -345.194857) (xy 19.103373 -345.159141) (xy 19.149254 -345.129655)
			(xy 19.198865 -345.106998) (xy 19.251194 -345.091633) (xy 19.305178 -345.083871) (xy 19.332448 -345.083384)
			(xy 20.196048 -345.083384) (xy 20.223319 -345.083855) (xy 20.277305 -345.091617) (xy 20.329638 -345.106983)
			(xy 20.379251 -345.12964) (xy 20.425134 -345.159128) (xy 20.466354 -345.194845) (xy 20.502071 -345.236064)
			(xy 20.531559 -345.281948) (xy 20.554216 -345.33156) (xy 20.569582 -345.383893) (xy 20.577345 -345.437879)
			(xy 20.577345 -345.49242) (xy 22.06013 -345.49242) (xy 22.06013 -345.43788) (xy 22.067892 -345.383896)
			(xy 22.083258 -345.331567) (xy 22.105914 -345.281956) (xy 22.1354 -345.236075) (xy 22.171115 -345.194857)
			(xy 22.212333 -345.159141) (xy 22.258214 -345.129655) (xy 22.307825 -345.106998) (xy 22.360154 -345.091633)
			(xy 22.414138 -345.083871) (xy 22.441408 -345.083384) (xy 23.305008 -345.083384) (xy 23.332279 -345.083855)
			(xy 23.386265 -345.091617) (xy 23.438598 -345.106983) (xy 23.488211 -345.12964) (xy 23.534094 -345.159128)
			(xy 23.575314 -345.194845) (xy 23.611031 -345.236064) (xy 23.640519 -345.281948) (xy 23.663176 -345.33156)
			(xy 23.678542 -345.383893) (xy 23.686305 -345.437879) (xy 23.686305 -345.492365) (xy 25.16917 -345.492365)
			(xy 25.16917 -345.437835) (xy 25.17693 -345.383861) (xy 25.192292 -345.33154) (xy 25.214943 -345.281938)
			(xy 25.244422 -345.236064) (xy 25.28013 -345.194853) (xy 25.321339 -345.159142) (xy 25.36721 -345.129658)
			(xy 25.41681 -345.107003) (xy 25.46913 -345.091637) (xy 25.523103 -345.083872) (xy 25.550368 -345.083384)
			(xy 26.413968 -345.083384) (xy 26.441244 -345.083753) (xy 26.495241 -345.091513) (xy 26.547583 -345.106878)
			(xy 26.597207 -345.129537) (xy 26.6431 -345.159027) (xy 26.684329 -345.194749) (xy 26.720054 -345.235975)
			(xy 26.749548 -345.281865) (xy 26.772211 -345.331487) (xy 26.78758 -345.383828) (xy 26.795344 -345.437824)
			(xy 26.795344 -345.492369) (xy 28.278047 -345.492369) (xy 28.278047 -345.437831) (xy 28.285809 -345.383848)
			(xy 28.301175 -345.33152) (xy 28.323832 -345.281911) (xy 28.353319 -345.236031) (xy 28.389035 -345.194815)
			(xy 28.430253 -345.159102) (xy 28.476135 -345.129619) (xy 28.525746 -345.106965) (xy 28.578076 -345.091603)
			(xy 28.632059 -345.083845) (xy 28.659328 -345.083384) (xy 29.522928 -345.083384) (xy 29.550199 -345.08378)
			(xy 29.604186 -345.091546) (xy 29.656519 -345.106916) (xy 29.706132 -345.129576) (xy 29.752014 -345.159067)
			(xy 29.793234 -345.194786) (xy 29.82895 -345.236008) (xy 29.858437 -345.281893) (xy 29.881094 -345.331507)
			(xy 29.89646 -345.383841) (xy 29.904222 -345.437829) (xy 29.904222 -345.492366) (xy 31.38707 -345.492366)
			(xy 31.38707 -345.437834) (xy 31.394831 -345.383858) (xy 31.410194 -345.331536) (xy 31.432846 -345.281933)
			(xy 31.462327 -345.236058) (xy 31.498037 -345.194846) (xy 31.539248 -345.159135) (xy 31.585122 -345.129652)
			(xy 31.634725 -345.106998) (xy 31.687047 -345.091633) (xy 31.741022 -345.083871) (xy 31.768288 -345.083384)
			(xy 32.631888 -345.083384) (xy 32.659163 -345.083755) (xy 32.713157 -345.091516) (xy 32.765498 -345.106884)
			(xy 32.815119 -345.129543) (xy 32.861009 -345.159034) (xy 32.902236 -345.194756) (xy 32.937959 -345.235981)
			(xy 32.967451 -345.281871) (xy 32.990112 -345.331491) (xy 33.005481 -345.383831) (xy 33.013244 -345.437825)
			(xy 33.013244 -345.49237) (xy 34.495948 -345.49237) (xy 34.495948 -345.43783) (xy 34.50371 -345.383846)
			(xy 34.519077 -345.331515) (xy 34.541735 -345.281905) (xy 34.571224 -345.236024) (xy 34.606942 -345.194808)
			(xy 34.648163 -345.159095) (xy 34.694047 -345.129612) (xy 34.74366 -345.10696) (xy 34.795992 -345.0916)
			(xy 34.849978 -345.083844) (xy 34.877248 -345.083384) (xy 35.740848 -345.083384) (xy 35.768118 -345.083782)
			(xy 35.822103 -345.09155) (xy 35.874433 -345.106921) (xy 35.924044 -345.129583) (xy 35.969924 -345.159074)
			(xy 36.011141 -345.194793) (xy 36.046855 -345.236015) (xy 36.07634 -345.281899) (xy 36.098995 -345.331512)
			(xy 36.11436 -345.383844) (xy 36.122122 -345.43783) (xy 36.122122 -345.492368) (xy 37.604947 -345.492368)
			(xy 37.604947 -345.437832) (xy 37.612709 -345.383851) (xy 37.628074 -345.331524) (xy 37.650729 -345.281916)
			(xy 37.680214 -345.236038) (xy 37.715928 -345.194822) (xy 37.757144 -345.159109) (xy 37.803023 -345.129625)
			(xy 37.852631 -345.106971) (xy 37.904959 -345.091607) (xy 37.95894 -345.083847) (xy 37.986208 -345.083384)
			(xy 38.849808 -345.083384) (xy 38.87708 -345.083779) (xy 38.93107 -345.091543) (xy 38.983404 -345.106911)
			(xy 39.03302 -345.12957) (xy 39.078905 -345.15906) (xy 39.120127 -345.194779) (xy 39.155845 -345.236001)
			(xy 39.185334 -345.281888) (xy 39.207992 -345.331503) (xy 39.223359 -345.383838) (xy 39.231121 -345.437828)
			(xy 39.231121 -345.492365) (xy 40.71397 -345.492365) (xy 40.71397 -345.437835) (xy 40.72173 -345.383861)
			(xy 40.737092 -345.33154) (xy 40.759743 -345.281938) (xy 40.789222 -345.236064) (xy 40.82493 -345.194853)
			(xy 40.866139 -345.159142) (xy 40.91201 -345.129658) (xy 40.96161 -345.107003) (xy 41.01393 -345.091637)
			(xy 41.067903 -345.083872) (xy 41.095168 -345.083384) (xy 41.958768 -345.083384) (xy 41.986044 -345.083753)
			(xy 42.040041 -345.091513) (xy 42.092383 -345.106878) (xy 42.142007 -345.129537) (xy 42.1879 -345.159027)
			(xy 42.229129 -345.194749) (xy 42.264854 -345.235975) (xy 42.294348 -345.281865) (xy 42.317011 -345.331487)
			(xy 42.33238 -345.383828) (xy 42.340144 -345.437824) (xy 42.340144 -345.492369) (xy 43.822847 -345.492369)
			(xy 43.822847 -345.437831) (xy 43.830609 -345.383848) (xy 43.845975 -345.33152) (xy 43.868632 -345.281911)
			(xy 43.898119 -345.236031) (xy 43.933835 -345.194815) (xy 43.975053 -345.159102) (xy 44.020935 -345.129619)
			(xy 44.070546 -345.106965) (xy 44.122876 -345.091603) (xy 44.176859 -345.083845) (xy 44.204128 -345.083384)
			(xy 45.067728 -345.083384) (xy 45.094999 -345.08378) (xy 45.148986 -345.091546) (xy 45.201319 -345.106916)
			(xy 45.250932 -345.129576) (xy 45.296814 -345.159067) (xy 45.338034 -345.194786) (xy 45.37375 -345.236008)
			(xy 45.403237 -345.281893) (xy 45.425894 -345.331507) (xy 45.44126 -345.383841) (xy 45.449022 -345.437829)
			(xy 45.449022 -345.492366) (xy 46.93187 -345.492366) (xy 46.93187 -345.437834) (xy 46.939631 -345.383858)
			(xy 46.954994 -345.331536) (xy 46.977646 -345.281933) (xy 47.007127 -345.236058) (xy 47.042837 -345.194846)
			(xy 47.084048 -345.159135) (xy 47.129922 -345.129652) (xy 47.179525 -345.106998) (xy 47.231847 -345.091633)
			(xy 47.285822 -345.083871) (xy 47.313088 -345.083384) (xy 48.176688 -345.083384) (xy 48.203963 -345.083755)
			(xy 48.257957 -345.091516) (xy 48.310298 -345.106884) (xy 48.359919 -345.129543) (xy 48.405809 -345.159034)
			(xy 48.447036 -345.194756) (xy 48.482759 -345.235981) (xy 48.512251 -345.281871) (xy 48.534912 -345.331491)
			(xy 48.550281 -345.383831) (xy 48.558044 -345.437825) (xy 48.558044 -345.49237) (xy 50.040748 -345.49237)
			(xy 50.040748 -345.43783) (xy 50.04851 -345.383846) (xy 50.063877 -345.331515) (xy 50.086535 -345.281905)
			(xy 50.116024 -345.236024) (xy 50.151742 -345.194808) (xy 50.192963 -345.159095) (xy 50.238847 -345.129612)
			(xy 50.28846 -345.10696) (xy 50.340792 -345.0916) (xy 50.394778 -345.083844) (xy 50.422048 -345.083384)
			(xy 51.285648 -345.083384) (xy 51.312918 -345.083782) (xy 51.366903 -345.09155) (xy 51.419233 -345.106921)
			(xy 51.468844 -345.129583) (xy 51.514724 -345.159074) (xy 51.555941 -345.194793) (xy 51.591655 -345.236015)
			(xy 51.62114 -345.281899) (xy 51.643795 -345.331512) (xy 51.65916 -345.383844) (xy 51.666922 -345.43783)
			(xy 51.666922 -345.49237) (xy 60.990948 -345.49237) (xy 60.990948 -345.43783) (xy 60.99871 -345.383846)
			(xy 61.014076 -345.331517) (xy 61.036734 -345.281907) (xy 61.066222 -345.236026) (xy 61.10194 -345.19481)
			(xy 61.14316 -345.159097) (xy 61.189044 -345.129614) (xy 61.238656 -345.106962) (xy 61.290987 -345.091601)
			(xy 61.344972 -345.083845) (xy 61.372242 -345.083384) (xy 62.235842 -345.083384) (xy 62.263113 -345.083781)
			(xy 62.317098 -345.091549) (xy 62.369429 -345.10692) (xy 62.41904 -345.129581) (xy 62.464921 -345.159072)
			(xy 62.506139 -345.194791) (xy 62.541854 -345.236013) (xy 62.571339 -345.281897) (xy 62.593995 -345.33151)
			(xy 62.60936 -345.383843) (xy 62.617122 -345.437829) (xy 62.617122 -345.492368) (xy 64.099947 -345.492368)
			(xy 64.099947 -345.437832) (xy 64.107709 -345.383852) (xy 64.123073 -345.331525) (xy 64.145728 -345.281918)
			(xy 64.175212 -345.23604) (xy 64.210926 -345.194824) (xy 64.252141 -345.159111) (xy 64.29802 -345.129627)
			(xy 64.347627 -345.106972) (xy 64.399954 -345.091608) (xy 64.453934 -345.083847) (xy 64.481202 -345.083384)
			(xy 65.344802 -345.083384) (xy 65.372075 -345.083779) (xy 65.426064 -345.091542) (xy 65.4784 -345.106909)
			(xy 65.528016 -345.129568) (xy 65.573902 -345.159057) (xy 65.615124 -345.194777) (xy 65.650844 -345.236)
			(xy 65.680333 -345.281886) (xy 65.702992 -345.331502) (xy 65.718359 -345.383838) (xy 65.726121 -345.437827)
			(xy 65.726121 -345.492364) (xy 67.20897 -345.492364) (xy 67.20897 -345.437836) (xy 67.21673 -345.383862)
			(xy 67.232092 -345.331542) (xy 67.254742 -345.28194) (xy 67.284221 -345.236066) (xy 67.319928 -345.194855)
			(xy 67.361136 -345.159144) (xy 67.407007 -345.12966) (xy 67.456606 -345.107005) (xy 67.508925 -345.091638)
			(xy 67.562898 -345.083873) (xy 67.590162 -345.083384) (xy 68.453762 -345.083384) (xy 68.481038 -345.083753)
			(xy 68.535036 -345.091512) (xy 68.587379 -345.106877) (xy 68.637003 -345.129535) (xy 68.682897 -345.159025)
			(xy 68.724127 -345.194747) (xy 68.759852 -345.235973) (xy 68.789347 -345.281864) (xy 68.81201 -345.331485)
			(xy 68.82738 -345.383827) (xy 68.835144 -345.437824) (xy 68.835144 -345.492369) (xy 70.317847 -345.492369)
			(xy 70.317847 -345.437831) (xy 70.325609 -345.383849) (xy 70.340975 -345.331521) (xy 70.363631 -345.281912)
			(xy 70.393117 -345.236033) (xy 70.428833 -345.194817) (xy 70.470051 -345.159104) (xy 70.515932 -345.129621)
			(xy 70.565541 -345.106967) (xy 70.617871 -345.091605) (xy 70.671853 -345.083846) (xy 70.699122 -345.083384)
			(xy 71.562722 -345.083384) (xy 71.589994 -345.08378) (xy 71.643981 -345.091545) (xy 71.696315 -345.106914)
			(xy 71.745928 -345.129574) (xy 71.791812 -345.159064) (xy 71.833032 -345.194784) (xy 71.868749 -345.236006)
			(xy 71.898236 -345.281891) (xy 71.920893 -345.331506) (xy 71.936259 -345.38384) (xy 71.944022 -345.437828)
			(xy 71.944022 -345.492365) (xy 73.42687 -345.492365) (xy 73.42687 -345.437835) (xy 73.434631 -345.383859)
			(xy 73.449993 -345.331537) (xy 73.472645 -345.281934) (xy 73.502126 -345.23606) (xy 73.537835 -345.194848)
			(xy 73.579045 -345.159137) (xy 73.624919 -345.129654) (xy 73.674521 -345.106999) (xy 73.726842 -345.091634)
			(xy 73.780817 -345.083872) (xy 73.808082 -345.083384) (xy 74.671682 -345.083384) (xy 74.698957 -345.083754)
			(xy 74.752952 -345.091515) (xy 74.805294 -345.106882) (xy 74.854915 -345.129541) (xy 74.900806 -345.159032)
			(xy 74.942034 -345.194754) (xy 74.977757 -345.235979) (xy 75.00725 -345.281869) (xy 75.029912 -345.33149)
			(xy 75.045281 -345.38383) (xy 75.053044 -345.437825) (xy 75.053044 -345.49237) (xy 76.535748 -345.49237)
			(xy 76.535748 -345.43783) (xy 76.54351 -345.383846) (xy 76.558876 -345.331517) (xy 76.581534 -345.281907)
			(xy 76.611022 -345.236026) (xy 76.64674 -345.19481) (xy 76.68796 -345.159097) (xy 76.733844 -345.129614)
			(xy 76.783456 -345.106962) (xy 76.835787 -345.091601) (xy 76.889772 -345.083845) (xy 76.917042 -345.083384)
			(xy 77.780642 -345.083384) (xy 77.807913 -345.083781) (xy 77.861898 -345.091549) (xy 77.914229 -345.10692)
			(xy 77.96384 -345.129581) (xy 78.009721 -345.159072) (xy 78.050939 -345.194791) (xy 78.086654 -345.236013)
			(xy 78.116139 -345.281897) (xy 78.138795 -345.33151) (xy 78.15416 -345.383843) (xy 78.161922 -345.437829)
			(xy 78.161922 -345.492368) (xy 79.644747 -345.492368) (xy 79.644747 -345.437832) (xy 79.652509 -345.383852)
			(xy 79.667873 -345.331525) (xy 79.690528 -345.281918) (xy 79.720012 -345.23604) (xy 79.755726 -345.194824)
			(xy 79.796941 -345.159111) (xy 79.84282 -345.129627) (xy 79.892427 -345.106972) (xy 79.944754 -345.091608)
			(xy 79.998734 -345.083847) (xy 80.026002 -345.083384) (xy 80.889602 -345.083384) (xy 80.916875 -345.083779)
			(xy 80.970864 -345.091542) (xy 81.0232 -345.106909) (xy 81.072816 -345.129568) (xy 81.118702 -345.159057)
			(xy 81.159924 -345.194777) (xy 81.195644 -345.236) (xy 81.225133 -345.281886) (xy 81.247792 -345.331502)
			(xy 81.263159 -345.383838) (xy 81.270921 -345.437827) (xy 81.270921 -345.492364) (xy 82.75377 -345.492364)
			(xy 82.75377 -345.437836) (xy 82.76153 -345.383862) (xy 82.776892 -345.331542) (xy 82.799542 -345.28194)
			(xy 82.829021 -345.236066) (xy 82.864728 -345.194855) (xy 82.905936 -345.159144) (xy 82.951807 -345.12966)
			(xy 83.001406 -345.107005) (xy 83.053725 -345.091638) (xy 83.107698 -345.083873) (xy 83.134962 -345.083384)
			(xy 83.998562 -345.083384) (xy 84.025838 -345.083753) (xy 84.079836 -345.091512) (xy 84.132179 -345.106877)
			(xy 84.181803 -345.129535) (xy 84.227697 -345.159025) (xy 84.268927 -345.194747) (xy 84.304652 -345.235973)
			(xy 84.334147 -345.281864) (xy 84.35681 -345.331485) (xy 84.37218 -345.383827) (xy 84.379944 -345.437824)
			(xy 84.379944 -345.492369) (xy 85.862647 -345.492369) (xy 85.862647 -345.437831) (xy 85.870409 -345.383849)
			(xy 85.885775 -345.331521) (xy 85.908431 -345.281912) (xy 85.937917 -345.236033) (xy 85.973633 -345.194817)
			(xy 86.014851 -345.159104) (xy 86.060732 -345.129621) (xy 86.110341 -345.106967) (xy 86.162671 -345.091605)
			(xy 86.216653 -345.083846) (xy 86.243922 -345.083384) (xy 87.107522 -345.083384) (xy 87.134794 -345.08378)
			(xy 87.188781 -345.091545) (xy 87.241115 -345.106914) (xy 87.290728 -345.129574) (xy 87.336612 -345.159064)
			(xy 87.377832 -345.194784) (xy 87.413549 -345.236006) (xy 87.443036 -345.281891) (xy 87.465693 -345.331506)
			(xy 87.481059 -345.38384) (xy 87.488822 -345.437828) (xy 87.488822 -345.492365) (xy 88.97167 -345.492365)
			(xy 88.97167 -345.437835) (xy 88.979431 -345.383859) (xy 88.994793 -345.331537) (xy 89.017445 -345.281934)
			(xy 89.046926 -345.23606) (xy 89.082635 -345.194848) (xy 89.123845 -345.159137) (xy 89.169719 -345.129654)
			(xy 89.219321 -345.106999) (xy 89.271642 -345.091634) (xy 89.325617 -345.083872) (xy 89.352882 -345.083384)
			(xy 90.216482 -345.083384) (xy 90.243757 -345.083754) (xy 90.297752 -345.091515) (xy 90.350094 -345.106882)
			(xy 90.399715 -345.129541) (xy 90.445606 -345.159032) (xy 90.486834 -345.194754) (xy 90.522557 -345.235979)
			(xy 90.55205 -345.281869) (xy 90.574712 -345.33149) (xy 90.590081 -345.38383) (xy 90.597844 -345.437825)
			(xy 90.597844 -345.49237) (xy 92.080548 -345.49237) (xy 92.080548 -345.43783) (xy 92.08831 -345.383846)
			(xy 92.103676 -345.331517) (xy 92.126334 -345.281907) (xy 92.155822 -345.236026) (xy 92.19154 -345.19481)
			(xy 92.23276 -345.159097) (xy 92.278644 -345.129614) (xy 92.328256 -345.106962) (xy 92.380587 -345.091601)
			(xy 92.434572 -345.083845) (xy 92.461842 -345.083384) (xy 93.325442 -345.083384) (xy 93.352713 -345.083781)
			(xy 93.406698 -345.091549) (xy 93.459029 -345.10692) (xy 93.50864 -345.129581) (xy 93.554521 -345.159072)
			(xy 93.595739 -345.194791) (xy 93.631454 -345.236013) (xy 93.660939 -345.281897) (xy 93.683595 -345.33151)
			(xy 93.69896 -345.383843) (xy 93.706722 -345.437829) (xy 93.706722 -345.492368) (xy 111.480847 -345.492368)
			(xy 111.480847 -345.437832) (xy 111.488609 -345.383851) (xy 111.503974 -345.331524) (xy 111.526629 -345.281916)
			(xy 111.556114 -345.236038) (xy 111.591828 -345.194822) (xy 111.633044 -345.159109) (xy 111.678923 -345.129625)
			(xy 111.728531 -345.106971) (xy 111.780859 -345.091607) (xy 111.83484 -345.083847) (xy 111.862108 -345.083384)
			(xy 112.725708 -345.083384) (xy 112.75298 -345.083779) (xy 112.80697 -345.091543) (xy 112.859304 -345.106911)
			(xy 112.90892 -345.12957) (xy 112.954805 -345.15906) (xy 112.996027 -345.194779) (xy 113.031745 -345.236001)
			(xy 113.061234 -345.281888) (xy 113.083892 -345.331503) (xy 113.099259 -345.383838) (xy 113.107021 -345.437828)
			(xy 113.107021 -345.492365) (xy 114.58987 -345.492365) (xy 114.58987 -345.437835) (xy 114.59763 -345.383861)
			(xy 114.612992 -345.33154) (xy 114.635643 -345.281938) (xy 114.665122 -345.236064) (xy 114.70083 -345.194853)
			(xy 114.742039 -345.159142) (xy 114.78791 -345.129658) (xy 114.83751 -345.107003) (xy 114.88983 -345.091637)
			(xy 114.943803 -345.083872) (xy 114.971068 -345.083384) (xy 115.834668 -345.083384) (xy 115.861944 -345.083753)
			(xy 115.915941 -345.091513) (xy 115.968283 -345.106878) (xy 116.017907 -345.129537) (xy 116.0638 -345.159027)
			(xy 116.105029 -345.194749) (xy 116.140754 -345.235975) (xy 116.170248 -345.281865) (xy 116.192911 -345.331487)
			(xy 116.20828 -345.383828) (xy 116.216044 -345.437824) (xy 116.216044 -345.492369) (xy 117.698747 -345.492369)
			(xy 117.698747 -345.437831) (xy 117.706509 -345.383848) (xy 117.721875 -345.33152) (xy 117.744532 -345.281911)
			(xy 117.774019 -345.236031) (xy 117.809735 -345.194815) (xy 117.850953 -345.159102) (xy 117.896835 -345.129619)
			(xy 117.946446 -345.106965) (xy 117.998776 -345.091603) (xy 118.052759 -345.083845) (xy 118.080028 -345.083384)
			(xy 118.943628 -345.083384) (xy 118.970899 -345.08378) (xy 119.024886 -345.091546) (xy 119.077219 -345.106916)
			(xy 119.126832 -345.129576) (xy 119.172714 -345.159067) (xy 119.213934 -345.194786) (xy 119.24965 -345.236008)
			(xy 119.279137 -345.281893) (xy 119.301794 -345.331507) (xy 119.31716 -345.383841) (xy 119.324922 -345.437829)
			(xy 119.324922 -345.492366) (xy 120.80777 -345.492366) (xy 120.80777 -345.437834) (xy 120.815531 -345.383858)
			(xy 120.830894 -345.331536) (xy 120.853546 -345.281933) (xy 120.883027 -345.236058) (xy 120.918737 -345.194846)
			(xy 120.959948 -345.159135) (xy 121.005822 -345.129652) (xy 121.055425 -345.106998) (xy 121.107747 -345.091633)
			(xy 121.161722 -345.083871) (xy 121.188988 -345.083384) (xy 122.052588 -345.083384) (xy 122.079863 -345.083755)
			(xy 122.133857 -345.091516) (xy 122.186198 -345.106884) (xy 122.235819 -345.129543) (xy 122.281709 -345.159034)
			(xy 122.322936 -345.194756) (xy 122.358659 -345.235981) (xy 122.388151 -345.281871) (xy 122.410812 -345.331491)
			(xy 122.426181 -345.383831) (xy 122.433944 -345.437825) (xy 122.433944 -345.49237) (xy 123.916648 -345.49237)
			(xy 123.916648 -345.43783) (xy 123.92441 -345.383846) (xy 123.939777 -345.331515) (xy 123.962435 -345.281905)
			(xy 123.991924 -345.236024) (xy 124.027642 -345.194808) (xy 124.068863 -345.159095) (xy 124.114747 -345.129612)
			(xy 124.16436 -345.10696) (xy 124.216692 -345.0916) (xy 124.270678 -345.083844) (xy 124.297948 -345.083384)
			(xy 125.161548 -345.083384) (xy 125.188818 -345.083782) (xy 125.242803 -345.09155) (xy 125.295133 -345.106921)
			(xy 125.344744 -345.129583) (xy 125.390624 -345.159074) (xy 125.431841 -345.194793) (xy 125.467555 -345.236015)
			(xy 125.49704 -345.281899) (xy 125.519695 -345.331512) (xy 125.53506 -345.383844) (xy 125.542822 -345.43783)
			(xy 125.542822 -345.492368) (xy 127.025647 -345.492368) (xy 127.025647 -345.437832) (xy 127.033409 -345.383851)
			(xy 127.048774 -345.331524) (xy 127.071429 -345.281916) (xy 127.100914 -345.236038) (xy 127.136628 -345.194822)
			(xy 127.177844 -345.159109) (xy 127.223723 -345.129625) (xy 127.273331 -345.106971) (xy 127.325659 -345.091607)
			(xy 127.37964 -345.083847) (xy 127.406908 -345.083384) (xy 128.270508 -345.083384) (xy 128.29778 -345.083779)
			(xy 128.35177 -345.091543) (xy 128.404104 -345.106911) (xy 128.45372 -345.12957) (xy 128.499605 -345.15906)
			(xy 128.540827 -345.194779) (xy 128.576545 -345.236001) (xy 128.606034 -345.281888) (xy 128.628692 -345.331503)
			(xy 128.644059 -345.383838) (xy 128.651821 -345.437828) (xy 128.651821 -345.492365) (xy 130.13467 -345.492365)
			(xy 130.13467 -345.437835) (xy 130.14243 -345.383861) (xy 130.157792 -345.33154) (xy 130.180443 -345.281938)
			(xy 130.209922 -345.236064) (xy 130.24563 -345.194853) (xy 130.286839 -345.159142) (xy 130.33271 -345.129658)
			(xy 130.38231 -345.107003) (xy 130.43463 -345.091637) (xy 130.488603 -345.083872) (xy 130.515868 -345.083384)
			(xy 131.379468 -345.083384) (xy 131.406744 -345.083753) (xy 131.460741 -345.091513) (xy 131.513083 -345.106878)
			(xy 131.562707 -345.129537) (xy 131.6086 -345.159027) (xy 131.649829 -345.194749) (xy 131.685554 -345.235975)
			(xy 131.715048 -345.281865) (xy 131.737711 -345.331487) (xy 131.75308 -345.383828) (xy 131.760844 -345.437824)
			(xy 131.760844 -345.492369) (xy 133.243547 -345.492369) (xy 133.243547 -345.437831) (xy 133.251309 -345.383848)
			(xy 133.266675 -345.33152) (xy 133.289332 -345.281911) (xy 133.318819 -345.236031) (xy 133.354535 -345.194815)
			(xy 133.395753 -345.159102) (xy 133.441635 -345.129619) (xy 133.491246 -345.106965) (xy 133.543576 -345.091603)
			(xy 133.597559 -345.083845) (xy 133.624828 -345.083384) (xy 134.488428 -345.083384) (xy 134.515699 -345.08378)
			(xy 134.569686 -345.091546) (xy 134.622019 -345.106916) (xy 134.671632 -345.129576) (xy 134.717514 -345.159067)
			(xy 134.758734 -345.194786) (xy 134.79445 -345.236008) (xy 134.823937 -345.281893) (xy 134.846594 -345.331507)
			(xy 134.86196 -345.383841) (xy 134.869722 -345.437829) (xy 134.869722 -345.492366) (xy 136.35257 -345.492366)
			(xy 136.35257 -345.437834) (xy 136.360331 -345.383858) (xy 136.375694 -345.331536) (xy 136.398346 -345.281933)
			(xy 136.427827 -345.236058) (xy 136.463537 -345.194846) (xy 136.504748 -345.159135) (xy 136.550622 -345.129652)
			(xy 136.600225 -345.106998) (xy 136.652547 -345.091633) (xy 136.706522 -345.083871) (xy 136.733788 -345.083384)
			(xy 137.597388 -345.083384) (xy 137.624663 -345.083755) (xy 137.678657 -345.091516) (xy 137.730998 -345.106884)
			(xy 137.780619 -345.129543) (xy 137.826509 -345.159034) (xy 137.867736 -345.194756) (xy 137.903459 -345.235981)
			(xy 137.932951 -345.281871) (xy 137.955612 -345.331491) (xy 137.970981 -345.383831) (xy 137.978744 -345.437825)
			(xy 137.978744 -345.49237) (xy 139.461448 -345.49237) (xy 139.461448 -345.43783) (xy 139.46921 -345.383846)
			(xy 139.484577 -345.331515) (xy 139.507235 -345.281905) (xy 139.536724 -345.236024) (xy 139.572442 -345.194808)
			(xy 139.613663 -345.159095) (xy 139.659547 -345.129612) (xy 139.70916 -345.10696) (xy 139.761492 -345.0916)
			(xy 139.815478 -345.083844) (xy 139.842748 -345.083384) (xy 140.706348 -345.083384) (xy 140.733618 -345.083782)
			(xy 140.787603 -345.09155) (xy 140.839933 -345.106921) (xy 140.889544 -345.129583) (xy 140.935424 -345.159074)
			(xy 140.976641 -345.194793) (xy 141.012355 -345.236015) (xy 141.04184 -345.281899) (xy 141.064495 -345.331512)
			(xy 141.07986 -345.383844) (xy 141.087622 -345.43783) (xy 141.087622 -345.492368) (xy 142.570447 -345.492368)
			(xy 142.570447 -345.437832) (xy 142.578209 -345.383851) (xy 142.593574 -345.331524) (xy 142.616229 -345.281916)
			(xy 142.645714 -345.236038) (xy 142.681428 -345.194822) (xy 142.722644 -345.159109) (xy 142.768523 -345.129625)
			(xy 142.818131 -345.106971) (xy 142.870459 -345.091607) (xy 142.92444 -345.083847) (xy 142.951708 -345.083384)
			(xy 143.815308 -345.083384) (xy 143.84258 -345.083779) (xy 143.89657 -345.091543) (xy 143.948904 -345.106911)
			(xy 143.99852 -345.12957) (xy 144.044405 -345.15906) (xy 144.085627 -345.194779) (xy 144.121345 -345.236001)
			(xy 144.150834 -345.281888) (xy 144.173492 -345.331503) (xy 144.188859 -345.383838) (xy 144.196621 -345.437828)
			(xy 144.196621 -345.492365) (xy 164.91387 -345.492365) (xy 164.91387 -345.437835) (xy 164.92163 -345.383861)
			(xy 164.936992 -345.33154) (xy 164.959644 -345.281937) (xy 164.989123 -345.236063) (xy 165.024831 -345.194851)
			(xy 165.066041 -345.15914) (xy 165.111913 -345.129657) (xy 165.161513 -345.107002) (xy 165.213833 -345.091636)
			(xy 165.267807 -345.083872) (xy 165.295072 -345.083384) (xy 166.158672 -345.083384) (xy 166.185948 -345.083754)
			(xy 166.239944 -345.091514) (xy 166.292286 -345.106879) (xy 166.341909 -345.129538) (xy 166.387802 -345.159028)
			(xy 166.42903 -345.19475) (xy 166.464755 -345.235976) (xy 166.494249 -345.281866) (xy 166.516911 -345.331487)
			(xy 166.532281 -345.383829) (xy 166.540044 -345.437824) (xy 166.540044 -345.492369) (xy 168.022747 -345.492369)
			(xy 168.022747 -345.437831) (xy 168.03051 -345.383848) (xy 168.045876 -345.331519) (xy 168.068533 -345.281909)
			(xy 168.09802 -345.23603) (xy 168.133736 -345.194814) (xy 168.174955 -345.159101) (xy 168.220838 -345.129617)
			(xy 168.270449 -345.106964) (xy 168.322779 -345.091603) (xy 168.376763 -345.083845) (xy 168.404032 -345.083384)
			(xy 169.267632 -345.083384) (xy 169.294903 -345.083781) (xy 169.34889 -345.091547) (xy 169.401222 -345.106917)
			(xy 169.450834 -345.129578) (xy 169.496716 -345.159068) (xy 169.537935 -345.194788) (xy 169.573651 -345.236009)
			(xy 169.603138 -345.281894) (xy 169.625794 -345.331508) (xy 169.64116 -345.383842) (xy 169.648922 -345.437829)
			(xy 169.648922 -345.492366) (xy 171.13177 -345.492366) (xy 171.13177 -345.437834) (xy 171.139531 -345.383858)
			(xy 171.154894 -345.331535) (xy 171.177547 -345.281932) (xy 171.207028 -345.236057) (xy 171.242738 -345.194844)
			(xy 171.28395 -345.159133) (xy 171.329825 -345.129651) (xy 171.379428 -345.106997) (xy 171.43175 -345.091633)
			(xy 171.485726 -345.083871) (xy 171.512992 -345.083384) (xy 172.376592 -345.083384) (xy 172.403867 -345.083755)
			(xy 172.457861 -345.091517) (xy 172.510201 -345.106885) (xy 172.559821 -345.129544) (xy 172.605711 -345.159035)
			(xy 172.646937 -345.194757) (xy 172.68266 -345.235982) (xy 172.712152 -345.281872) (xy 172.734813 -345.331492)
			(xy 172.750181 -345.383831) (xy 172.757944 -345.437825) (xy 172.757944 -345.492364) (xy 174.24077 -345.492364)
			(xy 174.24077 -345.437836) (xy 174.24853 -345.383863) (xy 174.263891 -345.331544) (xy 174.286541 -345.281943)
			(xy 174.316019 -345.23607) (xy 174.351724 -345.194858) (xy 174.392931 -345.159147) (xy 174.438801 -345.129664)
			(xy 174.488399 -345.107008) (xy 174.540716 -345.09164) (xy 174.594688 -345.083874) (xy 174.621952 -345.083384)
			(xy 175.485552 -345.083384) (xy 175.512829 -345.083752) (xy 175.566827 -345.09151) (xy 175.619172 -345.106874)
			(xy 175.668797 -345.129531) (xy 175.714692 -345.159021) (xy 175.755923 -345.194743) (xy 175.79165 -345.235969)
			(xy 175.821146 -345.281861) (xy 175.843809 -345.331483) (xy 175.85918 -345.383826) (xy 175.866944 -345.437824)
			(xy 175.866944 -345.492368) (xy 177.349647 -345.492368) (xy 177.349647 -345.437832) (xy 177.357409 -345.38385)
			(xy 177.372774 -345.331523) (xy 177.39543 -345.281915) (xy 177.424915 -345.236036) (xy 177.460629 -345.194821)
			(xy 177.501846 -345.159108) (xy 177.547726 -345.129624) (xy 177.597334 -345.10697) (xy 177.649662 -345.091606)
			(xy 177.703644 -345.083847) (xy 177.730912 -345.083384) (xy 178.594512 -345.083384) (xy 178.621784 -345.083779)
			(xy 178.675773 -345.091543) (xy 178.728107 -345.106912) (xy 178.777722 -345.129571) (xy 178.823607 -345.159061)
			(xy 178.864828 -345.194781) (xy 178.900546 -345.236003) (xy 178.930035 -345.281889) (xy 178.952693 -345.331504)
			(xy 178.968059 -345.383839) (xy 178.975821 -345.437828) (xy 178.975821 -345.492365) (xy 180.45867 -345.492365)
			(xy 180.45867 -345.437835) (xy 180.46643 -345.383861) (xy 180.481792 -345.33154) (xy 180.504444 -345.281937)
			(xy 180.533923 -345.236063) (xy 180.569631 -345.194851) (xy 180.610841 -345.15914) (xy 180.656713 -345.129657)
			(xy 180.706313 -345.107002) (xy 180.758633 -345.091636) (xy 180.812607 -345.083872) (xy 180.839872 -345.083384)
			(xy 181.703472 -345.083384) (xy 181.730748 -345.083754) (xy 181.784744 -345.091514) (xy 181.837086 -345.106879)
			(xy 181.886709 -345.129538) (xy 181.932602 -345.159028) (xy 181.97383 -345.19475) (xy 182.009555 -345.235976)
			(xy 182.039049 -345.281866) (xy 182.061711 -345.331487) (xy 182.077081 -345.383829) (xy 182.084844 -345.437824)
			(xy 182.084844 -345.492369) (xy 183.567547 -345.492369) (xy 183.567547 -345.437831) (xy 183.57531 -345.383848)
			(xy 183.590676 -345.331519) (xy 183.613333 -345.281909) (xy 183.64282 -345.23603) (xy 183.678536 -345.194814)
			(xy 183.719755 -345.159101) (xy 183.765638 -345.129617) (xy 183.815249 -345.106964) (xy 183.867579 -345.091603)
			(xy 183.921563 -345.083845) (xy 183.948832 -345.083384) (xy 184.812432 -345.083384) (xy 184.839703 -345.083781)
			(xy 184.89369 -345.091547) (xy 184.946022 -345.106917) (xy 184.995634 -345.129578) (xy 185.041516 -345.159068)
			(xy 185.082735 -345.194788) (xy 185.118451 -345.236009) (xy 185.147938 -345.281894) (xy 185.170594 -345.331508)
			(xy 185.18596 -345.383842) (xy 185.193722 -345.437829) (xy 185.193722 -345.492366) (xy 186.67657 -345.492366)
			(xy 186.67657 -345.437834) (xy 186.684331 -345.383858) (xy 186.699694 -345.331535) (xy 186.722347 -345.281932)
			(xy 186.751828 -345.236057) (xy 186.787538 -345.194844) (xy 186.82875 -345.159133) (xy 186.874625 -345.129651)
			(xy 186.924228 -345.106997) (xy 186.97655 -345.091633) (xy 187.030526 -345.083871) (xy 187.057792 -345.083384)
			(xy 187.921392 -345.083384) (xy 187.948667 -345.083755) (xy 188.002661 -345.091517) (xy 188.055001 -345.106885)
			(xy 188.104621 -345.129544) (xy 188.150511 -345.159035) (xy 188.191737 -345.194757) (xy 188.22746 -345.235982)
			(xy 188.256952 -345.281872) (xy 188.279613 -345.331492) (xy 188.294981 -345.383831) (xy 188.302744 -345.437825)
			(xy 188.302744 -345.492364) (xy 189.78557 -345.492364) (xy 189.78557 -345.437836) (xy 189.79333 -345.383863)
			(xy 189.808691 -345.331544) (xy 189.831341 -345.281943) (xy 189.860819 -345.23607) (xy 189.896524 -345.194858)
			(xy 189.937731 -345.159147) (xy 189.983601 -345.129664) (xy 190.033199 -345.107008) (xy 190.085516 -345.09164)
			(xy 190.139488 -345.083874) (xy 190.166752 -345.083384) (xy 191.030352 -345.083384) (xy 191.057629 -345.083752)
			(xy 191.111627 -345.09151) (xy 191.163972 -345.106874) (xy 191.213597 -345.129531) (xy 191.259492 -345.159021)
			(xy 191.300723 -345.194743) (xy 191.33645 -345.235969) (xy 191.365946 -345.281861) (xy 191.388609 -345.331483)
			(xy 191.40398 -345.383826) (xy 191.411744 -345.437824) (xy 191.411744 -345.492368) (xy 192.894447 -345.492368)
			(xy 192.894447 -345.437832) (xy 192.902209 -345.38385) (xy 192.917574 -345.331523) (xy 192.94023 -345.281915)
			(xy 192.969715 -345.236036) (xy 193.005429 -345.194821) (xy 193.046646 -345.159108) (xy 193.092526 -345.129624)
			(xy 193.142134 -345.10697) (xy 193.194462 -345.091606) (xy 193.248444 -345.083847) (xy 193.275712 -345.083384)
			(xy 194.139312 -345.083384) (xy 194.166584 -345.083779) (xy 194.220573 -345.091543) (xy 194.272907 -345.106912)
			(xy 194.322522 -345.129571) (xy 194.368407 -345.159061) (xy 194.409628 -345.194781) (xy 194.445346 -345.236003)
			(xy 194.474835 -345.281889) (xy 194.497493 -345.331504) (xy 194.512859 -345.383839) (xy 194.520621 -345.437828)
			(xy 194.520621 -345.492365) (xy 196.00347 -345.492365) (xy 196.00347 -345.437835) (xy 196.01123 -345.383861)
			(xy 196.026592 -345.33154) (xy 196.049244 -345.281937) (xy 196.078723 -345.236063) (xy 196.114431 -345.194851)
			(xy 196.155641 -345.15914) (xy 196.201513 -345.129657) (xy 196.251113 -345.107002) (xy 196.303433 -345.091636)
			(xy 196.357407 -345.083872) (xy 196.384672 -345.083384) (xy 197.248272 -345.083384) (xy 197.275548 -345.083754)
			(xy 197.329544 -345.091514) (xy 197.381886 -345.106879) (xy 197.431509 -345.129538) (xy 197.477402 -345.159028)
			(xy 197.51863 -345.19475) (xy 197.554355 -345.235976) (xy 197.583849 -345.281866) (xy 197.606511 -345.331487)
			(xy 197.621881 -345.383829) (xy 197.629644 -345.437824) (xy 197.629644 -345.492368) (xy 267.515847 -345.492368)
			(xy 267.515847 -345.437832) (xy 267.523609 -345.383852) (xy 267.538973 -345.331525) (xy 267.561628 -345.281918)
			(xy 267.591112 -345.23604) (xy 267.626826 -345.194824) (xy 267.668041 -345.159111) (xy 267.71392 -345.129627)
			(xy 267.763527 -345.106972) (xy 267.815854 -345.091608) (xy 267.869834 -345.083847) (xy 267.897102 -345.083384)
			(xy 268.760702 -345.083384) (xy 268.787975 -345.083779) (xy 268.841964 -345.091542) (xy 268.8943 -345.106909)
			(xy 268.943916 -345.129568) (xy 268.989802 -345.159057) (xy 269.031024 -345.194777) (xy 269.066744 -345.236)
			(xy 269.096233 -345.281886) (xy 269.118892 -345.331502) (xy 269.134259 -345.383838) (xy 269.142021 -345.437827)
			(xy 269.142021 -345.492364) (xy 270.62487 -345.492364) (xy 270.62487 -345.437836) (xy 270.63263 -345.383862)
			(xy 270.647992 -345.331542) (xy 270.670642 -345.28194) (xy 270.700121 -345.236066) (xy 270.735828 -345.194855)
			(xy 270.777036 -345.159144) (xy 270.822907 -345.12966) (xy 270.872506 -345.107005) (xy 270.924825 -345.091638)
			(xy 270.978798 -345.083873) (xy 271.006062 -345.083384) (xy 271.869662 -345.083384) (xy 271.896938 -345.083753)
			(xy 271.950936 -345.091512) (xy 272.003279 -345.106877) (xy 272.052903 -345.129535) (xy 272.098797 -345.159025)
			(xy 272.140027 -345.194747) (xy 272.175752 -345.235973) (xy 272.205247 -345.281864) (xy 272.22791 -345.331485)
			(xy 272.24328 -345.383827) (xy 272.251044 -345.437824) (xy 272.251044 -345.492369) (xy 273.733747 -345.492369)
			(xy 273.733747 -345.437831) (xy 273.741509 -345.383849) (xy 273.756875 -345.331521) (xy 273.779531 -345.281912)
			(xy 273.809017 -345.236033) (xy 273.844733 -345.194817) (xy 273.885951 -345.159104) (xy 273.931832 -345.129621)
			(xy 273.981441 -345.106967) (xy 274.033771 -345.091605) (xy 274.087753 -345.083846) (xy 274.115022 -345.083384)
			(xy 274.978622 -345.083384) (xy 275.005894 -345.08378) (xy 275.059881 -345.091545) (xy 275.112215 -345.106914)
			(xy 275.161828 -345.129574) (xy 275.207712 -345.159064) (xy 275.248932 -345.194784) (xy 275.284649 -345.236006)
			(xy 275.314136 -345.281891) (xy 275.336793 -345.331506) (xy 275.352159 -345.38384) (xy 275.359922 -345.437828)
			(xy 275.359922 -345.492365) (xy 276.84277 -345.492365) (xy 276.84277 -345.437835) (xy 276.850531 -345.383859)
			(xy 276.865893 -345.331537) (xy 276.888545 -345.281934) (xy 276.918026 -345.23606) (xy 276.953735 -345.194848)
			(xy 276.994945 -345.159137) (xy 277.040819 -345.129654) (xy 277.090421 -345.106999) (xy 277.142742 -345.091634)
			(xy 277.196717 -345.083872) (xy 277.223982 -345.083384) (xy 278.087582 -345.083384) (xy 278.114857 -345.083754)
			(xy 278.168852 -345.091515) (xy 278.221194 -345.106882) (xy 278.270815 -345.129541) (xy 278.316706 -345.159032)
			(xy 278.357934 -345.194754) (xy 278.393657 -345.235979) (xy 278.42315 -345.281869) (xy 278.445812 -345.33149)
			(xy 278.461181 -345.38383) (xy 278.468944 -345.437825) (xy 278.468944 -345.49237) (xy 279.951648 -345.49237)
			(xy 279.951648 -345.43783) (xy 279.95941 -345.383846) (xy 279.974776 -345.331517) (xy 279.997434 -345.281907)
			(xy 280.026922 -345.236026) (xy 280.06264 -345.19481) (xy 280.10386 -345.159097) (xy 280.149744 -345.129614)
			(xy 280.199356 -345.106962) (xy 280.251687 -345.091601) (xy 280.305672 -345.083845) (xy 280.332942 -345.083384)
			(xy 281.196542 -345.083384) (xy 281.223813 -345.083781) (xy 281.277798 -345.091549) (xy 281.330129 -345.10692)
			(xy 281.37974 -345.129581) (xy 281.425621 -345.159072) (xy 281.466839 -345.194791) (xy 281.502554 -345.236013)
			(xy 281.532039 -345.281897) (xy 281.554695 -345.33151) (xy 281.57006 -345.383843) (xy 281.577822 -345.437829)
			(xy 281.577822 -345.492368) (xy 283.060647 -345.492368) (xy 283.060647 -345.437832) (xy 283.068409 -345.383852)
			(xy 283.083773 -345.331525) (xy 283.106428 -345.281918) (xy 283.135912 -345.23604) (xy 283.171626 -345.194824)
			(xy 283.212841 -345.159111) (xy 283.25872 -345.129627) (xy 283.308327 -345.106972) (xy 283.360654 -345.091608)
			(xy 283.414634 -345.083847) (xy 283.441902 -345.083384) (xy 284.305502 -345.083384) (xy 284.332775 -345.083779)
			(xy 284.386764 -345.091542) (xy 284.4391 -345.106909) (xy 284.488716 -345.129568) (xy 284.534602 -345.159057)
			(xy 284.575824 -345.194777) (xy 284.611544 -345.236) (xy 284.641033 -345.281886) (xy 284.663692 -345.331502)
			(xy 284.679059 -345.383838) (xy 284.686821 -345.437827) (xy 284.686821 -345.492364) (xy 286.16967 -345.492364)
			(xy 286.16967 -345.437836) (xy 286.17743 -345.383862) (xy 286.192792 -345.331542) (xy 286.215442 -345.28194)
			(xy 286.244921 -345.236066) (xy 286.280628 -345.194855) (xy 286.321836 -345.159144) (xy 286.367707 -345.12966)
			(xy 286.417306 -345.107005) (xy 286.469625 -345.091638) (xy 286.523598 -345.083873) (xy 286.550862 -345.083384)
			(xy 287.414462 -345.083384) (xy 287.441738 -345.083753) (xy 287.495736 -345.091512) (xy 287.548079 -345.106877)
			(xy 287.597703 -345.129535) (xy 287.643597 -345.159025) (xy 287.684827 -345.194747) (xy 287.720552 -345.235973)
			(xy 287.750047 -345.281864) (xy 287.77271 -345.331485) (xy 287.78808 -345.383827) (xy 287.795844 -345.437824)
			(xy 287.795844 -345.492369) (xy 289.278547 -345.492369) (xy 289.278547 -345.437831) (xy 289.286309 -345.383849)
			(xy 289.301675 -345.331521) (xy 289.324331 -345.281912) (xy 289.353817 -345.236033) (xy 289.389533 -345.194817)
			(xy 289.430751 -345.159104) (xy 289.476632 -345.129621) (xy 289.526241 -345.106967) (xy 289.578571 -345.091605)
			(xy 289.632553 -345.083846) (xy 289.659822 -345.083384) (xy 290.523422 -345.083384) (xy 290.550694 -345.08378)
			(xy 290.604681 -345.091545) (xy 290.657015 -345.106914) (xy 290.706628 -345.129574) (xy 290.752512 -345.159064)
			(xy 290.793732 -345.194784) (xy 290.829449 -345.236006) (xy 290.858936 -345.281891) (xy 290.881593 -345.331506)
			(xy 290.896959 -345.38384) (xy 290.904722 -345.437828) (xy 290.904722 -345.492365) (xy 292.38757 -345.492365)
			(xy 292.38757 -345.437835) (xy 292.395331 -345.383859) (xy 292.410693 -345.331537) (xy 292.433345 -345.281934)
			(xy 292.462826 -345.23606) (xy 292.498535 -345.194848) (xy 292.539745 -345.159137) (xy 292.585619 -345.129654)
			(xy 292.635221 -345.106999) (xy 292.687542 -345.091634) (xy 292.741517 -345.083872) (xy 292.768782 -345.083384)
			(xy 293.632382 -345.083384) (xy 293.659657 -345.083754) (xy 293.713652 -345.091515) (xy 293.765994 -345.106882)
			(xy 293.815615 -345.129541) (xy 293.861506 -345.159032) (xy 293.902734 -345.194754) (xy 293.938457 -345.235979)
			(xy 293.96795 -345.281869) (xy 293.990612 -345.33149) (xy 294.005981 -345.38383) (xy 294.013744 -345.437825)
			(xy 294.013744 -345.49237) (xy 295.496448 -345.49237) (xy 295.496448 -345.43783) (xy 295.50421 -345.383846)
			(xy 295.519576 -345.331517) (xy 295.542234 -345.281907) (xy 295.571722 -345.236026) (xy 295.60744 -345.19481)
			(xy 295.64866 -345.159097) (xy 295.694544 -345.129614) (xy 295.744156 -345.106962) (xy 295.796487 -345.091601)
			(xy 295.850472 -345.083845) (xy 295.877742 -345.083384) (xy 296.741342 -345.083384) (xy 296.768613 -345.083781)
			(xy 296.822598 -345.091549) (xy 296.874929 -345.10692) (xy 296.92454 -345.129581) (xy 296.970421 -345.159072)
			(xy 297.011639 -345.194791) (xy 297.047354 -345.236013) (xy 297.076839 -345.281897) (xy 297.099495 -345.33151)
			(xy 297.11486 -345.383843) (xy 297.122622 -345.437829) (xy 297.122622 -345.492368) (xy 298.605447 -345.492368)
			(xy 298.605447 -345.437832) (xy 298.613209 -345.383852) (xy 298.628573 -345.331525) (xy 298.651228 -345.281918)
			(xy 298.680712 -345.23604) (xy 298.716426 -345.194824) (xy 298.757641 -345.159111) (xy 298.80352 -345.129627)
			(xy 298.853127 -345.106972) (xy 298.905454 -345.091608) (xy 298.959434 -345.083847) (xy 298.986702 -345.083384)
			(xy 299.850302 -345.083384) (xy 299.877575 -345.083779) (xy 299.931564 -345.091542) (xy 299.9839 -345.106909)
			(xy 300.033516 -345.129568) (xy 300.079402 -345.159057) (xy 300.120624 -345.194777) (xy 300.156344 -345.236)
			(xy 300.185833 -345.281886) (xy 300.208492 -345.331502) (xy 300.223859 -345.383838) (xy 300.231621 -345.437827)
			(xy 300.231621 -345.492368) (xy 312.121547 -345.492368) (xy 312.121547 -345.437832) (xy 312.129309 -345.383851)
			(xy 312.144673 -345.331525) (xy 312.167328 -345.281917) (xy 312.196813 -345.236039) (xy 312.232526 -345.194824)
			(xy 312.273742 -345.159111) (xy 312.319621 -345.129627) (xy 312.369228 -345.106972) (xy 312.421555 -345.091608)
			(xy 312.475536 -345.083847) (xy 312.502804 -345.083384) (xy 313.366404 -345.083384) (xy 313.393676 -345.083779)
			(xy 313.447666 -345.091542) (xy 313.500001 -345.106909) (xy 313.549617 -345.129569) (xy 313.595503 -345.159058)
			(xy 313.636725 -345.194778) (xy 313.672444 -345.236) (xy 313.701933 -345.281886) (xy 313.724592 -345.331502)
			(xy 313.739959 -345.383838) (xy 313.747721 -345.437828) (xy 313.747721 -345.492364) (xy 315.23057 -345.492364)
			(xy 315.23057 -345.437836) (xy 315.23833 -345.383862) (xy 315.253692 -345.331541) (xy 315.276343 -345.281939)
			(xy 315.305821 -345.236066) (xy 315.341529 -345.194854) (xy 315.382737 -345.159143) (xy 315.428608 -345.12966)
			(xy 315.478207 -345.107004) (xy 315.530526 -345.091638) (xy 315.5845 -345.083873) (xy 315.611764 -345.083384)
			(xy 316.475364 -345.083384) (xy 316.50264 -345.083753) (xy 316.556637 -345.091512) (xy 316.608981 -345.106877)
			(xy 316.658604 -345.129535) (xy 316.704498 -345.159026) (xy 316.745727 -345.194747) (xy 316.781453 -345.235973)
			(xy 316.810947 -345.281864) (xy 316.83361 -345.331486) (xy 316.84898 -345.383828) (xy 316.856744 -345.437824)
			(xy 316.856744 -345.492369) (xy 318.339447 -345.492369) (xy 318.339447 -345.437831) (xy 318.347209 -345.383849)
			(xy 318.362575 -345.33152) (xy 318.385231 -345.281912) (xy 318.414718 -345.236032) (xy 318.450434 -345.194817)
			(xy 318.491652 -345.159103) (xy 318.537533 -345.12962) (xy 318.587143 -345.106966) (xy 318.639472 -345.091604)
			(xy 318.693455 -345.083846) (xy 318.720724 -345.083384) (xy 319.584324 -345.083384) (xy 319.611596 -345.08378)
			(xy 319.665583 -345.091546) (xy 319.717916 -345.106915) (xy 319.767529 -345.129575) (xy 319.813413 -345.159065)
			(xy 319.854632 -345.194785) (xy 319.890349 -345.236007) (xy 319.919836 -345.281892) (xy 319.942494 -345.331507)
			(xy 319.95786 -345.38384) (xy 319.965622 -345.437828) (xy 319.965622 -345.492365) (xy 321.44847 -345.492365)
			(xy 321.44847 -345.437835) (xy 321.456231 -345.383859) (xy 321.471593 -345.331537) (xy 321.494246 -345.281934)
			(xy 321.523726 -345.236059) (xy 321.559436 -345.194847) (xy 321.600646 -345.159136) (xy 321.64652 -345.129653)
			(xy 321.696122 -345.106999) (xy 321.748443 -345.091634) (xy 321.802419 -345.083871) (xy 321.829684 -345.083384)
			(xy 322.693284 -345.083384) (xy 322.720559 -345.083755) (xy 322.774554 -345.091516) (xy 322.826895 -345.106882)
			(xy 322.876516 -345.129542) (xy 322.922407 -345.159033) (xy 322.963634 -345.194754) (xy 322.999358 -345.23598)
			(xy 323.02885 -345.28187) (xy 323.051512 -345.33149) (xy 323.066881 -345.38383) (xy 323.074644 -345.437825)
			(xy 323.074644 -345.49237) (xy 324.557348 -345.49237) (xy 324.557348 -345.43783) (xy 324.56511 -345.383846)
			(xy 324.580476 -345.331516) (xy 324.603135 -345.281906) (xy 324.632623 -345.236026) (xy 324.668341 -345.194809)
			(xy 324.709561 -345.159096) (xy 324.755445 -345.129613) (xy 324.805057 -345.106961) (xy 324.857389 -345.0916)
			(xy 324.911374 -345.083844) (xy 324.938644 -345.083384) (xy 325.802244 -345.083384) (xy 325.829515 -345.083782)
			(xy 325.8835 -345.091549) (xy 325.93583 -345.10692) (xy 325.985441 -345.129582) (xy 326.031322 -345.159072)
			(xy 326.072539 -345.194792) (xy 326.108254 -345.236013) (xy 326.137739 -345.281898) (xy 326.160395 -345.331511)
			(xy 326.17576 -345.383843) (xy 326.183522 -345.437829) (xy 326.183522 -345.492368) (xy 327.666347 -345.492368)
			(xy 327.666347 -345.437832) (xy 327.674109 -345.383851) (xy 327.689473 -345.331525) (xy 327.712128 -345.281917)
			(xy 327.741613 -345.236039) (xy 327.777326 -345.194824) (xy 327.818542 -345.159111) (xy 327.864421 -345.129627)
			(xy 327.914028 -345.106972) (xy 327.966355 -345.091608) (xy 328.020336 -345.083847) (xy 328.047604 -345.083384)
			(xy 328.911204 -345.083384) (xy 328.938476 -345.083779) (xy 328.992466 -345.091542) (xy 329.044801 -345.106909)
			(xy 329.094417 -345.129569) (xy 329.140303 -345.159058) (xy 329.181525 -345.194778) (xy 329.217244 -345.236)
			(xy 329.246733 -345.281886) (xy 329.269392 -345.331502) (xy 329.284759 -345.383838) (xy 329.292521 -345.437828)
			(xy 329.292521 -345.492364) (xy 330.77537 -345.492364) (xy 330.77537 -345.437836) (xy 330.78313 -345.383862)
			(xy 330.798492 -345.331541) (xy 330.821143 -345.281939) (xy 330.850621 -345.236066) (xy 330.886329 -345.194854)
			(xy 330.927537 -345.159143) (xy 330.973408 -345.12966) (xy 331.023007 -345.107004) (xy 331.075326 -345.091638)
			(xy 331.1293 -345.083873) (xy 331.156564 -345.083384) (xy 332.020164 -345.083384) (xy 332.04744 -345.083753)
			(xy 332.101437 -345.091512) (xy 332.153781 -345.106877) (xy 332.203404 -345.129535) (xy 332.249298 -345.159026)
			(xy 332.290527 -345.194747) (xy 332.326253 -345.235973) (xy 332.355747 -345.281864) (xy 332.37841 -345.331486)
			(xy 332.39378 -345.383828) (xy 332.401544 -345.437824) (xy 332.401544 -345.492369) (xy 333.884247 -345.492369)
			(xy 333.884247 -345.437831) (xy 333.892009 -345.383849) (xy 333.907375 -345.33152) (xy 333.930031 -345.281912)
			(xy 333.959518 -345.236032) (xy 333.995234 -345.194817) (xy 334.036452 -345.159103) (xy 334.082333 -345.12962)
			(xy 334.131943 -345.106966) (xy 334.184272 -345.091604) (xy 334.238255 -345.083846) (xy 334.265524 -345.083384)
			(xy 335.129124 -345.083384) (xy 335.156396 -345.08378) (xy 335.210383 -345.091546) (xy 335.262716 -345.106915)
			(xy 335.312329 -345.129575) (xy 335.358213 -345.159065) (xy 335.399432 -345.194785) (xy 335.435149 -345.236007)
			(xy 335.464636 -345.281892) (xy 335.487294 -345.331507) (xy 335.50266 -345.38384) (xy 335.510422 -345.437828)
			(xy 335.510422 -345.492365) (xy 336.99327 -345.492365) (xy 336.99327 -345.437835) (xy 337.001031 -345.383859)
			(xy 337.016393 -345.331537) (xy 337.039046 -345.281934) (xy 337.068526 -345.236059) (xy 337.104236 -345.194847)
			(xy 337.145446 -345.159136) (xy 337.19132 -345.129653) (xy 337.240922 -345.106999) (xy 337.293243 -345.091634)
			(xy 337.347219 -345.083871) (xy 337.374484 -345.083384) (xy 338.238084 -345.083384) (xy 338.265359 -345.083755)
			(xy 338.319354 -345.091516) (xy 338.371695 -345.106882) (xy 338.421316 -345.129542) (xy 338.467207 -345.159033)
			(xy 338.508434 -345.194754) (xy 338.544158 -345.23598) (xy 338.57365 -345.28187) (xy 338.596312 -345.33149)
			(xy 338.611681 -345.38383) (xy 338.619444 -345.437825) (xy 338.619444 -345.49237) (xy 340.102148 -345.49237)
			(xy 340.102148 -345.43783) (xy 340.10991 -345.383846) (xy 340.125276 -345.331516) (xy 340.147935 -345.281906)
			(xy 340.177423 -345.236026) (xy 340.213141 -345.194809) (xy 340.254361 -345.159096) (xy 340.300245 -345.129613)
			(xy 340.349857 -345.106961) (xy 340.402189 -345.0916) (xy 340.456174 -345.083844) (xy 340.483444 -345.083384)
			(xy 341.347044 -345.083384) (xy 341.374315 -345.083782) (xy 341.4283 -345.091549) (xy 341.48063 -345.10692)
			(xy 341.530241 -345.129582) (xy 341.576122 -345.159072) (xy 341.617339 -345.194792) (xy 341.653054 -345.236013)
			(xy 341.682539 -345.281898) (xy 341.705195 -345.331511) (xy 341.72056 -345.383843) (xy 341.728322 -345.437829)
			(xy 341.728322 -345.492368) (xy 343.211147 -345.492368) (xy 343.211147 -345.437832) (xy 343.218909 -345.383851)
			(xy 343.234273 -345.331525) (xy 343.256928 -345.281917) (xy 343.286413 -345.236039) (xy 343.322126 -345.194824)
			(xy 343.363342 -345.159111) (xy 343.409221 -345.129627) (xy 343.458828 -345.106972) (xy 343.511155 -345.091608)
			(xy 343.565136 -345.083847) (xy 343.592404 -345.083384) (xy 344.456004 -345.083384) (xy 344.483276 -345.083779)
			(xy 344.537266 -345.091542) (xy 344.589601 -345.106909) (xy 344.639217 -345.129569) (xy 344.685103 -345.159058)
			(xy 344.726325 -345.194778) (xy 344.762044 -345.236) (xy 344.791533 -345.281886) (xy 344.814192 -345.331502)
			(xy 344.829559 -345.383838) (xy 344.837321 -345.437828) (xy 344.837321 -345.492365) (xy 370.80677 -345.492365)
			(xy 370.80677 -345.437835) (xy 370.81453 -345.383859) (xy 370.829893 -345.331538) (xy 370.852545 -345.281935)
			(xy 370.882025 -345.236061) (xy 370.917734 -345.194848) (xy 370.958945 -345.159137) (xy 371.004817 -345.129655)
			(xy 371.054419 -345.107) (xy 371.10674 -345.091635) (xy 371.160715 -345.083872) (xy 371.18798 -345.083384)
			(xy 372.05158 -345.083384) (xy 372.078855 -345.083754) (xy 372.132851 -345.091515) (xy 372.185192 -345.106881)
			(xy 372.234814 -345.129541) (xy 372.280705 -345.159031) (xy 372.321933 -345.194753) (xy 372.357657 -345.235978)
			(xy 372.38715 -345.281869) (xy 372.409812 -345.331489) (xy 372.425181 -345.38383) (xy 372.432944 -345.437825)
			(xy 372.432944 -345.49237) (xy 373.915647 -345.49237) (xy 373.915647 -345.43783) (xy 373.92341 -345.383847)
			(xy 373.938776 -345.331517) (xy 373.961434 -345.281907) (xy 373.990922 -345.236027) (xy 374.026639 -345.194811)
			(xy 374.067859 -345.159098) (xy 374.113742 -345.129615) (xy 374.163355 -345.106962) (xy 374.215686 -345.091601)
			(xy 374.26967 -345.083845) (xy 374.29694 -345.083384) (xy 375.16054 -345.083384) (xy 375.187811 -345.083781)
			(xy 375.241797 -345.091549) (xy 375.294128 -345.106919) (xy 375.343739 -345.12958) (xy 375.38962 -345.159071)
			(xy 375.430838 -345.19479) (xy 375.466553 -345.236012) (xy 375.496039 -345.281896) (xy 375.518695 -345.33151)
			(xy 375.53406 -345.383843) (xy 375.541822 -345.437829) (xy 375.541822 -345.492366) (xy 377.02467 -345.492366)
			(xy 377.02467 -345.437834) (xy 377.032431 -345.383857) (xy 377.047795 -345.331534) (xy 377.070448 -345.281929)
			(xy 377.09993 -345.236054) (xy 377.135641 -345.194841) (xy 377.176854 -345.15913) (xy 377.222729 -345.129648)
			(xy 377.272334 -345.106995) (xy 377.324657 -345.091631) (xy 377.378634 -345.08387) (xy 377.4059 -345.083384)
			(xy 378.2695 -345.083384) (xy 378.296773 -345.083779) (xy 378.350763 -345.091541) (xy 378.403099 -345.106908)
			(xy 378.452715 -345.129567) (xy 378.498601 -345.159057) (xy 378.539824 -345.194776) (xy 378.575543 -345.235999)
			(xy 378.605033 -345.281885) (xy 378.627692 -345.331501) (xy 378.643059 -345.383837) (xy 378.650821 -345.437827)
			(xy 378.650821 -345.492364) (xy 380.13367 -345.492364) (xy 380.13367 -345.437836) (xy 380.14143 -345.383862)
			(xy 380.156791 -345.331542) (xy 380.179442 -345.281941) (xy 380.208921 -345.236067) (xy 380.244627 -345.194855)
			(xy 380.285835 -345.159145) (xy 380.331705 -345.129661) (xy 380.381305 -345.107005) (xy 380.433623 -345.091638)
			(xy 380.487596 -345.083873) (xy 380.51486 -345.083384) (xy 381.37846 -345.083384) (xy 381.405736 -345.083753)
			(xy 381.459734 -345.091511) (xy 381.512078 -345.106876) (xy 381.561702 -345.129534) (xy 381.607596 -345.159024)
			(xy 381.648826 -345.194746) (xy 381.684552 -345.235972) (xy 381.714047 -345.281863) (xy 381.73671 -345.331485)
			(xy 381.75208 -345.383827) (xy 381.759844 -345.437824) (xy 381.759844 -345.492369) (xy 383.242547 -345.492369)
			(xy 383.242547 -345.437831) (xy 383.250309 -345.383849) (xy 383.265675 -345.331521) (xy 383.288331 -345.281913)
			(xy 383.317817 -345.236034) (xy 383.353532 -345.194818) (xy 383.39475 -345.159105) (xy 383.44063 -345.129621)
			(xy 383.49024 -345.106968) (xy 383.542569 -345.091605) (xy 383.596551 -345.083846) (xy 383.62382 -345.083384)
			(xy 384.48742 -345.083384) (xy 384.514692 -345.08378) (xy 384.56868 -345.091545) (xy 384.621013 -345.106914)
			(xy 384.670627 -345.129574) (xy 384.716511 -345.159064) (xy 384.757731 -345.194783) (xy 384.793448 -345.236005)
			(xy 384.822936 -345.281891) (xy 384.845593 -345.331506) (xy 384.860959 -345.38384) (xy 384.868722 -345.437828)
			(xy 384.868722 -345.492365) (xy 386.35157 -345.492365) (xy 386.35157 -345.437835) (xy 386.35933 -345.383859)
			(xy 386.374693 -345.331538) (xy 386.397345 -345.281935) (xy 386.426825 -345.236061) (xy 386.462534 -345.194848)
			(xy 386.503745 -345.159137) (xy 386.549617 -345.129655) (xy 386.599219 -345.107) (xy 386.65154 -345.091635)
			(xy 386.705515 -345.083872) (xy 386.73278 -345.083384) (xy 387.59638 -345.083384) (xy 387.623655 -345.083754)
			(xy 387.677651 -345.091515) (xy 387.729992 -345.106881) (xy 387.779614 -345.129541) (xy 387.825505 -345.159031)
			(xy 387.866733 -345.194753) (xy 387.902457 -345.235978) (xy 387.93195 -345.281869) (xy 387.954612 -345.331489)
			(xy 387.969981 -345.38383) (xy 387.977744 -345.437825) (xy 387.977744 -345.49237) (xy 389.460447 -345.49237)
			(xy 389.460447 -345.43783) (xy 389.46821 -345.383847) (xy 389.483576 -345.331517) (xy 389.506234 -345.281907)
			(xy 389.535722 -345.236027) (xy 389.571439 -345.194811) (xy 389.612659 -345.159098) (xy 389.658542 -345.129615)
			(xy 389.708155 -345.106962) (xy 389.760486 -345.091601) (xy 389.81447 -345.083845) (xy 389.84174 -345.083384)
			(xy 390.70534 -345.083384) (xy 390.732611 -345.083781) (xy 390.786597 -345.091549) (xy 390.838928 -345.106919)
			(xy 390.888539 -345.12958) (xy 390.93442 -345.159071) (xy 390.975638 -345.19479) (xy 391.011353 -345.236012)
			(xy 391.040839 -345.281896) (xy 391.063495 -345.33151) (xy 391.07886 -345.383843) (xy 391.086622 -345.437829)
			(xy 391.086622 -345.492366) (xy 392.56947 -345.492366) (xy 392.56947 -345.437834) (xy 392.577231 -345.383857)
			(xy 392.592595 -345.331534) (xy 392.615248 -345.281929) (xy 392.64473 -345.236054) (xy 392.680441 -345.194841)
			(xy 392.721654 -345.15913) (xy 392.767529 -345.129648) (xy 392.817134 -345.106995) (xy 392.869457 -345.091631)
			(xy 392.923434 -345.08387) (xy 392.9507 -345.083384) (xy 393.8143 -345.083384) (xy 393.841573 -345.083779)
			(xy 393.895563 -345.091541) (xy 393.947899 -345.106908) (xy 393.997515 -345.129567) (xy 394.043401 -345.159057)
			(xy 394.084624 -345.194776) (xy 394.120343 -345.235999) (xy 394.149833 -345.281885) (xy 394.172492 -345.331501)
			(xy 394.187859 -345.383837) (xy 394.195621 -345.437827) (xy 394.195621 -345.492364) (xy 395.67847 -345.492364)
			(xy 395.67847 -345.437836) (xy 395.68623 -345.383862) (xy 395.701591 -345.331542) (xy 395.724242 -345.281941)
			(xy 395.753721 -345.236067) (xy 395.789427 -345.194855) (xy 395.830635 -345.159145) (xy 395.876505 -345.129661)
			(xy 395.926105 -345.107005) (xy 395.978423 -345.091638) (xy 396.032396 -345.083873) (xy 396.05966 -345.083384)
			(xy 396.92326 -345.083384) (xy 396.950536 -345.083753) (xy 397.004534 -345.091511) (xy 397.056878 -345.106876)
			(xy 397.106502 -345.129534) (xy 397.152396 -345.159024) (xy 397.193626 -345.194746) (xy 397.229352 -345.235972)
			(xy 397.258847 -345.281863) (xy 397.28151 -345.331485) (xy 397.29688 -345.383827) (xy 397.304644 -345.437824)
			(xy 397.304644 -345.492369) (xy 398.787347 -345.492369) (xy 398.787347 -345.437831) (xy 398.795109 -345.383849)
			(xy 398.810475 -345.331521) (xy 398.833131 -345.281913) (xy 398.862617 -345.236034) (xy 398.898332 -345.194818)
			(xy 398.93955 -345.159105) (xy 398.98543 -345.129621) (xy 399.03504 -345.106968) (xy 399.087369 -345.091605)
			(xy 399.141351 -345.083846) (xy 399.16862 -345.083384) (xy 400.03222 -345.083384) (xy 400.059492 -345.08378)
			(xy 400.11348 -345.091545) (xy 400.165813 -345.106914) (xy 400.215427 -345.129574) (xy 400.261311 -345.159064)
			(xy 400.302531 -345.194783) (xy 400.338248 -345.236005) (xy 400.367736 -345.281891) (xy 400.390393 -345.331506)
			(xy 400.405759 -345.38384) (xy 400.413522 -345.437828) (xy 400.413522 -345.492365) (xy 401.89637 -345.492365)
			(xy 401.89637 -345.437835) (xy 401.90413 -345.383859) (xy 401.919493 -345.331538) (xy 401.942145 -345.281935)
			(xy 401.971625 -345.236061) (xy 402.007334 -345.194848) (xy 402.048545 -345.159137) (xy 402.094417 -345.129655)
			(xy 402.144019 -345.107) (xy 402.19634 -345.091635) (xy 402.250315 -345.083872) (xy 402.27758 -345.083384)
			(xy 403.14118 -345.083384) (xy 403.168455 -345.083754) (xy 403.222451 -345.091515) (xy 403.274792 -345.106881)
			(xy 403.324414 -345.129541) (xy 403.370305 -345.159031) (xy 403.411533 -345.194753) (xy 403.447257 -345.235978)
			(xy 403.47675 -345.281869) (xy 403.499412 -345.331489) (xy 403.514781 -345.38383) (xy 403.522544 -345.437825)
			(xy 403.522544 -345.492366) (xy 408.91387 -345.492366) (xy 408.91387 -345.437834) (xy 408.921631 -345.383858)
			(xy 408.936994 -345.331535) (xy 408.959647 -345.281932) (xy 408.989128 -345.236057) (xy 409.024838 -345.194844)
			(xy 409.06605 -345.159133) (xy 409.111925 -345.129651) (xy 409.161528 -345.106997) (xy 409.21385 -345.091633)
			(xy 409.267826 -345.083871) (xy 409.295092 -345.083384) (xy 410.158692 -345.083384) (xy 410.185967 -345.083755)
			(xy 410.239961 -345.091517) (xy 410.292301 -345.106885) (xy 410.341921 -345.129544) (xy 410.387811 -345.159035)
			(xy 410.429037 -345.194757) (xy 410.46476 -345.235982) (xy 410.494252 -345.281872) (xy 410.516913 -345.331492)
			(xy 410.532281 -345.383831) (xy 410.540044 -345.437825) (xy 410.540044 -345.492364) (xy 412.02287 -345.492364)
			(xy 412.02287 -345.437836) (xy 412.03063 -345.383863) (xy 412.045991 -345.331544) (xy 412.068641 -345.281943)
			(xy 412.098119 -345.23607) (xy 412.133824 -345.194858) (xy 412.175031 -345.159147) (xy 412.220901 -345.129664)
			(xy 412.270499 -345.107008) (xy 412.322816 -345.09164) (xy 412.376788 -345.083874) (xy 412.404052 -345.083384)
			(xy 413.267652 -345.083384) (xy 413.294929 -345.083752) (xy 413.348927 -345.09151) (xy 413.401272 -345.106874)
			(xy 413.450897 -345.129531) (xy 413.496792 -345.159021) (xy 413.538023 -345.194743) (xy 413.57375 -345.235969)
			(xy 413.603246 -345.281861) (xy 413.625909 -345.331483) (xy 413.64128 -345.383826) (xy 413.649044 -345.437824)
			(xy 413.649044 -345.492368) (xy 415.131747 -345.492368) (xy 415.131747 -345.437832) (xy 415.139509 -345.38385)
			(xy 415.154874 -345.331523) (xy 415.17753 -345.281915) (xy 415.207015 -345.236036) (xy 415.242729 -345.194821)
			(xy 415.283946 -345.159108) (xy 415.329826 -345.129624) (xy 415.379434 -345.10697) (xy 415.431762 -345.091606)
			(xy 415.485744 -345.083847) (xy 415.513012 -345.083384) (xy 416.376612 -345.083384) (xy 416.403884 -345.083779)
			(xy 416.457873 -345.091543) (xy 416.510207 -345.106912) (xy 416.559822 -345.129571) (xy 416.605707 -345.159061)
			(xy 416.646928 -345.194781) (xy 416.682646 -345.236003) (xy 416.712135 -345.281889) (xy 416.734793 -345.331504)
			(xy 416.750159 -345.383839) (xy 416.757921 -345.437828) (xy 416.757921 -345.492365) (xy 418.24077 -345.492365)
			(xy 418.24077 -345.437835) (xy 418.24853 -345.383861) (xy 418.263892 -345.33154) (xy 418.286544 -345.281937)
			(xy 418.316023 -345.236063) (xy 418.351731 -345.194851) (xy 418.392941 -345.15914) (xy 418.438813 -345.129657)
			(xy 418.488413 -345.107002) (xy 418.540733 -345.091636) (xy 418.594707 -345.083872) (xy 418.621972 -345.083384)
			(xy 419.485572 -345.083384) (xy 419.512848 -345.083754) (xy 419.566844 -345.091514) (xy 419.619186 -345.106879)
			(xy 419.668809 -345.129538) (xy 419.714702 -345.159028) (xy 419.75593 -345.19475) (xy 419.791655 -345.235976)
			(xy 419.821149 -345.281866) (xy 419.843811 -345.331487) (xy 419.859181 -345.383829) (xy 419.866944 -345.437824)
			(xy 419.866944 -345.492369) (xy 421.349647 -345.492369) (xy 421.349647 -345.437831) (xy 421.35741 -345.383848)
			(xy 421.372776 -345.331519) (xy 421.395433 -345.281909) (xy 421.42492 -345.23603) (xy 421.460636 -345.194814)
			(xy 421.501855 -345.159101) (xy 421.547738 -345.129617) (xy 421.597349 -345.106964) (xy 421.649679 -345.091603)
			(xy 421.703663 -345.083845) (xy 421.730932 -345.083384) (xy 422.594532 -345.083384) (xy 422.621803 -345.083781)
			(xy 422.67579 -345.091547) (xy 422.728122 -345.106917) (xy 422.777734 -345.129578) (xy 422.823616 -345.159068)
			(xy 422.864835 -345.194788) (xy 422.900551 -345.236009) (xy 422.930038 -345.281894) (xy 422.952694 -345.331508)
			(xy 422.96806 -345.383842) (xy 422.975822 -345.437829) (xy 422.975822 -345.492366) (xy 424.45867 -345.492366)
			(xy 424.45867 -345.437834) (xy 424.466431 -345.383858) (xy 424.481794 -345.331535) (xy 424.504447 -345.281932)
			(xy 424.533928 -345.236057) (xy 424.569638 -345.194844) (xy 424.61085 -345.159133) (xy 424.656725 -345.129651)
			(xy 424.706328 -345.106997) (xy 424.75865 -345.091633) (xy 424.812626 -345.083871) (xy 424.839892 -345.083384)
			(xy 425.703492 -345.083384) (xy 425.730767 -345.083755) (xy 425.784761 -345.091517) (xy 425.837101 -345.106885)
			(xy 425.886721 -345.129544) (xy 425.932611 -345.159035) (xy 425.973837 -345.194757) (xy 426.00956 -345.235982)
			(xy 426.039052 -345.281872) (xy 426.061713 -345.331492) (xy 426.077081 -345.383831) (xy 426.084844 -345.437825)
			(xy 426.084844 -345.492364) (xy 427.56767 -345.492364) (xy 427.56767 -345.437836) (xy 427.57543 -345.383863)
			(xy 427.590791 -345.331544) (xy 427.613441 -345.281943) (xy 427.642919 -345.23607) (xy 427.678624 -345.194858)
			(xy 427.719831 -345.159147) (xy 427.765701 -345.129664) (xy 427.815299 -345.107008) (xy 427.867616 -345.09164)
			(xy 427.921588 -345.083874) (xy 427.948852 -345.083384) (xy 428.812452 -345.083384) (xy 428.839729 -345.083752)
			(xy 428.893727 -345.09151) (xy 428.946072 -345.106874) (xy 428.995697 -345.129531) (xy 429.041592 -345.159021)
			(xy 429.082823 -345.194743) (xy 429.11855 -345.235969) (xy 429.148046 -345.281861) (xy 429.170709 -345.331483)
			(xy 429.18608 -345.383826) (xy 429.193844 -345.437824) (xy 429.193844 -345.492368) (xy 430.676547 -345.492368)
			(xy 430.676547 -345.437832) (xy 430.684309 -345.38385) (xy 430.699674 -345.331523) (xy 430.72233 -345.281915)
			(xy 430.751815 -345.236036) (xy 430.787529 -345.194821) (xy 430.828746 -345.159108) (xy 430.874626 -345.129624)
			(xy 430.924234 -345.10697) (xy 430.976562 -345.091606) (xy 431.030544 -345.083847) (xy 431.057812 -345.083384)
			(xy 431.921412 -345.083384) (xy 431.948684 -345.083779) (xy 432.002673 -345.091543) (xy 432.055007 -345.106912)
			(xy 432.104622 -345.129571) (xy 432.150507 -345.159061) (xy 432.191728 -345.194781) (xy 432.227446 -345.236003)
			(xy 432.256935 -345.281889) (xy 432.279593 -345.331504) (xy 432.294959 -345.383839) (xy 432.302721 -345.437828)
			(xy 432.302721 -345.492365) (xy 433.78557 -345.492365) (xy 433.78557 -345.437835) (xy 433.79333 -345.383861)
			(xy 433.808692 -345.33154) (xy 433.831344 -345.281937) (xy 433.860823 -345.236063) (xy 433.896531 -345.194851)
			(xy 433.937741 -345.15914) (xy 433.983613 -345.129657) (xy 434.033213 -345.107002) (xy 434.085533 -345.091636)
			(xy 434.139507 -345.083872) (xy 434.166772 -345.083384) (xy 435.030372 -345.083384) (xy 435.057648 -345.083754)
			(xy 435.111644 -345.091514) (xy 435.163986 -345.106879) (xy 435.213609 -345.129538) (xy 435.259502 -345.159028)
			(xy 435.30073 -345.19475) (xy 435.336455 -345.235976) (xy 435.365949 -345.281866) (xy 435.388611 -345.331487)
			(xy 435.403981 -345.383829) (xy 435.411744 -345.437824) (xy 435.411744 -345.492369) (xy 436.894447 -345.492369)
			(xy 436.894447 -345.437831) (xy 436.90221 -345.383848) (xy 436.917576 -345.331519) (xy 436.940233 -345.281909)
			(xy 436.96972 -345.23603) (xy 437.005436 -345.194814) (xy 437.046655 -345.159101) (xy 437.092538 -345.129617)
			(xy 437.142149 -345.106964) (xy 437.194479 -345.091603) (xy 437.248463 -345.083845) (xy 437.275732 -345.083384)
			(xy 438.139332 -345.083384) (xy 438.166603 -345.083781) (xy 438.22059 -345.091547) (xy 438.272922 -345.106917)
			(xy 438.322534 -345.129578) (xy 438.368416 -345.159068) (xy 438.409635 -345.194788) (xy 438.445351 -345.236009)
			(xy 438.474838 -345.281894) (xy 438.497494 -345.331508) (xy 438.51286 -345.383842) (xy 438.520622 -345.437829)
			(xy 438.520622 -345.492366) (xy 440.00347 -345.492366) (xy 440.00347 -345.437834) (xy 440.011231 -345.383858)
			(xy 440.026594 -345.331535) (xy 440.049247 -345.281932) (xy 440.078728 -345.236057) (xy 440.114438 -345.194844)
			(xy 440.15565 -345.159133) (xy 440.201525 -345.129651) (xy 440.251128 -345.106997) (xy 440.30345 -345.091633)
			(xy 440.357426 -345.083871) (xy 440.384692 -345.083384) (xy 441.248292 -345.083384) (xy 441.275567 -345.083755)
			(xy 441.329561 -345.091517) (xy 441.381901 -345.106885) (xy 441.431521 -345.129544) (xy 441.477411 -345.159035)
			(xy 441.518637 -345.194757) (xy 441.55436 -345.235982) (xy 441.583852 -345.281872) (xy 441.606513 -345.331492)
			(xy 441.621881 -345.383831) (xy 441.629644 -345.437825) (xy 441.629644 -345.492375) (xy 441.621881 -345.546369)
			(xy 441.606513 -345.598708) (xy 441.583852 -345.648328) (xy 441.55436 -345.694218) (xy 441.518637 -345.735443)
			(xy 441.477411 -345.771165) (xy 441.431521 -345.800656) (xy 441.381901 -345.823315) (xy 441.329561 -345.838683)
			(xy 441.275567 -345.846445) (xy 441.248292 -345.846908) (xy 440.384692 -345.846908) (xy 440.357426 -345.846329)
			(xy 440.30345 -345.838567) (xy 440.251128 -345.823203) (xy 440.201525 -345.800549) (xy 440.15565 -345.771067)
			(xy 440.114438 -345.735356) (xy 440.078728 -345.694143) (xy 440.049247 -345.648268) (xy 440.026594 -345.598665)
			(xy 440.011231 -345.546342) (xy 440.00347 -345.492366) (xy 438.520622 -345.492366) (xy 438.520622 -345.492371)
			(xy 438.51286 -345.546358) (xy 438.497494 -345.598692) (xy 438.474838 -345.648306) (xy 438.445351 -345.694191)
			(xy 438.409635 -345.735412) (xy 438.368416 -345.771132) (xy 438.322534 -345.800622) (xy 438.272922 -345.823283)
			(xy 438.22059 -345.838653) (xy 438.166603 -345.846419) (xy 438.139332 -345.846908) (xy 437.275732 -345.846908)
			(xy 437.248463 -345.846355) (xy 437.194479 -345.838597) (xy 437.142149 -345.823236) (xy 437.092538 -345.800583)
			(xy 437.046655 -345.771099) (xy 437.005436 -345.735386) (xy 436.96972 -345.69417) (xy 436.940233 -345.648291)
			(xy 436.917576 -345.598681) (xy 436.90221 -345.546352) (xy 436.894447 -345.492369) (xy 435.411744 -345.492369)
			(xy 435.411744 -345.492376) (xy 435.403981 -345.546371) (xy 435.388611 -345.598713) (xy 435.365949 -345.648334)
			(xy 435.336455 -345.694224) (xy 435.30073 -345.73545) (xy 435.259502 -345.771172) (xy 435.213609 -345.800662)
			(xy 435.163986 -345.823321) (xy 435.111644 -345.838686) (xy 435.057648 -345.846446) (xy 435.030372 -345.846908)
			(xy 434.166772 -345.846908) (xy 434.139507 -345.846328) (xy 434.085533 -345.838564) (xy 434.033213 -345.823198)
			(xy 433.983613 -345.800543) (xy 433.937741 -345.77106) (xy 433.896531 -345.735349) (xy 433.860823 -345.694137)
			(xy 433.831344 -345.648263) (xy 433.808692 -345.59866) (xy 433.79333 -345.546339) (xy 433.78557 -345.492365)
			(xy 432.302721 -345.492365) (xy 432.302721 -345.492372) (xy 432.294959 -345.546361) (xy 432.279593 -345.598696)
			(xy 432.256935 -345.648311) (xy 432.227446 -345.694197) (xy 432.191728 -345.735419) (xy 432.150507 -345.771139)
			(xy 432.104622 -345.800629) (xy 432.055007 -345.823288) (xy 432.002673 -345.838657) (xy 431.948684 -345.846421)
			(xy 431.921412 -345.846908) (xy 431.057812 -345.846908) (xy 431.030544 -345.846353) (xy 430.976562 -345.838594)
			(xy 430.924234 -345.82323) (xy 430.874626 -345.800576) (xy 430.828746 -345.771092) (xy 430.787529 -345.735379)
			(xy 430.751815 -345.694164) (xy 430.72233 -345.648285) (xy 430.699674 -345.598677) (xy 430.684309 -345.54635)
			(xy 430.676547 -345.492368) (xy 429.193844 -345.492368) (xy 429.193844 -345.492376) (xy 429.18608 -345.546374)
			(xy 429.170709 -345.598717) (xy 429.148046 -345.648339) (xy 429.11855 -345.694231) (xy 429.082823 -345.735457)
			(xy 429.041592 -345.771179) (xy 428.995697 -345.800669) (xy 428.946072 -345.823326) (xy 428.893727 -345.83869)
			(xy 428.839729 -345.846448) (xy 428.812452 -345.846908) (xy 427.948852 -345.846908) (xy 427.921588 -345.846326)
			(xy 427.867616 -345.83856) (xy 427.815299 -345.823192) (xy 427.765701 -345.800536) (xy 427.719831 -345.771053)
			(xy 427.678624 -345.735342) (xy 427.642919 -345.69413) (xy 427.613441 -345.648257) (xy 427.590791 -345.598656)
			(xy 427.57543 -345.546337) (xy 427.56767 -345.492364) (xy 426.084844 -345.492364) (xy 426.084844 -345.492375)
			(xy 426.077081 -345.546369) (xy 426.061713 -345.598708) (xy 426.039052 -345.648328) (xy 426.00956 -345.694218)
			(xy 425.973837 -345.735443) (xy 425.932611 -345.771165) (xy 425.886721 -345.800656) (xy 425.837101 -345.823315)
			(xy 425.784761 -345.838683) (xy 425.730767 -345.846445) (xy 425.703492 -345.846908) (xy 424.839892 -345.846908)
			(xy 424.812626 -345.846329) (xy 424.75865 -345.838567) (xy 424.706328 -345.823203) (xy 424.656725 -345.800549)
			(xy 424.61085 -345.771067) (xy 424.569638 -345.735356) (xy 424.533928 -345.694143) (xy 424.504447 -345.648268)
			(xy 424.481794 -345.598665) (xy 424.466431 -345.546342) (xy 424.45867 -345.492366) (xy 422.975822 -345.492366)
			(xy 422.975822 -345.492371) (xy 422.96806 -345.546358) (xy 422.952694 -345.598692) (xy 422.930038 -345.648306)
			(xy 422.900551 -345.694191) (xy 422.864835 -345.735412) (xy 422.823616 -345.771132) (xy 422.777734 -345.800622)
			(xy 422.728122 -345.823283) (xy 422.67579 -345.838653) (xy 422.621803 -345.846419) (xy 422.594532 -345.846908)
			(xy 421.730932 -345.846908) (xy 421.703663 -345.846355) (xy 421.649679 -345.838597) (xy 421.597349 -345.823236)
			(xy 421.547738 -345.800583) (xy 421.501855 -345.771099) (xy 421.460636 -345.735386) (xy 421.42492 -345.69417)
			(xy 421.395433 -345.648291) (xy 421.372776 -345.598681) (xy 421.35741 -345.546352) (xy 421.349647 -345.492369)
			(xy 419.866944 -345.492369) (xy 419.866944 -345.492376) (xy 419.859181 -345.546371) (xy 419.843811 -345.598713)
			(xy 419.821149 -345.648334) (xy 419.791655 -345.694224) (xy 419.75593 -345.73545) (xy 419.714702 -345.771172)
			(xy 419.668809 -345.800662) (xy 419.619186 -345.823321) (xy 419.566844 -345.838686) (xy 419.512848 -345.846446)
			(xy 419.485572 -345.846908) (xy 418.621972 -345.846908) (xy 418.594707 -345.846328) (xy 418.540733 -345.838564)
			(xy 418.488413 -345.823198) (xy 418.438813 -345.800543) (xy 418.392941 -345.77106) (xy 418.351731 -345.735349)
			(xy 418.316023 -345.694137) (xy 418.286544 -345.648263) (xy 418.263892 -345.59866) (xy 418.24853 -345.546339)
			(xy 418.24077 -345.492365) (xy 416.757921 -345.492365) (xy 416.757921 -345.492372) (xy 416.750159 -345.546361)
			(xy 416.734793 -345.598696) (xy 416.712135 -345.648311) (xy 416.682646 -345.694197) (xy 416.646928 -345.735419)
			(xy 416.605707 -345.771139) (xy 416.559822 -345.800629) (xy 416.510207 -345.823288) (xy 416.457873 -345.838657)
			(xy 416.403884 -345.846421) (xy 416.376612 -345.846908) (xy 415.513012 -345.846908) (xy 415.485744 -345.846353)
			(xy 415.431762 -345.838594) (xy 415.379434 -345.82323) (xy 415.329826 -345.800576) (xy 415.283946 -345.771092)
			(xy 415.242729 -345.735379) (xy 415.207015 -345.694164) (xy 415.17753 -345.648285) (xy 415.154874 -345.598677)
			(xy 415.139509 -345.54635) (xy 415.131747 -345.492368) (xy 413.649044 -345.492368) (xy 413.649044 -345.492376)
			(xy 413.64128 -345.546374) (xy 413.625909 -345.598717) (xy 413.603246 -345.648339) (xy 413.57375 -345.694231)
			(xy 413.538023 -345.735457) (xy 413.496792 -345.771179) (xy 413.450897 -345.800669) (xy 413.401272 -345.823326)
			(xy 413.348927 -345.83869) (xy 413.294929 -345.846448) (xy 413.267652 -345.846908) (xy 412.404052 -345.846908)
			(xy 412.376788 -345.846326) (xy 412.322816 -345.83856) (xy 412.270499 -345.823192) (xy 412.220901 -345.800536)
			(xy 412.175031 -345.771053) (xy 412.133824 -345.735342) (xy 412.098119 -345.69413) (xy 412.068641 -345.648257)
			(xy 412.045991 -345.598656) (xy 412.03063 -345.546337) (xy 412.02287 -345.492364) (xy 410.540044 -345.492364)
			(xy 410.540044 -345.492375) (xy 410.532281 -345.546369) (xy 410.516913 -345.598708) (xy 410.494252 -345.648328)
			(xy 410.46476 -345.694218) (xy 410.429037 -345.735443) (xy 410.387811 -345.771165) (xy 410.341921 -345.800656)
			(xy 410.292301 -345.823315) (xy 410.239961 -345.838683) (xy 410.185967 -345.846445) (xy 410.158692 -345.846908)
			(xy 409.295092 -345.846908) (xy 409.267826 -345.846329) (xy 409.21385 -345.838567) (xy 409.161528 -345.823203)
			(xy 409.111925 -345.800549) (xy 409.06605 -345.771067) (xy 409.024838 -345.735356) (xy 408.989128 -345.694143)
			(xy 408.959647 -345.648268) (xy 408.936994 -345.598665) (xy 408.921631 -345.546342) (xy 408.91387 -345.492366)
			(xy 403.522544 -345.492366) (xy 403.522544 -345.492375) (xy 403.514781 -345.54637) (xy 403.499412 -345.598711)
			(xy 403.47675 -345.648331) (xy 403.447257 -345.694221) (xy 403.411533 -345.735447) (xy 403.370305 -345.771169)
			(xy 403.324414 -345.800659) (xy 403.274792 -345.823319) (xy 403.222451 -345.838685) (xy 403.168455 -345.846446)
			(xy 403.14118 -345.846908) (xy 402.27758 -345.846908) (xy 402.250315 -345.846328) (xy 402.19634 -345.838565)
			(xy 402.144019 -345.8232) (xy 402.094417 -345.800545) (xy 402.048545 -345.771063) (xy 402.007334 -345.735352)
			(xy 401.971625 -345.694139) (xy 401.942145 -345.648265) (xy 401.919493 -345.598662) (xy 401.90413 -345.546341)
			(xy 401.89637 -345.492365) (xy 400.413522 -345.492365) (xy 400.413522 -345.492372) (xy 400.405759 -345.54636)
			(xy 400.390393 -345.598694) (xy 400.367736 -345.648309) (xy 400.338248 -345.694195) (xy 400.302531 -345.735417)
			(xy 400.261311 -345.771136) (xy 400.215427 -345.800626) (xy 400.165813 -345.823286) (xy 400.11348 -345.838655)
			(xy 400.059492 -345.84642) (xy 400.03222 -345.846908) (xy 399.16862 -345.846908) (xy 399.141351 -345.846354)
			(xy 399.087369 -345.838595) (xy 399.03504 -345.823232) (xy 398.98543 -345.800579) (xy 398.93955 -345.771095)
			(xy 398.898332 -345.735382) (xy 398.862617 -345.694166) (xy 398.833131 -345.648287) (xy 398.810475 -345.598679)
			(xy 398.795109 -345.546351) (xy 398.787347 -345.492369) (xy 397.304644 -345.492369) (xy 397.304644 -345.492376)
			(xy 397.29688 -345.546373) (xy 397.28151 -345.598715) (xy 397.258847 -345.648337) (xy 397.229352 -345.694228)
			(xy 397.193626 -345.735454) (xy 397.152396 -345.771176) (xy 397.106502 -345.800666) (xy 397.056878 -345.823324)
			(xy 397.004534 -345.838689) (xy 396.950536 -345.846447) (xy 396.92326 -345.846908) (xy 396.05966 -345.846908)
			(xy 396.032396 -345.846327) (xy 395.978423 -345.838562) (xy 395.926105 -345.823195) (xy 395.876505 -345.800539)
			(xy 395.830635 -345.771055) (xy 395.789427 -345.735345) (xy 395.753721 -345.694133) (xy 395.724242 -345.648259)
			(xy 395.701591 -345.598658) (xy 395.68623 -345.546338) (xy 395.67847 -345.492364) (xy 394.195621 -345.492364)
			(xy 394.195621 -345.492373) (xy 394.187859 -345.546363) (xy 394.172492 -345.598699) (xy 394.149833 -345.648315)
			(xy 394.120343 -345.694201) (xy 394.084624 -345.735424) (xy 394.043401 -345.771143) (xy 393.997515 -345.800633)
			(xy 393.947899 -345.823292) (xy 393.895563 -345.838659) (xy 393.841573 -345.846421) (xy 393.8143 -345.846908)
			(xy 392.9507 -345.846908) (xy 392.923434 -345.84633) (xy 392.869457 -345.838569) (xy 392.817134 -345.823205)
			(xy 392.767529 -345.800552) (xy 392.721654 -345.77107) (xy 392.680441 -345.735359) (xy 392.64473 -345.694146)
			(xy 392.615248 -345.648271) (xy 392.592595 -345.598666) (xy 392.577231 -345.546343) (xy 392.56947 -345.492366)
			(xy 391.086622 -345.492366) (xy 391.086622 -345.492371) (xy 391.07886 -345.546357) (xy 391.063495 -345.59869)
			(xy 391.040839 -345.648304) (xy 391.011353 -345.694188) (xy 390.975638 -345.73541) (xy 390.93442 -345.771129)
			(xy 390.888539 -345.80062) (xy 390.838928 -345.823281) (xy 390.786597 -345.838651) (xy 390.732611 -345.846419)
			(xy 390.70534 -345.846908) (xy 389.84174 -345.846908) (xy 389.81447 -345.846355) (xy 389.760486 -345.838599)
			(xy 389.708155 -345.823238) (xy 389.658542 -345.800585) (xy 389.612659 -345.771102) (xy 389.571439 -345.735389)
			(xy 389.535722 -345.694173) (xy 389.506234 -345.648293) (xy 389.483576 -345.598683) (xy 389.46821 -345.546353)
			(xy 389.460447 -345.49237) (xy 387.977744 -345.49237) (xy 387.977744 -345.492375) (xy 387.969981 -345.54637)
			(xy 387.954612 -345.598711) (xy 387.93195 -345.648331) (xy 387.902457 -345.694221) (xy 387.866733 -345.735447)
			(xy 387.825505 -345.771169) (xy 387.779614 -345.800659) (xy 387.729992 -345.823319) (xy 387.677651 -345.838685)
			(xy 387.623655 -345.846446) (xy 387.59638 -345.846908) (xy 386.73278 -345.846908) (xy 386.705515 -345.846328)
			(xy 386.65154 -345.838565) (xy 386.599219 -345.8232) (xy 386.549617 -345.800545) (xy 386.503745 -345.771063)
			(xy 386.462534 -345.735352) (xy 386.426825 -345.694139) (xy 386.397345 -345.648265) (xy 386.374693 -345.598662)
			(xy 386.35933 -345.546341) (xy 386.35157 -345.492365) (xy 384.868722 -345.492365) (xy 384.868722 -345.492372)
			(xy 384.860959 -345.54636) (xy 384.845593 -345.598694) (xy 384.822936 -345.648309) (xy 384.793448 -345.694195)
			(xy 384.757731 -345.735417) (xy 384.716511 -345.771136) (xy 384.670627 -345.800626) (xy 384.621013 -345.823286)
			(xy 384.56868 -345.838655) (xy 384.514692 -345.84642) (xy 384.48742 -345.846908) (xy 383.62382 -345.846908)
			(xy 383.596551 -345.846354) (xy 383.542569 -345.838595) (xy 383.49024 -345.823232) (xy 383.44063 -345.800579)
			(xy 383.39475 -345.771095) (xy 383.353532 -345.735382) (xy 383.317817 -345.694166) (xy 383.288331 -345.648287)
			(xy 383.265675 -345.598679) (xy 383.250309 -345.546351) (xy 383.242547 -345.492369) (xy 381.759844 -345.492369)
			(xy 381.759844 -345.492376) (xy 381.75208 -345.546373) (xy 381.73671 -345.598715) (xy 381.714047 -345.648337)
			(xy 381.684552 -345.694228) (xy 381.648826 -345.735454) (xy 381.607596 -345.771176) (xy 381.561702 -345.800666)
			(xy 381.512078 -345.823324) (xy 381.459734 -345.838689) (xy 381.405736 -345.846447) (xy 381.37846 -345.846908)
			(xy 380.51486 -345.846908) (xy 380.487596 -345.846327) (xy 380.433623 -345.838562) (xy 380.381305 -345.823195)
			(xy 380.331705 -345.800539) (xy 380.285835 -345.771055) (xy 380.244627 -345.735345) (xy 380.208921 -345.694133)
			(xy 380.179442 -345.648259) (xy 380.156791 -345.598658) (xy 380.14143 -345.546338) (xy 380.13367 -345.492364)
			(xy 378.650821 -345.492364) (xy 378.650821 -345.492373) (xy 378.643059 -345.546363) (xy 378.627692 -345.598699)
			(xy 378.605033 -345.648315) (xy 378.575543 -345.694201) (xy 378.539824 -345.735424) (xy 378.498601 -345.771143)
			(xy 378.452715 -345.800633) (xy 378.403099 -345.823292) (xy 378.350763 -345.838659) (xy 378.296773 -345.846421)
			(xy 378.2695 -345.846908) (xy 377.4059 -345.846908) (xy 377.378634 -345.84633) (xy 377.324657 -345.838569)
			(xy 377.272334 -345.823205) (xy 377.222729 -345.800552) (xy 377.176854 -345.77107) (xy 377.135641 -345.735359)
			(xy 377.09993 -345.694146) (xy 377.070448 -345.648271) (xy 377.047795 -345.598666) (xy 377.032431 -345.546343)
			(xy 377.02467 -345.492366) (xy 375.541822 -345.492366) (xy 375.541822 -345.492371) (xy 375.53406 -345.546357)
			(xy 375.518695 -345.59869) (xy 375.496039 -345.648304) (xy 375.466553 -345.694188) (xy 375.430838 -345.73541)
			(xy 375.38962 -345.771129) (xy 375.343739 -345.80062) (xy 375.294128 -345.823281) (xy 375.241797 -345.838651)
			(xy 375.187811 -345.846419) (xy 375.16054 -345.846908) (xy 374.29694 -345.846908) (xy 374.26967 -345.846355)
			(xy 374.215686 -345.838599) (xy 374.163355 -345.823238) (xy 374.113742 -345.800585) (xy 374.067859 -345.771102)
			(xy 374.026639 -345.735389) (xy 373.990922 -345.694173) (xy 373.961434 -345.648293) (xy 373.938776 -345.598683)
			(xy 373.92341 -345.546353) (xy 373.915647 -345.49237) (xy 372.432944 -345.49237) (xy 372.432944 -345.492375)
			(xy 372.425181 -345.54637) (xy 372.409812 -345.598711) (xy 372.38715 -345.648331) (xy 372.357657 -345.694221)
			(xy 372.321933 -345.735447) (xy 372.280705 -345.771169) (xy 372.234814 -345.800659) (xy 372.185192 -345.823319)
			(xy 372.132851 -345.838685) (xy 372.078855 -345.846446) (xy 372.05158 -345.846908) (xy 371.18798 -345.846908)
			(xy 371.160715 -345.846328) (xy 371.10674 -345.838565) (xy 371.054419 -345.8232) (xy 371.004817 -345.800545)
			(xy 370.958945 -345.771063) (xy 370.917734 -345.735352) (xy 370.882025 -345.694139) (xy 370.852545 -345.648265)
			(xy 370.829893 -345.598662) (xy 370.81453 -345.546341) (xy 370.80677 -345.492365) (xy 344.837321 -345.492365)
			(xy 344.837321 -345.492372) (xy 344.829559 -345.546362) (xy 344.814192 -345.598698) (xy 344.791533 -345.648314)
			(xy 344.762044 -345.6942) (xy 344.726325 -345.735422) (xy 344.685103 -345.771142) (xy 344.639217 -345.800631)
			(xy 344.589601 -345.823291) (xy 344.537266 -345.838658) (xy 344.483276 -345.846421) (xy 344.456004 -345.846908)
			(xy 343.592404 -345.846908) (xy 343.565136 -345.846353) (xy 343.511155 -345.838592) (xy 343.458828 -345.823228)
			(xy 343.409221 -345.800573) (xy 343.363342 -345.771089) (xy 343.322126 -345.735376) (xy 343.286413 -345.694161)
			(xy 343.256928 -345.648283) (xy 343.234273 -345.598675) (xy 343.218909 -345.546349) (xy 343.211147 -345.492368)
			(xy 341.728322 -345.492368) (xy 341.728322 -345.492371) (xy 341.72056 -345.546357) (xy 341.705195 -345.598689)
			(xy 341.682539 -345.648302) (xy 341.653054 -345.694187) (xy 341.617339 -345.735408) (xy 341.576122 -345.771128)
			(xy 341.530241 -345.800618) (xy 341.48063 -345.82328) (xy 341.4283 -345.838651) (xy 341.374315 -345.846418)
			(xy 341.347044 -345.846908) (xy 340.483444 -345.846908) (xy 340.456174 -345.846356) (xy 340.402189 -345.8386)
			(xy 340.349857 -345.823239) (xy 340.300245 -345.800587) (xy 340.254361 -345.771104) (xy 340.213141 -345.735391)
			(xy 340.177423 -345.694174) (xy 340.147935 -345.648294) (xy 340.125276 -345.598684) (xy 340.10991 -345.546354)
			(xy 340.102148 -345.49237) (xy 338.619444 -345.49237) (xy 338.619444 -345.492375) (xy 338.611681 -345.54637)
			(xy 338.596312 -345.59871) (xy 338.57365 -345.64833) (xy 338.544158 -345.69422) (xy 338.508434 -345.735446)
			(xy 338.467207 -345.771167) (xy 338.421316 -345.800658) (xy 338.371695 -345.823318) (xy 338.319354 -345.838684)
			(xy 338.265359 -345.846445) (xy 338.238084 -345.846908) (xy 337.374484 -345.846908) (xy 337.347219 -345.846329)
			(xy 337.293243 -345.838566) (xy 337.240922 -345.823201) (xy 337.19132 -345.800547) (xy 337.145446 -345.771064)
			(xy 337.104236 -345.735353) (xy 337.068526 -345.694141) (xy 337.039046 -345.648266) (xy 337.016393 -345.598663)
			(xy 337.001031 -345.546341) (xy 336.99327 -345.492365) (xy 335.510422 -345.492365) (xy 335.510422 -345.492372)
			(xy 335.50266 -345.54636) (xy 335.487294 -345.598693) (xy 335.464636 -345.648308) (xy 335.435149 -345.694193)
			(xy 335.399432 -345.735415) (xy 335.358213 -345.771135) (xy 335.312329 -345.800625) (xy 335.262716 -345.823285)
			(xy 335.210383 -345.838654) (xy 335.156396 -345.84642) (xy 335.129124 -345.846908) (xy 334.265524 -345.846908)
			(xy 334.238255 -345.846354) (xy 334.184272 -345.838596) (xy 334.131943 -345.823234) (xy 334.082333 -345.80058)
			(xy 334.036452 -345.771097) (xy 333.995234 -345.735383) (xy 333.959518 -345.694168) (xy 333.930031 -345.648288)
			(xy 333.907375 -345.59868) (xy 333.892009 -345.546351) (xy 333.884247 -345.492369) (xy 332.401544 -345.492369)
			(xy 332.401544 -345.492376) (xy 332.39378 -345.546372) (xy 332.37841 -345.598714) (xy 332.355747 -345.648336)
			(xy 332.326253 -345.694227) (xy 332.290527 -345.735453) (xy 332.249298 -345.771174) (xy 332.203404 -345.800665)
			(xy 332.153781 -345.823323) (xy 332.101437 -345.838688) (xy 332.04744 -345.846447) (xy 332.020164 -345.846908)
			(xy 331.156564 -345.846908) (xy 331.1293 -345.846327) (xy 331.075326 -345.838562) (xy 331.023007 -345.823196)
			(xy 330.973408 -345.80054) (xy 330.927537 -345.771057) (xy 330.886329 -345.735346) (xy 330.850622 -345.694134)
			(xy 330.821143 -345.648261) (xy 330.798492 -345.598659) (xy 330.78313 -345.546338) (xy 330.77537 -345.492364)
			(xy 329.292521 -345.492364) (xy 329.292521 -345.492372) (xy 329.284759 -345.546362) (xy 329.269392 -345.598698)
			(xy 329.246733 -345.648314) (xy 329.217244 -345.6942) (xy 329.181525 -345.735422) (xy 329.140303 -345.771142)
			(xy 329.094417 -345.800631) (xy 329.044801 -345.823291) (xy 328.992466 -345.838658) (xy 328.938476 -345.846421)
			(xy 328.911204 -345.846908) (xy 328.047604 -345.846908) (xy 328.020336 -345.846353) (xy 327.966355 -345.838592)
			(xy 327.914028 -345.823228) (xy 327.864421 -345.800573) (xy 327.818542 -345.771089) (xy 327.777326 -345.735376)
			(xy 327.741613 -345.694161) (xy 327.712128 -345.648283) (xy 327.689473 -345.598675) (xy 327.674109 -345.546349)
			(xy 327.666347 -345.492368) (xy 326.183522 -345.492368) (xy 326.183522 -345.492371) (xy 326.17576 -345.546357)
			(xy 326.160395 -345.598689) (xy 326.137739 -345.648302) (xy 326.108254 -345.694187) (xy 326.072539 -345.735408)
			(xy 326.031322 -345.771128) (xy 325.985441 -345.800618) (xy 325.93583 -345.82328) (xy 325.8835 -345.838651)
			(xy 325.829515 -345.846418) (xy 325.802244 -345.846908) (xy 324.938644 -345.846908) (xy 324.911374 -345.846356)
			(xy 324.857389 -345.8386) (xy 324.805057 -345.823239) (xy 324.755445 -345.800587) (xy 324.709561 -345.771104)
			(xy 324.668341 -345.735391) (xy 324.632623 -345.694174) (xy 324.603135 -345.648294) (xy 324.580476 -345.598684)
			(xy 324.56511 -345.546354) (xy 324.557348 -345.49237) (xy 323.074644 -345.49237) (xy 323.074644 -345.492375)
			(xy 323.066881 -345.54637) (xy 323.051512 -345.59871) (xy 323.02885 -345.64833) (xy 322.999358 -345.69422)
			(xy 322.963634 -345.735446) (xy 322.922407 -345.771167) (xy 322.876516 -345.800658) (xy 322.826895 -345.823318)
			(xy 322.774554 -345.838684) (xy 322.720559 -345.846445) (xy 322.693284 -345.846908) (xy 321.829684 -345.846908)
			(xy 321.802419 -345.846329) (xy 321.748443 -345.838566) (xy 321.696122 -345.823201) (xy 321.64652 -345.800547)
			(xy 321.600646 -345.771064) (xy 321.559436 -345.735353) (xy 321.523726 -345.694141) (xy 321.494246 -345.648266)
			(xy 321.471593 -345.598663) (xy 321.456231 -345.546341) (xy 321.44847 -345.492365) (xy 319.965622 -345.492365)
			(xy 319.965622 -345.492372) (xy 319.95786 -345.54636) (xy 319.942494 -345.598693) (xy 319.919836 -345.648308)
			(xy 319.890349 -345.694193) (xy 319.854632 -345.735415) (xy 319.813413 -345.771135) (xy 319.767529 -345.800625)
			(xy 319.717916 -345.823285) (xy 319.665583 -345.838654) (xy 319.611596 -345.84642) (xy 319.584324 -345.846908)
			(xy 318.720724 -345.846908) (xy 318.693455 -345.846354) (xy 318.639472 -345.838596) (xy 318.587143 -345.823234)
			(xy 318.537533 -345.80058) (xy 318.491652 -345.771097) (xy 318.450434 -345.735383) (xy 318.414718 -345.694168)
			(xy 318.385231 -345.648288) (xy 318.362575 -345.59868) (xy 318.347209 -345.546351) (xy 318.339447 -345.492369)
			(xy 316.856744 -345.492369) (xy 316.856744 -345.492376) (xy 316.84898 -345.546372) (xy 316.83361 -345.598714)
			(xy 316.810947 -345.648336) (xy 316.781453 -345.694227) (xy 316.745727 -345.735453) (xy 316.704498 -345.771174)
			(xy 316.658604 -345.800665) (xy 316.608981 -345.823323) (xy 316.556637 -345.838688) (xy 316.50264 -345.846447)
			(xy 316.475364 -345.846908) (xy 315.611764 -345.846908) (xy 315.5845 -345.846327) (xy 315.530526 -345.838562)
			(xy 315.478207 -345.823196) (xy 315.428608 -345.80054) (xy 315.382737 -345.771057) (xy 315.341529 -345.735346)
			(xy 315.305822 -345.694134) (xy 315.276343 -345.648261) (xy 315.253692 -345.598659) (xy 315.23833 -345.546338)
			(xy 315.23057 -345.492364) (xy 313.747721 -345.492364) (xy 313.747721 -345.492372) (xy 313.739959 -345.546362)
			(xy 313.724592 -345.598698) (xy 313.701933 -345.648314) (xy 313.672444 -345.6942) (xy 313.636725 -345.735422)
			(xy 313.595503 -345.771142) (xy 313.549617 -345.800631) (xy 313.500001 -345.823291) (xy 313.447666 -345.838658)
			(xy 313.393676 -345.846421) (xy 313.366404 -345.846908) (xy 312.502804 -345.846908) (xy 312.475536 -345.846353)
			(xy 312.421555 -345.838592) (xy 312.369228 -345.823228) (xy 312.319621 -345.800573) (xy 312.273742 -345.771089)
			(xy 312.232526 -345.735376) (xy 312.196813 -345.694161) (xy 312.167328 -345.648283) (xy 312.144673 -345.598675)
			(xy 312.129309 -345.546349) (xy 312.121547 -345.492368) (xy 300.231621 -345.492368) (xy 300.231621 -345.492373)
			(xy 300.223859 -345.546362) (xy 300.208492 -345.598698) (xy 300.185833 -345.648314) (xy 300.156344 -345.6942)
			(xy 300.120624 -345.735423) (xy 300.079402 -345.771143) (xy 300.033516 -345.800632) (xy 299.9839 -345.823291)
			(xy 299.931564 -345.838658) (xy 299.877575 -345.846421) (xy 299.850302 -345.846908) (xy 298.986702 -345.846908)
			(xy 298.959434 -345.846353) (xy 298.905454 -345.838592) (xy 298.853127 -345.823228) (xy 298.80352 -345.800573)
			(xy 298.757641 -345.771089) (xy 298.716426 -345.735376) (xy 298.680712 -345.69416) (xy 298.651228 -345.648282)
			(xy 298.628573 -345.598675) (xy 298.613209 -345.546348) (xy 298.605447 -345.492368) (xy 297.122622 -345.492368)
			(xy 297.122622 -345.492371) (xy 297.11486 -345.546357) (xy 297.099495 -345.59869) (xy 297.076839 -345.648303)
			(xy 297.047354 -345.694187) (xy 297.011639 -345.735409) (xy 296.970421 -345.771128) (xy 296.92454 -345.800619)
			(xy 296.874929 -345.82328) (xy 296.822598 -345.838651) (xy 296.768613 -345.846419) (xy 296.741342 -345.846908)
			(xy 295.877742 -345.846908) (xy 295.850472 -345.846355) (xy 295.796487 -345.838599) (xy 295.744156 -345.823238)
			(xy 295.694543 -345.800586) (xy 295.64866 -345.771103) (xy 295.60744 -345.73539) (xy 295.571722 -345.694174)
			(xy 295.542234 -345.648293) (xy 295.519576 -345.598683) (xy 295.50421 -345.546354) (xy 295.496448 -345.49237)
			(xy 294.013744 -345.49237) (xy 294.013744 -345.492375) (xy 294.005981 -345.54637) (xy 293.990612 -345.59871)
			(xy 293.96795 -345.648331) (xy 293.938457 -345.694221) (xy 293.902734 -345.735446) (xy 293.861506 -345.771168)
			(xy 293.815615 -345.800659) (xy 293.765994 -345.823318) (xy 293.713652 -345.838685) (xy 293.659657 -345.846446)
			(xy 293.632382 -345.846908) (xy 292.768782 -345.846908) (xy 292.741517 -345.846328) (xy 292.687542 -345.838566)
			(xy 292.635221 -345.823201) (xy 292.585619 -345.800546) (xy 292.539745 -345.771063) (xy 292.498535 -345.735352)
			(xy 292.462826 -345.69414) (xy 292.433345 -345.648266) (xy 292.410693 -345.598663) (xy 292.395331 -345.546341)
			(xy 292.38757 -345.492365) (xy 290.904722 -345.492365) (xy 290.904722 -345.492372) (xy 290.896959 -345.54636)
			(xy 290.881593 -345.598694) (xy 290.858936 -345.648309) (xy 290.829449 -345.694194) (xy 290.793732 -345.735416)
			(xy 290.752512 -345.771136) (xy 290.706628 -345.800626) (xy 290.657015 -345.823286) (xy 290.604681 -345.838655)
			(xy 290.550694 -345.84642) (xy 290.523422 -345.846908) (xy 289.659822 -345.846908) (xy 289.632553 -345.846354)
			(xy 289.57857 -345.838595) (xy 289.526241 -345.823233) (xy 289.476632 -345.800579) (xy 289.430751 -345.771096)
			(xy 289.389533 -345.735383) (xy 289.353817 -345.694167) (xy 289.324331 -345.648288) (xy 289.301675 -345.598679)
			(xy 289.286309 -345.546351) (xy 289.278547 -345.492369) (xy 287.795844 -345.492369) (xy 287.795844 -345.492376)
			(xy 287.78808 -345.546373) (xy 287.77271 -345.598715) (xy 287.750047 -345.648336) (xy 287.720552 -345.694227)
			(xy 287.684827 -345.735453) (xy 287.643597 -345.771175) (xy 287.597703 -345.800665) (xy 287.548079 -345.823323)
			(xy 287.495736 -345.838688) (xy 287.441738 -345.846447) (xy 287.414462 -345.846908) (xy 286.550862 -345.846908)
			(xy 286.523598 -345.846327) (xy 286.469625 -345.838562) (xy 286.417306 -345.823195) (xy 286.367707 -345.80054)
			(xy 286.321836 -345.771056) (xy 286.280628 -345.735345) (xy 286.244921 -345.694134) (xy 286.215442 -345.64826)
			(xy 286.192792 -345.598658) (xy 286.17743 -345.546338) (xy 286.16967 -345.492364) (xy 284.686821 -345.492364)
			(xy 284.686821 -345.492373) (xy 284.679059 -345.546362) (xy 284.663692 -345.598698) (xy 284.641033 -345.648314)
			(xy 284.611544 -345.6942) (xy 284.575824 -345.735423) (xy 284.534602 -345.771143) (xy 284.488716 -345.800632)
			(xy 284.4391 -345.823291) (xy 284.386764 -345.838658) (xy 284.332775 -345.846421) (xy 284.305502 -345.846908)
			(xy 283.441902 -345.846908) (xy 283.414634 -345.846353) (xy 283.360654 -345.838592) (xy 283.308327 -345.823228)
			(xy 283.25872 -345.800573) (xy 283.212841 -345.771089) (xy 283.171626 -345.735376) (xy 283.135912 -345.69416)
			(xy 283.106428 -345.648282) (xy 283.083773 -345.598675) (xy 283.068409 -345.546348) (xy 283.060647 -345.492368)
			(xy 281.577822 -345.492368) (xy 281.577822 -345.492371) (xy 281.57006 -345.546357) (xy 281.554695 -345.59869)
			(xy 281.532039 -345.648303) (xy 281.502554 -345.694187) (xy 281.466839 -345.735409) (xy 281.425621 -345.771128)
			(xy 281.37974 -345.800619) (xy 281.330129 -345.82328) (xy 281.277798 -345.838651) (xy 281.223813 -345.846419)
			(xy 281.196542 -345.846908) (xy 280.332942 -345.846908) (xy 280.305672 -345.846355) (xy 280.251687 -345.838599)
			(xy 280.199356 -345.823238) (xy 280.149743 -345.800586) (xy 280.10386 -345.771103) (xy 280.06264 -345.73539)
			(xy 280.026922 -345.694174) (xy 279.997434 -345.648293) (xy 279.974776 -345.598683) (xy 279.95941 -345.546354)
			(xy 279.951648 -345.49237) (xy 278.468944 -345.49237) (xy 278.468944 -345.492375) (xy 278.461181 -345.54637)
			(xy 278.445812 -345.59871) (xy 278.42315 -345.648331) (xy 278.393657 -345.694221) (xy 278.357934 -345.735446)
			(xy 278.316706 -345.771168) (xy 278.270815 -345.800659) (xy 278.221194 -345.823318) (xy 278.168852 -345.838685)
			(xy 278.114857 -345.846446) (xy 278.087582 -345.846908) (xy 277.223982 -345.846908) (xy 277.196717 -345.846328)
			(xy 277.142742 -345.838566) (xy 277.090421 -345.823201) (xy 277.040819 -345.800546) (xy 276.994945 -345.771063)
			(xy 276.953735 -345.735352) (xy 276.918026 -345.69414) (xy 276.888545 -345.648266) (xy 276.865893 -345.598663)
			(xy 276.850531 -345.546341) (xy 276.84277 -345.492365) (xy 275.359922 -345.492365) (xy 275.359922 -345.492372)
			(xy 275.352159 -345.54636) (xy 275.336793 -345.598694) (xy 275.314136 -345.648309) (xy 275.284649 -345.694194)
			(xy 275.248932 -345.735416) (xy 275.207712 -345.771136) (xy 275.161828 -345.800626) (xy 275.112215 -345.823286)
			(xy 275.059881 -345.838655) (xy 275.005894 -345.84642) (xy 274.978622 -345.846908) (xy 274.115022 -345.846908)
			(xy 274.087753 -345.846354) (xy 274.03377 -345.838595) (xy 273.981441 -345.823233) (xy 273.931832 -345.800579)
			(xy 273.885951 -345.771096) (xy 273.844733 -345.735383) (xy 273.809017 -345.694167) (xy 273.779531 -345.648288)
			(xy 273.756875 -345.598679) (xy 273.741509 -345.546351) (xy 273.733747 -345.492369) (xy 272.251044 -345.492369)
			(xy 272.251044 -345.492376) (xy 272.24328 -345.546373) (xy 272.22791 -345.598715) (xy 272.205247 -345.648336)
			(xy 272.175752 -345.694227) (xy 272.140027 -345.735453) (xy 272.098797 -345.771175) (xy 272.052903 -345.800665)
			(xy 272.003279 -345.823323) (xy 271.950936 -345.838688) (xy 271.896938 -345.846447) (xy 271.869662 -345.846908)
			(xy 271.006062 -345.846908) (xy 270.978798 -345.846327) (xy 270.924825 -345.838562) (xy 270.872506 -345.823195)
			(xy 270.822907 -345.80054) (xy 270.777036 -345.771056) (xy 270.735828 -345.735345) (xy 270.700121 -345.694134)
			(xy 270.670642 -345.64826) (xy 270.647992 -345.598658) (xy 270.63263 -345.546338) (xy 270.62487 -345.492364)
			(xy 269.142021 -345.492364) (xy 269.142021 -345.492373) (xy 269.134259 -345.546362) (xy 269.118892 -345.598698)
			(xy 269.096233 -345.648314) (xy 269.066744 -345.6942) (xy 269.031024 -345.735423) (xy 268.989802 -345.771143)
			(xy 268.943916 -345.800632) (xy 268.8943 -345.823291) (xy 268.841964 -345.838658) (xy 268.787975 -345.846421)
			(xy 268.760702 -345.846908) (xy 267.897102 -345.846908) (xy 267.869834 -345.846353) (xy 267.815854 -345.838592)
			(xy 267.763527 -345.823228) (xy 267.71392 -345.800573) (xy 267.668041 -345.771089) (xy 267.626826 -345.735376)
			(xy 267.591112 -345.69416) (xy 267.561628 -345.648282) (xy 267.538973 -345.598675) (xy 267.523609 -345.546348)
			(xy 267.515847 -345.492368) (xy 197.629644 -345.492368) (xy 197.629644 -345.492376) (xy 197.621881 -345.546371)
			(xy 197.606511 -345.598713) (xy 197.583849 -345.648334) (xy 197.554355 -345.694224) (xy 197.51863 -345.73545)
			(xy 197.477402 -345.771172) (xy 197.431509 -345.800662) (xy 197.381886 -345.823321) (xy 197.329544 -345.838686)
			(xy 197.275548 -345.846446) (xy 197.248272 -345.846908) (xy 196.384672 -345.846908) (xy 196.357407 -345.846328)
			(xy 196.303433 -345.838564) (xy 196.251113 -345.823198) (xy 196.201513 -345.800543) (xy 196.155641 -345.77106)
			(xy 196.114431 -345.735349) (xy 196.078723 -345.694137) (xy 196.049244 -345.648263) (xy 196.026592 -345.59866)
			(xy 196.01123 -345.546339) (xy 196.00347 -345.492365) (xy 194.520621 -345.492365) (xy 194.520621 -345.492372)
			(xy 194.512859 -345.546361) (xy 194.497493 -345.598696) (xy 194.474835 -345.648311) (xy 194.445346 -345.694197)
			(xy 194.409628 -345.735419) (xy 194.368407 -345.771139) (xy 194.322522 -345.800629) (xy 194.272907 -345.823288)
			(xy 194.220573 -345.838657) (xy 194.166584 -345.846421) (xy 194.139312 -345.846908) (xy 193.275712 -345.846908)
			(xy 193.248444 -345.846353) (xy 193.194462 -345.838594) (xy 193.142134 -345.82323) (xy 193.092526 -345.800576)
			(xy 193.046646 -345.771092) (xy 193.005429 -345.735379) (xy 192.969715 -345.694164) (xy 192.94023 -345.648285)
			(xy 192.917574 -345.598677) (xy 192.902209 -345.54635) (xy 192.894447 -345.492368) (xy 191.411744 -345.492368)
			(xy 191.411744 -345.492376) (xy 191.40398 -345.546374) (xy 191.388609 -345.598717) (xy 191.365946 -345.648339)
			(xy 191.33645 -345.694231) (xy 191.300723 -345.735457) (xy 191.259492 -345.771179) (xy 191.213597 -345.800669)
			(xy 191.163972 -345.823326) (xy 191.111627 -345.83869) (xy 191.057629 -345.846448) (xy 191.030352 -345.846908)
			(xy 190.166752 -345.846908) (xy 190.139488 -345.846326) (xy 190.085516 -345.83856) (xy 190.033199 -345.823192)
			(xy 189.983601 -345.800536) (xy 189.937731 -345.771053) (xy 189.896524 -345.735342) (xy 189.860819 -345.69413)
			(xy 189.831341 -345.648257) (xy 189.808691 -345.598656) (xy 189.79333 -345.546337) (xy 189.78557 -345.492364)
			(xy 188.302744 -345.492364) (xy 188.302744 -345.492375) (xy 188.294981 -345.546369) (xy 188.279613 -345.598708)
			(xy 188.256952 -345.648328) (xy 188.22746 -345.694218) (xy 188.191737 -345.735443) (xy 188.150511 -345.771165)
			(xy 188.104621 -345.800656) (xy 188.055001 -345.823315) (xy 188.002661 -345.838683) (xy 187.948667 -345.846445)
			(xy 187.921392 -345.846908) (xy 187.057792 -345.846908) (xy 187.030526 -345.846329) (xy 186.97655 -345.838567)
			(xy 186.924228 -345.823203) (xy 186.874625 -345.800549) (xy 186.82875 -345.771067) (xy 186.787538 -345.735356)
			(xy 186.751828 -345.694143) (xy 186.722347 -345.648268) (xy 186.699694 -345.598665) (xy 186.684331 -345.546342)
			(xy 186.67657 -345.492366) (xy 185.193722 -345.492366) (xy 185.193722 -345.492371) (xy 185.18596 -345.546358)
			(xy 185.170594 -345.598692) (xy 185.147938 -345.648306) (xy 185.118451 -345.694191) (xy 185.082735 -345.735412)
			(xy 185.041516 -345.771132) (xy 184.995634 -345.800622) (xy 184.946022 -345.823283) (xy 184.89369 -345.838653)
			(xy 184.839703 -345.846419) (xy 184.812432 -345.846908) (xy 183.948832 -345.846908) (xy 183.921563 -345.846355)
			(xy 183.867579 -345.838597) (xy 183.815249 -345.823236) (xy 183.765638 -345.800583) (xy 183.719755 -345.771099)
			(xy 183.678536 -345.735386) (xy 183.64282 -345.69417) (xy 183.613333 -345.648291) (xy 183.590676 -345.598681)
			(xy 183.57531 -345.546352) (xy 183.567547 -345.492369) (xy 182.084844 -345.492369) (xy 182.084844 -345.492376)
			(xy 182.077081 -345.546371) (xy 182.061711 -345.598713) (xy 182.039049 -345.648334) (xy 182.009555 -345.694224)
			(xy 181.97383 -345.73545) (xy 181.932602 -345.771172) (xy 181.886709 -345.800662) (xy 181.837086 -345.823321)
			(xy 181.784744 -345.838686) (xy 181.730748 -345.846446) (xy 181.703472 -345.846908) (xy 180.839872 -345.846908)
			(xy 180.812607 -345.846328) (xy 180.758633 -345.838564) (xy 180.706313 -345.823198) (xy 180.656713 -345.800543)
			(xy 180.610841 -345.77106) (xy 180.569631 -345.735349) (xy 180.533923 -345.694137) (xy 180.504444 -345.648263)
			(xy 180.481792 -345.59866) (xy 180.46643 -345.546339) (xy 180.45867 -345.492365) (xy 178.975821 -345.492365)
			(xy 178.975821 -345.492372) (xy 178.968059 -345.546361) (xy 178.952693 -345.598696) (xy 178.930035 -345.648311)
			(xy 178.900546 -345.694197) (xy 178.864828 -345.735419) (xy 178.823607 -345.771139) (xy 178.777722 -345.800629)
			(xy 178.728107 -345.823288) (xy 178.675773 -345.838657) (xy 178.621784 -345.846421) (xy 178.594512 -345.846908)
			(xy 177.730912 -345.846908) (xy 177.703644 -345.846353) (xy 177.649662 -345.838594) (xy 177.597334 -345.82323)
			(xy 177.547726 -345.800576) (xy 177.501846 -345.771092) (xy 177.460629 -345.735379) (xy 177.424915 -345.694164)
			(xy 177.39543 -345.648285) (xy 177.372774 -345.598677) (xy 177.357409 -345.54635) (xy 177.349647 -345.492368)
			(xy 175.866944 -345.492368) (xy 175.866944 -345.492376) (xy 175.85918 -345.546374) (xy 175.843809 -345.598717)
			(xy 175.821146 -345.648339) (xy 175.79165 -345.694231) (xy 175.755923 -345.735457) (xy 175.714692 -345.771179)
			(xy 175.668797 -345.800669) (xy 175.619172 -345.823326) (xy 175.566827 -345.83869) (xy 175.512829 -345.846448)
			(xy 175.485552 -345.846908) (xy 174.621952 -345.846908) (xy 174.594688 -345.846326) (xy 174.540716 -345.83856)
			(xy 174.488399 -345.823192) (xy 174.438801 -345.800536) (xy 174.392931 -345.771053) (xy 174.351724 -345.735342)
			(xy 174.316019 -345.69413) (xy 174.286541 -345.648257) (xy 174.263891 -345.598656) (xy 174.24853 -345.546337)
			(xy 174.24077 -345.492364) (xy 172.757944 -345.492364) (xy 172.757944 -345.492375) (xy 172.750181 -345.546369)
			(xy 172.734813 -345.598708) (xy 172.712152 -345.648328) (xy 172.68266 -345.694218) (xy 172.646937 -345.735443)
			(xy 172.605711 -345.771165) (xy 172.559821 -345.800656) (xy 172.510201 -345.823315) (xy 172.457861 -345.838683)
			(xy 172.403867 -345.846445) (xy 172.376592 -345.846908) (xy 171.512992 -345.846908) (xy 171.485726 -345.846329)
			(xy 171.43175 -345.838567) (xy 171.379428 -345.823203) (xy 171.329825 -345.800549) (xy 171.28395 -345.771067)
			(xy 171.242738 -345.735356) (xy 171.207028 -345.694143) (xy 171.177547 -345.648268) (xy 171.154894 -345.598665)
			(xy 171.139531 -345.546342) (xy 171.13177 -345.492366) (xy 169.648922 -345.492366) (xy 169.648922 -345.492371)
			(xy 169.64116 -345.546358) (xy 169.625794 -345.598692) (xy 169.603138 -345.648306) (xy 169.573651 -345.694191)
			(xy 169.537935 -345.735412) (xy 169.496716 -345.771132) (xy 169.450834 -345.800622) (xy 169.401222 -345.823283)
			(xy 169.34889 -345.838653) (xy 169.294903 -345.846419) (xy 169.267632 -345.846908) (xy 168.404032 -345.846908)
			(xy 168.376763 -345.846355) (xy 168.322779 -345.838597) (xy 168.270449 -345.823236) (xy 168.220838 -345.800583)
			(xy 168.174955 -345.771099) (xy 168.133736 -345.735386) (xy 168.09802 -345.69417) (xy 168.068533 -345.648291)
			(xy 168.045876 -345.598681) (xy 168.03051 -345.546352) (xy 168.022747 -345.492369) (xy 166.540044 -345.492369)
			(xy 166.540044 -345.492376) (xy 166.532281 -345.546371) (xy 166.516911 -345.598713) (xy 166.494249 -345.648334)
			(xy 166.464755 -345.694224) (xy 166.42903 -345.73545) (xy 166.387802 -345.771172) (xy 166.341909 -345.800662)
			(xy 166.292286 -345.823321) (xy 166.239944 -345.838686) (xy 166.185948 -345.846446) (xy 166.158672 -345.846908)
			(xy 165.295072 -345.846908) (xy 165.267807 -345.846328) (xy 165.213833 -345.838564) (xy 165.161513 -345.823198)
			(xy 165.111913 -345.800543) (xy 165.066041 -345.77106) (xy 165.024831 -345.735349) (xy 164.989123 -345.694137)
			(xy 164.959644 -345.648263) (xy 164.936992 -345.59866) (xy 164.92163 -345.546339) (xy 164.91387 -345.492365)
			(xy 144.196621 -345.492365) (xy 144.196621 -345.492372) (xy 144.188859 -345.546362) (xy 144.173492 -345.598697)
			(xy 144.150834 -345.648312) (xy 144.121345 -345.694199) (xy 144.085627 -345.735421) (xy 144.044405 -345.77114)
			(xy 143.99852 -345.80063) (xy 143.948904 -345.82329) (xy 143.89657 -345.838657) (xy 143.84258 -345.846421)
			(xy 143.815308 -345.846908) (xy 142.951708 -345.846908) (xy 142.92444 -345.846353) (xy 142.870459 -345.838593)
			(xy 142.818131 -345.823229) (xy 142.768523 -345.800575) (xy 142.722644 -345.771091) (xy 142.681428 -345.735378)
			(xy 142.645714 -345.694162) (xy 142.616229 -345.648284) (xy 142.593574 -345.598676) (xy 142.578209 -345.546349)
			(xy 142.570447 -345.492368) (xy 141.087622 -345.492368) (xy 141.087622 -345.49237) (xy 141.07986 -345.546356)
			(xy 141.064495 -345.598688) (xy 141.04184 -345.648301) (xy 141.012355 -345.694185) (xy 140.976641 -345.735407)
			(xy 140.935424 -345.771126) (xy 140.889543 -345.800617) (xy 140.839933 -345.823279) (xy 140.787603 -345.83865)
			(xy 140.733618 -345.846418) (xy 140.706348 -345.846908) (xy 139.842748 -345.846908) (xy 139.815478 -345.846356)
			(xy 139.761492 -345.8386) (xy 139.70916 -345.82324) (xy 139.659547 -345.800588) (xy 139.613663 -345.771105)
			(xy 139.572442 -345.735392) (xy 139.536724 -345.694176) (xy 139.507235 -345.648295) (xy 139.484577 -345.598685)
			(xy 139.46921 -345.546354) (xy 139.461448 -345.49237) (xy 137.978744 -345.49237) (xy 137.978744 -345.492375)
			(xy 137.970981 -345.546369) (xy 137.955612 -345.598709) (xy 137.932951 -345.648329) (xy 137.903459 -345.694219)
			(xy 137.867736 -345.735444) (xy 137.826509 -345.771166) (xy 137.780619 -345.800657) (xy 137.730998 -345.823316)
			(xy 137.678658 -345.838684) (xy 137.624663 -345.846445) (xy 137.597388 -345.846908) (xy 136.733788 -345.846908)
			(xy 136.706522 -345.846329) (xy 136.652547 -345.838567) (xy 136.600225 -345.823202) (xy 136.550622 -345.800548)
			(xy 136.504748 -345.771065) (xy 136.463537 -345.735354) (xy 136.427827 -345.694142) (xy 136.398346 -345.648267)
			(xy 136.375694 -345.598664) (xy 136.360331 -345.546342) (xy 136.35257 -345.492366) (xy 134.869722 -345.492366)
			(xy 134.869722 -345.492371) (xy 134.86196 -345.546359) (xy 134.846594 -345.598693) (xy 134.823937 -345.648307)
			(xy 134.79445 -345.694192) (xy 134.758734 -345.735414) (xy 134.717514 -345.771133) (xy 134.671632 -345.800624)
			(xy 134.622019 -345.823284) (xy 134.569686 -345.838654) (xy 134.515699 -345.84642) (xy 134.488428 -345.846908)
			(xy 133.624828 -345.846908) (xy 133.597559 -345.846355) (xy 133.543576 -345.838597) (xy 133.491246 -345.823235)
			(xy 133.441635 -345.800581) (xy 133.395753 -345.771098) (xy 133.354535 -345.735385) (xy 133.318819 -345.694169)
			(xy 133.289332 -345.648289) (xy 133.266675 -345.59868) (xy 133.251309 -345.546352) (xy 133.243547 -345.492369)
			(xy 131.760844 -345.492369) (xy 131.760844 -345.492376) (xy 131.75308 -345.546372) (xy 131.737711 -345.598713)
			(xy 131.715048 -345.648335) (xy 131.685554 -345.694225) (xy 131.649829 -345.735451) (xy 131.6086 -345.771173)
			(xy 131.562707 -345.800663) (xy 131.513083 -345.823322) (xy 131.460741 -345.838687) (xy 131.406744 -345.846447)
			(xy 131.379468 -345.846908) (xy 130.515868 -345.846908) (xy 130.488603 -345.846328) (xy 130.43463 -345.838563)
			(xy 130.38231 -345.823197) (xy 130.33271 -345.800542) (xy 130.286839 -345.771058) (xy 130.24563 -345.735347)
			(xy 130.209922 -345.694136) (xy 130.180443 -345.648262) (xy 130.157792 -345.59866) (xy 130.14243 -345.546339)
			(xy 130.13467 -345.492365) (xy 128.651821 -345.492365) (xy 128.651821 -345.492372) (xy 128.644059 -345.546362)
			(xy 128.628692 -345.598697) (xy 128.606034 -345.648312) (xy 128.576545 -345.694199) (xy 128.540827 -345.735421)
			(xy 128.499605 -345.77114) (xy 128.45372 -345.80063) (xy 128.404104 -345.82329) (xy 128.35177 -345.838657)
			(xy 128.29778 -345.846421) (xy 128.270508 -345.846908) (xy 127.406908 -345.846908) (xy 127.37964 -345.846353)
			(xy 127.325659 -345.838593) (xy 127.273331 -345.823229) (xy 127.223723 -345.800575) (xy 127.177844 -345.771091)
			(xy 127.136628 -345.735378) (xy 127.100914 -345.694162) (xy 127.071429 -345.648284) (xy 127.048774 -345.598676)
			(xy 127.033409 -345.546349) (xy 127.025647 -345.492368) (xy 125.542822 -345.492368) (xy 125.542822 -345.49237)
			(xy 125.53506 -345.546356) (xy 125.519695 -345.598688) (xy 125.49704 -345.648301) (xy 125.467555 -345.694185)
			(xy 125.431841 -345.735407) (xy 125.390624 -345.771126) (xy 125.344743 -345.800617) (xy 125.295133 -345.823279)
			(xy 125.242803 -345.83865) (xy 125.188818 -345.846418) (xy 125.161548 -345.846908) (xy 124.297948 -345.846908)
			(xy 124.270678 -345.846356) (xy 124.216692 -345.8386) (xy 124.16436 -345.82324) (xy 124.114747 -345.800588)
			(xy 124.068863 -345.771105) (xy 124.027642 -345.735392) (xy 123.991924 -345.694176) (xy 123.962435 -345.648295)
			(xy 123.939777 -345.598685) (xy 123.92441 -345.546354) (xy 123.916648 -345.49237) (xy 122.433944 -345.49237)
			(xy 122.433944 -345.492375) (xy 122.426181 -345.546369) (xy 122.410812 -345.598709) (xy 122.388151 -345.648329)
			(xy 122.358659 -345.694219) (xy 122.322936 -345.735444) (xy 122.281709 -345.771166) (xy 122.235819 -345.800657)
			(xy 122.186198 -345.823316) (xy 122.133858 -345.838684) (xy 122.079863 -345.846445) (xy 122.052588 -345.846908)
			(xy 121.188988 -345.846908) (xy 121.161722 -345.846329) (xy 121.107747 -345.838567) (xy 121.055425 -345.823202)
			(xy 121.005822 -345.800548) (xy 120.959948 -345.771065) (xy 120.918737 -345.735354) (xy 120.883027 -345.694142)
			(xy 120.853546 -345.648267) (xy 120.830894 -345.598664) (xy 120.815531 -345.546342) (xy 120.80777 -345.492366)
			(xy 119.324922 -345.492366) (xy 119.324922 -345.492371) (xy 119.31716 -345.546359) (xy 119.301794 -345.598693)
			(xy 119.279137 -345.648307) (xy 119.24965 -345.694192) (xy 119.213934 -345.735414) (xy 119.172714 -345.771133)
			(xy 119.126832 -345.800624) (xy 119.077219 -345.823284) (xy 119.024886 -345.838654) (xy 118.970899 -345.84642)
			(xy 118.943628 -345.846908) (xy 118.080028 -345.846908) (xy 118.052759 -345.846355) (xy 117.998776 -345.838597)
			(xy 117.946446 -345.823235) (xy 117.896835 -345.800581) (xy 117.850953 -345.771098) (xy 117.809735 -345.735385)
			(xy 117.774019 -345.694169) (xy 117.744532 -345.648289) (xy 117.721875 -345.59868) (xy 117.706509 -345.546352)
			(xy 117.698747 -345.492369) (xy 116.216044 -345.492369) (xy 116.216044 -345.492376) (xy 116.20828 -345.546372)
			(xy 116.192911 -345.598713) (xy 116.170248 -345.648335) (xy 116.140754 -345.694225) (xy 116.105029 -345.735451)
			(xy 116.0638 -345.771173) (xy 116.017907 -345.800663) (xy 115.968283 -345.823322) (xy 115.915941 -345.838687)
			(xy 115.861944 -345.846447) (xy 115.834668 -345.846908) (xy 114.971068 -345.846908) (xy 114.943803 -345.846328)
			(xy 114.88983 -345.838563) (xy 114.83751 -345.823197) (xy 114.78791 -345.800542) (xy 114.742039 -345.771058)
			(xy 114.70083 -345.735347) (xy 114.665122 -345.694136) (xy 114.635643 -345.648262) (xy 114.612992 -345.59866)
			(xy 114.59763 -345.546339) (xy 114.58987 -345.492365) (xy 113.107021 -345.492365) (xy 113.107021 -345.492372)
			(xy 113.099259 -345.546362) (xy 113.083892 -345.598697) (xy 113.061234 -345.648312) (xy 113.031745 -345.694199)
			(xy 112.996027 -345.735421) (xy 112.954805 -345.77114) (xy 112.90892 -345.80063) (xy 112.859304 -345.82329)
			(xy 112.80697 -345.838657) (xy 112.75298 -345.846421) (xy 112.725708 -345.846908) (xy 111.862108 -345.846908)
			(xy 111.83484 -345.846353) (xy 111.780859 -345.838593) (xy 111.728531 -345.823229) (xy 111.678923 -345.800575)
			(xy 111.633044 -345.771091) (xy 111.591828 -345.735378) (xy 111.556114 -345.694162) (xy 111.526629 -345.648284)
			(xy 111.503974 -345.598676) (xy 111.488609 -345.546349) (xy 111.480847 -345.492368) (xy 93.706722 -345.492368)
			(xy 93.706722 -345.492371) (xy 93.69896 -345.546357) (xy 93.683595 -345.59869) (xy 93.660939 -345.648303)
			(xy 93.631454 -345.694187) (xy 93.595739 -345.735409) (xy 93.554521 -345.771128) (xy 93.50864 -345.800619)
			(xy 93.459029 -345.82328) (xy 93.406698 -345.838651) (xy 93.352713 -345.846419) (xy 93.325442 -345.846908)
			(xy 92.461842 -345.846908) (xy 92.434572 -345.846355) (xy 92.380587 -345.838599) (xy 92.328256 -345.823238)
			(xy 92.278643 -345.800586) (xy 92.23276 -345.771103) (xy 92.19154 -345.73539) (xy 92.155822 -345.694174)
			(xy 92.126334 -345.648293) (xy 92.103676 -345.598683) (xy 92.08831 -345.546354) (xy 92.080548 -345.49237)
			(xy 90.597844 -345.49237) (xy 90.597844 -345.492375) (xy 90.590081 -345.54637) (xy 90.574712 -345.59871)
			(xy 90.55205 -345.648331) (xy 90.522557 -345.694221) (xy 90.486834 -345.735446) (xy 90.445606 -345.771168)
			(xy 90.399715 -345.800659) (xy 90.350094 -345.823318) (xy 90.297752 -345.838685) (xy 90.243757 -345.846446)
			(xy 90.216482 -345.846908) (xy 89.352882 -345.846908) (xy 89.325617 -345.846328) (xy 89.271642 -345.838566)
			(xy 89.219321 -345.823201) (xy 89.169719 -345.800546) (xy 89.123845 -345.771063) (xy 89.082635 -345.735352)
			(xy 89.046926 -345.69414) (xy 89.017445 -345.648266) (xy 88.994793 -345.598663) (xy 88.979431 -345.546341)
			(xy 88.97167 -345.492365) (xy 87.488822 -345.492365) (xy 87.488822 -345.492372) (xy 87.481059 -345.54636)
			(xy 87.465693 -345.598694) (xy 87.443036 -345.648309) (xy 87.413549 -345.694194) (xy 87.377832 -345.735416)
			(xy 87.336612 -345.771136) (xy 87.290728 -345.800626) (xy 87.241115 -345.823286) (xy 87.188781 -345.838655)
			(xy 87.134794 -345.84642) (xy 87.107522 -345.846908) (xy 86.243922 -345.846908) (xy 86.216653 -345.846354)
			(xy 86.16267 -345.838595) (xy 86.110341 -345.823233) (xy 86.060732 -345.800579) (xy 86.014851 -345.771096)
			(xy 85.973633 -345.735383) (xy 85.937917 -345.694167) (xy 85.908431 -345.648288) (xy 85.885775 -345.598679)
			(xy 85.870409 -345.546351) (xy 85.862647 -345.492369) (xy 84.379944 -345.492369) (xy 84.379944 -345.492376)
			(xy 84.37218 -345.546373) (xy 84.35681 -345.598715) (xy 84.334147 -345.648336) (xy 84.304652 -345.694227)
			(xy 84.268927 -345.735453) (xy 84.227697 -345.771175) (xy 84.181803 -345.800665) (xy 84.132179 -345.823323)
			(xy 84.079836 -345.838688) (xy 84.025838 -345.846447) (xy 83.998562 -345.846908) (xy 83.134962 -345.846908)
			(xy 83.107698 -345.846327) (xy 83.053725 -345.838562) (xy 83.001406 -345.823195) (xy 82.951807 -345.80054)
			(xy 82.905936 -345.771056) (xy 82.864728 -345.735345) (xy 82.829021 -345.694134) (xy 82.799542 -345.64826)
			(xy 82.776892 -345.598658) (xy 82.76153 -345.546338) (xy 82.75377 -345.492364) (xy 81.270921 -345.492364)
			(xy 81.270921 -345.492373) (xy 81.263159 -345.546362) (xy 81.247792 -345.598698) (xy 81.225133 -345.648314)
			(xy 81.195644 -345.6942) (xy 81.159924 -345.735423) (xy 81.118702 -345.771143) (xy 81.072816 -345.800632)
			(xy 81.0232 -345.823291) (xy 80.970864 -345.838658) (xy 80.916875 -345.846421) (xy 80.889602 -345.846908)
			(xy 80.026002 -345.846908) (xy 79.998734 -345.846353) (xy 79.944754 -345.838592) (xy 79.892427 -345.823228)
			(xy 79.84282 -345.800573) (xy 79.796941 -345.771089) (xy 79.755726 -345.735376) (xy 79.720012 -345.69416)
			(xy 79.690528 -345.648282) (xy 79.667873 -345.598675) (xy 79.652509 -345.546348) (xy 79.644747 -345.492368)
			(xy 78.161922 -345.492368) (xy 78.161922 -345.492371) (xy 78.15416 -345.546357) (xy 78.138795 -345.59869)
			(xy 78.116139 -345.648303) (xy 78.086654 -345.694187) (xy 78.050939 -345.735409) (xy 78.009721 -345.771128)
			(xy 77.96384 -345.800619) (xy 77.914229 -345.82328) (xy 77.861898 -345.838651) (xy 77.807913 -345.846419)
			(xy 77.780642 -345.846908) (xy 76.917042 -345.846908) (xy 76.889772 -345.846355) (xy 76.835787 -345.838599)
			(xy 76.783456 -345.823238) (xy 76.733843 -345.800586) (xy 76.68796 -345.771103) (xy 76.64674 -345.73539)
			(xy 76.611022 -345.694174) (xy 76.581534 -345.648293) (xy 76.558876 -345.598683) (xy 76.54351 -345.546354)
			(xy 76.535748 -345.49237) (xy 75.053044 -345.49237) (xy 75.053044 -345.492375) (xy 75.045281 -345.54637)
			(xy 75.029912 -345.59871) (xy 75.00725 -345.648331) (xy 74.977757 -345.694221) (xy 74.942034 -345.735446)
			(xy 74.900806 -345.771168) (xy 74.854915 -345.800659) (xy 74.805294 -345.823318) (xy 74.752952 -345.838685)
			(xy 74.698957 -345.846446) (xy 74.671682 -345.846908) (xy 73.808082 -345.846908) (xy 73.780817 -345.846328)
			(xy 73.726842 -345.838566) (xy 73.674521 -345.823201) (xy 73.624919 -345.800546) (xy 73.579045 -345.771063)
			(xy 73.537835 -345.735352) (xy 73.502126 -345.69414) (xy 73.472645 -345.648266) (xy 73.449993 -345.598663)
			(xy 73.434631 -345.546341) (xy 73.42687 -345.492365) (xy 71.944022 -345.492365) (xy 71.944022 -345.492372)
			(xy 71.936259 -345.54636) (xy 71.920893 -345.598694) (xy 71.898236 -345.648309) (xy 71.868749 -345.694194)
			(xy 71.833032 -345.735416) (xy 71.791812 -345.771136) (xy 71.745928 -345.800626) (xy 71.696315 -345.823286)
			(xy 71.643981 -345.838655) (xy 71.589994 -345.84642) (xy 71.562722 -345.846908) (xy 70.699122 -345.846908)
			(xy 70.671853 -345.846354) (xy 70.61787 -345.838595) (xy 70.565541 -345.823233) (xy 70.515932 -345.800579)
			(xy 70.470051 -345.771096) (xy 70.428833 -345.735383) (xy 70.393117 -345.694167) (xy 70.363631 -345.648288)
			(xy 70.340975 -345.598679) (xy 70.325609 -345.546351) (xy 70.317847 -345.492369) (xy 68.835144 -345.492369)
			(xy 68.835144 -345.492376) (xy 68.82738 -345.546373) (xy 68.81201 -345.598715) (xy 68.789347 -345.648336)
			(xy 68.759852 -345.694227) (xy 68.724127 -345.735453) (xy 68.682897 -345.771175) (xy 68.637003 -345.800665)
			(xy 68.587379 -345.823323) (xy 68.535036 -345.838688) (xy 68.481038 -345.846447) (xy 68.453762 -345.846908)
			(xy 67.590162 -345.846908) (xy 67.562898 -345.846327) (xy 67.508925 -345.838562) (xy 67.456606 -345.823195)
			(xy 67.407007 -345.80054) (xy 67.361136 -345.771056) (xy 67.319928 -345.735345) (xy 67.284221 -345.694134)
			(xy 67.254742 -345.64826) (xy 67.232092 -345.598658) (xy 67.21673 -345.546338) (xy 67.20897 -345.492364)
			(xy 65.726121 -345.492364) (xy 65.726121 -345.492373) (xy 65.718359 -345.546362) (xy 65.702992 -345.598698)
			(xy 65.680333 -345.648314) (xy 65.650844 -345.6942) (xy 65.615124 -345.735423) (xy 65.573902 -345.771143)
			(xy 65.528016 -345.800632) (xy 65.4784 -345.823291) (xy 65.426064 -345.838658) (xy 65.372075 -345.846421)
			(xy 65.344802 -345.846908) (xy 64.481202 -345.846908) (xy 64.453934 -345.846353) (xy 64.399954 -345.838592)
			(xy 64.347627 -345.823228) (xy 64.29802 -345.800573) (xy 64.252141 -345.771089) (xy 64.210926 -345.735376)
			(xy 64.175212 -345.69416) (xy 64.145728 -345.648282) (xy 64.123073 -345.598675) (xy 64.107709 -345.546348)
			(xy 64.099947 -345.492368) (xy 62.617122 -345.492368) (xy 62.617122 -345.492371) (xy 62.60936 -345.546357)
			(xy 62.593995 -345.59869) (xy 62.571339 -345.648303) (xy 62.541854 -345.694187) (xy 62.506139 -345.735409)
			(xy 62.464921 -345.771128) (xy 62.41904 -345.800619) (xy 62.369429 -345.82328) (xy 62.317098 -345.838651)
			(xy 62.263113 -345.846419) (xy 62.235842 -345.846908) (xy 61.372242 -345.846908) (xy 61.344972 -345.846355)
			(xy 61.290987 -345.838599) (xy 61.238656 -345.823238) (xy 61.189043 -345.800586) (xy 61.14316 -345.771103)
			(xy 61.10194 -345.73539) (xy 61.066222 -345.694174) (xy 61.036734 -345.648293) (xy 61.014076 -345.598683)
			(xy 60.99871 -345.546354) (xy 60.990948 -345.49237) (xy 51.666922 -345.49237) (xy 51.65916 -345.546356)
			(xy 51.643795 -345.598688) (xy 51.62114 -345.648301) (xy 51.591655 -345.694185) (xy 51.555941 -345.735407)
			(xy 51.514724 -345.771126) (xy 51.468843 -345.800617) (xy 51.419233 -345.823279) (xy 51.366903 -345.83865)
			(xy 51.312918 -345.846418) (xy 51.285648 -345.846908) (xy 50.422048 -345.846908) (xy 50.394778 -345.846356)
			(xy 50.340792 -345.8386) (xy 50.28846 -345.82324) (xy 50.238847 -345.800588) (xy 50.192963 -345.771105)
			(xy 50.151742 -345.735392) (xy 50.116024 -345.694176) (xy 50.086535 -345.648295) (xy 50.063877 -345.598685)
			(xy 50.04851 -345.546354) (xy 50.040748 -345.49237) (xy 48.558044 -345.49237) (xy 48.558044 -345.492375)
			(xy 48.550281 -345.546369) (xy 48.534912 -345.598709) (xy 48.512251 -345.648329) (xy 48.482759 -345.694219)
			(xy 48.447036 -345.735444) (xy 48.405809 -345.771166) (xy 48.359919 -345.800657) (xy 48.310298 -345.823316)
			(xy 48.257958 -345.838684) (xy 48.203963 -345.846445) (xy 48.176688 -345.846908) (xy 47.313088 -345.846908)
			(xy 47.285822 -345.846329) (xy 47.231847 -345.838567) (xy 47.179525 -345.823202) (xy 47.129922 -345.800548)
			(xy 47.084048 -345.771065) (xy 47.042837 -345.735354) (xy 47.007127 -345.694142) (xy 46.977646 -345.648267)
			(xy 46.954994 -345.598664) (xy 46.939631 -345.546342) (xy 46.93187 -345.492366) (xy 45.449022 -345.492366)
			(xy 45.449022 -345.492371) (xy 45.44126 -345.546359) (xy 45.425894 -345.598693) (xy 45.403237 -345.648307)
			(xy 45.37375 -345.694192) (xy 45.338034 -345.735414) (xy 45.296814 -345.771133) (xy 45.250932 -345.800624)
			(xy 45.201319 -345.823284) (xy 45.148986 -345.838654) (xy 45.094999 -345.84642) (xy 45.067728 -345.846908)
			(xy 44.204128 -345.846908) (xy 44.176859 -345.846355) (xy 44.122876 -345.838597) (xy 44.070546 -345.823235)
			(xy 44.020935 -345.800581) (xy 43.975053 -345.771098) (xy 43.933835 -345.735385) (xy 43.898119 -345.694169)
			(xy 43.868632 -345.648289) (xy 43.845975 -345.59868) (xy 43.830609 -345.546352) (xy 43.822847 -345.492369)
			(xy 42.340144 -345.492369) (xy 42.340144 -345.492376) (xy 42.33238 -345.546372) (xy 42.317011 -345.598713)
			(xy 42.294348 -345.648335) (xy 42.264854 -345.694225) (xy 42.229129 -345.735451) (xy 42.1879 -345.771173)
			(xy 42.142007 -345.800663) (xy 42.092383 -345.823322) (xy 42.040041 -345.838687) (xy 41.986044 -345.846447)
			(xy 41.958768 -345.846908) (xy 41.095168 -345.846908) (xy 41.067903 -345.846328) (xy 41.01393 -345.838563)
			(xy 40.96161 -345.823197) (xy 40.91201 -345.800542) (xy 40.866139 -345.771058) (xy 40.82493 -345.735347)
			(xy 40.789222 -345.694136) (xy 40.759743 -345.648262) (xy 40.737092 -345.59866) (xy 40.72173 -345.546339)
			(xy 40.71397 -345.492365) (xy 39.231121 -345.492365) (xy 39.231121 -345.492372) (xy 39.223359 -345.546362)
			(xy 39.207992 -345.598697) (xy 39.185334 -345.648312) (xy 39.155845 -345.694199) (xy 39.120127 -345.735421)
			(xy 39.078905 -345.77114) (xy 39.03302 -345.80063) (xy 38.983404 -345.82329) (xy 38.93107 -345.838657)
			(xy 38.87708 -345.846421) (xy 38.849808 -345.846908) (xy 37.986208 -345.846908) (xy 37.95894 -345.846353)
			(xy 37.904959 -345.838593) (xy 37.852631 -345.823229) (xy 37.803023 -345.800575) (xy 37.757144 -345.771091)
			(xy 37.715928 -345.735378) (xy 37.680214 -345.694162) (xy 37.650729 -345.648284) (xy 37.628074 -345.598676)
			(xy 37.612709 -345.546349) (xy 37.604947 -345.492368) (xy 36.122122 -345.492368) (xy 36.122122 -345.49237)
			(xy 36.11436 -345.546356) (xy 36.098995 -345.598688) (xy 36.07634 -345.648301) (xy 36.046855 -345.694185)
			(xy 36.011141 -345.735407) (xy 35.969924 -345.771126) (xy 35.924043 -345.800617) (xy 35.874433 -345.823279)
			(xy 35.822103 -345.83865) (xy 35.768118 -345.846418) (xy 35.740848 -345.846908) (xy 34.877248 -345.846908)
			(xy 34.849978 -345.846356) (xy 34.795992 -345.8386) (xy 34.74366 -345.82324) (xy 34.694047 -345.800588)
			(xy 34.648163 -345.771105) (xy 34.606942 -345.735392) (xy 34.571224 -345.694176) (xy 34.541735 -345.648295)
			(xy 34.519077 -345.598685) (xy 34.50371 -345.546354) (xy 34.495948 -345.49237) (xy 33.013244 -345.49237)
			(xy 33.013244 -345.492375) (xy 33.005481 -345.546369) (xy 32.990112 -345.598709) (xy 32.967451 -345.648329)
			(xy 32.937959 -345.694219) (xy 32.902236 -345.735444) (xy 32.861009 -345.771166) (xy 32.815119 -345.800657)
			(xy 32.765498 -345.823316) (xy 32.713158 -345.838684) (xy 32.659163 -345.846445) (xy 32.631888 -345.846908)
			(xy 31.768288 -345.846908) (xy 31.741022 -345.846329) (xy 31.687047 -345.838567) (xy 31.634725 -345.823202)
			(xy 31.585122 -345.800548) (xy 31.539248 -345.771065) (xy 31.498037 -345.735354) (xy 31.462327 -345.694142)
			(xy 31.432846 -345.648267) (xy 31.410194 -345.598664) (xy 31.394831 -345.546342) (xy 31.38707 -345.492366)
			(xy 29.904222 -345.492366) (xy 29.904222 -345.492371) (xy 29.89646 -345.546359) (xy 29.881094 -345.598693)
			(xy 29.858437 -345.648307) (xy 29.82895 -345.694192) (xy 29.793234 -345.735414) (xy 29.752014 -345.771133)
			(xy 29.706132 -345.800624) (xy 29.656519 -345.823284) (xy 29.604186 -345.838654) (xy 29.550199 -345.84642)
			(xy 29.522928 -345.846908) (xy 28.659328 -345.846908) (xy 28.632059 -345.846355) (xy 28.578076 -345.838597)
			(xy 28.525746 -345.823235) (xy 28.476135 -345.800581) (xy 28.430253 -345.771098) (xy 28.389035 -345.735385)
			(xy 28.353319 -345.694169) (xy 28.323832 -345.648289) (xy 28.301175 -345.59868) (xy 28.285809 -345.546352)
			(xy 28.278047 -345.492369) (xy 26.795344 -345.492369) (xy 26.795344 -345.492376) (xy 26.78758 -345.546372)
			(xy 26.772211 -345.598713) (xy 26.749548 -345.648335) (xy 26.720054 -345.694225) (xy 26.684329 -345.735451)
			(xy 26.6431 -345.771173) (xy 26.597207 -345.800663) (xy 26.547583 -345.823322) (xy 26.495241 -345.838687)
			(xy 26.441244 -345.846447) (xy 26.413968 -345.846908) (xy 25.550368 -345.846908) (xy 25.523103 -345.846328)
			(xy 25.46913 -345.838563) (xy 25.41681 -345.823197) (xy 25.36721 -345.800542) (xy 25.321339 -345.771058)
			(xy 25.28013 -345.735347) (xy 25.244422 -345.694136) (xy 25.214943 -345.648262) (xy 25.192292 -345.59866)
			(xy 25.17693 -345.546339) (xy 25.16917 -345.492365) (xy 23.686305 -345.492365) (xy 23.686305 -345.492421)
			(xy 23.678542 -345.546407) (xy 23.663176 -345.59874) (xy 23.640519 -345.648352) (xy 23.611031 -345.694236)
			(xy 23.575314 -345.735455) (xy 23.534094 -345.771172) (xy 23.488211 -345.80066) (xy 23.438598 -345.823317)
			(xy 23.386265 -345.838683) (xy 23.332279 -345.846445) (xy 23.305008 -345.846908) (xy 22.441408 -345.846908)
			(xy 22.414138 -345.846429) (xy 22.360154 -345.838667) (xy 22.307825 -345.823302) (xy 22.258214 -345.800645)
			(xy 22.212333 -345.771159) (xy 22.171115 -345.735443) (xy 22.1354 -345.694225) (xy 22.105914 -345.648344)
			(xy 22.083258 -345.598733) (xy 22.067892 -345.546404) (xy 22.06013 -345.49242) (xy 20.577345 -345.49242)
			(xy 20.577345 -345.492421) (xy 20.569582 -345.546407) (xy 20.554216 -345.59874) (xy 20.531559 -345.648352)
			(xy 20.502071 -345.694236) (xy 20.466354 -345.735455) (xy 20.425134 -345.771172) (xy 20.379251 -345.80066)
			(xy 20.329638 -345.823317) (xy 20.277305 -345.838683) (xy 20.223319 -345.846445) (xy 20.196048 -345.846908)
			(xy 19.332448 -345.846908) (xy 19.305178 -345.846429) (xy 19.251194 -345.838667) (xy 19.198865 -345.823302)
			(xy 19.149254 -345.800645) (xy 19.103373 -345.771159) (xy 19.062155 -345.735443) (xy 19.02644 -345.694225)
			(xy 18.996954 -345.648344) (xy 18.974298 -345.598733) (xy 18.958932 -345.546404) (xy 18.95117 -345.49242)
			(xy 0.508 -345.49242) (xy 0.508 -348.976496) (xy 4.708641 -348.976496) (xy 4.708641 -348.847356)
			(xy 4.716591 -348.718461) (xy 4.732461 -348.590301) (xy 4.75619 -348.46336) (xy 4.787689 -348.338121)
			(xy 4.826838 -348.215058) (xy 4.873489 -348.094639) (xy 4.927464 -347.97732) (xy 4.988559 -347.863546)
			(xy 5.056542 -347.753749) (xy 5.131156 -347.648346) (xy 5.212117 -347.547736) (xy 5.299117 -347.452301)
			(xy 5.391828 -347.362402) (xy 5.489898 -347.278381) (xy 5.592953 -347.200557) (xy 5.700604 -347.129225)
			(xy 5.812443 -347.064655) (xy 5.928044 -347.007093) (xy 6.046969 -346.956756) (xy 6.168768 -346.913836)
			(xy 6.292978 -346.878495) (xy 6.419127 -346.850868) (xy 6.546739 -346.831059) (xy 6.675328 -346.819143)
			(xy 6.804406 -346.815167) (xy 6.933484 -346.819143) (xy 7.062073 -346.831059) (xy 7.189685 -346.850868)
			(xy 7.315834 -346.878495) (xy 7.440044 -346.913836) (xy 7.451736 -346.917956) (xy 245.50903 -346.917956)
			(xy 245.50903 -346.83326) (xy 245.517081 -346.748946) (xy 245.53311 -346.66578) (xy 245.556971 -346.584513)
			(xy 245.58845 -346.505883) (xy 245.627261 -346.430602) (xy 245.673051 -346.35935) (xy 245.725407 -346.292774)
			(xy 245.783855 -346.231476) (xy 245.847865 -346.176011) (xy 245.916857 -346.126882) (xy 245.990207 -346.084533)
			(xy 246.06725 -346.049349) (xy 246.147289 -346.021647) (xy 246.229598 -346.001679) (xy 246.313433 -345.989626)
			(xy 246.398034 -345.985596) (xy 246.482635 -345.989626) (xy 246.56647 -346.001679) (xy 246.648779 -346.021647)
			(xy 246.728818 -346.049349) (xy 246.805861 -346.084533) (xy 246.879211 -346.126882) (xy 246.948203 -346.176011)
			(xy 247.012213 -346.231476) (xy 247.070661 -346.292774) (xy 247.123017 -346.35935) (xy 247.168807 -346.430602)
			(xy 247.207618 -346.505883) (xy 247.239097 -346.584513) (xy 247.262958 -346.66578) (xy 247.278987 -346.748946)
			(xy 247.287038 -346.83326) (xy 247.287542 -346.875608) (xy 247.287038 -346.917956) (xy 247.278987 -347.00227)
			(xy 247.262958 -347.085436) (xy 247.239097 -347.166703) (xy 247.207618 -347.245333) (xy 247.168807 -347.320614)
			(xy 247.123017 -347.391866) (xy 247.070661 -347.458442) (xy 247.012213 -347.51974) (xy 246.948203 -347.575205)
			(xy 246.879211 -347.624334) (xy 246.805861 -347.666683) (xy 246.728818 -347.701867) (xy 246.648779 -347.729569)
			(xy 246.56647 -347.749537) (xy 246.482635 -347.76159) (xy 246.398034 -347.765621) (xy 246.313433 -347.76159)
			(xy 246.229598 -347.749537) (xy 246.147289 -347.729569) (xy 246.06725 -347.701867) (xy 245.990207 -347.666683)
			(xy 245.916857 -347.624334) (xy 245.847865 -347.575205) (xy 245.783855 -347.51974) (xy 245.725407 -347.458442)
			(xy 245.673051 -347.391866) (xy 245.627261 -347.320614) (xy 245.58845 -347.245333) (xy 245.556971 -347.166703)
			(xy 245.53311 -347.085436) (xy 245.517081 -347.00227) (xy 245.50903 -346.917956) (xy 7.451736 -346.917956)
			(xy 7.561843 -346.956756) (xy 7.680768 -347.007093) (xy 7.796369 -347.064655) (xy 7.908208 -347.129225)
			(xy 8.015859 -347.200557) (xy 8.118914 -347.278381) (xy 8.216984 -347.362402) (xy 8.309695 -347.452301)
			(xy 8.396695 -347.547736) (xy 8.477656 -347.648346) (xy 8.55227 -347.753749) (xy 8.620253 -347.863546)
			(xy 8.681348 -347.97732) (xy 8.735323 -348.094639) (xy 8.781974 -348.215058) (xy 8.821123 -348.338121)
			(xy 8.852622 -348.46336) (xy 8.876351 -348.590301) (xy 8.879169 -348.613059) (xy 18.951174 -348.613059)
			(xy 18.951174 -348.558521) (xy 18.958936 -348.504537) (xy 18.974301 -348.452208) (xy 18.996957 -348.402598)
			(xy 19.026443 -348.356717) (xy 19.062158 -348.315499) (xy 19.103375 -348.279784) (xy 19.149256 -348.250298)
			(xy 19.198866 -348.227642) (xy 19.251195 -348.212276) (xy 19.305179 -348.204515) (xy 19.332448 -348.204028)
			(xy 20.196048 -348.204028) (xy 20.223319 -348.204491) (xy 20.277306 -348.212253) (xy 20.329639 -348.227619)
			(xy 20.379253 -348.250277) (xy 20.425136 -348.279764) (xy 20.466357 -348.315482) (xy 20.502074 -348.356702)
			(xy 20.531562 -348.402586) (xy 20.55422 -348.452199) (xy 20.569586 -348.504532) (xy 20.577349 -348.558519)
			(xy 20.577349 -348.613061) (xy 20.577347 -348.613072) (xy 22.060092 -348.613072) (xy 22.060092 -348.558528)
			(xy 22.067854 -348.504539) (xy 22.083221 -348.452204) (xy 22.10588 -348.402589) (xy 22.135369 -348.356704)
			(xy 22.171088 -348.315483) (xy 22.21231 -348.279764) (xy 22.258196 -348.250276) (xy 22.307812 -348.227618)
			(xy 22.360147 -348.212252) (xy 22.414136 -348.204491) (xy 22.441408 -348.204028) (xy 23.305008 -348.204028)
			(xy 23.332276 -348.204535) (xy 23.386258 -348.212297) (xy 23.438585 -348.227663) (xy 23.488193 -348.250319)
			(xy 23.534071 -348.279804) (xy 23.575287 -348.315519) (xy 23.611 -348.356735) (xy 23.640485 -348.402614)
			(xy 23.66314 -348.452223) (xy 23.678504 -348.50455) (xy 23.686266 -348.558532) (xy 23.686266 -348.613068)
			(xy 23.686266 -348.613069) (xy 25.169114 -348.613069) (xy 25.169114 -348.558531) (xy 25.176875 -348.504549)
			(xy 25.19224 -348.452221) (xy 25.214894 -348.402611) (xy 25.244378 -348.356731) (xy 25.28009 -348.315513)
			(xy 25.321305 -348.279797) (xy 25.367183 -348.250309) (xy 25.416791 -348.227651) (xy 25.469118 -348.212282)
			(xy 25.523099 -348.204517) (xy 25.550368 -348.204028) (xy 26.413968 -348.204028) (xy 26.44124 -348.204509)
			(xy 26.495229 -348.212268) (xy 26.547564 -348.227631) (xy 26.59718 -348.250286) (xy 26.643066 -348.279772)
			(xy 26.684289 -348.315488) (xy 26.720009 -348.356708) (xy 26.749499 -348.402592) (xy 26.772158 -348.452206)
			(xy 26.787526 -348.50454) (xy 26.795288 -348.558528) (xy 26.795288 -348.613072) (xy 26.795288 -348.613073)
			(xy 28.277992 -348.613073) (xy 28.277992 -348.558527) (xy 28.285755 -348.504536) (xy 28.301123 -348.4522)
			(xy 28.323783 -348.402584) (xy 28.353274 -348.356697) (xy 28.388995 -348.315476) (xy 28.43022 -348.279757)
			(xy 28.476108 -348.25027) (xy 28.525726 -348.227613) (xy 28.578064 -348.212249) (xy 28.632055 -348.20449)
			(xy 28.659328 -348.204028) (xy 29.522928 -348.204028) (xy 29.550195 -348.204536) (xy 29.604175 -348.212301)
			(xy 29.656499 -348.227668) (xy 29.706105 -348.250326) (xy 29.751981 -348.279811) (xy 29.793194 -348.315526)
			(xy 29.828905 -348.356742) (xy 29.858388 -348.40262) (xy 29.881041 -348.452227) (xy 29.896405 -348.504553)
			(xy 29.904166 -348.558533) (xy 29.904166 -348.613067) (xy 29.904166 -348.61307) (xy 31.387014 -348.61307)
			(xy 31.387014 -348.55853) (xy 31.394776 -348.504546) (xy 31.410141 -348.452217) (xy 31.432797 -348.402606)
			(xy 31.462283 -348.356724) (xy 31.497997 -348.315506) (xy 31.539215 -348.27979) (xy 31.585095 -348.250303)
			(xy 31.634705 -348.227645) (xy 31.687035 -348.212279) (xy 31.741018 -348.204515) (xy 31.768288 -348.204028)
			(xy 32.631888 -348.204028) (xy 32.659159 -348.204511) (xy 32.713146 -348.212271) (xy 32.765478 -348.227636)
			(xy 32.815092 -348.250292) (xy 32.860976 -348.279779) (xy 32.902196 -348.315495) (xy 32.937914 -348.356715)
			(xy 32.967402 -348.402598) (xy 32.99006 -348.45221) (xy 33.005426 -348.504543) (xy 33.013189 -348.558529)
			(xy 33.013189 -348.613071) (xy 33.013189 -348.613074) (xy 34.495892 -348.613074) (xy 34.495892 -348.558526)
			(xy 34.503655 -348.504534) (xy 34.519024 -348.452196) (xy 34.541686 -348.402578) (xy 34.571179 -348.356691)
			(xy 34.606902 -348.315468) (xy 34.648129 -348.27975) (xy 34.69402 -348.250263) (xy 34.743641 -348.227608)
			(xy 34.795981 -348.212245) (xy 34.849974 -348.204488) (xy 34.877248 -348.204028) (xy 35.740848 -348.204028)
			(xy 35.768114 -348.204538) (xy 35.822091 -348.212305) (xy 35.874414 -348.227674) (xy 35.924017 -348.250332)
			(xy 35.96989 -348.279819) (xy 36.011101 -348.315533) (xy 36.04681 -348.356748) (xy 36.076291 -348.402626)
			(xy 36.098943 -348.452231) (xy 36.114306 -348.504556) (xy 36.122066 -348.558534) (xy 36.122066 -348.613066)
			(xy 36.122065 -348.613072) (xy 37.604892 -348.613072) (xy 37.604892 -348.558528) (xy 37.612654 -348.504539)
			(xy 37.628021 -348.452204) (xy 37.65068 -348.402589) (xy 37.680169 -348.356704) (xy 37.715888 -348.315483)
			(xy 37.75711 -348.279764) (xy 37.802996 -348.250276) (xy 37.852612 -348.227618) (xy 37.904947 -348.212252)
			(xy 37.958936 -348.204491) (xy 37.986208 -348.204028) (xy 38.849808 -348.204028) (xy 38.877076 -348.204535)
			(xy 38.931058 -348.212297) (xy 38.983385 -348.227663) (xy 39.032993 -348.250319) (xy 39.078871 -348.279804)
			(xy 39.120087 -348.315519) (xy 39.1558 -348.356735) (xy 39.185285 -348.402614) (xy 39.20794 -348.452223)
			(xy 39.223304 -348.50455) (xy 39.231066 -348.558532) (xy 39.231066 -348.613068) (xy 39.231066 -348.613069)
			(xy 40.713914 -348.613069) (xy 40.713914 -348.558531) (xy 40.721675 -348.504549) (xy 40.73704 -348.452221)
			(xy 40.759694 -348.402611) (xy 40.789178 -348.356731) (xy 40.82489 -348.315513) (xy 40.866105 -348.279797)
			(xy 40.911983 -348.250309) (xy 40.961591 -348.227651) (xy 41.013918 -348.212282) (xy 41.067899 -348.204517)
			(xy 41.095168 -348.204028) (xy 41.958768 -348.204028) (xy 41.98604 -348.204509) (xy 42.040029 -348.212268)
			(xy 42.092364 -348.227631) (xy 42.14198 -348.250286) (xy 42.187866 -348.279772) (xy 42.229089 -348.315488)
			(xy 42.264809 -348.356708) (xy 42.294299 -348.402592) (xy 42.316958 -348.452206) (xy 42.332326 -348.50454)
			(xy 42.340088 -348.558528) (xy 42.340088 -348.613072) (xy 42.340088 -348.613073) (xy 43.822792 -348.613073)
			(xy 43.822792 -348.558527) (xy 43.830555 -348.504536) (xy 43.845923 -348.4522) (xy 43.868583 -348.402584)
			(xy 43.898074 -348.356697) (xy 43.933795 -348.315476) (xy 43.97502 -348.279757) (xy 44.020908 -348.25027)
			(xy 44.070526 -348.227613) (xy 44.122864 -348.212249) (xy 44.176855 -348.20449) (xy 44.204128 -348.204028)
			(xy 45.067728 -348.204028) (xy 45.094995 -348.204536) (xy 45.148975 -348.212301) (xy 45.201299 -348.227668)
			(xy 45.250905 -348.250326) (xy 45.296781 -348.279811) (xy 45.337994 -348.315526) (xy 45.373705 -348.356742)
			(xy 45.403188 -348.40262) (xy 45.425841 -348.452227) (xy 45.441205 -348.504553) (xy 45.448966 -348.558533)
			(xy 45.448966 -348.613067) (xy 45.448966 -348.61307) (xy 46.931814 -348.61307) (xy 46.931814 -348.55853)
			(xy 46.939576 -348.504546) (xy 46.954941 -348.452217) (xy 46.977597 -348.402606) (xy 47.007083 -348.356724)
			(xy 47.042797 -348.315506) (xy 47.084015 -348.27979) (xy 47.129895 -348.250303) (xy 47.179505 -348.227645)
			(xy 47.231835 -348.212279) (xy 47.285818 -348.204515) (xy 47.313088 -348.204028) (xy 48.176688 -348.204028)
			(xy 48.203959 -348.204511) (xy 48.257946 -348.212271) (xy 48.310278 -348.227636) (xy 48.359892 -348.250292)
			(xy 48.405776 -348.279779) (xy 48.446996 -348.315495) (xy 48.482714 -348.356715) (xy 48.512202 -348.402598)
			(xy 48.53486 -348.45221) (xy 48.550226 -348.504543) (xy 48.557989 -348.558529) (xy 48.557989 -348.613071)
			(xy 48.557989 -348.613074) (xy 50.040692 -348.613074) (xy 50.040692 -348.558526) (xy 50.048455 -348.504534)
			(xy 50.063824 -348.452196) (xy 50.086486 -348.402578) (xy 50.115979 -348.356691) (xy 50.151702 -348.315468)
			(xy 50.192929 -348.27975) (xy 50.23882 -348.250263) (xy 50.288441 -348.227608) (xy 50.340781 -348.212245)
			(xy 50.394774 -348.204488) (xy 50.422048 -348.204028) (xy 51.285648 -348.204028) (xy 51.312914 -348.204538)
			(xy 51.366891 -348.212305) (xy 51.419214 -348.227674) (xy 51.468817 -348.250332) (xy 51.51469 -348.279819)
			(xy 51.555901 -348.315533) (xy 51.59161 -348.356748) (xy 51.621091 -348.402626) (xy 51.643743 -348.452231)
			(xy 51.659106 -348.504556) (xy 51.666866 -348.558534) (xy 51.666866 -348.613066) (xy 51.666865 -348.613074)
			(xy 60.990892 -348.613074) (xy 60.990892 -348.558526) (xy 60.998655 -348.504534) (xy 61.014024 -348.452197)
			(xy 61.036685 -348.40258) (xy 61.066177 -348.356693) (xy 61.1019 -348.315471) (xy 61.143127 -348.279752)
			(xy 61.189017 -348.250265) (xy 61.238636 -348.227609) (xy 61.290976 -348.212246) (xy 61.344968 -348.204489)
			(xy 61.372242 -348.204028) (xy 62.235842 -348.204028) (xy 62.263109 -348.204537) (xy 62.317086 -348.212304)
			(xy 62.369409 -348.227672) (xy 62.419013 -348.25033) (xy 62.464887 -348.279816) (xy 62.506099 -348.315531)
			(xy 62.541809 -348.356746) (xy 62.57129 -348.402624) (xy 62.593943 -348.45223) (xy 62.609305 -348.504555)
			(xy 62.617066 -348.558533) (xy 62.617066 -348.613067) (xy 62.617065 -348.613072) (xy 64.099892 -348.613072)
			(xy 64.099892 -348.558528) (xy 64.107654 -348.50454) (xy 64.123021 -348.452206) (xy 64.145679 -348.402591)
			(xy 64.175168 -348.356706) (xy 64.210886 -348.315485) (xy 64.252108 -348.279766) (xy 64.297993 -348.250278)
			(xy 64.347607 -348.22762) (xy 64.399942 -348.212253) (xy 64.45393 -348.204491) (xy 64.481202 -348.204028)
			(xy 65.344802 -348.204028) (xy 65.372071 -348.204535) (xy 65.426053 -348.212296) (xy 65.47838 -348.227661)
			(xy 65.527989 -348.250317) (xy 65.573869 -348.279802) (xy 65.615085 -348.315517) (xy 65.650799 -348.356733)
			(xy 65.680284 -348.402613) (xy 65.702939 -348.452221) (xy 65.718304 -348.504549) (xy 65.726066 -348.558531)
			(xy 65.726066 -348.613068) (xy 67.208914 -348.613068) (xy 67.208914 -348.558532) (xy 67.216675 -348.50455)
			(xy 67.232039 -348.452222) (xy 67.254693 -348.402613) (xy 67.284176 -348.356733) (xy 67.319888 -348.315515)
			(xy 67.361102 -348.279799) (xy 67.40698 -348.250311) (xy 67.456586 -348.227652) (xy 67.508913 -348.212283)
			(xy 67.562894 -348.204517) (xy 67.590162 -348.204028) (xy 68.453762 -348.204028) (xy 68.481034 -348.204509)
			(xy 68.535024 -348.212266) (xy 68.58736 -348.227629) (xy 68.636976 -348.250284) (xy 68.682863 -348.27977)
			(xy 68.724087 -348.315486) (xy 68.759808 -348.356706) (xy 68.789298 -348.40259) (xy 68.811958 -348.452205)
			(xy 68.827326 -348.504539) (xy 68.835088 -348.558528) (xy 68.835088 -348.613072) (xy 68.835088 -348.613073)
			(xy 70.317792 -348.613073) (xy 70.317792 -348.558527) (xy 70.325554 -348.504537) (xy 70.340922 -348.452201)
			(xy 70.363582 -348.402585) (xy 70.393072 -348.356699) (xy 70.428793 -348.315478) (xy 70.470017 -348.279759)
			(xy 70.515905 -348.250271) (xy 70.565522 -348.227615) (xy 70.617859 -348.21225) (xy 70.671849 -348.20449)
			(xy 70.699122 -348.204028) (xy 71.562722 -348.204028) (xy 71.58999 -348.204536) (xy 71.643969 -348.2123)
			(xy 71.696295 -348.227667) (xy 71.745901 -348.250324) (xy 71.791778 -348.279809) (xy 71.832992 -348.315524)
			(xy 71.868704 -348.35674) (xy 71.898187 -348.402618) (xy 71.920841 -348.452226) (xy 71.936205 -348.504552)
			(xy 71.943966 -348.558532) (xy 71.943966 -348.613068) (xy 71.943966 -348.613069) (xy 73.426814 -348.613069)
			(xy 73.426814 -348.558531) (xy 73.434576 -348.504547) (xy 73.449941 -348.452218) (xy 73.472596 -348.402608)
			(xy 73.502081 -348.356726) (xy 73.537795 -348.315508) (xy 73.579012 -348.279792) (xy 73.624892 -348.250305)
			(xy 73.674501 -348.227647) (xy 73.72683 -348.21228) (xy 73.780813 -348.204516) (xy 73.808082 -348.204028)
			(xy 74.671682 -348.204028) (xy 74.698953 -348.20451) (xy 74.752941 -348.21227) (xy 74.805274 -348.227634)
			(xy 74.854888 -348.25029) (xy 74.900773 -348.279777) (xy 74.941994 -348.315493) (xy 74.977712 -348.356713)
			(xy 75.007201 -348.402596) (xy 75.029859 -348.452209) (xy 75.045226 -348.504542) (xy 75.052988 -348.558529)
			(xy 75.052988 -348.613071) (xy 75.052988 -348.613074) (xy 76.535692 -348.613074) (xy 76.535692 -348.558526)
			(xy 76.543455 -348.504534) (xy 76.558824 -348.452197) (xy 76.581485 -348.40258) (xy 76.610977 -348.356693)
			(xy 76.6467 -348.315471) (xy 76.687927 -348.279752) (xy 76.733817 -348.250265) (xy 76.783436 -348.227609)
			(xy 76.835776 -348.212246) (xy 76.889768 -348.204489) (xy 76.917042 -348.204028) (xy 77.780642 -348.204028)
			(xy 77.807909 -348.204537) (xy 77.861886 -348.212304) (xy 77.914209 -348.227672) (xy 77.963813 -348.25033)
			(xy 78.009687 -348.279816) (xy 78.050899 -348.315531) (xy 78.086609 -348.356746) (xy 78.11609 -348.402624)
			(xy 78.138743 -348.45223) (xy 78.154105 -348.504555) (xy 78.161866 -348.558533) (xy 78.161866 -348.613067)
			(xy 78.161865 -348.613072) (xy 79.644692 -348.613072) (xy 79.644692 -348.558528) (xy 79.652454 -348.50454)
			(xy 79.667821 -348.452206) (xy 79.690479 -348.402591) (xy 79.719968 -348.356706) (xy 79.755686 -348.315485)
			(xy 79.796908 -348.279766) (xy 79.842793 -348.250278) (xy 79.892407 -348.22762) (xy 79.944742 -348.212253)
			(xy 79.99873 -348.204491) (xy 80.026002 -348.204028) (xy 80.889602 -348.204028) (xy 80.916871 -348.204535)
			(xy 80.970853 -348.212296) (xy 81.02318 -348.227661) (xy 81.072789 -348.250317) (xy 81.118669 -348.279802)
			(xy 81.159885 -348.315517) (xy 81.195599 -348.356733) (xy 81.225084 -348.402613) (xy 81.247739 -348.452221)
			(xy 81.263104 -348.504549) (xy 81.270866 -348.558531) (xy 81.270866 -348.613068) (xy 82.753714 -348.613068)
			(xy 82.753714 -348.558532) (xy 82.761475 -348.50455) (xy 82.776839 -348.452222) (xy 82.799493 -348.402613)
			(xy 82.828976 -348.356733) (xy 82.864688 -348.315515) (xy 82.905902 -348.279799) (xy 82.95178 -348.250311)
			(xy 83.001386 -348.227652) (xy 83.053713 -348.212283) (xy 83.107694 -348.204517) (xy 83.134962 -348.204028)
			(xy 83.998562 -348.204028) (xy 84.025834 -348.204509) (xy 84.079824 -348.212266) (xy 84.13216 -348.227629)
			(xy 84.181776 -348.250284) (xy 84.227663 -348.27977) (xy 84.268887 -348.315486) (xy 84.304608 -348.356706)
			(xy 84.334098 -348.40259) (xy 84.356758 -348.452205) (xy 84.372126 -348.504539) (xy 84.379888 -348.558528)
			(xy 84.379888 -348.613072) (xy 84.379888 -348.613073) (xy 85.862592 -348.613073) (xy 85.862592 -348.558527)
			(xy 85.870354 -348.504537) (xy 85.885722 -348.452201) (xy 85.908382 -348.402585) (xy 85.937872 -348.356699)
			(xy 85.973593 -348.315478) (xy 86.014817 -348.279759) (xy 86.060705 -348.250271) (xy 86.110322 -348.227615)
			(xy 86.162659 -348.21225) (xy 86.216649 -348.20449) (xy 86.243922 -348.204028) (xy 87.107522 -348.204028)
			(xy 87.13479 -348.204536) (xy 87.188769 -348.2123) (xy 87.241095 -348.227667) (xy 87.290701 -348.250324)
			(xy 87.336578 -348.279809) (xy 87.377792 -348.315524) (xy 87.413504 -348.35674) (xy 87.442987 -348.402618)
			(xy 87.465641 -348.452226) (xy 87.481005 -348.504552) (xy 87.488766 -348.558532) (xy 87.488766 -348.613068)
			(xy 87.488766 -348.613069) (xy 88.971614 -348.613069) (xy 88.971614 -348.558531) (xy 88.979376 -348.504547)
			(xy 88.994741 -348.452218) (xy 89.017396 -348.402608) (xy 89.046881 -348.356726) (xy 89.082595 -348.315508)
			(xy 89.123812 -348.279792) (xy 89.169692 -348.250305) (xy 89.219301 -348.227647) (xy 89.27163 -348.21228)
			(xy 89.325613 -348.204516) (xy 89.352882 -348.204028) (xy 90.216482 -348.204028) (xy 90.243753 -348.20451)
			(xy 90.297741 -348.21227) (xy 90.350074 -348.227634) (xy 90.399688 -348.25029) (xy 90.445573 -348.279777)
			(xy 90.486794 -348.315493) (xy 90.522512 -348.356713) (xy 90.552001 -348.402596) (xy 90.574659 -348.452209)
			(xy 90.590026 -348.504542) (xy 90.597788 -348.558529) (xy 90.597788 -348.613071) (xy 90.597788 -348.613074)
			(xy 92.080492 -348.613074) (xy 92.080492 -348.558526) (xy 92.088255 -348.504534) (xy 92.103624 -348.452197)
			(xy 92.126285 -348.40258) (xy 92.155777 -348.356693) (xy 92.1915 -348.315471) (xy 92.232727 -348.279752)
			(xy 92.278617 -348.250265) (xy 92.328236 -348.227609) (xy 92.380576 -348.212246) (xy 92.434568 -348.204489)
			(xy 92.461842 -348.204028) (xy 93.325442 -348.204028) (xy 93.352709 -348.204537) (xy 93.406686 -348.212304)
			(xy 93.459009 -348.227672) (xy 93.508613 -348.25033) (xy 93.554487 -348.279816) (xy 93.595699 -348.315531)
			(xy 93.631409 -348.356746) (xy 93.66089 -348.402624) (xy 93.683543 -348.45223) (xy 93.698905 -348.504555)
			(xy 93.706666 -348.558533) (xy 93.706666 -348.613067) (xy 93.706665 -348.613072) (xy 111.480792 -348.613072)
			(xy 111.480792 -348.558528) (xy 111.488554 -348.504539) (xy 111.503921 -348.452204) (xy 111.52658 -348.402589)
			(xy 111.556069 -348.356704) (xy 111.591788 -348.315483) (xy 111.63301 -348.279764) (xy 111.678896 -348.250276)
			(xy 111.728512 -348.227618) (xy 111.780847 -348.212252) (xy 111.834836 -348.204491) (xy 111.862108 -348.204028)
			(xy 112.725708 -348.204028) (xy 112.752976 -348.204535) (xy 112.806958 -348.212297) (xy 112.859285 -348.227663)
			(xy 112.908893 -348.250319) (xy 112.954771 -348.279804) (xy 112.995987 -348.315519) (xy 113.0317 -348.356735)
			(xy 113.061185 -348.402614) (xy 113.08384 -348.452223) (xy 113.099204 -348.50455) (xy 113.106966 -348.558532)
			(xy 113.106966 -348.613068) (xy 113.106966 -348.613069) (xy 114.589814 -348.613069) (xy 114.589814 -348.558531)
			(xy 114.597575 -348.504549) (xy 114.61294 -348.452221) (xy 114.635594 -348.402611) (xy 114.665078 -348.356731)
			(xy 114.70079 -348.315513) (xy 114.742005 -348.279797) (xy 114.787883 -348.250309) (xy 114.837491 -348.227651)
			(xy 114.889818 -348.212282) (xy 114.943799 -348.204517) (xy 114.971068 -348.204028) (xy 115.834668 -348.204028)
			(xy 115.86194 -348.204509) (xy 115.915929 -348.212268) (xy 115.968264 -348.227631) (xy 116.01788 -348.250286)
			(xy 116.063766 -348.279772) (xy 116.104989 -348.315488) (xy 116.140709 -348.356708) (xy 116.170199 -348.402592)
			(xy 116.192858 -348.452206) (xy 116.208226 -348.50454) (xy 116.215988 -348.558528) (xy 116.215988 -348.613072)
			(xy 116.215988 -348.613073) (xy 117.698692 -348.613073) (xy 117.698692 -348.558527) (xy 117.706455 -348.504536)
			(xy 117.721823 -348.4522) (xy 117.744483 -348.402584) (xy 117.773974 -348.356697) (xy 117.809695 -348.315476)
			(xy 117.85092 -348.279757) (xy 117.896808 -348.25027) (xy 117.946426 -348.227613) (xy 117.998764 -348.212249)
			(xy 118.052755 -348.20449) (xy 118.080028 -348.204028) (xy 118.943628 -348.204028) (xy 118.970895 -348.204536)
			(xy 119.024875 -348.212301) (xy 119.077199 -348.227668) (xy 119.126805 -348.250326) (xy 119.172681 -348.279811)
			(xy 119.213894 -348.315526) (xy 119.249605 -348.356742) (xy 119.279088 -348.40262) (xy 119.301741 -348.452227)
			(xy 119.317105 -348.504553) (xy 119.324866 -348.558533) (xy 119.324866 -348.613067) (xy 119.324866 -348.61307)
			(xy 120.807714 -348.61307) (xy 120.807714 -348.55853) (xy 120.815476 -348.504546) (xy 120.830841 -348.452217)
			(xy 120.853497 -348.402606) (xy 120.882983 -348.356724) (xy 120.918697 -348.315506) (xy 120.959915 -348.27979)
			(xy 121.005795 -348.250303) (xy 121.055405 -348.227645) (xy 121.107735 -348.212279) (xy 121.161718 -348.204515)
			(xy 121.188988 -348.204028) (xy 122.052588 -348.204028) (xy 122.079859 -348.204511) (xy 122.133846 -348.212271)
			(xy 122.186178 -348.227636) (xy 122.235792 -348.250292) (xy 122.281676 -348.279779) (xy 122.322896 -348.315495)
			(xy 122.358614 -348.356715) (xy 122.388102 -348.402598) (xy 122.41076 -348.45221) (xy 122.426126 -348.504543)
			(xy 122.433889 -348.558529) (xy 122.433889 -348.613071) (xy 122.433889 -348.613074) (xy 123.916592 -348.613074)
			(xy 123.916592 -348.558526) (xy 123.924355 -348.504534) (xy 123.939724 -348.452196) (xy 123.962386 -348.402578)
			(xy 123.991879 -348.356691) (xy 124.027602 -348.315468) (xy 124.068829 -348.27975) (xy 124.11472 -348.250263)
			(xy 124.164341 -348.227608) (xy 124.216681 -348.212245) (xy 124.270674 -348.204488) (xy 124.297948 -348.204028)
			(xy 125.161548 -348.204028) (xy 125.188814 -348.204538) (xy 125.242791 -348.212305) (xy 125.295114 -348.227674)
			(xy 125.344717 -348.250332) (xy 125.39059 -348.279819) (xy 125.431801 -348.315533) (xy 125.46751 -348.356748)
			(xy 125.496991 -348.402626) (xy 125.519643 -348.452231) (xy 125.535006 -348.504556) (xy 125.542766 -348.558534)
			(xy 125.542766 -348.613066) (xy 125.542765 -348.613072) (xy 127.025592 -348.613072) (xy 127.025592 -348.558528)
			(xy 127.033354 -348.504539) (xy 127.048721 -348.452204) (xy 127.07138 -348.402589) (xy 127.100869 -348.356704)
			(xy 127.136588 -348.315483) (xy 127.17781 -348.279764) (xy 127.223696 -348.250276) (xy 127.273312 -348.227618)
			(xy 127.325647 -348.212252) (xy 127.379636 -348.204491) (xy 127.406908 -348.204028) (xy 128.270508 -348.204028)
			(xy 128.297776 -348.204535) (xy 128.351758 -348.212297) (xy 128.404085 -348.227663) (xy 128.453693 -348.250319)
			(xy 128.499571 -348.279804) (xy 128.540787 -348.315519) (xy 128.5765 -348.356735) (xy 128.605985 -348.402614)
			(xy 128.62864 -348.452223) (xy 128.644004 -348.50455) (xy 128.651766 -348.558532) (xy 128.651766 -348.613068)
			(xy 128.651766 -348.613069) (xy 130.134614 -348.613069) (xy 130.134614 -348.558531) (xy 130.142375 -348.504549)
			(xy 130.15774 -348.452221) (xy 130.180394 -348.402611) (xy 130.209878 -348.356731) (xy 130.24559 -348.315513)
			(xy 130.286805 -348.279797) (xy 130.332683 -348.250309) (xy 130.382291 -348.227651) (xy 130.434618 -348.212282)
			(xy 130.488599 -348.204517) (xy 130.515868 -348.204028) (xy 131.379468 -348.204028) (xy 131.40674 -348.204509)
			(xy 131.460729 -348.212268) (xy 131.513064 -348.227631) (xy 131.56268 -348.250286) (xy 131.608566 -348.279772)
			(xy 131.649789 -348.315488) (xy 131.685509 -348.356708) (xy 131.714999 -348.402592) (xy 131.737658 -348.452206)
			(xy 131.753026 -348.50454) (xy 131.760788 -348.558528) (xy 131.760788 -348.613072) (xy 131.760788 -348.613073)
			(xy 133.243492 -348.613073) (xy 133.243492 -348.558527) (xy 133.251255 -348.504536) (xy 133.266623 -348.4522)
			(xy 133.289283 -348.402584) (xy 133.318774 -348.356697) (xy 133.354495 -348.315476) (xy 133.39572 -348.279757)
			(xy 133.441608 -348.25027) (xy 133.491226 -348.227613) (xy 133.543564 -348.212249) (xy 133.597555 -348.20449)
			(xy 133.624828 -348.204028) (xy 134.488428 -348.204028) (xy 134.515695 -348.204536) (xy 134.569675 -348.212301)
			(xy 134.621999 -348.227668) (xy 134.671605 -348.250326) (xy 134.717481 -348.279811) (xy 134.758694 -348.315526)
			(xy 134.794405 -348.356742) (xy 134.823888 -348.40262) (xy 134.846541 -348.452227) (xy 134.861905 -348.504553)
			(xy 134.869666 -348.558533) (xy 134.869666 -348.613067) (xy 134.869666 -348.61307) (xy 136.352514 -348.61307)
			(xy 136.352514 -348.55853) (xy 136.360276 -348.504546) (xy 136.375641 -348.452217) (xy 136.398297 -348.402606)
			(xy 136.427783 -348.356724) (xy 136.463497 -348.315506) (xy 136.504715 -348.27979) (xy 136.550595 -348.250303)
			(xy 136.600205 -348.227645) (xy 136.652535 -348.212279) (xy 136.706518 -348.204515) (xy 136.733788 -348.204028)
			(xy 137.597388 -348.204028) (xy 137.624659 -348.204511) (xy 137.678646 -348.212271) (xy 137.730978 -348.227636)
			(xy 137.780592 -348.250292) (xy 137.826476 -348.279779) (xy 137.867696 -348.315495) (xy 137.903414 -348.356715)
			(xy 137.932902 -348.402598) (xy 137.95556 -348.45221) (xy 137.970926 -348.504543) (xy 137.978689 -348.558529)
			(xy 137.978689 -348.613071) (xy 137.978689 -348.613074) (xy 139.461392 -348.613074) (xy 139.461392 -348.558526)
			(xy 139.469155 -348.504534) (xy 139.484524 -348.452196) (xy 139.507186 -348.402578) (xy 139.536679 -348.356691)
			(xy 139.572402 -348.315468) (xy 139.613629 -348.27975) (xy 139.65952 -348.250263) (xy 139.709141 -348.227608)
			(xy 139.761481 -348.212245) (xy 139.815474 -348.204488) (xy 139.842748 -348.204028) (xy 140.706348 -348.204028)
			(xy 140.733614 -348.204538) (xy 140.787591 -348.212305) (xy 140.839914 -348.227674) (xy 140.889517 -348.250332)
			(xy 140.93539 -348.279819) (xy 140.976601 -348.315533) (xy 141.01231 -348.356748) (xy 141.041791 -348.402626)
			(xy 141.064443 -348.452231) (xy 141.079806 -348.504556) (xy 141.087566 -348.558534) (xy 141.087566 -348.613066)
			(xy 141.087565 -348.613072) (xy 142.570392 -348.613072) (xy 142.570392 -348.558528) (xy 142.578154 -348.504539)
			(xy 142.593521 -348.452204) (xy 142.61618 -348.402589) (xy 142.645669 -348.356704) (xy 142.681388 -348.315483)
			(xy 142.72261 -348.279764) (xy 142.768496 -348.250276) (xy 142.818112 -348.227618) (xy 142.870447 -348.212252)
			(xy 142.924436 -348.204491) (xy 142.951708 -348.204028) (xy 143.815308 -348.204028) (xy 143.842576 -348.204535)
			(xy 143.896558 -348.212297) (xy 143.948885 -348.227663) (xy 143.998493 -348.250319) (xy 144.044371 -348.279804)
			(xy 144.085587 -348.315519) (xy 144.1213 -348.356735) (xy 144.150785 -348.402614) (xy 144.17344 -348.452223)
			(xy 144.188804 -348.50455) (xy 144.196566 -348.558532) (xy 144.196566 -348.613068) (xy 144.196565 -348.613072)
			(xy 161.804792 -348.613072) (xy 161.804792 -348.558528) (xy 161.812554 -348.504538) (xy 161.827921 -348.452203)
			(xy 161.850581 -348.402588) (xy 161.88007 -348.356703) (xy 161.91579 -348.315481) (xy 161.957012 -348.279763)
			(xy 162.002899 -348.250275) (xy 162.052515 -348.227617) (xy 162.10485 -348.212252) (xy 162.15884 -348.204491)
			(xy 162.186112 -348.204028) (xy 163.049712 -348.204028) (xy 163.07698 -348.204535) (xy 163.130961 -348.212298)
			(xy 163.183288 -348.227664) (xy 163.232895 -348.25032) (xy 163.278773 -348.279806) (xy 163.319988 -348.31552)
			(xy 163.355701 -348.356736) (xy 163.385185 -348.402615) (xy 163.40784 -348.452224) (xy 163.423204 -348.504551)
			(xy 163.430966 -348.558532) (xy 163.430966 -348.613068) (xy 163.430966 -348.613069) (xy 164.913814 -348.613069)
			(xy 164.913814 -348.558531) (xy 164.921576 -348.504549) (xy 164.93694 -348.45222) (xy 164.959595 -348.40261)
			(xy 164.989079 -348.35673) (xy 165.024792 -348.315512) (xy 165.066007 -348.279795) (xy 165.111886 -348.250308)
			(xy 165.161494 -348.22765) (xy 165.213821 -348.212281) (xy 165.267803 -348.204516) (xy 165.295072 -348.204028)
			(xy 166.158672 -348.204028) (xy 166.185944 -348.20451) (xy 166.239932 -348.212268) (xy 166.292267 -348.227632)
			(xy 166.341882 -348.250287) (xy 166.387768 -348.279773) (xy 166.42899 -348.31549) (xy 166.46471 -348.356709)
			(xy 166.494199 -348.402593) (xy 166.516859 -348.452207) (xy 166.532226 -348.504541) (xy 166.539988 -348.558528)
			(xy 166.539988 -348.613072) (xy 166.539988 -348.613073) (xy 168.022692 -348.613073) (xy 168.022692 -348.558527)
			(xy 168.030455 -348.504536) (xy 168.045823 -348.452199) (xy 168.068484 -348.402583) (xy 168.097975 -348.356696)
			(xy 168.133697 -348.315474) (xy 168.174922 -348.279756) (xy 168.220811 -348.250268) (xy 168.270429 -348.227612)
			(xy 168.322767 -348.212248) (xy 168.376759 -348.204489) (xy 168.404032 -348.204028) (xy 169.267632 -348.204028)
			(xy 169.294899 -348.204537) (xy 169.348878 -348.212302) (xy 169.401202 -348.227669) (xy 169.450807 -348.250327)
			(xy 169.496683 -348.279813) (xy 169.537895 -348.315527) (xy 169.573606 -348.356743) (xy 169.603088 -348.402621)
			(xy 169.625742 -348.452228) (xy 169.641105 -348.504553) (xy 169.648866 -348.558533) (xy 169.648866 -348.613067)
			(xy 169.648866 -348.61307) (xy 171.131714 -348.61307) (xy 171.131714 -348.55853) (xy 171.139476 -348.504546)
			(xy 171.154841 -348.452216) (xy 171.177498 -348.402605) (xy 171.206984 -348.356723) (xy 171.242699 -348.315505)
			(xy 171.283917 -348.279788) (xy 171.329798 -348.250301) (xy 171.379408 -348.227644) (xy 171.431738 -348.212278)
			(xy 171.485722 -348.204515) (xy 171.512992 -348.204028) (xy 172.376592 -348.204028) (xy 172.403863 -348.204511)
			(xy 172.457849 -348.212272) (xy 172.510181 -348.227637) (xy 172.559794 -348.250294) (xy 172.605678 -348.27978)
			(xy 172.646898 -348.315497) (xy 172.682615 -348.356716) (xy 172.712103 -348.402599) (xy 172.73476 -348.452211)
			(xy 172.750126 -348.504543) (xy 172.757889 -348.558529) (xy 172.757889 -348.613068) (xy 174.240714 -348.613068)
			(xy 174.240714 -348.558532) (xy 174.248475 -348.504551) (xy 174.263838 -348.452224) (xy 174.286492 -348.402616)
			(xy 174.315974 -348.356736) (xy 174.351685 -348.315519) (xy 174.392898 -348.279803) (xy 174.438774 -348.250315)
			(xy 174.488379 -348.227655) (xy 174.540704 -348.212285) (xy 174.594684 -348.204518) (xy 174.621952 -348.204028)
			(xy 175.485552 -348.204028) (xy 175.512825 -348.204508) (xy 175.566815 -348.212265) (xy 175.619152 -348.227626)
			(xy 175.66877 -348.250281) (xy 175.714659 -348.279766) (xy 175.755883 -348.315483) (xy 175.791605 -348.356703)
			(xy 175.821096 -348.402588) (xy 175.843757 -348.452203) (xy 175.859125 -348.504538) (xy 175.866888 -348.558528)
			(xy 175.866888 -348.613072) (xy 177.349592 -348.613072) (xy 177.349592 -348.558528) (xy 177.357354 -348.504538)
			(xy 177.372721 -348.452203) (xy 177.395381 -348.402588) (xy 177.42487 -348.356703) (xy 177.46059 -348.315481)
			(xy 177.501812 -348.279763) (xy 177.547699 -348.250275) (xy 177.597315 -348.227617) (xy 177.64965 -348.212252)
			(xy 177.70364 -348.204491) (xy 177.730912 -348.204028) (xy 178.594512 -348.204028) (xy 178.62178 -348.204535)
			(xy 178.675761 -348.212298) (xy 178.728088 -348.227664) (xy 178.777695 -348.25032) (xy 178.823573 -348.279806)
			(xy 178.864788 -348.31552) (xy 178.900501 -348.356736) (xy 178.929985 -348.402615) (xy 178.95264 -348.452224)
			(xy 178.968004 -348.504551) (xy 178.975766 -348.558532) (xy 178.975766 -348.613068) (xy 178.975766 -348.613069)
			(xy 180.458614 -348.613069) (xy 180.458614 -348.558531) (xy 180.466376 -348.504549) (xy 180.48174 -348.45222)
			(xy 180.504395 -348.40261) (xy 180.533879 -348.35673) (xy 180.569592 -348.315512) (xy 180.610807 -348.279795)
			(xy 180.656686 -348.250308) (xy 180.706294 -348.22765) (xy 180.758621 -348.212281) (xy 180.812603 -348.204516)
			(xy 180.839872 -348.204028) (xy 181.703472 -348.204028) (xy 181.730744 -348.20451) (xy 181.784732 -348.212268)
			(xy 181.837067 -348.227632) (xy 181.886682 -348.250287) (xy 181.932568 -348.279773) (xy 181.97379 -348.31549)
			(xy 182.00951 -348.356709) (xy 182.038999 -348.402593) (xy 182.061659 -348.452207) (xy 182.077026 -348.504541)
			(xy 182.084788 -348.558528) (xy 182.084788 -348.613072) (xy 182.084788 -348.613073) (xy 183.567492 -348.613073)
			(xy 183.567492 -348.558527) (xy 183.575255 -348.504536) (xy 183.590623 -348.452199) (xy 183.613284 -348.402583)
			(xy 183.642775 -348.356696) (xy 183.678497 -348.315474) (xy 183.719722 -348.279756) (xy 183.765611 -348.250268)
			(xy 183.815229 -348.227612) (xy 183.867567 -348.212248) (xy 183.921559 -348.204489) (xy 183.948832 -348.204028)
			(xy 184.812432 -348.204028) (xy 184.839699 -348.204537) (xy 184.893678 -348.212302) (xy 184.946002 -348.227669)
			(xy 184.995607 -348.250327) (xy 185.041483 -348.279813) (xy 185.082695 -348.315527) (xy 185.118406 -348.356743)
			(xy 185.147888 -348.402621) (xy 185.170542 -348.452228) (xy 185.185905 -348.504553) (xy 185.193666 -348.558533)
			(xy 185.193666 -348.613067) (xy 185.193666 -348.61307) (xy 186.676514 -348.61307) (xy 186.676514 -348.55853)
			(xy 186.684276 -348.504546) (xy 186.699641 -348.452216) (xy 186.722298 -348.402605) (xy 186.751784 -348.356723)
			(xy 186.787499 -348.315505) (xy 186.828717 -348.279788) (xy 186.874598 -348.250301) (xy 186.924208 -348.227644)
			(xy 186.976538 -348.212278) (xy 187.030522 -348.204515) (xy 187.057792 -348.204028) (xy 187.921392 -348.204028)
			(xy 187.948663 -348.204511) (xy 188.002649 -348.212272) (xy 188.054981 -348.227637) (xy 188.104594 -348.250294)
			(xy 188.150478 -348.27978) (xy 188.191698 -348.315497) (xy 188.227415 -348.356716) (xy 188.256903 -348.402599)
			(xy 188.27956 -348.452211) (xy 188.294926 -348.504543) (xy 188.302689 -348.558529) (xy 188.302689 -348.613068)
			(xy 189.785514 -348.613068) (xy 189.785514 -348.558532) (xy 189.793275 -348.504551) (xy 189.808638 -348.452224)
			(xy 189.831292 -348.402616) (xy 189.860774 -348.356736) (xy 189.896485 -348.315519) (xy 189.937698 -348.279803)
			(xy 189.983574 -348.250315) (xy 190.033179 -348.227655) (xy 190.085504 -348.212285) (xy 190.139484 -348.204518)
			(xy 190.166752 -348.204028) (xy 191.030352 -348.204028) (xy 191.057625 -348.204508) (xy 191.111615 -348.212265)
			(xy 191.163952 -348.227626) (xy 191.21357 -348.250281) (xy 191.259459 -348.279766) (xy 191.300683 -348.315483)
			(xy 191.336405 -348.356703) (xy 191.365896 -348.402588) (xy 191.388557 -348.452203) (xy 191.403925 -348.504538)
			(xy 191.411688 -348.558528) (xy 191.411688 -348.613072) (xy 192.894392 -348.613072) (xy 192.894392 -348.558528)
			(xy 192.902154 -348.504538) (xy 192.917521 -348.452203) (xy 192.940181 -348.402588) (xy 192.96967 -348.356703)
			(xy 193.00539 -348.315481) (xy 193.046612 -348.279763) (xy 193.092499 -348.250275) (xy 193.142115 -348.227617)
			(xy 193.19445 -348.212252) (xy 193.24844 -348.204491) (xy 193.275712 -348.204028) (xy 194.139312 -348.204028)
			(xy 194.16658 -348.204535) (xy 194.220561 -348.212298) (xy 194.272888 -348.227664) (xy 194.322495 -348.25032)
			(xy 194.368373 -348.279806) (xy 194.409588 -348.31552) (xy 194.445301 -348.356736) (xy 194.474785 -348.402615)
			(xy 194.49744 -348.452224) (xy 194.512804 -348.504551) (xy 194.520566 -348.558532) (xy 194.520566 -348.613068)
			(xy 194.520565 -348.613072) (xy 267.515792 -348.613072) (xy 267.515792 -348.558528) (xy 267.523554 -348.50454)
			(xy 267.538921 -348.452206) (xy 267.561579 -348.402591) (xy 267.591068 -348.356706) (xy 267.626786 -348.315485)
			(xy 267.668008 -348.279766) (xy 267.713893 -348.250278) (xy 267.763507 -348.22762) (xy 267.815842 -348.212253)
			(xy 267.86983 -348.204491) (xy 267.897102 -348.204028) (xy 268.760702 -348.204028) (xy 268.787971 -348.204535)
			(xy 268.841953 -348.212296) (xy 268.89428 -348.227661) (xy 268.943889 -348.250317) (xy 268.989769 -348.279802)
			(xy 269.030985 -348.315517) (xy 269.066699 -348.356733) (xy 269.096184 -348.402613) (xy 269.118839 -348.452221)
			(xy 269.134204 -348.504549) (xy 269.141966 -348.558531) (xy 269.141966 -348.613068) (xy 270.624814 -348.613068)
			(xy 270.624814 -348.558532) (xy 270.632575 -348.50455) (xy 270.647939 -348.452222) (xy 270.670593 -348.402613)
			(xy 270.700076 -348.356733) (xy 270.735788 -348.315515) (xy 270.777002 -348.279799) (xy 270.82288 -348.250311)
			(xy 270.872486 -348.227652) (xy 270.924813 -348.212283) (xy 270.978794 -348.204517) (xy 271.006062 -348.204028)
			(xy 271.869662 -348.204028) (xy 271.896934 -348.204509) (xy 271.950924 -348.212266) (xy 272.00326 -348.227629)
			(xy 272.052876 -348.250284) (xy 272.098763 -348.27977) (xy 272.139987 -348.315486) (xy 272.175708 -348.356706)
			(xy 272.205198 -348.40259) (xy 272.227858 -348.452205) (xy 272.243226 -348.504539) (xy 272.250988 -348.558528)
			(xy 272.250988 -348.613072) (xy 272.250988 -348.613073) (xy 273.733692 -348.613073) (xy 273.733692 -348.558527)
			(xy 273.741454 -348.504537) (xy 273.756822 -348.452201) (xy 273.779482 -348.402585) (xy 273.808972 -348.356699)
			(xy 273.844693 -348.315478) (xy 273.885917 -348.279759) (xy 273.931805 -348.250271) (xy 273.981422 -348.227615)
			(xy 274.033759 -348.21225) (xy 274.087749 -348.20449) (xy 274.115022 -348.204028) (xy 274.978622 -348.204028)
			(xy 275.00589 -348.204536) (xy 275.059869 -348.2123) (xy 275.112195 -348.227667) (xy 275.161801 -348.250324)
			(xy 275.207678 -348.279809) (xy 275.248892 -348.315524) (xy 275.284604 -348.35674) (xy 275.314087 -348.402618)
			(xy 275.336741 -348.452226) (xy 275.352105 -348.504552) (xy 275.359866 -348.558532) (xy 275.359866 -348.613068)
			(xy 275.359866 -348.613069) (xy 276.842714 -348.613069) (xy 276.842714 -348.558531) (xy 276.850476 -348.504547)
			(xy 276.865841 -348.452218) (xy 276.888496 -348.402608) (xy 276.917981 -348.356726) (xy 276.953695 -348.315508)
			(xy 276.994912 -348.279792) (xy 277.040792 -348.250305) (xy 277.090401 -348.227647) (xy 277.14273 -348.21228)
			(xy 277.196713 -348.204516) (xy 277.223982 -348.204028) (xy 278.087582 -348.204028) (xy 278.114853 -348.20451)
			(xy 278.168841 -348.21227) (xy 278.221174 -348.227634) (xy 278.270788 -348.25029) (xy 278.316673 -348.279777)
			(xy 278.357894 -348.315493) (xy 278.393612 -348.356713) (xy 278.423101 -348.402596) (xy 278.445759 -348.452209)
			(xy 278.461126 -348.504542) (xy 278.468888 -348.558529) (xy 278.468888 -348.613071) (xy 278.468888 -348.613074)
			(xy 279.951592 -348.613074) (xy 279.951592 -348.558526) (xy 279.959355 -348.504534) (xy 279.974724 -348.452197)
			(xy 279.997385 -348.40258) (xy 280.026877 -348.356693) (xy 280.0626 -348.315471) (xy 280.103827 -348.279752)
			(xy 280.149717 -348.250265) (xy 280.199336 -348.227609) (xy 280.251676 -348.212246) (xy 280.305668 -348.204489)
			(xy 280.332942 -348.204028) (xy 281.196542 -348.204028) (xy 281.223809 -348.204537) (xy 281.277786 -348.212304)
			(xy 281.330109 -348.227672) (xy 281.379713 -348.25033) (xy 281.425587 -348.279816) (xy 281.466799 -348.315531)
			(xy 281.502509 -348.356746) (xy 281.53199 -348.402624) (xy 281.554643 -348.45223) (xy 281.570005 -348.504555)
			(xy 281.577766 -348.558533) (xy 281.577766 -348.613067) (xy 281.577765 -348.613072) (xy 283.060592 -348.613072)
			(xy 283.060592 -348.558528) (xy 283.068354 -348.50454) (xy 283.083721 -348.452206) (xy 283.106379 -348.402591)
			(xy 283.135868 -348.356706) (xy 283.171586 -348.315485) (xy 283.212808 -348.279766) (xy 283.258693 -348.250278)
			(xy 283.308307 -348.22762) (xy 283.360642 -348.212253) (xy 283.41463 -348.204491) (xy 283.441902 -348.204028)
			(xy 284.305502 -348.204028) (xy 284.332771 -348.204535) (xy 284.386753 -348.212296) (xy 284.43908 -348.227661)
			(xy 284.488689 -348.250317) (xy 284.534569 -348.279802) (xy 284.575785 -348.315517) (xy 284.611499 -348.356733)
			(xy 284.640984 -348.402613) (xy 284.663639 -348.452221) (xy 284.679004 -348.504549) (xy 284.686766 -348.558531)
			(xy 284.686766 -348.613068) (xy 286.169614 -348.613068) (xy 286.169614 -348.558532) (xy 286.177375 -348.50455)
			(xy 286.192739 -348.452222) (xy 286.215393 -348.402613) (xy 286.244876 -348.356733) (xy 286.280588 -348.315515)
			(xy 286.321802 -348.279799) (xy 286.36768 -348.250311) (xy 286.417286 -348.227652) (xy 286.469613 -348.212283)
			(xy 286.523594 -348.204517) (xy 286.550862 -348.204028) (xy 287.414462 -348.204028) (xy 287.441734 -348.204509)
			(xy 287.495724 -348.212266) (xy 287.54806 -348.227629) (xy 287.597676 -348.250284) (xy 287.643563 -348.27977)
			(xy 287.684787 -348.315486) (xy 287.720508 -348.356706) (xy 287.749998 -348.40259) (xy 287.772658 -348.452205)
			(xy 287.788026 -348.504539) (xy 287.795788 -348.558528) (xy 287.795788 -348.613072) (xy 287.795788 -348.613073)
			(xy 289.278492 -348.613073) (xy 289.278492 -348.558527) (xy 289.286254 -348.504537) (xy 289.301622 -348.452201)
			(xy 289.324282 -348.402585) (xy 289.353772 -348.356699) (xy 289.389493 -348.315478) (xy 289.430717 -348.279759)
			(xy 289.476605 -348.250271) (xy 289.526222 -348.227615) (xy 289.578559 -348.21225) (xy 289.632549 -348.20449)
			(xy 289.659822 -348.204028) (xy 290.523422 -348.204028) (xy 290.55069 -348.204536) (xy 290.604669 -348.2123)
			(xy 290.656995 -348.227667) (xy 290.706601 -348.250324) (xy 290.752478 -348.279809) (xy 290.793692 -348.315524)
			(xy 290.829404 -348.35674) (xy 290.858887 -348.402618) (xy 290.881541 -348.452226) (xy 290.896905 -348.504552)
			(xy 290.904666 -348.558532) (xy 290.904666 -348.613068) (xy 290.904666 -348.613069) (xy 292.387514 -348.613069)
			(xy 292.387514 -348.558531) (xy 292.395276 -348.504547) (xy 292.410641 -348.452218) (xy 292.433296 -348.402608)
			(xy 292.462781 -348.356726) (xy 292.498495 -348.315508) (xy 292.539712 -348.279792) (xy 292.585592 -348.250305)
			(xy 292.635201 -348.227647) (xy 292.68753 -348.21228) (xy 292.741513 -348.204516) (xy 292.768782 -348.204028)
			(xy 293.632382 -348.204028) (xy 293.659653 -348.20451) (xy 293.713641 -348.21227) (xy 293.765974 -348.227634)
			(xy 293.815588 -348.25029) (xy 293.861473 -348.279777) (xy 293.902694 -348.315493) (xy 293.938412 -348.356713)
			(xy 293.967901 -348.402596) (xy 293.990559 -348.452209) (xy 294.005926 -348.504542) (xy 294.013688 -348.558529)
			(xy 294.013688 -348.613071) (xy 294.013688 -348.613074) (xy 295.496392 -348.613074) (xy 295.496392 -348.558526)
			(xy 295.504155 -348.504534) (xy 295.519524 -348.452197) (xy 295.542185 -348.40258) (xy 295.571677 -348.356693)
			(xy 295.6074 -348.315471) (xy 295.648627 -348.279752) (xy 295.694517 -348.250265) (xy 295.744136 -348.227609)
			(xy 295.796476 -348.212246) (xy 295.850468 -348.204489) (xy 295.877742 -348.204028) (xy 296.741342 -348.204028)
			(xy 296.768609 -348.204537) (xy 296.822586 -348.212304) (xy 296.874909 -348.227672) (xy 296.924513 -348.25033)
			(xy 296.970387 -348.279816) (xy 297.011599 -348.315531) (xy 297.047309 -348.356746) (xy 297.07679 -348.402624)
			(xy 297.099443 -348.45223) (xy 297.114805 -348.504555) (xy 297.122566 -348.558533) (xy 297.122566 -348.613067)
			(xy 297.122565 -348.613072) (xy 298.605392 -348.613072) (xy 298.605392 -348.558528) (xy 298.613154 -348.50454)
			(xy 298.628521 -348.452206) (xy 298.651179 -348.402591) (xy 298.680668 -348.356706) (xy 298.716386 -348.315485)
			(xy 298.757608 -348.279766) (xy 298.803493 -348.250278) (xy 298.853107 -348.22762) (xy 298.905442 -348.212253)
			(xy 298.95943 -348.204491) (xy 298.986702 -348.204028) (xy 299.850302 -348.204028) (xy 299.877571 -348.204535)
			(xy 299.931553 -348.212296) (xy 299.98388 -348.227661) (xy 300.033489 -348.250317) (xy 300.079369 -348.279802)
			(xy 300.120585 -348.315517) (xy 300.156299 -348.356733) (xy 300.185784 -348.402613) (xy 300.208439 -348.452221)
			(xy 300.223804 -348.504549) (xy 300.231566 -348.558531) (xy 300.231566 -348.613069) (xy 300.231566 -348.613072)
			(xy 312.121492 -348.613072) (xy 312.121492 -348.558528) (xy 312.129254 -348.504539) (xy 312.144621 -348.452205)
			(xy 312.167279 -348.40259) (xy 312.196768 -348.356705) (xy 312.232487 -348.315484) (xy 312.273709 -348.279766)
			(xy 312.319594 -348.250277) (xy 312.369209 -348.227619) (xy 312.421543 -348.212253) (xy 312.475532 -348.204491)
			(xy 312.502804 -348.204028) (xy 313.366404 -348.204028) (xy 313.393672 -348.204535) (xy 313.447654 -348.212297)
			(xy 313.499982 -348.227662) (xy 313.54959 -348.250318) (xy 313.595469 -348.279803) (xy 313.636686 -348.315517)
			(xy 313.672399 -348.356734) (xy 313.701884 -348.402613) (xy 313.72454 -348.452222) (xy 313.739904 -348.50455)
			(xy 313.747666 -348.558532) (xy 313.747666 -348.613068) (xy 315.230514 -348.613068) (xy 315.230514 -348.558532)
			(xy 315.238275 -348.50455) (xy 315.253639 -348.452222) (xy 315.276293 -348.402613) (xy 315.305777 -348.356732)
			(xy 315.341489 -348.315514) (xy 315.382703 -348.279798) (xy 315.428581 -348.250311) (xy 315.478188 -348.227652)
			(xy 315.530514 -348.212283) (xy 315.584496 -348.204517) (xy 315.611764 -348.204028) (xy 316.475364 -348.204028)
			(xy 316.502636 -348.204509) (xy 316.556625 -348.212267) (xy 316.608961 -348.22763) (xy 316.658577 -348.250284)
			(xy 316.704464 -348.27977) (xy 316.745688 -348.315487) (xy 316.781408 -348.356707) (xy 316.810898 -348.402591)
			(xy 316.833558 -348.452205) (xy 316.848926 -348.504539) (xy 316.856688 -348.558528) (xy 316.856688 -348.613072)
			(xy 316.856688 -348.613073) (xy 318.339392 -348.613073) (xy 318.339392 -348.558527) (xy 318.347155 -348.504537)
			(xy 318.362522 -348.452201) (xy 318.385182 -348.402585) (xy 318.414673 -348.356699) (xy 318.450394 -348.315477)
			(xy 318.491618 -348.279759) (xy 318.537506 -348.250271) (xy 318.587123 -348.227614) (xy 318.63946 -348.212249)
			(xy 318.693451 -348.20449) (xy 318.720724 -348.204028) (xy 319.584324 -348.204028) (xy 319.611592 -348.204536)
			(xy 319.665571 -348.2123) (xy 319.717896 -348.227667) (xy 319.767502 -348.250324) (xy 319.813379 -348.27981)
			(xy 319.854593 -348.315524) (xy 319.890304 -348.35674) (xy 319.919787 -348.402619) (xy 319.942441 -348.452226)
			(xy 319.957805 -348.504552) (xy 319.965566 -348.558532) (xy 319.965566 -348.613068) (xy 319.965566 -348.613069)
			(xy 321.448414 -348.613069) (xy 321.448414 -348.558531) (xy 321.456176 -348.504547) (xy 321.471541 -348.452217)
			(xy 321.494196 -348.402607) (xy 321.523682 -348.356726) (xy 321.559396 -348.315507) (xy 321.600613 -348.279791)
			(xy 321.646493 -348.250304) (xy 321.696102 -348.227646) (xy 321.748431 -348.212279) (xy 321.802415 -348.204516)
			(xy 321.829684 -348.204028) (xy 322.693284 -348.204028) (xy 322.720555 -348.20451) (xy 322.774542 -348.21227)
			(xy 322.826875 -348.227635) (xy 322.876489 -348.250291) (xy 322.922374 -348.279777) (xy 322.963595 -348.315494)
			(xy 322.999313 -348.356713) (xy 323.028801 -348.402597) (xy 323.051459 -348.45221) (xy 323.066826 -348.504542)
			(xy 323.074588 -348.558529) (xy 323.074588 -348.613071) (xy 323.074588 -348.613074) (xy 324.557292 -348.613074)
			(xy 324.557292 -348.558526) (xy 324.565055 -348.504534) (xy 324.580424 -348.452197) (xy 324.603085 -348.402579)
			(xy 324.632578 -348.356692) (xy 324.668301 -348.31547) (xy 324.709527 -348.279751) (xy 324.755418 -348.250264)
			(xy 324.805038 -348.227609) (xy 324.857377 -348.212246) (xy 324.91137 -348.204489) (xy 324.938644 -348.204028)
			(xy 325.802244 -348.204028) (xy 325.829511 -348.204537) (xy 325.883488 -348.212304) (xy 325.935811 -348.227673)
			(xy 325.985414 -348.250331) (xy 326.031288 -348.279817) (xy 326.0725 -348.315531) (xy 326.108209 -348.356747)
			(xy 326.13769 -348.402624) (xy 326.160343 -348.45223) (xy 326.175705 -348.504555) (xy 326.183466 -348.558533)
			(xy 326.183466 -348.613067) (xy 326.183465 -348.613072) (xy 327.666292 -348.613072) (xy 327.666292 -348.558528)
			(xy 327.674054 -348.504539) (xy 327.689421 -348.452205) (xy 327.712079 -348.40259) (xy 327.741568 -348.356705)
			(xy 327.777287 -348.315484) (xy 327.818509 -348.279766) (xy 327.864394 -348.250277) (xy 327.914009 -348.227619)
			(xy 327.966343 -348.212253) (xy 328.020332 -348.204491) (xy 328.047604 -348.204028) (xy 328.911204 -348.204028)
			(xy 328.938472 -348.204535) (xy 328.992454 -348.212297) (xy 329.044782 -348.227662) (xy 329.09439 -348.250318)
			(xy 329.140269 -348.279803) (xy 329.181486 -348.315517) (xy 329.217199 -348.356734) (xy 329.246684 -348.402613)
			(xy 329.26934 -348.452222) (xy 329.284704 -348.50455) (xy 329.292466 -348.558532) (xy 329.292466 -348.613068)
			(xy 330.775314 -348.613068) (xy 330.775314 -348.558532) (xy 330.783075 -348.50455) (xy 330.798439 -348.452222)
			(xy 330.821093 -348.402613) (xy 330.850577 -348.356732) (xy 330.886289 -348.315514) (xy 330.927503 -348.279798)
			(xy 330.973381 -348.250311) (xy 331.022988 -348.227652) (xy 331.075314 -348.212283) (xy 331.129296 -348.204517)
			(xy 331.156564 -348.204028) (xy 332.020164 -348.204028) (xy 332.047436 -348.204509) (xy 332.101425 -348.212267)
			(xy 332.153761 -348.22763) (xy 332.203377 -348.250284) (xy 332.249264 -348.27977) (xy 332.290488 -348.315487)
			(xy 332.326208 -348.356707) (xy 332.355698 -348.402591) (xy 332.378358 -348.452205) (xy 332.393726 -348.504539)
			(xy 332.401488 -348.558528) (xy 332.401488 -348.613072) (xy 332.401488 -348.613073) (xy 333.884192 -348.613073)
			(xy 333.884192 -348.558527) (xy 333.891955 -348.504537) (xy 333.907322 -348.452201) (xy 333.929982 -348.402585)
			(xy 333.959473 -348.356699) (xy 333.995194 -348.315477) (xy 334.036418 -348.279759) (xy 334.082306 -348.250271)
			(xy 334.131923 -348.227614) (xy 334.18426 -348.212249) (xy 334.238251 -348.20449) (xy 334.265524 -348.204028)
			(xy 335.129124 -348.204028) (xy 335.156392 -348.204536) (xy 335.210371 -348.2123) (xy 335.262696 -348.227667)
			(xy 335.312302 -348.250324) (xy 335.358179 -348.27981) (xy 335.399393 -348.315524) (xy 335.435104 -348.35674)
			(xy 335.464587 -348.402619) (xy 335.487241 -348.452226) (xy 335.502605 -348.504552) (xy 335.510366 -348.558532)
			(xy 335.510366 -348.613068) (xy 335.510366 -348.613069) (xy 336.993214 -348.613069) (xy 336.993214 -348.558531)
			(xy 337.000976 -348.504547) (xy 337.016341 -348.452217) (xy 337.038996 -348.402607) (xy 337.068482 -348.356726)
			(xy 337.104196 -348.315507) (xy 337.145413 -348.279791) (xy 337.191293 -348.250304) (xy 337.240902 -348.227646)
			(xy 337.293231 -348.212279) (xy 337.347215 -348.204516) (xy 337.374484 -348.204028) (xy 338.238084 -348.204028)
			(xy 338.265355 -348.20451) (xy 338.319342 -348.21227) (xy 338.371675 -348.227635) (xy 338.421289 -348.250291)
			(xy 338.467174 -348.279777) (xy 338.508395 -348.315494) (xy 338.544113 -348.356713) (xy 338.573601 -348.402597)
			(xy 338.596259 -348.45221) (xy 338.611626 -348.504542) (xy 338.619388 -348.558529) (xy 338.619388 -348.613071)
			(xy 338.619388 -348.613074) (xy 340.102092 -348.613074) (xy 340.102092 -348.558526) (xy 340.109855 -348.504534)
			(xy 340.125224 -348.452197) (xy 340.147885 -348.402579) (xy 340.177378 -348.356692) (xy 340.213101 -348.31547)
			(xy 340.254327 -348.279751) (xy 340.300218 -348.250264) (xy 340.349838 -348.227609) (xy 340.402177 -348.212246)
			(xy 340.45617 -348.204489) (xy 340.483444 -348.204028) (xy 341.347044 -348.204028) (xy 341.374311 -348.204537)
			(xy 341.428288 -348.212304) (xy 341.480611 -348.227673) (xy 341.530214 -348.250331) (xy 341.576088 -348.279817)
			(xy 341.6173 -348.315531) (xy 341.653009 -348.356747) (xy 341.68249 -348.402624) (xy 341.705143 -348.45223)
			(xy 341.720505 -348.504555) (xy 341.728266 -348.558533) (xy 341.728266 -348.613067) (xy 341.728265 -348.613072)
			(xy 343.211092 -348.613072) (xy 343.211092 -348.558528) (xy 343.218854 -348.504539) (xy 343.234221 -348.452205)
			(xy 343.256879 -348.40259) (xy 343.286368 -348.356705) (xy 343.322087 -348.315484) (xy 343.363309 -348.279766)
			(xy 343.409194 -348.250277) (xy 343.458809 -348.227619) (xy 343.511143 -348.212253) (xy 343.565132 -348.204491)
			(xy 343.592404 -348.204028) (xy 344.456004 -348.204028) (xy 344.483272 -348.204535) (xy 344.537254 -348.212297)
			(xy 344.589582 -348.227662) (xy 344.63919 -348.250318) (xy 344.685069 -348.279803) (xy 344.726286 -348.315517)
			(xy 344.761999 -348.356734) (xy 344.791484 -348.402613) (xy 344.81414 -348.452222) (xy 344.829504 -348.50455)
			(xy 344.837266 -348.558532) (xy 344.837266 -348.613068) (xy 344.837266 -348.613069) (xy 370.806714 -348.613069)
			(xy 370.806714 -348.558531) (xy 370.814476 -348.504548) (xy 370.82984 -348.452218) (xy 370.852496 -348.402608)
			(xy 370.881981 -348.356727) (xy 370.917695 -348.315509) (xy 370.958911 -348.279793) (xy 371.004791 -348.250305)
			(xy 371.054399 -348.227647) (xy 371.106728 -348.21228) (xy 371.160711 -348.204516) (xy 371.18798 -348.204028)
			(xy 372.05158 -348.204028) (xy 372.078851 -348.20451) (xy 372.132839 -348.21227) (xy 372.185173 -348.227634)
			(xy 372.234787 -348.25029) (xy 372.280672 -348.279776) (xy 372.321893 -348.315493) (xy 372.357612 -348.356712)
			(xy 372.387101 -348.402595) (xy 372.409759 -348.452209) (xy 372.425126 -348.504542) (xy 372.432888 -348.558529)
			(xy 372.432888 -348.613071) (xy 372.432888 -348.613074) (xy 373.915592 -348.613074) (xy 373.915592 -348.558526)
			(xy 373.923355 -348.504535) (xy 373.938724 -348.452197) (xy 373.961385 -348.40258) (xy 373.990877 -348.356694)
			(xy 374.0266 -348.315471) (xy 374.067826 -348.279753) (xy 374.113715 -348.250266) (xy 374.163335 -348.22761)
			(xy 374.215674 -348.212246) (xy 374.269666 -348.204489) (xy 374.29694 -348.204028) (xy 375.16054 -348.204028)
			(xy 375.187807 -348.204537) (xy 375.241785 -348.212303) (xy 375.294108 -348.227672) (xy 375.343712 -348.25033)
			(xy 375.389587 -348.279816) (xy 375.430798 -348.31553) (xy 375.466508 -348.356746) (xy 375.49599 -348.402623)
			(xy 375.518642 -348.45223) (xy 375.534005 -348.504554) (xy 375.541766 -348.558533) (xy 375.541766 -348.613067)
			(xy 375.541766 -348.61307) (xy 377.024614 -348.61307) (xy 377.024614 -348.55853) (xy 377.032376 -348.504545)
			(xy 377.047742 -348.452214) (xy 377.070399 -348.402603) (xy 377.099886 -348.35672) (xy 377.135602 -348.315502)
			(xy 377.17682 -348.279786) (xy 377.222703 -348.250299) (xy 377.272314 -348.227642) (xy 377.324645 -348.212276)
			(xy 377.37863 -348.204514) (xy 377.4059 -348.204028) (xy 378.2695 -348.204028) (xy 378.296769 -348.204534)
			(xy 378.350751 -348.212296) (xy 378.403079 -348.227661) (xy 378.452688 -348.250316) (xy 378.498568 -348.279802)
			(xy 378.539784 -348.315516) (xy 378.575498 -348.356732) (xy 378.604984 -348.402612) (xy 378.627639 -348.452221)
			(xy 378.643004 -348.504549) (xy 378.650766 -348.558531) (xy 378.650766 -348.613068) (xy 380.133614 -348.613068)
			(xy 380.133614 -348.558532) (xy 380.141375 -348.50455) (xy 380.156739 -348.452223) (xy 380.179393 -348.402614)
			(xy 380.208876 -348.356734) (xy 380.244588 -348.315516) (xy 380.285801 -348.2798) (xy 380.331679 -348.250312)
			(xy 380.381285 -348.227653) (xy 380.433611 -348.212284) (xy 380.487592 -348.204517) (xy 380.51486 -348.204028)
			(xy 381.37846 -348.204028) (xy 381.405732 -348.204509) (xy 381.459722 -348.212266) (xy 381.512058 -348.227628)
			(xy 381.561675 -348.250283) (xy 381.607562 -348.279769) (xy 381.648786 -348.315485) (xy 381.684507 -348.356706)
			(xy 381.713998 -348.40259) (xy 381.736658 -348.452204) (xy 381.752025 -348.504539) (xy 381.759788 -348.558528)
			(xy 381.759788 -348.613072) (xy 381.759788 -348.613073) (xy 383.242492 -348.613073) (xy 383.242492 -348.558527)
			(xy 383.250254 -348.504537) (xy 383.265622 -348.452202) (xy 383.288282 -348.402586) (xy 383.317772 -348.3567)
			(xy 383.353493 -348.315478) (xy 383.394716 -348.27976) (xy 383.440603 -348.250272) (xy 383.49022 -348.227615)
			(xy 383.542557 -348.21225) (xy 383.596547 -348.20449) (xy 383.62382 -348.204028) (xy 384.48742 -348.204028)
			(xy 384.514688 -348.204536) (xy 384.568668 -348.2123) (xy 384.620994 -348.227666) (xy 384.6706 -348.250323)
			(xy 384.716477 -348.279809) (xy 384.757691 -348.315523) (xy 384.793403 -348.356739) (xy 384.822887 -348.402618)
			(xy 384.845541 -348.452225) (xy 384.860905 -348.504552) (xy 384.868666 -348.558532) (xy 384.868666 -348.613068)
			(xy 384.868666 -348.613069) (xy 386.351514 -348.613069) (xy 386.351514 -348.558531) (xy 386.359276 -348.504548)
			(xy 386.37464 -348.452218) (xy 386.397296 -348.402608) (xy 386.426781 -348.356727) (xy 386.462495 -348.315509)
			(xy 386.503711 -348.279793) (xy 386.549591 -348.250305) (xy 386.599199 -348.227647) (xy 386.651528 -348.21228)
			(xy 386.705511 -348.204516) (xy 386.73278 -348.204028) (xy 387.59638 -348.204028) (xy 387.623651 -348.20451)
			(xy 387.677639 -348.21227) (xy 387.729973 -348.227634) (xy 387.779587 -348.25029) (xy 387.825472 -348.279776)
			(xy 387.866693 -348.315493) (xy 387.902412 -348.356712) (xy 387.931901 -348.402595) (xy 387.954559 -348.452209)
			(xy 387.969926 -348.504542) (xy 387.977688 -348.558529) (xy 387.977688 -348.613071) (xy 387.977688 -348.613074)
			(xy 389.460392 -348.613074) (xy 389.460392 -348.558526) (xy 389.468155 -348.504535) (xy 389.483524 -348.452197)
			(xy 389.506185 -348.40258) (xy 389.535677 -348.356694) (xy 389.5714 -348.315471) (xy 389.612626 -348.279753)
			(xy 389.658515 -348.250266) (xy 389.708135 -348.22761) (xy 389.760474 -348.212246) (xy 389.814466 -348.204489)
			(xy 389.84174 -348.204028) (xy 390.70534 -348.204028) (xy 390.732607 -348.204537) (xy 390.786585 -348.212303)
			(xy 390.838908 -348.227672) (xy 390.888512 -348.25033) (xy 390.934387 -348.279816) (xy 390.975598 -348.31553)
			(xy 391.011308 -348.356746) (xy 391.04079 -348.402623) (xy 391.063442 -348.45223) (xy 391.078805 -348.504554)
			(xy 391.086566 -348.558533) (xy 391.086566 -348.613067) (xy 391.086566 -348.61307) (xy 392.569414 -348.61307)
			(xy 392.569414 -348.55853) (xy 392.577176 -348.504545) (xy 392.592542 -348.452214) (xy 392.615199 -348.402603)
			(xy 392.644686 -348.35672) (xy 392.680402 -348.315502) (xy 392.72162 -348.279786) (xy 392.767503 -348.250299)
			(xy 392.817114 -348.227642) (xy 392.869445 -348.212276) (xy 392.92343 -348.204514) (xy 392.9507 -348.204028)
			(xy 393.8143 -348.204028) (xy 393.841569 -348.204534) (xy 393.895551 -348.212296) (xy 393.947879 -348.227661)
			(xy 393.997488 -348.250316) (xy 394.043368 -348.279802) (xy 394.084584 -348.315516) (xy 394.120298 -348.356732)
			(xy 394.149784 -348.402612) (xy 394.172439 -348.452221) (xy 394.187804 -348.504549) (xy 394.195566 -348.558531)
			(xy 394.195566 -348.613068) (xy 395.678414 -348.613068) (xy 395.678414 -348.558532) (xy 395.686175 -348.50455)
			(xy 395.701539 -348.452223) (xy 395.724193 -348.402614) (xy 395.753676 -348.356734) (xy 395.789388 -348.315516)
			(xy 395.830601 -348.2798) (xy 395.876479 -348.250312) (xy 395.926085 -348.227653) (xy 395.978411 -348.212284)
			(xy 396.032392 -348.204517) (xy 396.05966 -348.204028) (xy 396.92326 -348.204028) (xy 396.950532 -348.204509)
			(xy 397.004522 -348.212266) (xy 397.056858 -348.227628) (xy 397.106475 -348.250283) (xy 397.152362 -348.279769)
			(xy 397.193586 -348.315485) (xy 397.229307 -348.356706) (xy 397.258798 -348.40259) (xy 397.281458 -348.452204)
			(xy 397.296825 -348.504539) (xy 397.304588 -348.558528) (xy 397.304588 -348.613072) (xy 397.304588 -348.613073)
			(xy 398.787292 -348.613073) (xy 398.787292 -348.558527) (xy 398.795054 -348.504537) (xy 398.810422 -348.452202)
			(xy 398.833082 -348.402586) (xy 398.862572 -348.3567) (xy 398.898293 -348.315478) (xy 398.939516 -348.27976)
			(xy 398.985403 -348.250272) (xy 399.03502 -348.227615) (xy 399.087357 -348.21225) (xy 399.141347 -348.20449)
			(xy 399.16862 -348.204028) (xy 400.03222 -348.204028) (xy 400.059488 -348.204536) (xy 400.113468 -348.2123)
			(xy 400.165794 -348.227666) (xy 400.2154 -348.250323) (xy 400.261277 -348.279809) (xy 400.302491 -348.315523)
			(xy 400.338203 -348.356739) (xy 400.367687 -348.402618) (xy 400.390341 -348.452225) (xy 400.405705 -348.504552)
			(xy 400.413466 -348.558532) (xy 400.413466 -348.613068) (xy 400.413466 -348.613069) (xy 401.896314 -348.613069)
			(xy 401.896314 -348.558531) (xy 401.904076 -348.504548) (xy 401.91944 -348.452218) (xy 401.942096 -348.402608)
			(xy 401.971581 -348.356727) (xy 402.007295 -348.315509) (xy 402.048511 -348.279793) (xy 402.094391 -348.250305)
			(xy 402.143999 -348.227647) (xy 402.196328 -348.21228) (xy 402.250311 -348.204516) (xy 402.27758 -348.204028)
			(xy 403.14118 -348.204028) (xy 403.168451 -348.20451) (xy 403.222439 -348.21227) (xy 403.274773 -348.227634)
			(xy 403.324387 -348.25029) (xy 403.370272 -348.279776) (xy 403.411493 -348.315493) (xy 403.447212 -348.356712)
			(xy 403.476701 -348.402595) (xy 403.499359 -348.452209) (xy 403.514726 -348.504542) (xy 403.522488 -348.558529)
			(xy 403.522488 -348.61307) (xy 408.913814 -348.61307) (xy 408.913814 -348.55853) (xy 408.921576 -348.504546)
			(xy 408.936941 -348.452216) (xy 408.959598 -348.402605) (xy 408.989084 -348.356723) (xy 409.024799 -348.315505)
			(xy 409.066017 -348.279788) (xy 409.111898 -348.250301) (xy 409.161508 -348.227644) (xy 409.213838 -348.212278)
			(xy 409.267822 -348.204515) (xy 409.295092 -348.204028) (xy 410.158692 -348.204028) (xy 410.185963 -348.204511)
			(xy 410.239949 -348.212272) (xy 410.292281 -348.227637) (xy 410.341894 -348.250294) (xy 410.387778 -348.27978)
			(xy 410.428998 -348.315497) (xy 410.464715 -348.356716) (xy 410.494203 -348.402599) (xy 410.51686 -348.452211)
			(xy 410.532226 -348.504543) (xy 410.539989 -348.558529) (xy 410.539989 -348.613068) (xy 412.022814 -348.613068)
			(xy 412.022814 -348.558532) (xy 412.030575 -348.504551) (xy 412.045938 -348.452224) (xy 412.068592 -348.402616)
			(xy 412.098074 -348.356736) (xy 412.133785 -348.315519) (xy 412.174998 -348.279803) (xy 412.220874 -348.250315)
			(xy 412.270479 -348.227655) (xy 412.322804 -348.212285) (xy 412.376784 -348.204518) (xy 412.404052 -348.204028)
			(xy 413.267652 -348.204028) (xy 413.294925 -348.204508) (xy 413.348915 -348.212265) (xy 413.401252 -348.227626)
			(xy 413.45087 -348.250281) (xy 413.496759 -348.279766) (xy 413.537983 -348.315483) (xy 413.573705 -348.356703)
			(xy 413.603196 -348.402588) (xy 413.625857 -348.452203) (xy 413.641225 -348.504538) (xy 413.648988 -348.558528)
			(xy 413.648988 -348.613072) (xy 415.131692 -348.613072) (xy 415.131692 -348.558528) (xy 415.139454 -348.504538)
			(xy 415.154821 -348.452203) (xy 415.177481 -348.402588) (xy 415.20697 -348.356703) (xy 415.24269 -348.315481)
			(xy 415.283912 -348.279763) (xy 415.329799 -348.250275) (xy 415.379415 -348.227617) (xy 415.43175 -348.212252)
			(xy 415.48574 -348.204491) (xy 415.513012 -348.204028) (xy 416.376612 -348.204028) (xy 416.40388 -348.204535)
			(xy 416.457861 -348.212298) (xy 416.510188 -348.227664) (xy 416.559795 -348.25032) (xy 416.605673 -348.279806)
			(xy 416.646888 -348.31552) (xy 416.682601 -348.356736) (xy 416.712085 -348.402615) (xy 416.73474 -348.452224)
			(xy 416.750104 -348.504551) (xy 416.757866 -348.558532) (xy 416.757866 -348.613068) (xy 416.757866 -348.613069)
			(xy 418.240714 -348.613069) (xy 418.240714 -348.558531) (xy 418.248476 -348.504549) (xy 418.26384 -348.45222)
			(xy 418.286495 -348.40261) (xy 418.315979 -348.35673) (xy 418.351692 -348.315512) (xy 418.392907 -348.279795)
			(xy 418.438786 -348.250308) (xy 418.488394 -348.22765) (xy 418.540721 -348.212281) (xy 418.594703 -348.204516)
			(xy 418.621972 -348.204028) (xy 419.485572 -348.204028) (xy 419.512844 -348.20451) (xy 419.566832 -348.212268)
			(xy 419.619167 -348.227632) (xy 419.668782 -348.250287) (xy 419.714668 -348.279773) (xy 419.75589 -348.31549)
			(xy 419.79161 -348.356709) (xy 419.821099 -348.402593) (xy 419.843759 -348.452207) (xy 419.859126 -348.504541)
			(xy 419.866888 -348.558528) (xy 419.866888 -348.613072) (xy 419.866888 -348.613073) (xy 421.349592 -348.613073)
			(xy 421.349592 -348.558527) (xy 421.357355 -348.504536) (xy 421.372723 -348.452199) (xy 421.395384 -348.402583)
			(xy 421.424875 -348.356696) (xy 421.460597 -348.315474) (xy 421.501822 -348.279756) (xy 421.547711 -348.250268)
			(xy 421.597329 -348.227612) (xy 421.649667 -348.212248) (xy 421.703659 -348.204489) (xy 421.730932 -348.204028)
			(xy 422.594532 -348.204028) (xy 422.621799 -348.204537) (xy 422.675778 -348.212302) (xy 422.728102 -348.227669)
			(xy 422.777707 -348.250327) (xy 422.823583 -348.279813) (xy 422.864795 -348.315527) (xy 422.900506 -348.356743)
			(xy 422.929988 -348.402621) (xy 422.952642 -348.452228) (xy 422.968005 -348.504553) (xy 422.975766 -348.558533)
			(xy 422.975766 -348.613067) (xy 422.975766 -348.61307) (xy 424.458614 -348.61307) (xy 424.458614 -348.55853)
			(xy 424.466376 -348.504546) (xy 424.481741 -348.452216) (xy 424.504398 -348.402605) (xy 424.533884 -348.356723)
			(xy 424.569599 -348.315505) (xy 424.610817 -348.279788) (xy 424.656698 -348.250301) (xy 424.706308 -348.227644)
			(xy 424.758638 -348.212278) (xy 424.812622 -348.204515) (xy 424.839892 -348.204028) (xy 425.703492 -348.204028)
			(xy 425.730763 -348.204511) (xy 425.784749 -348.212272) (xy 425.837081 -348.227637) (xy 425.886694 -348.250294)
			(xy 425.932578 -348.27978) (xy 425.973798 -348.315497) (xy 426.009515 -348.356716) (xy 426.039003 -348.402599)
			(xy 426.06166 -348.452211) (xy 426.077026 -348.504543) (xy 426.084789 -348.558529) (xy 426.084789 -348.613068)
			(xy 427.567614 -348.613068) (xy 427.567614 -348.558532) (xy 427.575375 -348.504551) (xy 427.590738 -348.452224)
			(xy 427.613392 -348.402616) (xy 427.642874 -348.356736) (xy 427.678585 -348.315519) (xy 427.719798 -348.279803)
			(xy 427.765674 -348.250315) (xy 427.815279 -348.227655) (xy 427.867604 -348.212285) (xy 427.921584 -348.204518)
			(xy 427.948852 -348.204028) (xy 428.812452 -348.204028) (xy 428.839725 -348.204508) (xy 428.893715 -348.212265)
			(xy 428.946052 -348.227626) (xy 428.99567 -348.250281) (xy 429.041559 -348.279766) (xy 429.082783 -348.315483)
			(xy 429.118505 -348.356703) (xy 429.147996 -348.402588) (xy 429.170657 -348.452203) (xy 429.186025 -348.504538)
			(xy 429.193788 -348.558528) (xy 429.193788 -348.613072) (xy 430.676492 -348.613072) (xy 430.676492 -348.558528)
			(xy 430.684254 -348.504538) (xy 430.699621 -348.452203) (xy 430.722281 -348.402588) (xy 430.75177 -348.356703)
			(xy 430.78749 -348.315481) (xy 430.828712 -348.279763) (xy 430.874599 -348.250275) (xy 430.924215 -348.227617)
			(xy 430.97655 -348.212252) (xy 431.03054 -348.204491) (xy 431.057812 -348.204028) (xy 431.921412 -348.204028)
			(xy 431.94868 -348.204535) (xy 432.002661 -348.212298) (xy 432.054988 -348.227664) (xy 432.104595 -348.25032)
			(xy 432.150473 -348.279806) (xy 432.191688 -348.31552) (xy 432.227401 -348.356736) (xy 432.256885 -348.402615)
			(xy 432.27954 -348.452224) (xy 432.294904 -348.504551) (xy 432.302666 -348.558532) (xy 432.302666 -348.613068)
			(xy 432.302666 -348.613069) (xy 433.785514 -348.613069) (xy 433.785514 -348.558531) (xy 433.793276 -348.504549)
			(xy 433.80864 -348.45222) (xy 433.831295 -348.40261) (xy 433.860779 -348.35673) (xy 433.896492 -348.315512)
			(xy 433.937707 -348.279795) (xy 433.983586 -348.250308) (xy 434.033194 -348.22765) (xy 434.085521 -348.212281)
			(xy 434.139503 -348.204516) (xy 434.166772 -348.204028) (xy 435.030372 -348.204028) (xy 435.057644 -348.20451)
			(xy 435.111632 -348.212268) (xy 435.163967 -348.227632) (xy 435.213582 -348.250287) (xy 435.259468 -348.279773)
			(xy 435.30069 -348.31549) (xy 435.33641 -348.356709) (xy 435.365899 -348.402593) (xy 435.388559 -348.452207)
			(xy 435.403926 -348.504541) (xy 435.411688 -348.558528) (xy 435.411688 -348.613072) (xy 435.411688 -348.613073)
			(xy 436.894392 -348.613073) (xy 436.894392 -348.558527) (xy 436.902155 -348.504536) (xy 436.917523 -348.452199)
			(xy 436.940184 -348.402583) (xy 436.969675 -348.356696) (xy 437.005397 -348.315474) (xy 437.046622 -348.279756)
			(xy 437.092511 -348.250268) (xy 437.142129 -348.227612) (xy 437.194467 -348.212248) (xy 437.248459 -348.204489)
			(xy 437.275732 -348.204028) (xy 438.139332 -348.204028) (xy 438.166599 -348.204537) (xy 438.220578 -348.212302)
			(xy 438.272902 -348.227669) (xy 438.322507 -348.250327) (xy 438.368383 -348.279813) (xy 438.409595 -348.315527)
			(xy 438.445306 -348.356743) (xy 438.474788 -348.402621) (xy 438.497442 -348.452228) (xy 438.512805 -348.504553)
			(xy 438.520566 -348.558533) (xy 438.520566 -348.613067) (xy 438.520566 -348.61307) (xy 440.003414 -348.61307)
			(xy 440.003414 -348.55853) (xy 440.011176 -348.504546) (xy 440.026541 -348.452216) (xy 440.049198 -348.402605)
			(xy 440.078684 -348.356723) (xy 440.114399 -348.315505) (xy 440.155617 -348.279788) (xy 440.201498 -348.250301)
			(xy 440.251108 -348.227644) (xy 440.303438 -348.212278) (xy 440.357422 -348.204515) (xy 440.384692 -348.204028)
			(xy 441.248292 -348.204028) (xy 441.275563 -348.204511) (xy 441.329549 -348.212272) (xy 441.381881 -348.227637)
			(xy 441.431494 -348.250294) (xy 441.477378 -348.27978) (xy 441.518598 -348.315497) (xy 441.554315 -348.356716)
			(xy 441.583803 -348.402599) (xy 441.60646 -348.452211) (xy 441.621826 -348.504543) (xy 441.629589 -348.558529)
			(xy 441.629589 -348.613071) (xy 441.621826 -348.667057) (xy 441.60646 -348.719389) (xy 441.583803 -348.769001)
			(xy 441.554315 -348.814884) (xy 441.518598 -348.856103) (xy 441.477378 -348.89182) (xy 441.431494 -348.921306)
			(xy 441.381881 -348.943963) (xy 441.329549 -348.959328) (xy 441.275563 -348.967089) (xy 441.248292 -348.967552)
			(xy 440.384692 -348.967552) (xy 440.357422 -348.967085) (xy 440.303438 -348.959322) (xy 440.251108 -348.943956)
			(xy 440.201498 -348.921299) (xy 440.155617 -348.891812) (xy 440.114399 -348.856095) (xy 440.078684 -348.814877)
			(xy 440.049198 -348.768995) (xy 440.026541 -348.719384) (xy 440.011176 -348.667054) (xy 440.003414 -348.61307)
			(xy 438.520566 -348.61307) (xy 438.512805 -348.667047) (xy 438.497442 -348.719372) (xy 438.474788 -348.768979)
			(xy 438.445306 -348.814857) (xy 438.409595 -348.856073) (xy 438.368383 -348.891787) (xy 438.322507 -348.921273)
			(xy 438.272902 -348.943931) (xy 438.220578 -348.959298) (xy 438.166599 -348.967063) (xy 438.139332 -348.967552)
			(xy 437.275732 -348.967552) (xy 437.248459 -348.967111) (xy 437.194467 -348.959352) (xy 437.142129 -348.943988)
			(xy 437.092511 -348.921332) (xy 437.046622 -348.891844) (xy 437.005397 -348.856126) (xy 436.969675 -348.814904)
			(xy 436.940184 -348.769017) (xy 436.917523 -348.719401) (xy 436.902155 -348.667064) (xy 436.894392 -348.613073)
			(xy 435.411688 -348.613073) (xy 435.403926 -348.667059) (xy 435.388559 -348.719393) (xy 435.365899 -348.769007)
			(xy 435.33641 -348.814891) (xy 435.30069 -348.85611) (xy 435.259468 -348.891827) (xy 435.213582 -348.921313)
			(xy 435.163967 -348.943968) (xy 435.111632 -348.959332) (xy 435.057644 -348.96709) (xy 435.030372 -348.967552)
			(xy 434.166772 -348.967552) (xy 434.139503 -348.967084) (xy 434.085521 -348.959319) (xy 434.033194 -348.94395)
			(xy 433.983586 -348.921292) (xy 433.937707 -348.891805) (xy 433.896492 -348.856088) (xy 433.860779 -348.81487)
			(xy 433.831295 -348.76899) (xy 433.80864 -348.71938) (xy 433.793276 -348.667051) (xy 433.785514 -348.613069)
			(xy 432.302666 -348.613069) (xy 432.294904 -348.667049) (xy 432.27954 -348.719376) (xy 432.256885 -348.768985)
			(xy 432.227401 -348.814864) (xy 432.191688 -348.85608) (xy 432.150473 -348.891794) (xy 432.104595 -348.92128)
			(xy 432.054988 -348.943936) (xy 432.002661 -348.959302) (xy 431.94868 -348.967065) (xy 431.921412 -348.967552)
			(xy 431.057812 -348.967552) (xy 431.03054 -348.967109) (xy 430.97655 -348.959348) (xy 430.924215 -348.943983)
			(xy 430.874599 -348.921325) (xy 430.828712 -348.891837) (xy 430.78749 -348.856119) (xy 430.75177 -348.814897)
			(xy 430.722281 -348.769012) (xy 430.699621 -348.719397) (xy 430.684254 -348.667062) (xy 430.676492 -348.613072)
			(xy 429.193788 -348.613072) (xy 429.186025 -348.667062) (xy 429.170657 -348.719397) (xy 429.147996 -348.769012)
			(xy 429.118505 -348.814897) (xy 429.082783 -348.856117) (xy 429.041559 -348.891834) (xy 428.99567 -348.921319)
			(xy 428.946052 -348.943974) (xy 428.893715 -348.959335) (xy 428.839725 -348.967092) (xy 428.812452 -348.967552)
			(xy 427.948852 -348.967552) (xy 427.921584 -348.967082) (xy 427.867604 -348.959315) (xy 427.815279 -348.943945)
			(xy 427.765674 -348.921285) (xy 427.719798 -348.891797) (xy 427.678585 -348.856081) (xy 427.642874 -348.814864)
			(xy 427.613392 -348.768984) (xy 427.590738 -348.719376) (xy 427.575375 -348.667049) (xy 427.567614 -348.613068)
			(xy 426.084789 -348.613068) (xy 426.084789 -348.613071) (xy 426.077026 -348.667057) (xy 426.06166 -348.719389)
			(xy 426.039003 -348.769001) (xy 426.009515 -348.814884) (xy 425.973798 -348.856103) (xy 425.932578 -348.89182)
			(xy 425.886694 -348.921306) (xy 425.837081 -348.943963) (xy 425.784749 -348.959328) (xy 425.730763 -348.967089)
			(xy 425.703492 -348.967552) (xy 424.839892 -348.967552) (xy 424.812622 -348.967085) (xy 424.758638 -348.959322)
			(xy 424.706308 -348.943956) (xy 424.656698 -348.921299) (xy 424.610817 -348.891812) (xy 424.569599 -348.856095)
			(xy 424.533884 -348.814877) (xy 424.504398 -348.768995) (xy 424.481741 -348.719384) (xy 424.466376 -348.667054)
			(xy 424.458614 -348.61307) (xy 422.975766 -348.61307) (xy 422.968005 -348.667047) (xy 422.952642 -348.719372)
			(xy 422.929988 -348.768979) (xy 422.900506 -348.814857) (xy 422.864795 -348.856073) (xy 422.823583 -348.891787)
			(xy 422.777707 -348.921273) (xy 422.728102 -348.943931) (xy 422.675778 -348.959298) (xy 422.621799 -348.967063)
			(xy 422.594532 -348.967552) (xy 421.730932 -348.967552) (xy 421.703659 -348.967111) (xy 421.649667 -348.959352)
			(xy 421.597329 -348.943988) (xy 421.547711 -348.921332) (xy 421.501822 -348.891844) (xy 421.460597 -348.856126)
			(xy 421.424875 -348.814904) (xy 421.395384 -348.769017) (xy 421.372723 -348.719401) (xy 421.357355 -348.667064)
			(xy 421.349592 -348.613073) (xy 419.866888 -348.613073) (xy 419.859126 -348.667059) (xy 419.843759 -348.719393)
			(xy 419.821099 -348.769007) (xy 419.79161 -348.814891) (xy 419.75589 -348.85611) (xy 419.714668 -348.891827)
			(xy 419.668782 -348.921313) (xy 419.619167 -348.943968) (xy 419.566832 -348.959332) (xy 419.512844 -348.96709)
			(xy 419.485572 -348.967552) (xy 418.621972 -348.967552) (xy 418.594703 -348.967084) (xy 418.540721 -348.959319)
			(xy 418.488394 -348.94395) (xy 418.438786 -348.921292) (xy 418.392907 -348.891805) (xy 418.351692 -348.856088)
			(xy 418.315979 -348.81487) (xy 418.286495 -348.76899) (xy 418.26384 -348.71938) (xy 418.248476 -348.667051)
			(xy 418.240714 -348.613069) (xy 416.757866 -348.613069) (xy 416.750104 -348.667049) (xy 416.73474 -348.719376)
			(xy 416.712085 -348.768985) (xy 416.682601 -348.814864) (xy 416.646888 -348.85608) (xy 416.605673 -348.891794)
			(xy 416.559795 -348.92128) (xy 416.510188 -348.943936) (xy 416.457861 -348.959302) (xy 416.40388 -348.967065)
			(xy 416.376612 -348.967552) (xy 415.513012 -348.967552) (xy 415.48574 -348.967109) (xy 415.43175 -348.959348)
			(xy 415.379415 -348.943983) (xy 415.329799 -348.921325) (xy 415.283912 -348.891837) (xy 415.24269 -348.856119)
			(xy 415.20697 -348.814897) (xy 415.177481 -348.769012) (xy 415.154821 -348.719397) (xy 415.139454 -348.667062)
			(xy 415.131692 -348.613072) (xy 413.648988 -348.613072) (xy 413.641225 -348.667062) (xy 413.625857 -348.719397)
			(xy 413.603196 -348.769012) (xy 413.573705 -348.814897) (xy 413.537983 -348.856117) (xy 413.496759 -348.891834)
			(xy 413.45087 -348.921319) (xy 413.401252 -348.943974) (xy 413.348915 -348.959335) (xy 413.294925 -348.967092)
			(xy 413.267652 -348.967552) (xy 412.404052 -348.967552) (xy 412.376784 -348.967082) (xy 412.322804 -348.959315)
			(xy 412.270479 -348.943945) (xy 412.220874 -348.921285) (xy 412.174998 -348.891797) (xy 412.133785 -348.856081)
			(xy 412.098074 -348.814864) (xy 412.068592 -348.768984) (xy 412.045938 -348.719376) (xy 412.030575 -348.667049)
			(xy 412.022814 -348.613068) (xy 410.539989 -348.613068) (xy 410.539989 -348.613071) (xy 410.532226 -348.667057)
			(xy 410.51686 -348.719389) (xy 410.494203 -348.769001) (xy 410.464715 -348.814884) (xy 410.428998 -348.856103)
			(xy 410.387778 -348.89182) (xy 410.341894 -348.921306) (xy 410.292281 -348.943963) (xy 410.239949 -348.959328)
			(xy 410.185963 -348.967089) (xy 410.158692 -348.967552) (xy 409.295092 -348.967552) (xy 409.267822 -348.967085)
			(xy 409.213838 -348.959322) (xy 409.161508 -348.943956) (xy 409.111898 -348.921299) (xy 409.066017 -348.891812)
			(xy 409.024799 -348.856095) (xy 408.989084 -348.814877) (xy 408.959598 -348.768995) (xy 408.936941 -348.719384)
			(xy 408.921576 -348.667054) (xy 408.913814 -348.61307) (xy 403.522488 -348.61307) (xy 403.522488 -348.613071)
			(xy 403.514726 -348.667058) (xy 403.499359 -348.719391) (xy 403.476701 -348.769005) (xy 403.447212 -348.814888)
			(xy 403.411493 -348.856107) (xy 403.370272 -348.891824) (xy 403.324387 -348.92131) (xy 403.274773 -348.943966)
			(xy 403.222439 -348.95933) (xy 403.168451 -348.96709) (xy 403.14118 -348.967552) (xy 402.27758 -348.967552)
			(xy 402.250311 -348.967084) (xy 402.196328 -348.95932) (xy 402.143999 -348.943953) (xy 402.094391 -348.921295)
			(xy 402.048511 -348.891807) (xy 402.007295 -348.856091) (xy 401.971581 -348.814873) (xy 401.942096 -348.768992)
			(xy 401.91944 -348.719382) (xy 401.904076 -348.667052) (xy 401.896314 -348.613069) (xy 400.413466 -348.613069)
			(xy 400.405705 -348.667048) (xy 400.390341 -348.719375) (xy 400.367687 -348.768982) (xy 400.338203 -348.814861)
			(xy 400.302491 -348.856077) (xy 400.261277 -348.891791) (xy 400.2154 -348.921277) (xy 400.165794 -348.943934)
			(xy 400.113468 -348.9593) (xy 400.059488 -348.967064) (xy 400.03222 -348.967552) (xy 399.16862 -348.967552)
			(xy 399.141347 -348.96711) (xy 399.087357 -348.95935) (xy 399.03502 -348.943985) (xy 398.985403 -348.921328)
			(xy 398.939516 -348.89184) (xy 398.898293 -348.856122) (xy 398.862572 -348.8149) (xy 398.833082 -348.769014)
			(xy 398.810422 -348.719398) (xy 398.795054 -348.667063) (xy 398.787292 -348.613073) (xy 397.304588 -348.613073)
			(xy 397.296825 -348.667061) (xy 397.281458 -348.719396) (xy 397.258798 -348.76901) (xy 397.229307 -348.814894)
			(xy 397.193586 -348.856115) (xy 397.152362 -348.891831) (xy 397.106475 -348.921317) (xy 397.056858 -348.943972)
			(xy 397.004522 -348.959334) (xy 396.950532 -348.967091) (xy 396.92326 -348.967552) (xy 396.05966 -348.967552)
			(xy 396.032392 -348.967083) (xy 395.978411 -348.959316) (xy 395.926085 -348.943947) (xy 395.876479 -348.921288)
			(xy 395.830601 -348.8918) (xy 395.789388 -348.856084) (xy 395.753676 -348.814866) (xy 395.724193 -348.768986)
			(xy 395.701539 -348.719377) (xy 395.686175 -348.66705) (xy 395.678414 -348.613068) (xy 394.195566 -348.613068)
			(xy 394.195566 -348.613069) (xy 394.187804 -348.667051) (xy 394.172439 -348.719379) (xy 394.149784 -348.768988)
			(xy 394.120298 -348.814868) (xy 394.084584 -348.856084) (xy 394.043368 -348.891798) (xy 393.997488 -348.921284)
			(xy 393.947879 -348.943939) (xy 393.895551 -348.959304) (xy 393.841569 -348.967066) (xy 393.8143 -348.967552)
			(xy 392.9507 -348.967552) (xy 392.92343 -348.967086) (xy 392.869445 -348.959324) (xy 392.817114 -348.943958)
			(xy 392.767503 -348.921301) (xy 392.72162 -348.891814) (xy 392.680402 -348.856098) (xy 392.644686 -348.81488)
			(xy 392.615199 -348.768997) (xy 392.592542 -348.719386) (xy 392.577176 -348.667055) (xy 392.569414 -348.61307)
			(xy 391.086566 -348.61307) (xy 391.078805 -348.667046) (xy 391.063442 -348.71937) (xy 391.04079 -348.768977)
			(xy 391.011308 -348.814854) (xy 390.975598 -348.85607) (xy 390.934387 -348.891784) (xy 390.888512 -348.92127)
			(xy 390.838908 -348.943928) (xy 390.786585 -348.959297) (xy 390.732607 -348.967063) (xy 390.70534 -348.967552)
			(xy 389.84174 -348.967552) (xy 389.814466 -348.967111) (xy 389.760474 -348.959354) (xy 389.708135 -348.94399)
			(xy 389.658515 -348.921334) (xy 389.612626 -348.891847) (xy 389.5714 -348.856129) (xy 389.535677 -348.814906)
			(xy 389.506185 -348.76902) (xy 389.483524 -348.719403) (xy 389.468155 -348.667065) (xy 389.460392 -348.613074)
			(xy 387.977688 -348.613074) (xy 387.969926 -348.667058) (xy 387.954559 -348.719391) (xy 387.931901 -348.769005)
			(xy 387.902412 -348.814888) (xy 387.866693 -348.856107) (xy 387.825472 -348.891824) (xy 387.779587 -348.92131)
			(xy 387.729973 -348.943966) (xy 387.677639 -348.95933) (xy 387.623651 -348.96709) (xy 387.59638 -348.967552)
			(xy 386.73278 -348.967552) (xy 386.705511 -348.967084) (xy 386.651528 -348.95932) (xy 386.599199 -348.943953)
			(xy 386.549591 -348.921295) (xy 386.503711 -348.891807) (xy 386.462495 -348.856091) (xy 386.426781 -348.814873)
			(xy 386.397296 -348.768992) (xy 386.37464 -348.719382) (xy 386.359276 -348.667052) (xy 386.351514 -348.613069)
			(xy 384.868666 -348.613069) (xy 384.860905 -348.667048) (xy 384.845541 -348.719375) (xy 384.822887 -348.768982)
			(xy 384.793403 -348.814861) (xy 384.757691 -348.856077) (xy 384.716477 -348.891791) (xy 384.6706 -348.921277)
			(xy 384.620994 -348.943934) (xy 384.568668 -348.9593) (xy 384.514688 -348.967064) (xy 384.48742 -348.967552)
			(xy 383.62382 -348.967552) (xy 383.596547 -348.96711) (xy 383.542557 -348.95935) (xy 383.49022 -348.943985)
			(xy 383.440603 -348.921328) (xy 383.394716 -348.89184) (xy 383.353493 -348.856122) (xy 383.317772 -348.8149)
			(xy 383.288282 -348.769014) (xy 383.265622 -348.719398) (xy 383.250254 -348.667063) (xy 383.242492 -348.613073)
			(xy 381.759788 -348.613073) (xy 381.752025 -348.667061) (xy 381.736658 -348.719396) (xy 381.713998 -348.76901)
			(xy 381.684507 -348.814894) (xy 381.648786 -348.856115) (xy 381.607562 -348.891831) (xy 381.561675 -348.921317)
			(xy 381.512058 -348.943972) (xy 381.459722 -348.959334) (xy 381.405732 -348.967091) (xy 381.37846 -348.967552)
			(xy 380.51486 -348.967552) (xy 380.487592 -348.967083) (xy 380.433611 -348.959316) (xy 380.381285 -348.943947)
			(xy 380.331679 -348.921288) (xy 380.285801 -348.8918) (xy 380.244588 -348.856084) (xy 380.208876 -348.814866)
			(xy 380.179393 -348.768986) (xy 380.156739 -348.719377) (xy 380.141375 -348.66705) (xy 380.133614 -348.613068)
			(xy 378.650766 -348.613068) (xy 378.650766 -348.613069) (xy 378.643004 -348.667051) (xy 378.627639 -348.719379)
			(xy 378.604984 -348.768988) (xy 378.575498 -348.814868) (xy 378.539784 -348.856084) (xy 378.498568 -348.891798)
			(xy 378.452688 -348.921284) (xy 378.403079 -348.943939) (xy 378.350751 -348.959304) (xy 378.296769 -348.967066)
			(xy 378.2695 -348.967552) (xy 377.4059 -348.967552) (xy 377.37863 -348.967086) (xy 377.324645 -348.959324)
			(xy 377.272314 -348.943958) (xy 377.222703 -348.921301) (xy 377.17682 -348.891814) (xy 377.135602 -348.856098)
			(xy 377.099886 -348.81488) (xy 377.070399 -348.768997) (xy 377.047742 -348.719386) (xy 377.032376 -348.667055)
			(xy 377.024614 -348.61307) (xy 375.541766 -348.61307) (xy 375.534005 -348.667046) (xy 375.518642 -348.71937)
			(xy 375.49599 -348.768977) (xy 375.466508 -348.814854) (xy 375.430798 -348.85607) (xy 375.389587 -348.891784)
			(xy 375.343712 -348.92127) (xy 375.294108 -348.943928) (xy 375.241785 -348.959297) (xy 375.187807 -348.967063)
			(xy 375.16054 -348.967552) (xy 374.29694 -348.967552) (xy 374.269666 -348.967111) (xy 374.215674 -348.959354)
			(xy 374.163335 -348.94399) (xy 374.113715 -348.921334) (xy 374.067826 -348.891847) (xy 374.0266 -348.856129)
			(xy 373.990877 -348.814906) (xy 373.961385 -348.76902) (xy 373.938724 -348.719403) (xy 373.923355 -348.667065)
			(xy 373.915592 -348.613074) (xy 372.432888 -348.613074) (xy 372.425126 -348.667058) (xy 372.409759 -348.719391)
			(xy 372.387101 -348.769005) (xy 372.357612 -348.814888) (xy 372.321893 -348.856107) (xy 372.280672 -348.891824)
			(xy 372.234787 -348.92131) (xy 372.185173 -348.943966) (xy 372.132839 -348.95933) (xy 372.078851 -348.96709)
			(xy 372.05158 -348.967552) (xy 371.18798 -348.967552) (xy 371.160711 -348.967084) (xy 371.106728 -348.95932)
			(xy 371.054399 -348.943953) (xy 371.004791 -348.921295) (xy 370.958911 -348.891807) (xy 370.917695 -348.856091)
			(xy 370.881981 -348.814873) (xy 370.852496 -348.768992) (xy 370.82984 -348.719382) (xy 370.814476 -348.667052)
			(xy 370.806714 -348.613069) (xy 344.837266 -348.613069) (xy 344.829504 -348.66705) (xy 344.81414 -348.719378)
			(xy 344.791484 -348.768987) (xy 344.761999 -348.814866) (xy 344.726286 -348.856083) (xy 344.685069 -348.891797)
			(xy 344.63919 -348.921282) (xy 344.589582 -348.943938) (xy 344.537254 -348.959303) (xy 344.483272 -348.967065)
			(xy 344.456004 -348.967552) (xy 343.592404 -348.967552) (xy 343.565132 -348.967109) (xy 343.511143 -348.959347)
			(xy 343.458809 -348.943981) (xy 343.409194 -348.921323) (xy 343.363309 -348.891834) (xy 343.322087 -348.856116)
			(xy 343.286368 -348.814895) (xy 343.256879 -348.76901) (xy 343.234221 -348.719395) (xy 343.218854 -348.667061)
			(xy 343.211092 -348.613072) (xy 341.728265 -348.613072) (xy 341.720505 -348.667045) (xy 341.705143 -348.71937)
			(xy 341.68249 -348.768976) (xy 341.653009 -348.814853) (xy 341.6173 -348.856069) (xy 341.576088 -348.891783)
			(xy 341.530214 -348.921269) (xy 341.480611 -348.943927) (xy 341.428288 -348.959296) (xy 341.374311 -348.967063)
			(xy 341.347044 -348.967552) (xy 340.483444 -348.967552) (xy 340.45617 -348.967111) (xy 340.402177 -348.959354)
			(xy 340.349838 -348.943991) (xy 340.300218 -348.921336) (xy 340.254327 -348.891849) (xy 340.213101 -348.85613)
			(xy 340.177378 -348.814908) (xy 340.147885 -348.769021) (xy 340.125224 -348.719403) (xy 340.109855 -348.667066)
			(xy 340.102092 -348.613074) (xy 338.619388 -348.613074) (xy 338.611626 -348.667058) (xy 338.596259 -348.71939)
			(xy 338.573601 -348.769003) (xy 338.544113 -348.814887) (xy 338.508395 -348.856106) (xy 338.467174 -348.891823)
			(xy 338.421289 -348.921309) (xy 338.371675 -348.943965) (xy 338.319342 -348.95933) (xy 338.265355 -348.96709)
			(xy 338.238084 -348.967552) (xy 337.374484 -348.967552) (xy 337.347215 -348.967084) (xy 337.293231 -348.959321)
			(xy 337.240902 -348.943954) (xy 337.191293 -348.921296) (xy 337.145413 -348.891809) (xy 337.104196 -348.856093)
			(xy 337.068482 -348.814874) (xy 337.038996 -348.768993) (xy 337.016341 -348.719383) (xy 337.000976 -348.667053)
			(xy 336.993214 -348.613069) (xy 335.510366 -348.613069) (xy 335.502605 -348.667048) (xy 335.487241 -348.719374)
			(xy 335.464587 -348.768981) (xy 335.435104 -348.81486) (xy 335.399393 -348.856076) (xy 335.358179 -348.89179)
			(xy 335.312302 -348.921276) (xy 335.262696 -348.943933) (xy 335.210371 -348.9593) (xy 335.156392 -348.967064)
			(xy 335.129124 -348.967552) (xy 334.265524 -348.967552) (xy 334.238251 -348.96711) (xy 334.18426 -348.959351)
			(xy 334.131923 -348.943986) (xy 334.082306 -348.921329) (xy 334.036418 -348.891841) (xy 333.995194 -348.856123)
			(xy 333.959473 -348.814901) (xy 333.929982 -348.769015) (xy 333.907322 -348.719399) (xy 333.891955 -348.667063)
			(xy 333.884192 -348.613073) (xy 332.401488 -348.613073) (xy 332.393726 -348.667061) (xy 332.378358 -348.719395)
			(xy 332.355698 -348.769009) (xy 332.326208 -348.814893) (xy 332.290488 -348.856113) (xy 332.249264 -348.89183)
			(xy 332.203377 -348.921316) (xy 332.153761 -348.94397) (xy 332.101425 -348.959333) (xy 332.047436 -348.967091)
			(xy 332.020164 -348.967552) (xy 331.156564 -348.967552) (xy 331.129296 -348.967083) (xy 331.075314 -348.959317)
			(xy 331.022988 -348.943948) (xy 330.973381 -348.921289) (xy 330.927503 -348.891802) (xy 330.886289 -348.856086)
			(xy 330.850577 -348.814868) (xy 330.821093 -348.768987) (xy 330.798439 -348.719378) (xy 330.783075 -348.66705)
			(xy 330.775314 -348.613068) (xy 329.292466 -348.613068) (xy 329.284704 -348.66705) (xy 329.26934 -348.719378)
			(xy 329.246684 -348.768987) (xy 329.217199 -348.814866) (xy 329.181486 -348.856083) (xy 329.140269 -348.891797)
			(xy 329.09439 -348.921282) (xy 329.044782 -348.943938) (xy 328.992454 -348.959303) (xy 328.938472 -348.967065)
			(xy 328.911204 -348.967552) (xy 328.047604 -348.967552) (xy 328.020332 -348.967109) (xy 327.966343 -348.959347)
			(xy 327.914009 -348.943981) (xy 327.864394 -348.921323) (xy 327.818509 -348.891834) (xy 327.777287 -348.856116)
			(xy 327.741568 -348.814895) (xy 327.712079 -348.76901) (xy 327.689421 -348.719395) (xy 327.674054 -348.667061)
			(xy 327.666292 -348.613072) (xy 326.183465 -348.613072) (xy 326.175705 -348.667045) (xy 326.160343 -348.71937)
			(xy 326.13769 -348.768976) (xy 326.108209 -348.814853) (xy 326.0725 -348.856069) (xy 326.031288 -348.891783)
			(xy 325.985414 -348.921269) (xy 325.935811 -348.943927) (xy 325.883488 -348.959296) (xy 325.829511 -348.967063)
			(xy 325.802244 -348.967552) (xy 324.938644 -348.967552) (xy 324.91137 -348.967111) (xy 324.857377 -348.959354)
			(xy 324.805038 -348.943991) (xy 324.755418 -348.921336) (xy 324.709527 -348.891849) (xy 324.668301 -348.85613)
			(xy 324.632578 -348.814908) (xy 324.603085 -348.769021) (xy 324.580424 -348.719403) (xy 324.565055 -348.667066)
			(xy 324.557292 -348.613074) (xy 323.074588 -348.613074) (xy 323.066826 -348.667058) (xy 323.051459 -348.71939)
			(xy 323.028801 -348.769003) (xy 322.999313 -348.814887) (xy 322.963595 -348.856106) (xy 322.922374 -348.891823)
			(xy 322.876489 -348.921309) (xy 322.826875 -348.943965) (xy 322.774542 -348.95933) (xy 322.720555 -348.96709)
			(xy 322.693284 -348.967552) (xy 321.829684 -348.967552) (xy 321.802415 -348.967084) (xy 321.748431 -348.959321)
			(xy 321.696102 -348.943954) (xy 321.646493 -348.921296) (xy 321.600613 -348.891809) (xy 321.559396 -348.856093)
			(xy 321.523682 -348.814874) (xy 321.494196 -348.768993) (xy 321.471541 -348.719383) (xy 321.456176 -348.667053)
			(xy 321.448414 -348.613069) (xy 319.965566 -348.613069) (xy 319.957805 -348.667048) (xy 319.942441 -348.719374)
			(xy 319.919787 -348.768981) (xy 319.890304 -348.81486) (xy 319.854593 -348.856076) (xy 319.813379 -348.89179)
			(xy 319.767502 -348.921276) (xy 319.717896 -348.943933) (xy 319.665571 -348.9593) (xy 319.611592 -348.967064)
			(xy 319.584324 -348.967552) (xy 318.720724 -348.967552) (xy 318.693451 -348.96711) (xy 318.63946 -348.959351)
			(xy 318.587123 -348.943986) (xy 318.537506 -348.921329) (xy 318.491618 -348.891841) (xy 318.450394 -348.856123)
			(xy 318.414673 -348.814901) (xy 318.385182 -348.769015) (xy 318.362522 -348.719399) (xy 318.347155 -348.667063)
			(xy 318.339392 -348.613073) (xy 316.856688 -348.613073) (xy 316.848926 -348.667061) (xy 316.833558 -348.719395)
			(xy 316.810898 -348.769009) (xy 316.781408 -348.814893) (xy 316.745688 -348.856113) (xy 316.704464 -348.89183)
			(xy 316.658577 -348.921316) (xy 316.608961 -348.94397) (xy 316.556625 -348.959333) (xy 316.502636 -348.967091)
			(xy 316.475364 -348.967552) (xy 315.611764 -348.967552) (xy 315.584496 -348.967083) (xy 315.530514 -348.959317)
			(xy 315.478188 -348.943948) (xy 315.428581 -348.921289) (xy 315.382703 -348.891802) (xy 315.341489 -348.856086)
			(xy 315.305777 -348.814868) (xy 315.276293 -348.768987) (xy 315.253639 -348.719378) (xy 315.238275 -348.66705)
			(xy 315.230514 -348.613068) (xy 313.747666 -348.613068) (xy 313.739904 -348.66705) (xy 313.72454 -348.719378)
			(xy 313.701884 -348.768987) (xy 313.672399 -348.814866) (xy 313.636686 -348.856083) (xy 313.595469 -348.891797)
			(xy 313.54959 -348.921282) (xy 313.499982 -348.943938) (xy 313.447654 -348.959303) (xy 313.393672 -348.967065)
			(xy 313.366404 -348.967552) (xy 312.502804 -348.967552) (xy 312.475532 -348.967109) (xy 312.421543 -348.959347)
			(xy 312.369209 -348.943981) (xy 312.319594 -348.921323) (xy 312.273709 -348.891834) (xy 312.232487 -348.856116)
			(xy 312.196768 -348.814895) (xy 312.167279 -348.76901) (xy 312.144621 -348.719395) (xy 312.129254 -348.667061)
			(xy 312.121492 -348.613072) (xy 300.231566 -348.613072) (xy 300.223804 -348.667051) (xy 300.208439 -348.719379)
			(xy 300.185784 -348.768987) (xy 300.156299 -348.814867) (xy 300.120585 -348.856083) (xy 300.079369 -348.891798)
			(xy 300.033489 -348.921283) (xy 299.98388 -348.943939) (xy 299.931553 -348.959304) (xy 299.877571 -348.967065)
			(xy 299.850302 -348.967552) (xy 298.986702 -348.967552) (xy 298.95943 -348.967109) (xy 298.905442 -348.959347)
			(xy 298.853107 -348.94398) (xy 298.803493 -348.921322) (xy 298.757608 -348.891834) (xy 298.716386 -348.856115)
			(xy 298.680668 -348.814894) (xy 298.651179 -348.769009) (xy 298.628521 -348.719394) (xy 298.613154 -348.66706)
			(xy 298.605392 -348.613072) (xy 297.122565 -348.613072) (xy 297.114805 -348.667045) (xy 297.099443 -348.71937)
			(xy 297.07679 -348.768976) (xy 297.047309 -348.814854) (xy 297.011599 -348.856069) (xy 296.970387 -348.891784)
			(xy 296.924513 -348.92127) (xy 296.874909 -348.943928) (xy 296.822586 -348.959296) (xy 296.768609 -348.967063)
			(xy 296.741342 -348.967552) (xy 295.877742 -348.967552) (xy 295.850468 -348.967111) (xy 295.796476 -348.959354)
			(xy 295.744136 -348.943991) (xy 295.694517 -348.921335) (xy 295.648627 -348.891848) (xy 295.6074 -348.856129)
			(xy 295.571677 -348.814907) (xy 295.542185 -348.76902) (xy 295.519524 -348.719403) (xy 295.504155 -348.667066)
			(xy 295.496392 -348.613074) (xy 294.013688 -348.613074) (xy 294.005926 -348.667058) (xy 293.990559 -348.719391)
			(xy 293.967901 -348.769004) (xy 293.938412 -348.814887) (xy 293.902694 -348.856107) (xy 293.861473 -348.891823)
			(xy 293.815588 -348.92131) (xy 293.765974 -348.943966) (xy 293.713641 -348.95933) (xy 293.659653 -348.96709)
			(xy 293.632382 -348.967552) (xy 292.768782 -348.967552) (xy 292.741513 -348.967084) (xy 292.68753 -348.95932)
			(xy 292.635201 -348.943953) (xy 292.585592 -348.921295) (xy 292.539712 -348.891808) (xy 292.498495 -348.856092)
			(xy 292.462781 -348.814874) (xy 292.433296 -348.768992) (xy 292.410641 -348.719382) (xy 292.395276 -348.667053)
			(xy 292.387514 -348.613069) (xy 290.904666 -348.613069) (xy 290.896905 -348.667048) (xy 290.881541 -348.719374)
			(xy 290.858887 -348.768982) (xy 290.829404 -348.81486) (xy 290.793692 -348.856076) (xy 290.752478 -348.891791)
			(xy 290.706601 -348.921276) (xy 290.656995 -348.943933) (xy 290.604669 -348.9593) (xy 290.55069 -348.967064)
			(xy 290.523422 -348.967552) (xy 289.659822 -348.967552) (xy 289.632549 -348.96711) (xy 289.578559 -348.95935)
			(xy 289.526222 -348.943985) (xy 289.476605 -348.921329) (xy 289.430717 -348.891841) (xy 289.389493 -348.856122)
			(xy 289.353772 -348.814901) (xy 289.324282 -348.769015) (xy 289.301622 -348.719399) (xy 289.286254 -348.667063)
			(xy 289.278492 -348.613073) (xy 287.795788 -348.613073) (xy 287.788026 -348.667061) (xy 287.772658 -348.719395)
			(xy 287.749998 -348.76901) (xy 287.720508 -348.814894) (xy 287.684787 -348.856114) (xy 287.643563 -348.89183)
			(xy 287.597676 -348.921316) (xy 287.54806 -348.943971) (xy 287.495724 -348.959334) (xy 287.441734 -348.967091)
			(xy 287.414462 -348.967552) (xy 286.550862 -348.967552) (xy 286.523594 -348.967083) (xy 286.469613 -348.959317)
			(xy 286.417286 -348.943948) (xy 286.36768 -348.921289) (xy 286.321802 -348.891801) (xy 286.280588 -348.856085)
			(xy 286.244876 -348.814867) (xy 286.215393 -348.768987) (xy 286.192739 -348.719378) (xy 286.177375 -348.66705)
			(xy 286.169614 -348.613068) (xy 284.686766 -348.613068) (xy 284.686766 -348.613069) (xy 284.679004 -348.667051)
			(xy 284.663639 -348.719379) (xy 284.640984 -348.768987) (xy 284.611499 -348.814867) (xy 284.575785 -348.856083)
			(xy 284.534569 -348.891798) (xy 284.488689 -348.921283) (xy 284.43908 -348.943939) (xy 284.386753 -348.959304)
			(xy 284.332771 -348.967065) (xy 284.305502 -348.967552) (xy 283.441902 -348.967552) (xy 283.41463 -348.967109)
			(xy 283.360642 -348.959347) (xy 283.308307 -348.94398) (xy 283.258693 -348.921322) (xy 283.212808 -348.891834)
			(xy 283.171586 -348.856115) (xy 283.135868 -348.814894) (xy 283.106379 -348.769009) (xy 283.083721 -348.719394)
			(xy 283.068354 -348.66706) (xy 283.060592 -348.613072) (xy 281.577765 -348.613072) (xy 281.570005 -348.667045)
			(xy 281.554643 -348.71937) (xy 281.53199 -348.768976) (xy 281.502509 -348.814854) (xy 281.466799 -348.856069)
			(xy 281.425587 -348.891784) (xy 281.379713 -348.92127) (xy 281.330109 -348.943928) (xy 281.277786 -348.959296)
			(xy 281.223809 -348.967063) (xy 281.196542 -348.967552) (xy 280.332942 -348.967552) (xy 280.305668 -348.967111)
			(xy 280.251676 -348.959354) (xy 280.199336 -348.943991) (xy 280.149717 -348.921335) (xy 280.103827 -348.891848)
			(xy 280.0626 -348.856129) (xy 280.026877 -348.814907) (xy 279.997385 -348.76902) (xy 279.974724 -348.719403)
			(xy 279.959355 -348.667066) (xy 279.951592 -348.613074) (xy 278.468888 -348.613074) (xy 278.461126 -348.667058)
			(xy 278.445759 -348.719391) (xy 278.423101 -348.769004) (xy 278.393612 -348.814887) (xy 278.357894 -348.856107)
			(xy 278.316673 -348.891823) (xy 278.270788 -348.92131) (xy 278.221174 -348.943966) (xy 278.168841 -348.95933)
			(xy 278.114853 -348.96709) (xy 278.087582 -348.967552) (xy 277.223982 -348.967552) (xy 277.196713 -348.967084)
			(xy 277.14273 -348.95932) (xy 277.090401 -348.943953) (xy 277.040792 -348.921295) (xy 276.994912 -348.891808)
			(xy 276.953695 -348.856092) (xy 276.917981 -348.814874) (xy 276.888496 -348.768992) (xy 276.865841 -348.719382)
			(xy 276.850476 -348.667053) (xy 276.842714 -348.613069) (xy 275.359866 -348.613069) (xy 275.352105 -348.667048)
			(xy 275.336741 -348.719374) (xy 275.314087 -348.768982) (xy 275.284604 -348.81486) (xy 275.248892 -348.856076)
			(xy 275.207678 -348.891791) (xy 275.161801 -348.921276) (xy 275.112195 -348.943933) (xy 275.059869 -348.9593)
			(xy 275.00589 -348.967064) (xy 274.978622 -348.967552) (xy 274.115022 -348.967552) (xy 274.087749 -348.96711)
			(xy 274.033759 -348.95935) (xy 273.981422 -348.943985) (xy 273.931805 -348.921329) (xy 273.885917 -348.891841)
			(xy 273.844693 -348.856122) (xy 273.808972 -348.814901) (xy 273.779482 -348.769015) (xy 273.756822 -348.719399)
			(xy 273.741454 -348.667063) (xy 273.733692 -348.613073) (xy 272.250988 -348.613073) (xy 272.243226 -348.667061)
			(xy 272.227858 -348.719395) (xy 272.205198 -348.76901) (xy 272.175708 -348.814894) (xy 272.139987 -348.856114)
			(xy 272.098763 -348.89183) (xy 272.052876 -348.921316) (xy 272.00326 -348.943971) (xy 271.950924 -348.959334)
			(xy 271.896934 -348.967091) (xy 271.869662 -348.967552) (xy 271.006062 -348.967552) (xy 270.978794 -348.967083)
			(xy 270.924813 -348.959317) (xy 270.872486 -348.943948) (xy 270.82288 -348.921289) (xy 270.777002 -348.891801)
			(xy 270.735788 -348.856085) (xy 270.700076 -348.814867) (xy 270.670593 -348.768987) (xy 270.647939 -348.719378)
			(xy 270.632575 -348.66705) (xy 270.624814 -348.613068) (xy 269.141966 -348.613068) (xy 269.141966 -348.613069)
			(xy 269.134204 -348.667051) (xy 269.118839 -348.719379) (xy 269.096184 -348.768987) (xy 269.066699 -348.814867)
			(xy 269.030985 -348.856083) (xy 268.989769 -348.891798) (xy 268.943889 -348.921283) (xy 268.89428 -348.943939)
			(xy 268.841953 -348.959304) (xy 268.787971 -348.967065) (xy 268.760702 -348.967552) (xy 267.897102 -348.967552)
			(xy 267.86983 -348.967109) (xy 267.815842 -348.959347) (xy 267.763507 -348.94398) (xy 267.713893 -348.921322)
			(xy 267.668008 -348.891834) (xy 267.626786 -348.856115) (xy 267.591068 -348.814894) (xy 267.561579 -348.769009)
			(xy 267.538921 -348.719394) (xy 267.523554 -348.66706) (xy 267.515792 -348.613072) (xy 194.520565 -348.613072)
			(xy 194.512804 -348.667049) (xy 194.49744 -348.719376) (xy 194.474785 -348.768985) (xy 194.445301 -348.814864)
			(xy 194.409588 -348.85608) (xy 194.368373 -348.891794) (xy 194.322495 -348.92128) (xy 194.272888 -348.943936)
			(xy 194.220561 -348.959302) (xy 194.16658 -348.967065) (xy 194.139312 -348.967552) (xy 193.275712 -348.967552)
			(xy 193.24844 -348.967109) (xy 193.19445 -348.959348) (xy 193.142115 -348.943983) (xy 193.092499 -348.921325)
			(xy 193.046612 -348.891837) (xy 193.00539 -348.856119) (xy 192.96967 -348.814897) (xy 192.940181 -348.769012)
			(xy 192.917521 -348.719397) (xy 192.902154 -348.667062) (xy 192.894392 -348.613072) (xy 191.411688 -348.613072)
			(xy 191.403925 -348.667062) (xy 191.388557 -348.719397) (xy 191.365896 -348.769012) (xy 191.336405 -348.814897)
			(xy 191.300683 -348.856117) (xy 191.259459 -348.891834) (xy 191.21357 -348.921319) (xy 191.163952 -348.943974)
			(xy 191.111615 -348.959335) (xy 191.057625 -348.967092) (xy 191.030352 -348.967552) (xy 190.166752 -348.967552)
			(xy 190.139484 -348.967082) (xy 190.085504 -348.959315) (xy 190.033179 -348.943945) (xy 189.983574 -348.921285)
			(xy 189.937698 -348.891797) (xy 189.896485 -348.856081) (xy 189.860774 -348.814864) (xy 189.831292 -348.768984)
			(xy 189.808638 -348.719376) (xy 189.793275 -348.667049) (xy 189.785514 -348.613068) (xy 188.302689 -348.613068)
			(xy 188.302689 -348.613071) (xy 188.294926 -348.667057) (xy 188.27956 -348.719389) (xy 188.256903 -348.769001)
			(xy 188.227415 -348.814884) (xy 188.191698 -348.856103) (xy 188.150478 -348.89182) (xy 188.104594 -348.921306)
			(xy 188.054981 -348.943963) (xy 188.002649 -348.959328) (xy 187.948663 -348.967089) (xy 187.921392 -348.967552)
			(xy 187.057792 -348.967552) (xy 187.030522 -348.967085) (xy 186.976538 -348.959322) (xy 186.924208 -348.943956)
			(xy 186.874598 -348.921299) (xy 186.828717 -348.891812) (xy 186.787499 -348.856095) (xy 186.751784 -348.814877)
			(xy 186.722298 -348.768995) (xy 186.699641 -348.719384) (xy 186.684276 -348.667054) (xy 186.676514 -348.61307)
			(xy 185.193666 -348.61307) (xy 185.185905 -348.667047) (xy 185.170542 -348.719372) (xy 185.147888 -348.768979)
			(xy 185.118406 -348.814857) (xy 185.082695 -348.856073) (xy 185.041483 -348.891787) (xy 184.995607 -348.921273)
			(xy 184.946002 -348.943931) (xy 184.893678 -348.959298) (xy 184.839699 -348.967063) (xy 184.812432 -348.967552)
			(xy 183.948832 -348.967552) (xy 183.921559 -348.967111) (xy 183.867567 -348.959352) (xy 183.815229 -348.943988)
			(xy 183.765611 -348.921332) (xy 183.719722 -348.891844) (xy 183.678497 -348.856126) (xy 183.642775 -348.814904)
			(xy 183.613284 -348.769017) (xy 183.590623 -348.719401) (xy 183.575255 -348.667064) (xy 183.567492 -348.613073)
			(xy 182.084788 -348.613073) (xy 182.077026 -348.667059) (xy 182.061659 -348.719393) (xy 182.038999 -348.769007)
			(xy 182.00951 -348.814891) (xy 181.97379 -348.85611) (xy 181.932568 -348.891827) (xy 181.886682 -348.921313)
			(xy 181.837067 -348.943968) (xy 181.784732 -348.959332) (xy 181.730744 -348.96709) (xy 181.703472 -348.967552)
			(xy 180.839872 -348.967552) (xy 180.812603 -348.967084) (xy 180.758621 -348.959319) (xy 180.706294 -348.94395)
			(xy 180.656686 -348.921292) (xy 180.610807 -348.891805) (xy 180.569592 -348.856088) (xy 180.533879 -348.81487)
			(xy 180.504395 -348.76899) (xy 180.48174 -348.71938) (xy 180.466376 -348.667051) (xy 180.458614 -348.613069)
			(xy 178.975766 -348.613069) (xy 178.968004 -348.667049) (xy 178.95264 -348.719376) (xy 178.929985 -348.768985)
			(xy 178.900501 -348.814864) (xy 178.864788 -348.85608) (xy 178.823573 -348.891794) (xy 178.777695 -348.92128)
			(xy 178.728088 -348.943936) (xy 178.675761 -348.959302) (xy 178.62178 -348.967065) (xy 178.594512 -348.967552)
			(xy 177.730912 -348.967552) (xy 177.70364 -348.967109) (xy 177.64965 -348.959348) (xy 177.597315 -348.943983)
			(xy 177.547699 -348.921325) (xy 177.501812 -348.891837) (xy 177.46059 -348.856119) (xy 177.42487 -348.814897)
			(xy 177.395381 -348.769012) (xy 177.372721 -348.719397) (xy 177.357354 -348.667062) (xy 177.349592 -348.613072)
			(xy 175.866888 -348.613072) (xy 175.859125 -348.667062) (xy 175.843757 -348.719397) (xy 175.821096 -348.769012)
			(xy 175.791605 -348.814897) (xy 175.755883 -348.856117) (xy 175.714659 -348.891834) (xy 175.66877 -348.921319)
			(xy 175.619152 -348.943974) (xy 175.566815 -348.959335) (xy 175.512825 -348.967092) (xy 175.485552 -348.967552)
			(xy 174.621952 -348.967552) (xy 174.594684 -348.967082) (xy 174.540704 -348.959315) (xy 174.488379 -348.943945)
			(xy 174.438774 -348.921285) (xy 174.392898 -348.891797) (xy 174.351685 -348.856081) (xy 174.315974 -348.814864)
			(xy 174.286492 -348.768984) (xy 174.263838 -348.719376) (xy 174.248475 -348.667049) (xy 174.240714 -348.613068)
			(xy 172.757889 -348.613068) (xy 172.757889 -348.613071) (xy 172.750126 -348.667057) (xy 172.73476 -348.719389)
			(xy 172.712103 -348.769001) (xy 172.682615 -348.814884) (xy 172.646898 -348.856103) (xy 172.605678 -348.89182)
			(xy 172.559794 -348.921306) (xy 172.510181 -348.943963) (xy 172.457849 -348.959328) (xy 172.403863 -348.967089)
			(xy 172.376592 -348.967552) (xy 171.512992 -348.967552) (xy 171.485722 -348.967085) (xy 171.431738 -348.959322)
			(xy 171.379408 -348.943956) (xy 171.329798 -348.921299) (xy 171.283917 -348.891812) (xy 171.242699 -348.856095)
			(xy 171.206984 -348.814877) (xy 171.177498 -348.768995) (xy 171.154841 -348.719384) (xy 171.139476 -348.667054)
			(xy 171.131714 -348.61307) (xy 169.648866 -348.61307) (xy 169.641105 -348.667047) (xy 169.625742 -348.719372)
			(xy 169.603088 -348.768979) (xy 169.573606 -348.814857) (xy 169.537895 -348.856073) (xy 169.496683 -348.891787)
			(xy 169.450807 -348.921273) (xy 169.401202 -348.943931) (xy 169.348878 -348.959298) (xy 169.294899 -348.967063)
			(xy 169.267632 -348.967552) (xy 168.404032 -348.967552) (xy 168.376759 -348.967111) (xy 168.322767 -348.959352)
			(xy 168.270429 -348.943988) (xy 168.220811 -348.921332) (xy 168.174922 -348.891844) (xy 168.133697 -348.856126)
			(xy 168.097975 -348.814904) (xy 168.068484 -348.769017) (xy 168.045823 -348.719401) (xy 168.030455 -348.667064)
			(xy 168.022692 -348.613073) (xy 166.539988 -348.613073) (xy 166.532226 -348.667059) (xy 166.516859 -348.719393)
			(xy 166.494199 -348.769007) (xy 166.46471 -348.814891) (xy 166.42899 -348.85611) (xy 166.387768 -348.891827)
			(xy 166.341882 -348.921313) (xy 166.292267 -348.943968) (xy 166.239932 -348.959332) (xy 166.185944 -348.96709)
			(xy 166.158672 -348.967552) (xy 165.295072 -348.967552) (xy 165.267803 -348.967084) (xy 165.213821 -348.959319)
			(xy 165.161494 -348.94395) (xy 165.111886 -348.921292) (xy 165.066007 -348.891805) (xy 165.024792 -348.856088)
			(xy 164.989079 -348.81487) (xy 164.959595 -348.76899) (xy 164.93694 -348.71938) (xy 164.921576 -348.667051)
			(xy 164.913814 -348.613069) (xy 163.430966 -348.613069) (xy 163.423204 -348.667049) (xy 163.40784 -348.719376)
			(xy 163.385185 -348.768985) (xy 163.355701 -348.814864) (xy 163.319988 -348.85608) (xy 163.278773 -348.891794)
			(xy 163.232895 -348.92128) (xy 163.183288 -348.943936) (xy 163.130961 -348.959302) (xy 163.07698 -348.967065)
			(xy 163.049712 -348.967552) (xy 162.186112 -348.967552) (xy 162.15884 -348.967109) (xy 162.10485 -348.959348)
			(xy 162.052515 -348.943983) (xy 162.002899 -348.921325) (xy 161.957012 -348.891837) (xy 161.91579 -348.856119)
			(xy 161.88007 -348.814897) (xy 161.850581 -348.769012) (xy 161.827921 -348.719397) (xy 161.812554 -348.667062)
			(xy 161.804792 -348.613072) (xy 144.196565 -348.613072) (xy 144.188804 -348.66705) (xy 144.17344 -348.719377)
			(xy 144.150785 -348.768986) (xy 144.1213 -348.814865) (xy 144.085587 -348.856081) (xy 144.044371 -348.891796)
			(xy 143.998493 -348.921281) (xy 143.948885 -348.943937) (xy 143.896558 -348.959303) (xy 143.842576 -348.967065)
			(xy 143.815308 -348.967552) (xy 142.951708 -348.967552) (xy 142.924436 -348.967109) (xy 142.870447 -348.959348)
			(xy 142.818112 -348.943982) (xy 142.768496 -348.921324) (xy 142.72261 -348.891836) (xy 142.681388 -348.856117)
			(xy 142.645669 -348.814896) (xy 142.61618 -348.769011) (xy 142.593521 -348.719396) (xy 142.578154 -348.667061)
			(xy 142.570392 -348.613072) (xy 141.087565 -348.613072) (xy 141.079806 -348.667044) (xy 141.064443 -348.719369)
			(xy 141.041791 -348.768974) (xy 141.01231 -348.814852) (xy 140.976601 -348.856067) (xy 140.93539 -348.891781)
			(xy 140.889517 -348.921268) (xy 140.839914 -348.943926) (xy 140.787591 -348.959295) (xy 140.733614 -348.967062)
			(xy 140.706348 -348.967552) (xy 139.842748 -348.967552) (xy 139.815474 -348.967112) (xy 139.761481 -348.959355)
			(xy 139.709141 -348.943992) (xy 139.65952 -348.921337) (xy 139.613629 -348.89185) (xy 139.572402 -348.856132)
			(xy 139.536679 -348.814909) (xy 139.507186 -348.769022) (xy 139.484524 -348.719404) (xy 139.469155 -348.667066)
			(xy 139.461392 -348.613074) (xy 137.978689 -348.613074) (xy 137.970926 -348.667057) (xy 137.95556 -348.71939)
			(xy 137.932902 -348.769002) (xy 137.903414 -348.814885) (xy 137.867696 -348.856105) (xy 137.826476 -348.891821)
			(xy 137.780592 -348.921308) (xy 137.730978 -348.943964) (xy 137.678646 -348.959329) (xy 137.624659 -348.967089)
			(xy 137.597388 -348.967552) (xy 136.733788 -348.967552) (xy 136.706518 -348.967085) (xy 136.652535 -348.959321)
			(xy 136.600205 -348.943955) (xy 136.550595 -348.921297) (xy 136.504715 -348.89181) (xy 136.463497 -348.856094)
			(xy 136.427783 -348.814876) (xy 136.398297 -348.768994) (xy 136.375641 -348.719383) (xy 136.360276 -348.667053)
			(xy 136.352514 -348.61307) (xy 134.869666 -348.61307) (xy 134.861905 -348.667047) (xy 134.846541 -348.719373)
			(xy 134.823888 -348.76898) (xy 134.794405 -348.814858) (xy 134.758694 -348.856074) (xy 134.717481 -348.891789)
			(xy 134.671605 -348.921274) (xy 134.621999 -348.943932) (xy 134.569675 -348.959299) (xy 134.515695 -348.967064)
			(xy 134.488428 -348.967552) (xy 133.624828 -348.967552) (xy 133.597555 -348.96711) (xy 133.543564 -348.959351)
			(xy 133.491226 -348.943987) (xy 133.441608 -348.92133) (xy 133.39572 -348.891843) (xy 133.354495 -348.856124)
			(xy 133.318774 -348.814903) (xy 133.289283 -348.769016) (xy 133.266623 -348.7194) (xy 133.251255 -348.667064)
			(xy 133.243492 -348.613073) (xy 131.760788 -348.613073) (xy 131.753026 -348.66706) (xy 131.737658 -348.719394)
			(xy 131.714999 -348.769008) (xy 131.685509 -348.814892) (xy 131.649789 -348.856112) (xy 131.608566 -348.891828)
			(xy 131.56268 -348.921314) (xy 131.513064 -348.943969) (xy 131.460729 -348.959332) (xy 131.40674 -348.967091)
			(xy 131.379468 -348.967552) (xy 130.515868 -348.967552) (xy 130.488599 -348.967083) (xy 130.434618 -348.959318)
			(xy 130.382291 -348.943949) (xy 130.332683 -348.921291) (xy 130.286805 -348.891803) (xy 130.24559 -348.856087)
			(xy 130.209878 -348.814869) (xy 130.180394 -348.768989) (xy 130.15774 -348.719379) (xy 130.142375 -348.667051)
			(xy 130.134614 -348.613069) (xy 128.651766 -348.613069) (xy 128.644004 -348.66705) (xy 128.62864 -348.719377)
			(xy 128.605985 -348.768986) (xy 128.5765 -348.814865) (xy 128.540787 -348.856081) (xy 128.499571 -348.891796)
			(xy 128.453693 -348.921281) (xy 128.404085 -348.943937) (xy 128.351758 -348.959303) (xy 128.297776 -348.967065)
			(xy 128.270508 -348.967552) (xy 127.406908 -348.967552) (xy 127.379636 -348.967109) (xy 127.325647 -348.959348)
			(xy 127.273312 -348.943982) (xy 127.223696 -348.921324) (xy 127.17781 -348.891836) (xy 127.136588 -348.856117)
			(xy 127.100869 -348.814896) (xy 127.07138 -348.769011) (xy 127.048721 -348.719396) (xy 127.033354 -348.667061)
			(xy 127.025592 -348.613072) (xy 125.542765 -348.613072) (xy 125.535006 -348.667044) (xy 125.519643 -348.719369)
			(xy 125.496991 -348.768974) (xy 125.46751 -348.814852) (xy 125.431801 -348.856067) (xy 125.39059 -348.891781)
			(xy 125.344717 -348.921268) (xy 125.295114 -348.943926) (xy 125.242791 -348.959295) (xy 125.188814 -348.967062)
			(xy 125.161548 -348.967552) (xy 124.297948 -348.967552) (xy 124.270674 -348.967112) (xy 124.216681 -348.959355)
			(xy 124.164341 -348.943992) (xy 124.11472 -348.921337) (xy 124.068829 -348.89185) (xy 124.027602 -348.856132)
			(xy 123.991879 -348.814909) (xy 123.962386 -348.769022) (xy 123.939724 -348.719404) (xy 123.924355 -348.667066)
			(xy 123.916592 -348.613074) (xy 122.433889 -348.613074) (xy 122.426126 -348.667057) (xy 122.41076 -348.71939)
			(xy 122.388102 -348.769002) (xy 122.358614 -348.814885) (xy 122.322896 -348.856105) (xy 122.281676 -348.891821)
			(xy 122.235792 -348.921308) (xy 122.186178 -348.943964) (xy 122.133846 -348.959329) (xy 122.079859 -348.967089)
			(xy 122.052588 -348.967552) (xy 121.188988 -348.967552) (xy 121.161718 -348.967085) (xy 121.107735 -348.959321)
			(xy 121.055405 -348.943955) (xy 121.005795 -348.921297) (xy 120.959915 -348.89181) (xy 120.918697 -348.856094)
			(xy 120.882983 -348.814876) (xy 120.853497 -348.768994) (xy 120.830841 -348.719383) (xy 120.815476 -348.667053)
			(xy 120.807714 -348.61307) (xy 119.324866 -348.61307) (xy 119.317105 -348.667047) (xy 119.301741 -348.719373)
			(xy 119.279088 -348.76898) (xy 119.249605 -348.814858) (xy 119.213894 -348.856074) (xy 119.172681 -348.891789)
			(xy 119.126805 -348.921274) (xy 119.077199 -348.943932) (xy 119.024875 -348.959299) (xy 118.970895 -348.967064)
			(xy 118.943628 -348.967552) (xy 118.080028 -348.967552) (xy 118.052755 -348.96711) (xy 117.998764 -348.959351)
			(xy 117.946426 -348.943987) (xy 117.896808 -348.92133) (xy 117.85092 -348.891843) (xy 117.809695 -348.856124)
			(xy 117.773974 -348.814903) (xy 117.744483 -348.769016) (xy 117.721823 -348.7194) (xy 117.706455 -348.667064)
			(xy 117.698692 -348.613073) (xy 116.215988 -348.613073) (xy 116.208226 -348.66706) (xy 116.192858 -348.719394)
			(xy 116.170199 -348.769008) (xy 116.140709 -348.814892) (xy 116.104989 -348.856112) (xy 116.063766 -348.891828)
			(xy 116.01788 -348.921314) (xy 115.968264 -348.943969) (xy 115.915929 -348.959332) (xy 115.86194 -348.967091)
			(xy 115.834668 -348.967552) (xy 114.971068 -348.967552) (xy 114.943799 -348.967083) (xy 114.889818 -348.959318)
			(xy 114.837491 -348.943949) (xy 114.787883 -348.921291) (xy 114.742005 -348.891803) (xy 114.70079 -348.856087)
			(xy 114.665078 -348.814869) (xy 114.635594 -348.768989) (xy 114.61294 -348.719379) (xy 114.597575 -348.667051)
			(xy 114.589814 -348.613069) (xy 113.106966 -348.613069) (xy 113.099204 -348.66705) (xy 113.08384 -348.719377)
			(xy 113.061185 -348.768986) (xy 113.0317 -348.814865) (xy 112.995987 -348.856081) (xy 112.954771 -348.891796)
			(xy 112.908893 -348.921281) (xy 112.859285 -348.943937) (xy 112.806958 -348.959303) (xy 112.752976 -348.967065)
			(xy 112.725708 -348.967552) (xy 111.862108 -348.967552) (xy 111.834836 -348.967109) (xy 111.780847 -348.959348)
			(xy 111.728512 -348.943982) (xy 111.678896 -348.921324) (xy 111.63301 -348.891836) (xy 111.591788 -348.856117)
			(xy 111.556069 -348.814896) (xy 111.52658 -348.769011) (xy 111.503921 -348.719396) (xy 111.488554 -348.667061)
			(xy 111.480792 -348.613072) (xy 93.706665 -348.613072) (xy 93.698905 -348.667045) (xy 93.683543 -348.71937)
			(xy 93.66089 -348.768976) (xy 93.631409 -348.814854) (xy 93.595699 -348.856069) (xy 93.554487 -348.891784)
			(xy 93.508613 -348.92127) (xy 93.459009 -348.943928) (xy 93.406686 -348.959296) (xy 93.352709 -348.967063)
			(xy 93.325442 -348.967552) (xy 92.461842 -348.967552) (xy 92.434568 -348.967111) (xy 92.380576 -348.959354)
			(xy 92.328236 -348.943991) (xy 92.278617 -348.921335) (xy 92.232727 -348.891848) (xy 92.1915 -348.856129)
			(xy 92.155777 -348.814907) (xy 92.126285 -348.76902) (xy 92.103624 -348.719403) (xy 92.088255 -348.667066)
			(xy 92.080492 -348.613074) (xy 90.597788 -348.613074) (xy 90.590026 -348.667058) (xy 90.574659 -348.719391)
			(xy 90.552001 -348.769004) (xy 90.522512 -348.814887) (xy 90.486794 -348.856107) (xy 90.445573 -348.891823)
			(xy 90.399688 -348.92131) (xy 90.350074 -348.943966) (xy 90.297741 -348.95933) (xy 90.243753 -348.96709)
			(xy 90.216482 -348.967552) (xy 89.352882 -348.967552) (xy 89.325613 -348.967084) (xy 89.27163 -348.95932)
			(xy 89.219301 -348.943953) (xy 89.169692 -348.921295) (xy 89.123812 -348.891808) (xy 89.082595 -348.856092)
			(xy 89.046881 -348.814874) (xy 89.017396 -348.768992) (xy 88.994741 -348.719382) (xy 88.979376 -348.667053)
			(xy 88.971614 -348.613069) (xy 87.488766 -348.613069) (xy 87.481005 -348.667048) (xy 87.465641 -348.719374)
			(xy 87.442987 -348.768982) (xy 87.413504 -348.81486) (xy 87.377792 -348.856076) (xy 87.336578 -348.891791)
			(xy 87.290701 -348.921276) (xy 87.241095 -348.943933) (xy 87.188769 -348.9593) (xy 87.13479 -348.967064)
			(xy 87.107522 -348.967552) (xy 86.243922 -348.967552) (xy 86.216649 -348.96711) (xy 86.162659 -348.95935)
			(xy 86.110322 -348.943985) (xy 86.060705 -348.921329) (xy 86.014817 -348.891841) (xy 85.973593 -348.856122)
			(xy 85.937872 -348.814901) (xy 85.908382 -348.769015) (xy 85.885722 -348.719399) (xy 85.870354 -348.667063)
			(xy 85.862592 -348.613073) (xy 84.379888 -348.613073) (xy 84.372126 -348.667061) (xy 84.356758 -348.719395)
			(xy 84.334098 -348.76901) (xy 84.304608 -348.814894) (xy 84.268887 -348.856114) (xy 84.227663 -348.89183)
			(xy 84.181776 -348.921316) (xy 84.13216 -348.943971) (xy 84.079824 -348.959334) (xy 84.025834 -348.967091)
			(xy 83.998562 -348.967552) (xy 83.134962 -348.967552) (xy 83.107694 -348.967083) (xy 83.053713 -348.959317)
			(xy 83.001386 -348.943948) (xy 82.95178 -348.921289) (xy 82.905902 -348.891801) (xy 82.864688 -348.856085)
			(xy 82.828976 -348.814867) (xy 82.799493 -348.768987) (xy 82.776839 -348.719378) (xy 82.761475 -348.66705)
			(xy 82.753714 -348.613068) (xy 81.270866 -348.613068) (xy 81.270866 -348.613069) (xy 81.263104 -348.667051)
			(xy 81.247739 -348.719379) (xy 81.225084 -348.768987) (xy 81.195599 -348.814867) (xy 81.159885 -348.856083)
			(xy 81.118669 -348.891798) (xy 81.072789 -348.921283) (xy 81.02318 -348.943939) (xy 80.970853 -348.959304)
			(xy 80.916871 -348.967065) (xy 80.889602 -348.967552) (xy 80.026002 -348.967552) (xy 79.99873 -348.967109)
			(xy 79.944742 -348.959347) (xy 79.892407 -348.94398) (xy 79.842793 -348.921322) (xy 79.796908 -348.891834)
			(xy 79.755686 -348.856115) (xy 79.719968 -348.814894) (xy 79.690479 -348.769009) (xy 79.667821 -348.719394)
			(xy 79.652454 -348.66706) (xy 79.644692 -348.613072) (xy 78.161865 -348.613072) (xy 78.154105 -348.667045)
			(xy 78.138743 -348.71937) (xy 78.11609 -348.768976) (xy 78.086609 -348.814854) (xy 78.050899 -348.856069)
			(xy 78.009687 -348.891784) (xy 77.963813 -348.92127) (xy 77.914209 -348.943928) (xy 77.861886 -348.959296)
			(xy 77.807909 -348.967063) (xy 77.780642 -348.967552) (xy 76.917042 -348.967552) (xy 76.889768 -348.967111)
			(xy 76.835776 -348.959354) (xy 76.783436 -348.943991) (xy 76.733817 -348.921335) (xy 76.687927 -348.891848)
			(xy 76.6467 -348.856129) (xy 76.610977 -348.814907) (xy 76.581485 -348.76902) (xy 76.558824 -348.719403)
			(xy 76.543455 -348.667066) (xy 76.535692 -348.613074) (xy 75.052988 -348.613074) (xy 75.045226 -348.667058)
			(xy 75.029859 -348.719391) (xy 75.007201 -348.769004) (xy 74.977712 -348.814887) (xy 74.941994 -348.856107)
			(xy 74.900773 -348.891823) (xy 74.854888 -348.92131) (xy 74.805274 -348.943966) (xy 74.752941 -348.95933)
			(xy 74.698953 -348.96709) (xy 74.671682 -348.967552) (xy 73.808082 -348.967552) (xy 73.780813 -348.967084)
			(xy 73.72683 -348.95932) (xy 73.674501 -348.943953) (xy 73.624892 -348.921295) (xy 73.579012 -348.891808)
			(xy 73.537795 -348.856092) (xy 73.502081 -348.814874) (xy 73.472596 -348.768992) (xy 73.449941 -348.719382)
			(xy 73.434576 -348.667053) (xy 73.426814 -348.613069) (xy 71.943966 -348.613069) (xy 71.936205 -348.667048)
			(xy 71.920841 -348.719374) (xy 71.898187 -348.768982) (xy 71.868704 -348.81486) (xy 71.832992 -348.856076)
			(xy 71.791778 -348.891791) (xy 71.745901 -348.921276) (xy 71.696295 -348.943933) (xy 71.643969 -348.9593)
			(xy 71.58999 -348.967064) (xy 71.562722 -348.967552) (xy 70.699122 -348.967552) (xy 70.671849 -348.96711)
			(xy 70.617859 -348.95935) (xy 70.565522 -348.943985) (xy 70.515905 -348.921329) (xy 70.470017 -348.891841)
			(xy 70.428793 -348.856122) (xy 70.393072 -348.814901) (xy 70.363582 -348.769015) (xy 70.340922 -348.719399)
			(xy 70.325554 -348.667063) (xy 70.317792 -348.613073) (xy 68.835088 -348.613073) (xy 68.827326 -348.667061)
			(xy 68.811958 -348.719395) (xy 68.789298 -348.76901) (xy 68.759808 -348.814894) (xy 68.724087 -348.856114)
			(xy 68.682863 -348.89183) (xy 68.636976 -348.921316) (xy 68.58736 -348.943971) (xy 68.535024 -348.959334)
			(xy 68.481034 -348.967091) (xy 68.453762 -348.967552) (xy 67.590162 -348.967552) (xy 67.562894 -348.967083)
			(xy 67.508913 -348.959317) (xy 67.456586 -348.943948) (xy 67.40698 -348.921289) (xy 67.361102 -348.891801)
			(xy 67.319888 -348.856085) (xy 67.284176 -348.814867) (xy 67.254693 -348.768987) (xy 67.232039 -348.719378)
			(xy 67.216675 -348.66705) (xy 67.208914 -348.613068) (xy 65.726066 -348.613068) (xy 65.726066 -348.613069)
			(xy 65.718304 -348.667051) (xy 65.702939 -348.719379) (xy 65.680284 -348.768987) (xy 65.650799 -348.814867)
			(xy 65.615085 -348.856083) (xy 65.573869 -348.891798) (xy 65.527989 -348.921283) (xy 65.47838 -348.943939)
			(xy 65.426053 -348.959304) (xy 65.372071 -348.967065) (xy 65.344802 -348.967552) (xy 64.481202 -348.967552)
			(xy 64.45393 -348.967109) (xy 64.399942 -348.959347) (xy 64.347607 -348.94398) (xy 64.297993 -348.921322)
			(xy 64.252108 -348.891834) (xy 64.210886 -348.856115) (xy 64.175168 -348.814894) (xy 64.145679 -348.769009)
			(xy 64.123021 -348.719394) (xy 64.107654 -348.66706) (xy 64.099892 -348.613072) (xy 62.617065 -348.613072)
			(xy 62.609305 -348.667045) (xy 62.593943 -348.71937) (xy 62.57129 -348.768976) (xy 62.541809 -348.814854)
			(xy 62.506099 -348.856069) (xy 62.464887 -348.891784) (xy 62.419013 -348.92127) (xy 62.369409 -348.943928)
			(xy 62.317086 -348.959296) (xy 62.263109 -348.967063) (xy 62.235842 -348.967552) (xy 61.372242 -348.967552)
			(xy 61.344968 -348.967111) (xy 61.290976 -348.959354) (xy 61.238636 -348.943991) (xy 61.189017 -348.921335)
			(xy 61.143127 -348.891848) (xy 61.1019 -348.856129) (xy 61.066177 -348.814907) (xy 61.036685 -348.76902)
			(xy 61.014024 -348.719403) (xy 60.998655 -348.667066) (xy 60.990892 -348.613074) (xy 51.666865 -348.613074)
			(xy 51.659106 -348.667044) (xy 51.643743 -348.719369) (xy 51.621091 -348.768974) (xy 51.59161 -348.814852)
			(xy 51.555901 -348.856067) (xy 51.51469 -348.891781) (xy 51.468817 -348.921268) (xy 51.419214 -348.943926)
			(xy 51.366891 -348.959295) (xy 51.312914 -348.967062) (xy 51.285648 -348.967552) (xy 50.422048 -348.967552)
			(xy 50.394774 -348.967112) (xy 50.340781 -348.959355) (xy 50.288441 -348.943992) (xy 50.23882 -348.921337)
			(xy 50.192929 -348.89185) (xy 50.151702 -348.856132) (xy 50.115979 -348.814909) (xy 50.086486 -348.769022)
			(xy 50.063824 -348.719404) (xy 50.048455 -348.667066) (xy 50.040692 -348.613074) (xy 48.557989 -348.613074)
			(xy 48.550226 -348.667057) (xy 48.53486 -348.71939) (xy 48.512202 -348.769002) (xy 48.482714 -348.814885)
			(xy 48.446996 -348.856105) (xy 48.405776 -348.891821) (xy 48.359892 -348.921308) (xy 48.310278 -348.943964)
			(xy 48.257946 -348.959329) (xy 48.203959 -348.967089) (xy 48.176688 -348.967552) (xy 47.313088 -348.967552)
			(xy 47.285818 -348.967085) (xy 47.231835 -348.959321) (xy 47.179505 -348.943955) (xy 47.129895 -348.921297)
			(xy 47.084015 -348.89181) (xy 47.042797 -348.856094) (xy 47.007083 -348.814876) (xy 46.977597 -348.768994)
			(xy 46.954941 -348.719383) (xy 46.939576 -348.667053) (xy 46.931814 -348.61307) (xy 45.448966 -348.61307)
			(xy 45.441205 -348.667047) (xy 45.425841 -348.719373) (xy 45.403188 -348.76898) (xy 45.373705 -348.814858)
			(xy 45.337994 -348.856074) (xy 45.296781 -348.891789) (xy 45.250905 -348.921274) (xy 45.201299 -348.943932)
			(xy 45.148975 -348.959299) (xy 45.094995 -348.967064) (xy 45.067728 -348.967552) (xy 44.204128 -348.967552)
			(xy 44.176855 -348.96711) (xy 44.122864 -348.959351) (xy 44.070526 -348.943987) (xy 44.020908 -348.92133)
			(xy 43.97502 -348.891843) (xy 43.933795 -348.856124) (xy 43.898074 -348.814903) (xy 43.868583 -348.769016)
			(xy 43.845923 -348.7194) (xy 43.830555 -348.667064) (xy 43.822792 -348.613073) (xy 42.340088 -348.613073)
			(xy 42.332326 -348.66706) (xy 42.316958 -348.719394) (xy 42.294299 -348.769008) (xy 42.264809 -348.814892)
			(xy 42.229089 -348.856112) (xy 42.187866 -348.891828) (xy 42.14198 -348.921314) (xy 42.092364 -348.943969)
			(xy 42.040029 -348.959332) (xy 41.98604 -348.967091) (xy 41.958768 -348.967552) (xy 41.095168 -348.967552)
			(xy 41.067899 -348.967083) (xy 41.013918 -348.959318) (xy 40.961591 -348.943949) (xy 40.911983 -348.921291)
			(xy 40.866105 -348.891803) (xy 40.82489 -348.856087) (xy 40.789178 -348.814869) (xy 40.759694 -348.768989)
			(xy 40.73704 -348.719379) (xy 40.721675 -348.667051) (xy 40.713914 -348.613069) (xy 39.231066 -348.613069)
			(xy 39.223304 -348.66705) (xy 39.20794 -348.719377) (xy 39.185285 -348.768986) (xy 39.1558 -348.814865)
			(xy 39.120087 -348.856081) (xy 39.078871 -348.891796) (xy 39.032993 -348.921281) (xy 38.983385 -348.943937)
			(xy 38.931058 -348.959303) (xy 38.877076 -348.967065) (xy 38.849808 -348.967552) (xy 37.986208 -348.967552)
			(xy 37.958936 -348.967109) (xy 37.904947 -348.959348) (xy 37.852612 -348.943982) (xy 37.802996 -348.921324)
			(xy 37.75711 -348.891836) (xy 37.715888 -348.856117) (xy 37.680169 -348.814896) (xy 37.65068 -348.769011)
			(xy 37.628021 -348.719396) (xy 37.612654 -348.667061) (xy 37.604892 -348.613072) (xy 36.122065 -348.613072)
			(xy 36.114306 -348.667044) (xy 36.098943 -348.719369) (xy 36.076291 -348.768974) (xy 36.04681 -348.814852)
			(xy 36.011101 -348.856067) (xy 35.96989 -348.891781) (xy 35.924017 -348.921268) (xy 35.874414 -348.943926)
			(xy 35.822091 -348.959295) (xy 35.768114 -348.967062) (xy 35.740848 -348.967552) (xy 34.877248 -348.967552)
			(xy 34.849974 -348.967112) (xy 34.795981 -348.959355) (xy 34.743641 -348.943992) (xy 34.69402 -348.921337)
			(xy 34.648129 -348.89185) (xy 34.606902 -348.856132) (xy 34.571179 -348.814909) (xy 34.541686 -348.769022)
			(xy 34.519024 -348.719404) (xy 34.503655 -348.667066) (xy 34.495892 -348.613074) (xy 33.013189 -348.613074)
			(xy 33.005426 -348.667057) (xy 32.99006 -348.71939) (xy 32.967402 -348.769002) (xy 32.937914 -348.814885)
			(xy 32.902196 -348.856105) (xy 32.860976 -348.891821) (xy 32.815092 -348.921308) (xy 32.765478 -348.943964)
			(xy 32.713146 -348.959329) (xy 32.659159 -348.967089) (xy 32.631888 -348.967552) (xy 31.768288 -348.967552)
			(xy 31.741018 -348.967085) (xy 31.687035 -348.959321) (xy 31.634705 -348.943955) (xy 31.585095 -348.921297)
			(xy 31.539215 -348.89181) (xy 31.497997 -348.856094) (xy 31.462283 -348.814876) (xy 31.432797 -348.768994)
			(xy 31.410141 -348.719383) (xy 31.394776 -348.667053) (xy 31.387014 -348.61307) (xy 29.904166 -348.61307)
			(xy 29.896405 -348.667047) (xy 29.881041 -348.719373) (xy 29.858388 -348.76898) (xy 29.828905 -348.814858)
			(xy 29.793194 -348.856074) (xy 29.751981 -348.891789) (xy 29.706105 -348.921274) (xy 29.656499 -348.943932)
			(xy 29.604175 -348.959299) (xy 29.550195 -348.967064) (xy 29.522928 -348.967552) (xy 28.659328 -348.967552)
			(xy 28.632055 -348.96711) (xy 28.578064 -348.959351) (xy 28.525726 -348.943987) (xy 28.476108 -348.92133)
			(xy 28.43022 -348.891843) (xy 28.388995 -348.856124) (xy 28.353274 -348.814903) (xy 28.323783 -348.769016)
			(xy 28.301123 -348.7194) (xy 28.285755 -348.667064) (xy 28.277992 -348.613073) (xy 26.795288 -348.613073)
			(xy 26.787526 -348.66706) (xy 26.772158 -348.719394) (xy 26.749499 -348.769008) (xy 26.720009 -348.814892)
			(xy 26.684289 -348.856112) (xy 26.643066 -348.891828) (xy 26.59718 -348.921314) (xy 26.547564 -348.943969)
			(xy 26.495229 -348.959332) (xy 26.44124 -348.967091) (xy 26.413968 -348.967552) (xy 25.550368 -348.967552)
			(xy 25.523099 -348.967083) (xy 25.469118 -348.959318) (xy 25.416791 -348.943949) (xy 25.367183 -348.921291)
			(xy 25.321305 -348.891803) (xy 25.28009 -348.856087) (xy 25.244378 -348.814869) (xy 25.214894 -348.768989)
			(xy 25.19224 -348.719379) (xy 25.176875 -348.667051) (xy 25.169114 -348.613069) (xy 23.686266 -348.613069)
			(xy 23.678504 -348.66705) (xy 23.66314 -348.719377) (xy 23.640485 -348.768986) (xy 23.611 -348.814865)
			(xy 23.575287 -348.856081) (xy 23.534071 -348.891796) (xy 23.488193 -348.921281) (xy 23.438585 -348.943937)
			(xy 23.386258 -348.959303) (xy 23.332276 -348.967065) (xy 23.305008 -348.967552) (xy 22.441408 -348.967552)
			(xy 22.414136 -348.967109) (xy 22.360147 -348.959348) (xy 22.307812 -348.943982) (xy 22.258196 -348.921324)
			(xy 22.21231 -348.891836) (xy 22.171088 -348.856117) (xy 22.135369 -348.814896) (xy 22.10588 -348.769011)
			(xy 22.083221 -348.719396) (xy 22.067854 -348.667061) (xy 22.060092 -348.613072) (xy 20.577347 -348.613072)
			(xy 20.569586 -348.667048) (xy 20.55422 -348.719381) (xy 20.531562 -348.768994) (xy 20.502074 -348.814878)
			(xy 20.466357 -348.856098) (xy 20.425136 -348.891816) (xy 20.379253 -348.921303) (xy 20.329639 -348.943961)
			(xy 20.277306 -348.959327) (xy 20.223319 -348.967089) (xy 20.196048 -348.967552) (xy 19.332448 -348.967552)
			(xy 19.305179 -348.967065) (xy 19.251195 -348.959304) (xy 19.198866 -348.943938) (xy 19.149256 -348.921282)
			(xy 19.103375 -348.891796) (xy 19.062158 -348.856081) (xy 19.026443 -348.814863) (xy 18.996957 -348.768982)
			(xy 18.974301 -348.719372) (xy 18.958936 -348.667043) (xy 18.951174 -348.613059) (xy 8.879169 -348.613059)
			(xy 8.892221 -348.718461) (xy 8.900171 -348.847356) (xy 8.900668 -348.911926) (xy 8.900171 -348.976496)
			(xy 8.892221 -349.105391) (xy 8.876351 -349.233551) (xy 8.852622 -349.360492) (xy 8.821123 -349.485731)
			(xy 8.781974 -349.608794) (xy 8.735323 -349.729213) (xy 8.681348 -349.846532) (xy 8.620253 -349.960306)
			(xy 8.55227 -350.070103) (xy 8.477656 -350.175506) (xy 8.396695 -350.276116) (xy 8.309695 -350.371551)
			(xy 8.216984 -350.46145) (xy 8.118914 -350.545471) (xy 8.015859 -350.623295) (xy 7.908208 -350.694627)
			(xy 7.796369 -350.759197) (xy 7.680768 -350.816759) (xy 7.561843 -350.867096) (xy 7.440044 -350.910016)
			(xy 7.315834 -350.945357) (xy 7.189685 -350.972984) (xy 7.062073 -350.992793) (xy 6.933484 -351.004709)
			(xy 6.804406 -351.008686) (xy 6.675328 -351.004709) (xy 6.546739 -350.992793) (xy 6.419127 -350.972984)
			(xy 6.292978 -350.945357) (xy 6.168768 -350.910016) (xy 6.046969 -350.867096) (xy 5.928044 -350.816759)
			(xy 5.812443 -350.759197) (xy 5.700604 -350.694627) (xy 5.592953 -350.623295) (xy 5.489898 -350.545471)
			(xy 5.391828 -350.46145) (xy 5.299117 -350.371551) (xy 5.212117 -350.276116) (xy 5.131156 -350.175506)
			(xy 5.056542 -350.070103) (xy 4.988559 -349.960306) (xy 4.927464 -349.846532) (xy 4.873489 -349.729213)
			(xy 4.826838 -349.608794) (xy 4.787689 -349.485731) (xy 4.75619 -349.360492) (xy 4.732461 -349.233551)
			(xy 4.716591 -349.105391) (xy 4.708641 -348.976496) (xy 0.508 -348.976496) (xy 0.508 -351.638709)
			(xy 18.951172 -351.638709) (xy 18.951172 -351.584171) (xy 18.958934 -351.530187) (xy 18.974299 -351.477857)
			(xy 18.996956 -351.428247) (xy 19.026441 -351.382366) (xy 19.062157 -351.341148) (xy 19.103374 -351.305433)
			(xy 19.149255 -351.275947) (xy 19.198865 -351.25329) (xy 19.251195 -351.237925) (xy 19.305179 -351.230163)
			(xy 19.332448 -351.229676) (xy 20.196048 -351.229676) (xy 20.223319 -351.230143) (xy 20.277306 -351.237905)
			(xy 20.329638 -351.253271) (xy 20.379252 -351.275929) (xy 20.425135 -351.305416) (xy 20.466355 -351.341133)
			(xy 20.502073 -351.382353) (xy 20.53156 -351.428237) (xy 20.554218 -351.47785) (xy 20.569584 -351.530182)
			(xy 20.577347 -351.584169) (xy 20.577347 -351.638669) (xy 22.060139 -351.638669) (xy 22.060139 -351.584131)
			(xy 22.067901 -351.530149) (xy 22.083266 -351.477821) (xy 22.105922 -351.428212) (xy 22.135407 -351.382333)
			(xy 22.171122 -351.341117) (xy 22.212339 -351.305403) (xy 22.258219 -351.275918) (xy 22.307829 -351.253263)
			(xy 22.360157 -351.237899) (xy 22.414139 -351.230139) (xy 22.441408 -351.229676) (xy 23.305008 -351.229676)
			(xy 23.33228 -351.230087) (xy 23.386268 -351.23785) (xy 23.438602 -351.253218) (xy 23.488216 -351.275877)
			(xy 23.5341 -351.305366) (xy 23.575321 -351.341085) (xy 23.611039 -351.382306) (xy 23.640527 -351.428191)
			(xy 23.663185 -351.477806) (xy 23.678551 -351.53014) (xy 23.686314 -351.584128) (xy 23.686314 -351.638665)
			(xy 25.169162 -351.638665) (xy 25.169162 -351.584135) (xy 25.176922 -351.530159) (xy 25.192284 -351.477838)
			(xy 25.214936 -351.428234) (xy 25.244416 -351.38236) (xy 25.280124 -351.341147) (xy 25.321334 -351.305435)
			(xy 25.367206 -351.275951) (xy 25.416808 -351.253296) (xy 25.469128 -351.237929) (xy 25.523103 -351.230165)
			(xy 25.550368 -351.229676) (xy 26.413968 -351.229676) (xy 26.441243 -351.230061) (xy 26.495239 -351.237821)
			(xy 26.547581 -351.253186) (xy 26.597203 -351.275844) (xy 26.643095 -351.305333) (xy 26.684323 -351.341054)
			(xy 26.720047 -351.382279) (xy 26.749541 -351.428169) (xy 26.772203 -351.477789) (xy 26.787573 -351.53013)
			(xy 26.795336 -351.584125) (xy 26.795336 -351.63867) (xy 28.278039 -351.63867) (xy 28.278039 -351.58413)
			(xy 28.285802 -351.530146) (xy 28.301168 -351.477817) (xy 28.323825 -351.428207) (xy 28.353312 -351.382326)
			(xy 28.389029 -351.341109) (xy 28.430249 -351.305396) (xy 28.476131 -351.275912) (xy 28.525743 -351.253258)
			(xy 28.578074 -351.237896) (xy 28.632058 -351.230137) (xy 28.659328 -351.229676) (xy 29.522928 -351.229676)
			(xy 29.550199 -351.230088) (xy 29.604185 -351.237854) (xy 29.656516 -351.253223) (xy 29.706128 -351.275883)
			(xy 29.75201 -351.305373) (xy 29.793228 -351.341092) (xy 29.828944 -351.382313) (xy 29.85843 -351.428197)
			(xy 29.881086 -351.47781) (xy 29.896452 -351.530143) (xy 29.904214 -351.584129) (xy 29.904214 -351.638666)
			(xy 31.387062 -351.638666) (xy 31.387062 -351.584134) (xy 31.394823 -351.530157) (xy 31.410186 -351.477833)
			(xy 31.432839 -351.428229) (xy 31.462321 -351.382353) (xy 31.498031 -351.34114) (xy 31.539243 -351.305428)
			(xy 31.585118 -351.275945) (xy 31.634722 -351.25329) (xy 31.687045 -351.237925) (xy 31.741022 -351.230163)
			(xy 31.768288 -351.229676) (xy 32.631888 -351.229676) (xy 32.659162 -351.230063) (xy 32.713156 -351.237824)
			(xy 32.765495 -351.253191) (xy 32.815115 -351.27585) (xy 32.861004 -351.30534) (xy 32.90223 -351.341061)
			(xy 32.937952 -351.382286) (xy 32.967444 -351.428175) (xy 32.990105 -351.477794) (xy 33.005473 -351.530132)
			(xy 33.013236 -351.584126) (xy 33.013236 -351.63867) (xy 34.49594 -351.63867) (xy 34.49594 -351.58413)
			(xy 34.503702 -351.530144) (xy 34.519069 -351.477812) (xy 34.541728 -351.428201) (xy 34.571217 -351.38232)
			(xy 34.606936 -351.341102) (xy 34.648158 -351.305388) (xy 34.694043 -351.275905) (xy 34.743658 -351.253253)
			(xy 34.795991 -351.237892) (xy 34.849977 -351.230136) (xy 34.877248 -351.229676) (xy 35.740848 -351.229676)
			(xy 35.768118 -351.23009) (xy 35.822102 -351.237858) (xy 35.874431 -351.253229) (xy 35.92404 -351.27589)
			(xy 35.969919 -351.30538) (xy 36.011135 -351.341099) (xy 36.046849 -351.382319) (xy 36.076333 -351.428203)
			(xy 36.098988 -351.477814) (xy 36.114352 -351.530145) (xy 36.122114 -351.58413) (xy 36.122114 -351.638669)
			(xy 37.604939 -351.638669) (xy 37.604939 -351.584131) (xy 37.612701 -351.530149) (xy 37.628066 -351.477821)
			(xy 37.650722 -351.428212) (xy 37.680207 -351.382333) (xy 37.715922 -351.341117) (xy 37.757139 -351.305403)
			(xy 37.803019 -351.275918) (xy 37.852629 -351.253263) (xy 37.904957 -351.237899) (xy 37.958939 -351.230139)
			(xy 37.986208 -351.229676) (xy 38.849808 -351.229676) (xy 38.87708 -351.230087) (xy 38.931068 -351.23785)
			(xy 38.983402 -351.253218) (xy 39.033016 -351.275877) (xy 39.0789 -351.305366) (xy 39.120121 -351.341085)
			(xy 39.155839 -351.382306) (xy 39.185327 -351.428191) (xy 39.207985 -351.477806) (xy 39.223351 -351.53014)
			(xy 39.231114 -351.584128) (xy 39.231114 -351.638665) (xy 40.713962 -351.638665) (xy 40.713962 -351.584135)
			(xy 40.721722 -351.530159) (xy 40.737084 -351.477838) (xy 40.759736 -351.428234) (xy 40.789216 -351.38236)
			(xy 40.824924 -351.341147) (xy 40.866134 -351.305435) (xy 40.912006 -351.275951) (xy 40.961608 -351.253296)
			(xy 41.013928 -351.237929) (xy 41.067903 -351.230165) (xy 41.095168 -351.229676) (xy 41.958768 -351.229676)
			(xy 41.986043 -351.230061) (xy 42.040039 -351.237821) (xy 42.092381 -351.253186) (xy 42.142003 -351.275844)
			(xy 42.187895 -351.305333) (xy 42.229123 -351.341054) (xy 42.264847 -351.382279) (xy 42.294341 -351.428169)
			(xy 42.317003 -351.477789) (xy 42.332373 -351.53013) (xy 42.340136 -351.584125) (xy 42.340136 -351.63867)
			(xy 43.822839 -351.63867) (xy 43.822839 -351.58413) (xy 43.830602 -351.530146) (xy 43.845968 -351.477817)
			(xy 43.868625 -351.428207) (xy 43.898112 -351.382326) (xy 43.933829 -351.341109) (xy 43.975049 -351.305396)
			(xy 44.020931 -351.275912) (xy 44.070543 -351.253258) (xy 44.122874 -351.237896) (xy 44.176858 -351.230137)
			(xy 44.204128 -351.229676) (xy 45.067728 -351.229676) (xy 45.094999 -351.230088) (xy 45.148985 -351.237854)
			(xy 45.201316 -351.253223) (xy 45.250928 -351.275883) (xy 45.29681 -351.305373) (xy 45.338028 -351.341092)
			(xy 45.373744 -351.382313) (xy 45.40323 -351.428197) (xy 45.425886 -351.47781) (xy 45.441252 -351.530143)
			(xy 45.449014 -351.584129) (xy 45.449014 -351.638666) (xy 46.931862 -351.638666) (xy 46.931862 -351.584134)
			(xy 46.939623 -351.530157) (xy 46.954986 -351.477833) (xy 46.977639 -351.428229) (xy 47.007121 -351.382353)
			(xy 47.042831 -351.34114) (xy 47.084043 -351.305428) (xy 47.129918 -351.275945) (xy 47.179522 -351.25329)
			(xy 47.231845 -351.237925) (xy 47.285822 -351.230163) (xy 47.313088 -351.229676) (xy 48.176688 -351.229676)
			(xy 48.203962 -351.230063) (xy 48.257956 -351.237824) (xy 48.310295 -351.253191) (xy 48.359915 -351.27585)
			(xy 48.405804 -351.30534) (xy 48.44703 -351.341061) (xy 48.482752 -351.382286) (xy 48.512244 -351.428175)
			(xy 48.534905 -351.477794) (xy 48.550273 -351.530132) (xy 48.558036 -351.584126) (xy 48.558036 -351.63867)
			(xy 50.04074 -351.63867) (xy 50.04074 -351.58413) (xy 50.048502 -351.530144) (xy 50.063869 -351.477812)
			(xy 50.086528 -351.428201) (xy 50.116017 -351.38232) (xy 50.151736 -351.341102) (xy 50.192958 -351.305388)
			(xy 50.238843 -351.275905) (xy 50.288458 -351.253253) (xy 50.340791 -351.237892) (xy 50.394777 -351.230136)
			(xy 50.422048 -351.229676) (xy 51.285648 -351.229676) (xy 51.312918 -351.23009) (xy 51.366902 -351.237858)
			(xy 51.419231 -351.253229) (xy 51.46884 -351.27589) (xy 51.514719 -351.30538) (xy 51.555935 -351.341099)
			(xy 51.591649 -351.382319) (xy 51.621133 -351.428203) (xy 51.643788 -351.477814) (xy 51.659152 -351.530145)
			(xy 51.666914 -351.58413) (xy 51.666914 -351.63867) (xy 60.99094 -351.63867) (xy 60.99094 -351.58413)
			(xy 60.998702 -351.530145) (xy 61.014069 -351.477814) (xy 61.036727 -351.428203) (xy 61.066216 -351.382322)
			(xy 61.101934 -351.341105) (xy 61.143155 -351.305391) (xy 61.18904 -351.275907) (xy 61.238653 -351.253254)
			(xy 61.290986 -351.237893) (xy 61.344972 -351.230137) (xy 61.372242 -351.229676) (xy 62.235842 -351.229676)
			(xy 62.263112 -351.230089) (xy 62.317097 -351.237857) (xy 62.369426 -351.253227) (xy 62.419036 -351.275888)
			(xy 62.464916 -351.305378) (xy 62.506133 -351.341097) (xy 62.541847 -351.382317) (xy 62.571332 -351.428201)
			(xy 62.593988 -351.477813) (xy 62.609352 -351.530145) (xy 62.617114 -351.58413) (xy 62.617114 -351.638668)
			(xy 64.099939 -351.638668) (xy 64.099939 -351.584132) (xy 64.107701 -351.53015) (xy 64.123066 -351.477822)
			(xy 64.145721 -351.428214) (xy 64.175206 -351.382335) (xy 64.21092 -351.341119) (xy 64.252136 -351.305405)
			(xy 64.298016 -351.27592) (xy 64.347624 -351.253265) (xy 64.399952 -351.2379) (xy 64.453934 -351.230139)
			(xy 64.481202 -351.229676) (xy 65.344802 -351.229676) (xy 65.372074 -351.230087) (xy 65.426063 -351.237849)
			(xy 65.478397 -351.253216) (xy 65.528012 -351.275875) (xy 65.573897 -351.305364) (xy 65.615119 -351.341083)
			(xy 65.650837 -351.382304) (xy 65.680326 -351.42819) (xy 65.702984 -351.477805) (xy 65.718351 -351.530139)
			(xy 65.726113 -351.584128) (xy 65.726113 -351.638665) (xy 67.208962 -351.638665) (xy 67.208962 -351.584135)
			(xy 67.216722 -351.53016) (xy 67.232084 -351.477839) (xy 67.254735 -351.428236) (xy 67.284215 -351.382362)
			(xy 67.319922 -351.341149) (xy 67.361131 -351.305437) (xy 67.407003 -351.275953) (xy 67.456603 -351.253297)
			(xy 67.508923 -351.23793) (xy 67.562897 -351.230165) (xy 67.590162 -351.229676) (xy 68.453762 -351.229676)
			(xy 68.481037 -351.230061) (xy 68.535034 -351.23782) (xy 68.587376 -351.253184) (xy 68.636999 -351.275842)
			(xy 68.682892 -351.305331) (xy 68.724121 -351.341052) (xy 68.759846 -351.382277) (xy 68.78934 -351.428167)
			(xy 68.812003 -351.477788) (xy 68.827372 -351.530129) (xy 68.835136 -351.584125) (xy 68.835136 -351.638669)
			(xy 70.317839 -351.638669) (xy 70.317839 -351.584131) (xy 70.325601 -351.530147) (xy 70.340967 -351.477818)
			(xy 70.363624 -351.428208) (xy 70.393111 -351.382328) (xy 70.428827 -351.341112) (xy 70.470046 -351.305398)
			(xy 70.515928 -351.275914) (xy 70.565539 -351.25326) (xy 70.617869 -351.237897) (xy 70.671853 -351.230138)
			(xy 70.699122 -351.229676) (xy 71.562722 -351.229676) (xy 71.589993 -351.230088) (xy 71.64398 -351.237853)
			(xy 71.696312 -351.253222) (xy 71.745924 -351.275881) (xy 71.791807 -351.305371) (xy 71.833026 -351.34109)
			(xy 71.868742 -351.382311) (xy 71.898229 -351.428195) (xy 71.920886 -351.477809) (xy 71.936252 -351.530142)
			(xy 71.944014 -351.584129) (xy 71.944014 -351.638666) (xy 73.426862 -351.638666) (xy 73.426862 -351.584134)
			(xy 73.434623 -351.530158) (xy 73.449986 -351.477835) (xy 73.472638 -351.428231) (xy 73.50212 -351.382355)
			(xy 73.537829 -351.341142) (xy 73.579041 -351.30543) (xy 73.624915 -351.275947) (xy 73.674518 -351.253292)
			(xy 73.72684 -351.237927) (xy 73.780816 -351.230164) (xy 73.808082 -351.229676) (xy 74.671682 -351.229676)
			(xy 74.698957 -351.230062) (xy 74.752951 -351.237823) (xy 74.805291 -351.253189) (xy 74.854911 -351.275848)
			(xy 74.900802 -351.305338) (xy 74.942028 -351.341059) (xy 74.977751 -351.382284) (xy 75.007243 -351.428173)
			(xy 75.029904 -351.477792) (xy 75.045273 -351.530132) (xy 75.053036 -351.584125) (xy 75.053036 -351.63867)
			(xy 76.53574 -351.63867) (xy 76.53574 -351.58413) (xy 76.543502 -351.530145) (xy 76.558869 -351.477814)
			(xy 76.581527 -351.428203) (xy 76.611016 -351.382322) (xy 76.646734 -351.341105) (xy 76.687955 -351.305391)
			(xy 76.73384 -351.275907) (xy 76.783453 -351.253254) (xy 76.835786 -351.237893) (xy 76.889772 -351.230137)
			(xy 76.917042 -351.229676) (xy 77.780642 -351.229676) (xy 77.807912 -351.230089) (xy 77.861897 -351.237857)
			(xy 77.914226 -351.253227) (xy 77.963836 -351.275888) (xy 78.009716 -351.305378) (xy 78.050933 -351.341097)
			(xy 78.086647 -351.382317) (xy 78.116132 -351.428201) (xy 78.138788 -351.477813) (xy 78.154152 -351.530145)
			(xy 78.161914 -351.58413) (xy 78.161914 -351.638668) (xy 79.644739 -351.638668) (xy 79.644739 -351.584132)
			(xy 79.652501 -351.53015) (xy 79.667866 -351.477822) (xy 79.690521 -351.428214) (xy 79.720006 -351.382335)
			(xy 79.75572 -351.341119) (xy 79.796936 -351.305405) (xy 79.842816 -351.27592) (xy 79.892424 -351.253265)
			(xy 79.944752 -351.2379) (xy 79.998734 -351.230139) (xy 80.026002 -351.229676) (xy 80.889602 -351.229676)
			(xy 80.916874 -351.230087) (xy 80.970863 -351.237849) (xy 81.023197 -351.253216) (xy 81.072812 -351.275875)
			(xy 81.118697 -351.305364) (xy 81.159919 -351.341083) (xy 81.195637 -351.382304) (xy 81.225126 -351.42819)
			(xy 81.247784 -351.477805) (xy 81.263151 -351.530139) (xy 81.270913 -351.584128) (xy 81.270913 -351.638665)
			(xy 82.753762 -351.638665) (xy 82.753762 -351.584135) (xy 82.761522 -351.53016) (xy 82.776884 -351.477839)
			(xy 82.799535 -351.428236) (xy 82.829015 -351.382362) (xy 82.864722 -351.341149) (xy 82.905931 -351.305437)
			(xy 82.951803 -351.275953) (xy 83.001403 -351.253297) (xy 83.053723 -351.23793) (xy 83.107697 -351.230165)
			(xy 83.134962 -351.229676) (xy 83.998562 -351.229676) (xy 84.025837 -351.230061) (xy 84.079834 -351.23782)
			(xy 84.132176 -351.253184) (xy 84.181799 -351.275842) (xy 84.227692 -351.305331) (xy 84.268921 -351.341052)
			(xy 84.304646 -351.382277) (xy 84.33414 -351.428167) (xy 84.356803 -351.477788) (xy 84.372172 -351.530129)
			(xy 84.379936 -351.584125) (xy 84.379936 -351.638669) (xy 85.862639 -351.638669) (xy 85.862639 -351.584131)
			(xy 85.870401 -351.530147) (xy 85.885767 -351.477818) (xy 85.908424 -351.428208) (xy 85.937911 -351.382328)
			(xy 85.973627 -351.341112) (xy 86.014846 -351.305398) (xy 86.060728 -351.275914) (xy 86.110339 -351.25326)
			(xy 86.162669 -351.237897) (xy 86.216653 -351.230138) (xy 86.243922 -351.229676) (xy 87.107522 -351.229676)
			(xy 87.134793 -351.230088) (xy 87.18878 -351.237853) (xy 87.241112 -351.253222) (xy 87.290724 -351.275881)
			(xy 87.336607 -351.305371) (xy 87.377826 -351.34109) (xy 87.413542 -351.382311) (xy 87.443029 -351.428195)
			(xy 87.465686 -351.477809) (xy 87.481052 -351.530142) (xy 87.488814 -351.584129) (xy 87.488814 -351.638666)
			(xy 88.971662 -351.638666) (xy 88.971662 -351.584134) (xy 88.979423 -351.530158) (xy 88.994786 -351.477835)
			(xy 89.017438 -351.428231) (xy 89.04692 -351.382355) (xy 89.082629 -351.341142) (xy 89.123841 -351.30543)
			(xy 89.169715 -351.275947) (xy 89.219318 -351.253292) (xy 89.27164 -351.237927) (xy 89.325616 -351.230164)
			(xy 89.352882 -351.229676) (xy 90.216482 -351.229676) (xy 90.243757 -351.230062) (xy 90.297751 -351.237823)
			(xy 90.350091 -351.253189) (xy 90.399711 -351.275848) (xy 90.445602 -351.305338) (xy 90.486828 -351.341059)
			(xy 90.522551 -351.382284) (xy 90.552043 -351.428173) (xy 90.574704 -351.477792) (xy 90.590073 -351.530132)
			(xy 90.597836 -351.584125) (xy 90.597836 -351.63867) (xy 92.08054 -351.63867) (xy 92.08054 -351.58413)
			(xy 92.088302 -351.530145) (xy 92.103669 -351.477814) (xy 92.126327 -351.428203) (xy 92.155816 -351.382322)
			(xy 92.191534 -351.341105) (xy 92.232755 -351.305391) (xy 92.27864 -351.275907) (xy 92.328253 -351.253254)
			(xy 92.380586 -351.237893) (xy 92.434572 -351.230137) (xy 92.461842 -351.229676) (xy 93.325442 -351.229676)
			(xy 93.352712 -351.230089) (xy 93.406697 -351.237857) (xy 93.459026 -351.253227) (xy 93.508636 -351.275888)
			(xy 93.554516 -351.305378) (xy 93.595733 -351.341097) (xy 93.631447 -351.382317) (xy 93.660932 -351.428201)
			(xy 93.683588 -351.477813) (xy 93.698952 -351.530145) (xy 93.706714 -351.58413) (xy 93.706714 -351.638669)
			(xy 111.480839 -351.638669) (xy 111.480839 -351.584131) (xy 111.488601 -351.530149) (xy 111.503966 -351.477821)
			(xy 111.526622 -351.428212) (xy 111.556107 -351.382333) (xy 111.591822 -351.341117) (xy 111.633039 -351.305403)
			(xy 111.678919 -351.275918) (xy 111.728529 -351.253263) (xy 111.780857 -351.237899) (xy 111.834839 -351.230139)
			(xy 111.862108 -351.229676) (xy 112.725708 -351.229676) (xy 112.75298 -351.230087) (xy 112.806968 -351.23785)
			(xy 112.859302 -351.253218) (xy 112.908916 -351.275877) (xy 112.9548 -351.305366) (xy 112.996021 -351.341085)
			(xy 113.031739 -351.382306) (xy 113.061227 -351.428191) (xy 113.083885 -351.477806) (xy 113.099251 -351.53014)
			(xy 113.107014 -351.584128) (xy 113.107014 -351.638665) (xy 114.589862 -351.638665) (xy 114.589862 -351.584135)
			(xy 114.597622 -351.530159) (xy 114.612984 -351.477838) (xy 114.635636 -351.428234) (xy 114.665116 -351.38236)
			(xy 114.700824 -351.341147) (xy 114.742034 -351.305435) (xy 114.787906 -351.275951) (xy 114.837508 -351.253296)
			(xy 114.889828 -351.237929) (xy 114.943803 -351.230165) (xy 114.971068 -351.229676) (xy 115.834668 -351.229676)
			(xy 115.861943 -351.230061) (xy 115.915939 -351.237821) (xy 115.968281 -351.253186) (xy 116.017903 -351.275844)
			(xy 116.063795 -351.305333) (xy 116.105023 -351.341054) (xy 116.140747 -351.382279) (xy 116.170241 -351.428169)
			(xy 116.192903 -351.477789) (xy 116.208273 -351.53013) (xy 116.216036 -351.584125) (xy 116.216036 -351.63867)
			(xy 117.698739 -351.63867) (xy 117.698739 -351.58413) (xy 117.706502 -351.530146) (xy 117.721868 -351.477817)
			(xy 117.744525 -351.428207) (xy 117.774012 -351.382326) (xy 117.809729 -351.341109) (xy 117.850949 -351.305396)
			(xy 117.896831 -351.275912) (xy 117.946443 -351.253258) (xy 117.998774 -351.237896) (xy 118.052758 -351.230137)
			(xy 118.080028 -351.229676) (xy 118.943628 -351.229676) (xy 118.970899 -351.230088) (xy 119.024885 -351.237854)
			(xy 119.077216 -351.253223) (xy 119.126828 -351.275883) (xy 119.17271 -351.305373) (xy 119.213928 -351.341092)
			(xy 119.249644 -351.382313) (xy 119.27913 -351.428197) (xy 119.301786 -351.47781) (xy 119.317152 -351.530143)
			(xy 119.324914 -351.584129) (xy 119.324914 -351.638666) (xy 120.807762 -351.638666) (xy 120.807762 -351.584134)
			(xy 120.815523 -351.530157) (xy 120.830886 -351.477833) (xy 120.853539 -351.428229) (xy 120.883021 -351.382353)
			(xy 120.918731 -351.34114) (xy 120.959943 -351.305428) (xy 121.005818 -351.275945) (xy 121.055422 -351.25329)
			(xy 121.107745 -351.237925) (xy 121.161722 -351.230163) (xy 121.188988 -351.229676) (xy 122.052588 -351.229676)
			(xy 122.079862 -351.230063) (xy 122.133856 -351.237824) (xy 122.186195 -351.253191) (xy 122.235815 -351.27585)
			(xy 122.281704 -351.30534) (xy 122.32293 -351.341061) (xy 122.358652 -351.382286) (xy 122.388144 -351.428175)
			(xy 122.410805 -351.477794) (xy 122.426173 -351.530132) (xy 122.433936 -351.584126) (xy 122.433936 -351.63867)
			(xy 123.91664 -351.63867) (xy 123.91664 -351.58413) (xy 123.924402 -351.530144) (xy 123.939769 -351.477812)
			(xy 123.962428 -351.428201) (xy 123.991917 -351.38232) (xy 124.027636 -351.341102) (xy 124.068858 -351.305388)
			(xy 124.114743 -351.275905) (xy 124.164358 -351.253253) (xy 124.216691 -351.237892) (xy 124.270677 -351.230136)
			(xy 124.297948 -351.229676) (xy 125.161548 -351.229676) (xy 125.188818 -351.23009) (xy 125.242802 -351.237858)
			(xy 125.295131 -351.253229) (xy 125.34474 -351.27589) (xy 125.390619 -351.30538) (xy 125.431835 -351.341099)
			(xy 125.467549 -351.382319) (xy 125.497033 -351.428203) (xy 125.519688 -351.477814) (xy 125.535052 -351.530145)
			(xy 125.542814 -351.58413) (xy 125.542814 -351.638669) (xy 127.025639 -351.638669) (xy 127.025639 -351.584131)
			(xy 127.033401 -351.530149) (xy 127.048766 -351.477821) (xy 127.071422 -351.428212) (xy 127.100907 -351.382333)
			(xy 127.136622 -351.341117) (xy 127.177839 -351.305403) (xy 127.223719 -351.275918) (xy 127.273329 -351.253263)
			(xy 127.325657 -351.237899) (xy 127.379639 -351.230139) (xy 127.406908 -351.229676) (xy 128.270508 -351.229676)
			(xy 128.29778 -351.230087) (xy 128.351768 -351.23785) (xy 128.404102 -351.253218) (xy 128.453716 -351.275877)
			(xy 128.4996 -351.305366) (xy 128.540821 -351.341085) (xy 128.576539 -351.382306) (xy 128.606027 -351.428191)
			(xy 128.628685 -351.477806) (xy 128.644051 -351.53014) (xy 128.651814 -351.584128) (xy 128.651814 -351.638665)
			(xy 130.134662 -351.638665) (xy 130.134662 -351.584135) (xy 130.142422 -351.530159) (xy 130.157784 -351.477838)
			(xy 130.180436 -351.428234) (xy 130.209916 -351.38236) (xy 130.245624 -351.341147) (xy 130.286834 -351.305435)
			(xy 130.332706 -351.275951) (xy 130.382308 -351.253296) (xy 130.434628 -351.237929) (xy 130.488603 -351.230165)
			(xy 130.515868 -351.229676) (xy 131.379468 -351.229676) (xy 131.406743 -351.230061) (xy 131.460739 -351.237821)
			(xy 131.513081 -351.253186) (xy 131.562703 -351.275844) (xy 131.608595 -351.305333) (xy 131.649823 -351.341054)
			(xy 131.685547 -351.382279) (xy 131.715041 -351.428169) (xy 131.737703 -351.477789) (xy 131.753073 -351.53013)
			(xy 131.760836 -351.584125) (xy 131.760836 -351.63867) (xy 133.243539 -351.63867) (xy 133.243539 -351.58413)
			(xy 133.251302 -351.530146) (xy 133.266668 -351.477817) (xy 133.289325 -351.428207) (xy 133.318812 -351.382326)
			(xy 133.354529 -351.341109) (xy 133.395749 -351.305396) (xy 133.441631 -351.275912) (xy 133.491243 -351.253258)
			(xy 133.543574 -351.237896) (xy 133.597558 -351.230137) (xy 133.624828 -351.229676) (xy 134.488428 -351.229676)
			(xy 134.515699 -351.230088) (xy 134.569685 -351.237854) (xy 134.622016 -351.253223) (xy 134.671628 -351.275883)
			(xy 134.71751 -351.305373) (xy 134.758728 -351.341092) (xy 134.794444 -351.382313) (xy 134.82393 -351.428197)
			(xy 134.846586 -351.47781) (xy 134.861952 -351.530143) (xy 134.869714 -351.584129) (xy 134.869714 -351.638666)
			(xy 136.352562 -351.638666) (xy 136.352562 -351.584134) (xy 136.360323 -351.530157) (xy 136.375686 -351.477833)
			(xy 136.398339 -351.428229) (xy 136.427821 -351.382353) (xy 136.463531 -351.34114) (xy 136.504743 -351.305428)
			(xy 136.550618 -351.275945) (xy 136.600222 -351.25329) (xy 136.652545 -351.237925) (xy 136.706522 -351.230163)
			(xy 136.733788 -351.229676) (xy 137.597388 -351.229676) (xy 137.624662 -351.230063) (xy 137.678656 -351.237824)
			(xy 137.730995 -351.253191) (xy 137.780615 -351.27585) (xy 137.826504 -351.30534) (xy 137.86773 -351.341061)
			(xy 137.903452 -351.382286) (xy 137.932944 -351.428175) (xy 137.955605 -351.477794) (xy 137.970973 -351.530132)
			(xy 137.978736 -351.584126) (xy 137.978736 -351.63867) (xy 139.46144 -351.63867) (xy 139.46144 -351.58413)
			(xy 139.469202 -351.530144) (xy 139.484569 -351.477812) (xy 139.507228 -351.428201) (xy 139.536717 -351.38232)
			(xy 139.572436 -351.341102) (xy 139.613658 -351.305388) (xy 139.659543 -351.275905) (xy 139.709158 -351.253253)
			(xy 139.761491 -351.237892) (xy 139.815477 -351.230136) (xy 139.842748 -351.229676) (xy 140.706348 -351.229676)
			(xy 140.733618 -351.23009) (xy 140.787602 -351.237858) (xy 140.839931 -351.253229) (xy 140.88954 -351.27589)
			(xy 140.935419 -351.30538) (xy 140.976635 -351.341099) (xy 141.012349 -351.382319) (xy 141.041833 -351.428203)
			(xy 141.064488 -351.477814) (xy 141.079852 -351.530145) (xy 141.087614 -351.58413) (xy 141.087614 -351.638669)
			(xy 142.570439 -351.638669) (xy 142.570439 -351.584131) (xy 142.578201 -351.530149) (xy 142.593566 -351.477821)
			(xy 142.616222 -351.428212) (xy 142.645707 -351.382333) (xy 142.681422 -351.341117) (xy 142.722639 -351.305403)
			(xy 142.768519 -351.275918) (xy 142.818129 -351.253263) (xy 142.870457 -351.237899) (xy 142.924439 -351.230139)
			(xy 142.951708 -351.229676) (xy 143.815308 -351.229676) (xy 143.84258 -351.230087) (xy 143.896568 -351.23785)
			(xy 143.948902 -351.253218) (xy 143.998516 -351.275877) (xy 144.0444 -351.305366) (xy 144.085621 -351.341085)
			(xy 144.121339 -351.382306) (xy 144.150827 -351.428191) (xy 144.173485 -351.477806) (xy 144.188851 -351.53014)
			(xy 144.196614 -351.584128) (xy 144.196614 -351.638669) (xy 161.804839 -351.638669) (xy 161.804839 -351.584131)
			(xy 161.812601 -351.530149) (xy 161.827966 -351.47782) (xy 161.850623 -351.428211) (xy 161.880108 -351.382331)
			(xy 161.915824 -351.341115) (xy 161.957041 -351.305401) (xy 162.002922 -351.275917) (xy 162.052531 -351.253262)
			(xy 162.10486 -351.237899) (xy 162.158843 -351.230139) (xy 162.186112 -351.229676) (xy 163.049712 -351.229676)
			(xy 163.076984 -351.230087) (xy 163.130971 -351.237851) (xy 163.183304 -351.253219) (xy 163.232918 -351.275878)
			(xy 163.278802 -351.305367) (xy 163.320022 -351.341086) (xy 163.35574 -351.382308) (xy 163.385228 -351.428192)
			(xy 163.407885 -351.477807) (xy 163.423251 -351.530141) (xy 163.431014 -351.584128) (xy 163.431014 -351.638665)
			(xy 164.913862 -351.638665) (xy 164.913862 -351.584135) (xy 164.921622 -351.530159) (xy 164.936985 -351.477837)
			(xy 164.959637 -351.428233) (xy 164.989117 -351.382358) (xy 165.024826 -351.341146) (xy 165.066036 -351.305434)
			(xy 165.111909 -351.27595) (xy 165.16151 -351.253295) (xy 165.213831 -351.237928) (xy 165.267807 -351.230164)
			(xy 165.295072 -351.229676) (xy 166.158672 -351.229676) (xy 166.185947 -351.230062) (xy 166.239942 -351.237821)
			(xy 166.292284 -351.253187) (xy 166.341905 -351.275845) (xy 166.387797 -351.305335) (xy 166.429024 -351.341056)
			(xy 166.464748 -351.382281) (xy 166.494242 -351.42817) (xy 166.516903 -351.47779) (xy 166.532273 -351.53013)
			(xy 166.540036 -351.584125) (xy 166.540036 -351.63867) (xy 168.022739 -351.63867) (xy 168.022739 -351.58413)
			(xy 168.030502 -351.530146) (xy 168.045868 -351.477816) (xy 168.068526 -351.428206) (xy 168.098013 -351.382325)
			(xy 168.133731 -351.341108) (xy 168.174951 -351.305394) (xy 168.220834 -351.27591) (xy 168.270446 -351.253257)
			(xy 168.322777 -351.237895) (xy 168.376762 -351.230137) (xy 168.404032 -351.229676) (xy 169.267632 -351.229676)
			(xy 169.294903 -351.230089) (xy 169.348888 -351.237855) (xy 169.401219 -351.253224) (xy 169.45083 -351.275885)
			(xy 169.496712 -351.305374) (xy 169.537929 -351.341093) (xy 169.573645 -351.382314) (xy 169.603131 -351.428198)
			(xy 169.625787 -351.477811) (xy 169.641152 -351.530143) (xy 169.648914 -351.584129) (xy 169.648914 -351.638666)
			(xy 171.131762 -351.638666) (xy 171.131762 -351.584134) (xy 171.139523 -351.530156) (xy 171.154886 -351.477832)
			(xy 171.17754 -351.428228) (xy 171.207022 -351.382352) (xy 171.242733 -351.341138) (xy 171.283945 -351.305427)
			(xy 171.329821 -351.275944) (xy 171.379425 -351.253289) (xy 171.431748 -351.237925) (xy 171.485726 -351.230163)
			(xy 171.512992 -351.229676) (xy 172.376592 -351.229676) (xy 172.403866 -351.230063) (xy 172.457859 -351.237825)
			(xy 172.510198 -351.253192) (xy 172.559817 -351.275851) (xy 172.605706 -351.305342) (xy 172.646932 -351.341063)
			(xy 172.682653 -351.382287) (xy 172.712145 -351.428176) (xy 172.734805 -351.477794) (xy 172.750173 -351.530133)
			(xy 172.757936 -351.584126) (xy 172.757936 -351.638664) (xy 174.240762 -351.638664) (xy 174.240762 -351.584136)
			(xy 174.248522 -351.530162) (xy 174.263883 -351.477841) (xy 174.286534 -351.428239) (xy 174.316012 -351.382365)
			(xy 174.351719 -351.341153) (xy 174.392926 -351.305441) (xy 174.438797 -351.275957) (xy 174.488396 -351.2533)
			(xy 174.540715 -351.237932) (xy 174.594688 -351.230166) (xy 174.621952 -351.229676) (xy 175.485552 -351.229676)
			(xy 175.512828 -351.23006) (xy 175.566825 -351.237818) (xy 175.619169 -351.253181) (xy 175.668793 -351.275838)
			(xy 175.714687 -351.305328) (xy 175.755917 -351.341049) (xy 175.791644 -351.382274) (xy 175.821139 -351.428165)
			(xy 175.843802 -351.477786) (xy 175.859172 -351.530128) (xy 175.866936 -351.584124) (xy 175.866936 -351.638669)
			(xy 177.349639 -351.638669) (xy 177.349639 -351.584131) (xy 177.357401 -351.530149) (xy 177.372766 -351.47782)
			(xy 177.395423 -351.428211) (xy 177.424908 -351.382331) (xy 177.460624 -351.341115) (xy 177.501841 -351.305401)
			(xy 177.547722 -351.275917) (xy 177.597331 -351.253262) (xy 177.64966 -351.237899) (xy 177.703643 -351.230139)
			(xy 177.730912 -351.229676) (xy 178.594512 -351.229676) (xy 178.621784 -351.230087) (xy 178.675771 -351.237851)
			(xy 178.728104 -351.253219) (xy 178.777718 -351.275878) (xy 178.823602 -351.305367) (xy 178.864822 -351.341086)
			(xy 178.90054 -351.382308) (xy 178.930028 -351.428192) (xy 178.952685 -351.477807) (xy 178.968051 -351.530141)
			(xy 178.975814 -351.584128) (xy 178.975814 -351.638665) (xy 180.458662 -351.638665) (xy 180.458662 -351.584135)
			(xy 180.466422 -351.530159) (xy 180.481785 -351.477837) (xy 180.504437 -351.428233) (xy 180.533917 -351.382358)
			(xy 180.569626 -351.341146) (xy 180.610836 -351.305434) (xy 180.656709 -351.27595) (xy 180.70631 -351.253295)
			(xy 180.758631 -351.237928) (xy 180.812607 -351.230164) (xy 180.839872 -351.229676) (xy 181.703472 -351.229676)
			(xy 181.730747 -351.230062) (xy 181.784742 -351.237821) (xy 181.837084 -351.253187) (xy 181.886705 -351.275845)
			(xy 181.932597 -351.305335) (xy 181.973824 -351.341056) (xy 182.009548 -351.382281) (xy 182.039042 -351.42817)
			(xy 182.061703 -351.47779) (xy 182.077073 -351.53013) (xy 182.084836 -351.584125) (xy 182.084836 -351.63867)
			(xy 183.567539 -351.63867) (xy 183.567539 -351.58413) (xy 183.575302 -351.530146) (xy 183.590668 -351.477816)
			(xy 183.613326 -351.428206) (xy 183.642813 -351.382325) (xy 183.678531 -351.341108) (xy 183.719751 -351.305394)
			(xy 183.765634 -351.27591) (xy 183.815246 -351.253257) (xy 183.867577 -351.237895) (xy 183.921562 -351.230137)
			(xy 183.948832 -351.229676) (xy 184.812432 -351.229676) (xy 184.839703 -351.230089) (xy 184.893688 -351.237855)
			(xy 184.946019 -351.253224) (xy 184.99563 -351.275885) (xy 185.041512 -351.305374) (xy 185.082729 -351.341093)
			(xy 185.118445 -351.382314) (xy 185.147931 -351.428198) (xy 185.170587 -351.477811) (xy 185.185952 -351.530143)
			(xy 185.193714 -351.584129) (xy 185.193714 -351.638666) (xy 186.676562 -351.638666) (xy 186.676562 -351.584134)
			(xy 186.684323 -351.530156) (xy 186.699686 -351.477832) (xy 186.72234 -351.428228) (xy 186.751822 -351.382352)
			(xy 186.787533 -351.341138) (xy 186.828745 -351.305427) (xy 186.874621 -351.275944) (xy 186.924225 -351.253289)
			(xy 186.976548 -351.237925) (xy 187.030526 -351.230163) (xy 187.057792 -351.229676) (xy 187.921392 -351.229676)
			(xy 187.948666 -351.230063) (xy 188.002659 -351.237825) (xy 188.054998 -351.253192) (xy 188.104617 -351.275851)
			(xy 188.150506 -351.305342) (xy 188.191732 -351.341063) (xy 188.227453 -351.382287) (xy 188.256945 -351.428176)
			(xy 188.279605 -351.477794) (xy 188.294973 -351.530133) (xy 188.302736 -351.584126) (xy 188.302736 -351.638664)
			(xy 189.785562 -351.638664) (xy 189.785562 -351.584136) (xy 189.793322 -351.530162) (xy 189.808683 -351.477841)
			(xy 189.831334 -351.428239) (xy 189.860812 -351.382365) (xy 189.896519 -351.341153) (xy 189.937726 -351.305441)
			(xy 189.983597 -351.275957) (xy 190.033196 -351.2533) (xy 190.085515 -351.237932) (xy 190.139488 -351.230166)
			(xy 190.166752 -351.229676) (xy 191.030352 -351.229676) (xy 191.057628 -351.23006) (xy 191.111625 -351.237818)
			(xy 191.163969 -351.253181) (xy 191.213593 -351.275838) (xy 191.259487 -351.305328) (xy 191.300717 -351.341049)
			(xy 191.336444 -351.382274) (xy 191.365939 -351.428165) (xy 191.388602 -351.477786) (xy 191.403972 -351.530128)
			(xy 191.411736 -351.584124) (xy 191.411736 -351.638669) (xy 192.894439 -351.638669) (xy 192.894439 -351.584131)
			(xy 192.902201 -351.530149) (xy 192.917566 -351.47782) (xy 192.940223 -351.428211) (xy 192.969708 -351.382331)
			(xy 193.005424 -351.341115) (xy 193.046641 -351.305401) (xy 193.092522 -351.275917) (xy 193.142131 -351.253262)
			(xy 193.19446 -351.237899) (xy 193.248443 -351.230139) (xy 193.275712 -351.229676) (xy 194.139312 -351.229676)
			(xy 194.166584 -351.230087) (xy 194.220571 -351.237851) (xy 194.272904 -351.253219) (xy 194.322518 -351.275878)
			(xy 194.368402 -351.305367) (xy 194.409622 -351.341086) (xy 194.44534 -351.382308) (xy 194.474828 -351.428192)
			(xy 194.497485 -351.477807) (xy 194.512851 -351.530141) (xy 194.520614 -351.584128) (xy 194.520614 -351.638668)
			(xy 267.515839 -351.638668) (xy 267.515839 -351.584132) (xy 267.523601 -351.53015) (xy 267.538966 -351.477822)
			(xy 267.561621 -351.428214) (xy 267.591106 -351.382335) (xy 267.62682 -351.341119) (xy 267.668036 -351.305405)
			(xy 267.713916 -351.27592) (xy 267.763524 -351.253265) (xy 267.815852 -351.2379) (xy 267.869834 -351.230139)
			(xy 267.897102 -351.229676) (xy 268.760702 -351.229676) (xy 268.787974 -351.230087) (xy 268.841963 -351.237849)
			(xy 268.894297 -351.253216) (xy 268.943912 -351.275875) (xy 268.989797 -351.305364) (xy 269.031019 -351.341083)
			(xy 269.066737 -351.382304) (xy 269.096226 -351.42819) (xy 269.118884 -351.477805) (xy 269.134251 -351.530139)
			(xy 269.142013 -351.584128) (xy 269.142013 -351.638665) (xy 270.624862 -351.638665) (xy 270.624862 -351.584135)
			(xy 270.632622 -351.53016) (xy 270.647984 -351.477839) (xy 270.670635 -351.428236) (xy 270.700115 -351.382362)
			(xy 270.735822 -351.341149) (xy 270.777031 -351.305437) (xy 270.822903 -351.275953) (xy 270.872503 -351.253297)
			(xy 270.924823 -351.23793) (xy 270.978797 -351.230165) (xy 271.006062 -351.229676) (xy 271.869662 -351.229676)
			(xy 271.896937 -351.230061) (xy 271.950934 -351.23782) (xy 272.003276 -351.253184) (xy 272.052899 -351.275842)
			(xy 272.098792 -351.305331) (xy 272.140021 -351.341052) (xy 272.175746 -351.382277) (xy 272.20524 -351.428167)
			(xy 272.227903 -351.477788) (xy 272.243272 -351.530129) (xy 272.251036 -351.584125) (xy 272.251036 -351.638669)
			(xy 273.733739 -351.638669) (xy 273.733739 -351.584131) (xy 273.741501 -351.530147) (xy 273.756867 -351.477818)
			(xy 273.779524 -351.428208) (xy 273.809011 -351.382328) (xy 273.844727 -351.341112) (xy 273.885946 -351.305398)
			(xy 273.931828 -351.275914) (xy 273.981439 -351.25326) (xy 274.033769 -351.237897) (xy 274.087753 -351.230138)
			(xy 274.115022 -351.229676) (xy 274.978622 -351.229676) (xy 275.005893 -351.230088) (xy 275.05988 -351.237853)
			(xy 275.112212 -351.253222) (xy 275.161824 -351.275881) (xy 275.207707 -351.305371) (xy 275.248926 -351.34109)
			(xy 275.284642 -351.382311) (xy 275.314129 -351.428195) (xy 275.336786 -351.477809) (xy 275.352152 -351.530142)
			(xy 275.359914 -351.584129) (xy 275.359914 -351.638666) (xy 276.842762 -351.638666) (xy 276.842762 -351.584134)
			(xy 276.850523 -351.530158) (xy 276.865886 -351.477835) (xy 276.888538 -351.428231) (xy 276.91802 -351.382355)
			(xy 276.953729 -351.341142) (xy 276.994941 -351.30543) (xy 277.040815 -351.275947) (xy 277.090418 -351.253292)
			(xy 277.14274 -351.237927) (xy 277.196716 -351.230164) (xy 277.223982 -351.229676) (xy 278.087582 -351.229676)
			(xy 278.114857 -351.230062) (xy 278.168851 -351.237823) (xy 278.221191 -351.253189) (xy 278.270811 -351.275848)
			(xy 278.316702 -351.305338) (xy 278.357928 -351.341059) (xy 278.393651 -351.382284) (xy 278.423143 -351.428173)
			(xy 278.445804 -351.477792) (xy 278.461173 -351.530132) (xy 278.468936 -351.584125) (xy 278.468936 -351.63867)
			(xy 279.95164 -351.63867) (xy 279.95164 -351.58413) (xy 279.959402 -351.530145) (xy 279.974769 -351.477814)
			(xy 279.997427 -351.428203) (xy 280.026916 -351.382322) (xy 280.062634 -351.341105) (xy 280.103855 -351.305391)
			(xy 280.14974 -351.275907) (xy 280.199353 -351.253254) (xy 280.251686 -351.237893) (xy 280.305672 -351.230137)
			(xy 280.332942 -351.229676) (xy 281.196542 -351.229676) (xy 281.223812 -351.230089) (xy 281.277797 -351.237857)
			(xy 281.330126 -351.253227) (xy 281.379736 -351.275888) (xy 281.425616 -351.305378) (xy 281.466833 -351.341097)
			(xy 281.502547 -351.382317) (xy 281.532032 -351.428201) (xy 281.554688 -351.477813) (xy 281.570052 -351.530145)
			(xy 281.577814 -351.58413) (xy 281.577814 -351.638668) (xy 283.060639 -351.638668) (xy 283.060639 -351.584132)
			(xy 283.068401 -351.53015) (xy 283.083766 -351.477822) (xy 283.106421 -351.428214) (xy 283.135906 -351.382335)
			(xy 283.17162 -351.341119) (xy 283.212836 -351.305405) (xy 283.258716 -351.27592) (xy 283.308324 -351.253265)
			(xy 283.360652 -351.2379) (xy 283.414634 -351.230139) (xy 283.441902 -351.229676) (xy 284.305502 -351.229676)
			(xy 284.332774 -351.230087) (xy 284.386763 -351.237849) (xy 284.439097 -351.253216) (xy 284.488712 -351.275875)
			(xy 284.534597 -351.305364) (xy 284.575819 -351.341083) (xy 284.611537 -351.382304) (xy 284.641026 -351.42819)
			(xy 284.663684 -351.477805) (xy 284.679051 -351.530139) (xy 284.686813 -351.584128) (xy 284.686813 -351.638665)
			(xy 286.169662 -351.638665) (xy 286.169662 -351.584135) (xy 286.177422 -351.53016) (xy 286.192784 -351.477839)
			(xy 286.215435 -351.428236) (xy 286.244915 -351.382362) (xy 286.280622 -351.341149) (xy 286.321831 -351.305437)
			(xy 286.367703 -351.275953) (xy 286.417303 -351.253297) (xy 286.469623 -351.23793) (xy 286.523597 -351.230165)
			(xy 286.550862 -351.229676) (xy 287.414462 -351.229676) (xy 287.441737 -351.230061) (xy 287.495734 -351.23782)
			(xy 287.548076 -351.253184) (xy 287.597699 -351.275842) (xy 287.643592 -351.305331) (xy 287.684821 -351.341052)
			(xy 287.720546 -351.382277) (xy 287.75004 -351.428167) (xy 287.772703 -351.477788) (xy 287.788072 -351.530129)
			(xy 287.795836 -351.584125) (xy 287.795836 -351.638669) (xy 289.278539 -351.638669) (xy 289.278539 -351.584131)
			(xy 289.286301 -351.530147) (xy 289.301667 -351.477818) (xy 289.324324 -351.428208) (xy 289.353811 -351.382328)
			(xy 289.389527 -351.341112) (xy 289.430746 -351.305398) (xy 289.476628 -351.275914) (xy 289.526239 -351.25326)
			(xy 289.578569 -351.237897) (xy 289.632553 -351.230138) (xy 289.659822 -351.229676) (xy 290.523422 -351.229676)
			(xy 290.550693 -351.230088) (xy 290.60468 -351.237853) (xy 290.657012 -351.253222) (xy 290.706624 -351.275881)
			(xy 290.752507 -351.305371) (xy 290.793726 -351.34109) (xy 290.829442 -351.382311) (xy 290.858929 -351.428195)
			(xy 290.881586 -351.477809) (xy 290.896952 -351.530142) (xy 290.904714 -351.584129) (xy 290.904714 -351.638666)
			(xy 292.387562 -351.638666) (xy 292.387562 -351.584134) (xy 292.395323 -351.530158) (xy 292.410686 -351.477835)
			(xy 292.433338 -351.428231) (xy 292.46282 -351.382355) (xy 292.498529 -351.341142) (xy 292.539741 -351.30543)
			(xy 292.585615 -351.275947) (xy 292.635218 -351.253292) (xy 292.68754 -351.237927) (xy 292.741516 -351.230164)
			(xy 292.768782 -351.229676) (xy 293.632382 -351.229676) (xy 293.659657 -351.230062) (xy 293.713651 -351.237823)
			(xy 293.765991 -351.253189) (xy 293.815611 -351.275848) (xy 293.861502 -351.305338) (xy 293.902728 -351.341059)
			(xy 293.938451 -351.382284) (xy 293.967943 -351.428173) (xy 293.990604 -351.477792) (xy 294.005973 -351.530132)
			(xy 294.013736 -351.584125) (xy 294.013736 -351.63867) (xy 295.49644 -351.63867) (xy 295.49644 -351.58413)
			(xy 295.504202 -351.530145) (xy 295.519569 -351.477814) (xy 295.542227 -351.428203) (xy 295.571716 -351.382322)
			(xy 295.607434 -351.341105) (xy 295.648655 -351.305391) (xy 295.69454 -351.275907) (xy 295.744153 -351.253254)
			(xy 295.796486 -351.237893) (xy 295.850472 -351.230137) (xy 295.877742 -351.229676) (xy 296.741342 -351.229676)
			(xy 296.768612 -351.230089) (xy 296.822597 -351.237857) (xy 296.874926 -351.253227) (xy 296.924536 -351.275888)
			(xy 296.970416 -351.305378) (xy 297.011633 -351.341097) (xy 297.047347 -351.382317) (xy 297.076832 -351.428201)
			(xy 297.099488 -351.477813) (xy 297.114852 -351.530145) (xy 297.122614 -351.58413) (xy 297.122614 -351.638668)
			(xy 298.605439 -351.638668) (xy 298.605439 -351.584132) (xy 298.613201 -351.53015) (xy 298.628566 -351.477822)
			(xy 298.651221 -351.428214) (xy 298.680706 -351.382335) (xy 298.71642 -351.341119) (xy 298.757636 -351.305405)
			(xy 298.803516 -351.27592) (xy 298.853124 -351.253265) (xy 298.905452 -351.2379) (xy 298.959434 -351.230139)
			(xy 298.986702 -351.229676) (xy 299.850302 -351.229676) (xy 299.877574 -351.230087) (xy 299.931563 -351.237849)
			(xy 299.983897 -351.253216) (xy 300.033512 -351.275875) (xy 300.079397 -351.305364) (xy 300.120619 -351.341083)
			(xy 300.156337 -351.382304) (xy 300.185826 -351.42819) (xy 300.208484 -351.477805) (xy 300.223851 -351.530139)
			(xy 300.231613 -351.584128) (xy 300.231613 -351.638668) (xy 312.121539 -351.638668) (xy 312.121539 -351.584132)
			(xy 312.129301 -351.53015) (xy 312.144666 -351.477822) (xy 312.167321 -351.428213) (xy 312.196807 -351.382334)
			(xy 312.232521 -351.341118) (xy 312.273737 -351.305404) (xy 312.319617 -351.27592) (xy 312.369226 -351.253264)
			(xy 312.421554 -351.2379) (xy 312.475536 -351.230139) (xy 312.502804 -351.229676) (xy 313.366404 -351.229676)
			(xy 313.393676 -351.230087) (xy 313.447664 -351.23785) (xy 313.499999 -351.253217) (xy 313.549613 -351.275876)
			(xy 313.595498 -351.305365) (xy 313.63672 -351.341083) (xy 313.672438 -351.382305) (xy 313.701926 -351.42819)
			(xy 313.724584 -351.477805) (xy 313.739951 -351.530139) (xy 313.747713 -351.584128) (xy 313.747713 -351.638665)
			(xy 315.230562 -351.638665) (xy 315.230562 -351.584135) (xy 315.238322 -351.53016) (xy 315.253684 -351.477838)
			(xy 315.276335 -351.428236) (xy 315.305815 -351.382361) (xy 315.341523 -351.341148) (xy 315.382732 -351.305437)
			(xy 315.428604 -351.275953) (xy 315.478205 -351.253297) (xy 315.530525 -351.23793) (xy 315.584499 -351.230165)
			(xy 315.611764 -351.229676) (xy 316.475364 -351.229676) (xy 316.502639 -351.230061) (xy 316.556636 -351.23782)
			(xy 316.608978 -351.253185) (xy 316.6586 -351.275842) (xy 316.704493 -351.305332) (xy 316.745722 -351.341053)
			(xy 316.781446 -351.382278) (xy 316.81094 -351.428168) (xy 316.833603 -351.477788) (xy 316.848972 -351.530129)
			(xy 316.856736 -351.584125) (xy 316.856736 -351.638669) (xy 318.339439 -351.638669) (xy 318.339439 -351.584131)
			(xy 318.347201 -351.530147) (xy 318.362567 -351.477818) (xy 318.385224 -351.428208) (xy 318.414711 -351.382328)
			(xy 318.450428 -351.341111) (xy 318.491647 -351.305397) (xy 318.537529 -351.275913) (xy 318.58714 -351.253259)
			(xy 318.63947 -351.237896) (xy 318.693455 -351.230138) (xy 318.720724 -351.229676) (xy 319.584324 -351.229676)
			(xy 319.611595 -351.230088) (xy 319.665581 -351.237853) (xy 319.717913 -351.253222) (xy 319.767525 -351.275882)
			(xy 319.813408 -351.305372) (xy 319.854627 -351.34109) (xy 319.890343 -351.382312) (xy 319.919829 -351.428196)
			(xy 319.942486 -351.477809) (xy 319.957852 -351.530142) (xy 319.965614 -351.584129) (xy 319.965614 -351.638666)
			(xy 321.448462 -351.638666) (xy 321.448462 -351.584134) (xy 321.456223 -351.530157) (xy 321.471586 -351.477834)
			(xy 321.494239 -351.42823) (xy 321.52372 -351.382354) (xy 321.55943 -351.341141) (xy 321.600642 -351.30543)
			(xy 321.646516 -351.275946) (xy 321.696119 -351.253291) (xy 321.748442 -351.237926) (xy 321.802418 -351.230163)
			(xy 321.829684 -351.229676) (xy 322.693284 -351.229676) (xy 322.720558 -351.230062) (xy 322.774552 -351.237824)
			(xy 322.826892 -351.25319) (xy 322.876512 -351.275849) (xy 322.922403 -351.305339) (xy 322.963629 -351.34106)
			(xy 322.999351 -351.382285) (xy 323.028843 -351.428174) (xy 323.051504 -351.477793) (xy 323.066873 -351.530132)
			(xy 323.074636 -351.584126) (xy 323.074636 -351.63867) (xy 324.55734 -351.63867) (xy 324.55734 -351.58413)
			(xy 324.565102 -351.530144) (xy 324.580469 -351.477813) (xy 324.603128 -351.428202) (xy 324.632616 -351.382321)
			(xy 324.668335 -351.341104) (xy 324.709556 -351.30539) (xy 324.755441 -351.275906) (xy 324.805055 -351.253254)
			(xy 324.857387 -351.237893) (xy 324.911374 -351.230136) (xy 324.938644 -351.229676) (xy 325.802244 -351.229676)
			(xy 325.829514 -351.23009) (xy 325.883498 -351.237857) (xy 325.935828 -351.253228) (xy 325.985437 -351.275889)
			(xy 326.031317 -351.305379) (xy 326.072534 -351.341097) (xy 326.108248 -351.382318) (xy 326.137732 -351.428201)
			(xy 326.160388 -351.477814) (xy 326.175752 -351.530145) (xy 326.183514 -351.58413) (xy 326.183514 -351.638668)
			(xy 327.666339 -351.638668) (xy 327.666339 -351.584132) (xy 327.674101 -351.53015) (xy 327.689466 -351.477822)
			(xy 327.712121 -351.428213) (xy 327.741607 -351.382334) (xy 327.777321 -351.341118) (xy 327.818537 -351.305404)
			(xy 327.864417 -351.27592) (xy 327.914026 -351.253264) (xy 327.966354 -351.2379) (xy 328.020336 -351.230139)
			(xy 328.047604 -351.229676) (xy 328.911204 -351.229676) (xy 328.938476 -351.230087) (xy 328.992464 -351.23785)
			(xy 329.044799 -351.253217) (xy 329.094413 -351.275876) (xy 329.140298 -351.305365) (xy 329.18152 -351.341083)
			(xy 329.217238 -351.382305) (xy 329.246726 -351.42819) (xy 329.269384 -351.477805) (xy 329.284751 -351.530139)
			(xy 329.292513 -351.584128) (xy 329.292513 -351.638665) (xy 330.775362 -351.638665) (xy 330.775362 -351.584135)
			(xy 330.783122 -351.53016) (xy 330.798484 -351.477838) (xy 330.821135 -351.428236) (xy 330.850615 -351.382361)
			(xy 330.886323 -351.341148) (xy 330.927532 -351.305437) (xy 330.973404 -351.275953) (xy 331.023005 -351.253297)
			(xy 331.075325 -351.23793) (xy 331.129299 -351.230165) (xy 331.156564 -351.229676) (xy 332.020164 -351.229676)
			(xy 332.047439 -351.230061) (xy 332.101436 -351.23782) (xy 332.153778 -351.253185) (xy 332.2034 -351.275842)
			(xy 332.249293 -351.305332) (xy 332.290522 -351.341053) (xy 332.326246 -351.382278) (xy 332.35574 -351.428168)
			(xy 332.378403 -351.477788) (xy 332.393772 -351.530129) (xy 332.401536 -351.584125) (xy 332.401536 -351.638669)
			(xy 333.884239 -351.638669) (xy 333.884239 -351.584131) (xy 333.892001 -351.530147) (xy 333.907367 -351.477818)
			(xy 333.930024 -351.428208) (xy 333.959511 -351.382328) (xy 333.995228 -351.341111) (xy 334.036447 -351.305397)
			(xy 334.082329 -351.275913) (xy 334.13194 -351.253259) (xy 334.18427 -351.237896) (xy 334.238255 -351.230138)
			(xy 334.265524 -351.229676) (xy 335.129124 -351.229676) (xy 335.156395 -351.230088) (xy 335.210381 -351.237853)
			(xy 335.262713 -351.253222) (xy 335.312325 -351.275882) (xy 335.358208 -351.305372) (xy 335.399427 -351.34109)
			(xy 335.435143 -351.382312) (xy 335.464629 -351.428196) (xy 335.487286 -351.477809) (xy 335.502652 -351.530142)
			(xy 335.510414 -351.584129) (xy 335.510414 -351.638666) (xy 336.993262 -351.638666) (xy 336.993262 -351.584134)
			(xy 337.001023 -351.530157) (xy 337.016386 -351.477834) (xy 337.039039 -351.42823) (xy 337.06852 -351.382354)
			(xy 337.10423 -351.341141) (xy 337.145442 -351.30543) (xy 337.191316 -351.275946) (xy 337.240919 -351.253291)
			(xy 337.293242 -351.237926) (xy 337.347218 -351.230163) (xy 337.374484 -351.229676) (xy 338.238084 -351.229676)
			(xy 338.265358 -351.230062) (xy 338.319352 -351.237824) (xy 338.371692 -351.25319) (xy 338.421312 -351.275849)
			(xy 338.467203 -351.305339) (xy 338.508429 -351.34106) (xy 338.544151 -351.382285) (xy 338.573643 -351.428174)
			(xy 338.596304 -351.477793) (xy 338.611673 -351.530132) (xy 338.619436 -351.584126) (xy 338.619436 -351.63867)
			(xy 340.10214 -351.63867) (xy 340.10214 -351.58413) (xy 340.109902 -351.530144) (xy 340.125269 -351.477813)
			(xy 340.147928 -351.428202) (xy 340.177416 -351.382321) (xy 340.213135 -351.341104) (xy 340.254356 -351.30539)
			(xy 340.300241 -351.275906) (xy 340.349855 -351.253254) (xy 340.402187 -351.237893) (xy 340.456174 -351.230136)
			(xy 340.483444 -351.229676) (xy 341.347044 -351.229676) (xy 341.374314 -351.23009) (xy 341.428298 -351.237857)
			(xy 341.480628 -351.253228) (xy 341.530237 -351.275889) (xy 341.576117 -351.305379) (xy 341.617334 -351.341097)
			(xy 341.653048 -351.382318) (xy 341.682532 -351.428201) (xy 341.705188 -351.477814) (xy 341.720552 -351.530145)
			(xy 341.728314 -351.58413) (xy 341.728314 -351.638668) (xy 343.211139 -351.638668) (xy 343.211139 -351.584132)
			(xy 343.218901 -351.53015) (xy 343.234266 -351.477822) (xy 343.256921 -351.428213) (xy 343.286407 -351.382334)
			(xy 343.322121 -351.341118) (xy 343.363337 -351.305404) (xy 343.409217 -351.27592) (xy 343.458826 -351.253264)
			(xy 343.511154 -351.2379) (xy 343.565136 -351.230139) (xy 343.592404 -351.229676) (xy 344.456004 -351.229676)
			(xy 344.483276 -351.230087) (xy 344.537264 -351.23785) (xy 344.589599 -351.253217) (xy 344.639213 -351.275876)
			(xy 344.685098 -351.305365) (xy 344.72632 -351.341083) (xy 344.762038 -351.382305) (xy 344.791526 -351.42819)
			(xy 344.814184 -351.477805) (xy 344.829551 -351.530139) (xy 344.837313 -351.584128) (xy 344.837313 -351.638666)
			(xy 370.806762 -351.638666) (xy 370.806762 -351.584134) (xy 370.814523 -351.530158) (xy 370.829885 -351.477835)
			(xy 370.852538 -351.428231) (xy 370.882019 -351.382356) (xy 370.917729 -351.341143) (xy 370.95894 -351.305431)
			(xy 371.004814 -351.275948) (xy 371.054416 -351.253292) (xy 371.106738 -351.237927) (xy 371.160714 -351.230164)
			(xy 371.18798 -351.229676) (xy 372.05158 -351.229676) (xy 372.078855 -351.230062) (xy 372.132849 -351.237823)
			(xy 372.185189 -351.253189) (xy 372.23481 -351.275848) (xy 372.280701 -351.305338) (xy 372.321927 -351.341059)
			(xy 372.35765 -351.382283) (xy 372.387143 -351.428172) (xy 372.409804 -351.477792) (xy 372.425173 -351.530131)
			(xy 372.432936 -351.584125) (xy 372.432936 -351.63867) (xy 373.91564 -351.63867) (xy 373.91564 -351.58413)
			(xy 373.923402 -351.530145) (xy 373.938769 -351.477814) (xy 373.961427 -351.428203) (xy 373.990915 -351.382322)
			(xy 374.026634 -351.341105) (xy 374.067854 -351.305391) (xy 374.113738 -351.275908) (xy 374.163352 -351.253255)
			(xy 374.215684 -351.237893) (xy 374.26967 -351.230137) (xy 374.29694 -351.229676) (xy 375.16054 -351.229676)
			(xy 375.18781 -351.230089) (xy 375.241795 -351.237856) (xy 375.294125 -351.253227) (xy 375.343735 -351.275887)
			(xy 375.389615 -351.305377) (xy 375.430832 -351.341096) (xy 375.466547 -351.382317) (xy 375.496032 -351.4282)
			(xy 375.518687 -351.477813) (xy 375.534052 -351.530144) (xy 375.541814 -351.58413) (xy 375.541814 -351.638667)
			(xy 377.024662 -351.638667) (xy 377.024662 -351.584133) (xy 377.032423 -351.530155) (xy 377.047787 -351.477831)
			(xy 377.070441 -351.428226) (xy 377.099924 -351.382349) (xy 377.135636 -351.341136) (xy 377.176849 -351.305424)
			(xy 377.222726 -351.275941) (xy 377.272331 -351.253287) (xy 377.324655 -351.237923) (xy 377.378633 -351.230162)
			(xy 377.4059 -351.229676) (xy 378.2695 -351.229676) (xy 378.296772 -351.230087) (xy 378.350761 -351.237849)
			(xy 378.403096 -351.253216) (xy 378.452711 -351.275874) (xy 378.498596 -351.305363) (xy 378.539818 -351.341082)
			(xy 378.575537 -351.382304) (xy 378.605026 -351.428189) (xy 378.627684 -351.477804) (xy 378.643051 -351.530139)
			(xy 378.650813 -351.584128) (xy 378.650813 -351.638665) (xy 380.133662 -351.638665) (xy 380.133662 -351.584135)
			(xy 380.141422 -351.53016) (xy 380.156784 -351.477839) (xy 380.179435 -351.428237) (xy 380.208914 -351.382362)
			(xy 380.244621 -351.34115) (xy 380.28583 -351.305438) (xy 380.331702 -351.275954) (xy 380.381302 -351.253298)
			(xy 380.433621 -351.237931) (xy 380.487595 -351.230165) (xy 380.51486 -351.229676) (xy 381.37846 -351.229676)
			(xy 381.405736 -351.230061) (xy 381.459732 -351.237819) (xy 381.512075 -351.253183) (xy 381.561698 -351.275841)
			(xy 381.607591 -351.30533) (xy 381.64882 -351.341051) (xy 381.684546 -351.382277) (xy 381.71404 -351.428167)
			(xy 381.736703 -351.477788) (xy 381.752072 -351.530129) (xy 381.759836 -351.584124) (xy 381.759836 -351.638669)
			(xy 383.242539 -351.638669) (xy 383.242539 -351.584131) (xy 383.250301 -351.530148) (xy 383.265667 -351.477818)
			(xy 383.288324 -351.428209) (xy 383.31781 -351.382329) (xy 383.353526 -351.341112) (xy 383.394745 -351.305398)
			(xy 383.440626 -351.275914) (xy 383.490237 -351.25326) (xy 383.542567 -351.237897) (xy 383.596551 -351.230138)
			(xy 383.62382 -351.229676) (xy 384.48742 -351.229676) (xy 384.514691 -351.230088) (xy 384.568678 -351.237853)
			(xy 384.62101 -351.253221) (xy 384.670623 -351.275881) (xy 384.716506 -351.30537) (xy 384.757725 -351.341089)
			(xy 384.793442 -351.38231) (xy 384.822929 -351.428195) (xy 384.845586 -351.477808) (xy 384.860952 -351.530142)
			(xy 384.868714 -351.584129) (xy 384.868714 -351.638666) (xy 386.351562 -351.638666) (xy 386.351562 -351.584134)
			(xy 386.359323 -351.530158) (xy 386.374685 -351.477835) (xy 386.397338 -351.428231) (xy 386.426819 -351.382356)
			(xy 386.462529 -351.341143) (xy 386.50374 -351.305431) (xy 386.549614 -351.275948) (xy 386.599216 -351.253292)
			(xy 386.651538 -351.237927) (xy 386.705514 -351.230164) (xy 386.73278 -351.229676) (xy 387.59638 -351.229676)
			(xy 387.623655 -351.230062) (xy 387.677649 -351.237823) (xy 387.729989 -351.253189) (xy 387.77961 -351.275848)
			(xy 387.825501 -351.305338) (xy 387.866727 -351.341059) (xy 387.90245 -351.382283) (xy 387.931943 -351.428172)
			(xy 387.954604 -351.477792) (xy 387.969973 -351.530131) (xy 387.977736 -351.584125) (xy 387.977736 -351.63867)
			(xy 389.46044 -351.63867) (xy 389.46044 -351.58413) (xy 389.468202 -351.530145) (xy 389.483569 -351.477814)
			(xy 389.506227 -351.428203) (xy 389.535715 -351.382322) (xy 389.571434 -351.341105) (xy 389.612654 -351.305391)
			(xy 389.658538 -351.275908) (xy 389.708152 -351.253255) (xy 389.760484 -351.237893) (xy 389.81447 -351.230137)
			(xy 389.84174 -351.229676) (xy 390.70534 -351.229676) (xy 390.73261 -351.230089) (xy 390.786595 -351.237856)
			(xy 390.838925 -351.253227) (xy 390.888535 -351.275887) (xy 390.934415 -351.305377) (xy 390.975632 -351.341096)
			(xy 391.011347 -351.382317) (xy 391.040832 -351.4282) (xy 391.063487 -351.477813) (xy 391.078852 -351.530144)
			(xy 391.086614 -351.58413) (xy 391.086614 -351.638667) (xy 392.569462 -351.638667) (xy 392.569462 -351.584133)
			(xy 392.577223 -351.530155) (xy 392.592587 -351.477831) (xy 392.615241 -351.428226) (xy 392.644724 -351.382349)
			(xy 392.680436 -351.341136) (xy 392.721649 -351.305424) (xy 392.767526 -351.275941) (xy 392.817131 -351.253287)
			(xy 392.869455 -351.237923) (xy 392.923433 -351.230162) (xy 392.9507 -351.229676) (xy 393.8143 -351.229676)
			(xy 393.841572 -351.230087) (xy 393.895561 -351.237849) (xy 393.947896 -351.253216) (xy 393.997511 -351.275874)
			(xy 394.043396 -351.305363) (xy 394.084618 -351.341082) (xy 394.120337 -351.382304) (xy 394.149826 -351.428189)
			(xy 394.172484 -351.477804) (xy 394.187851 -351.530139) (xy 394.195613 -351.584128) (xy 394.195613 -351.638665)
			(xy 395.678462 -351.638665) (xy 395.678462 -351.584135) (xy 395.686222 -351.53016) (xy 395.701584 -351.477839)
			(xy 395.724235 -351.428237) (xy 395.753714 -351.382362) (xy 395.789421 -351.34115) (xy 395.83063 -351.305438)
			(xy 395.876502 -351.275954) (xy 395.926102 -351.253298) (xy 395.978421 -351.237931) (xy 396.032395 -351.230165)
			(xy 396.05966 -351.229676) (xy 396.92326 -351.229676) (xy 396.950536 -351.230061) (xy 397.004532 -351.237819)
			(xy 397.056875 -351.253183) (xy 397.106498 -351.275841) (xy 397.152391 -351.30533) (xy 397.19362 -351.341051)
			(xy 397.229346 -351.382277) (xy 397.25884 -351.428167) (xy 397.281503 -351.477788) (xy 397.296872 -351.530129)
			(xy 397.304636 -351.584124) (xy 397.304636 -351.638669) (xy 398.787339 -351.638669) (xy 398.787339 -351.584131)
			(xy 398.795101 -351.530148) (xy 398.810467 -351.477818) (xy 398.833124 -351.428209) (xy 398.86261 -351.382329)
			(xy 398.898326 -351.341112) (xy 398.939545 -351.305398) (xy 398.985426 -351.275914) (xy 399.035037 -351.25326)
			(xy 399.087367 -351.237897) (xy 399.141351 -351.230138) (xy 399.16862 -351.229676) (xy 400.03222 -351.229676)
			(xy 400.059491 -351.230088) (xy 400.113478 -351.237853) (xy 400.16581 -351.253221) (xy 400.215423 -351.275881)
			(xy 400.261306 -351.30537) (xy 400.302525 -351.341089) (xy 400.338242 -351.38231) (xy 400.367729 -351.428195)
			(xy 400.390386 -351.477808) (xy 400.405752 -351.530142) (xy 400.413514 -351.584129) (xy 400.413514 -351.638666)
			(xy 401.896362 -351.638666) (xy 401.896362 -351.584134) (xy 401.904123 -351.530158) (xy 401.919485 -351.477835)
			(xy 401.942138 -351.428231) (xy 401.971619 -351.382356) (xy 402.007329 -351.341143) (xy 402.04854 -351.305431)
			(xy 402.094414 -351.275948) (xy 402.144016 -351.253292) (xy 402.196338 -351.237927) (xy 402.250314 -351.230164)
			(xy 402.27758 -351.229676) (xy 403.14118 -351.229676) (xy 403.168455 -351.230062) (xy 403.222449 -351.237823)
			(xy 403.274789 -351.253189) (xy 403.32441 -351.275848) (xy 403.370301 -351.305338) (xy 403.411527 -351.341059)
			(xy 403.44725 -351.382283) (xy 403.476743 -351.428172) (xy 403.499404 -351.477792) (xy 403.514773 -351.530131)
			(xy 403.522536 -351.584125) (xy 403.522536 -351.638666) (xy 408.913862 -351.638666) (xy 408.913862 -351.584134)
			(xy 408.921623 -351.530156) (xy 408.936986 -351.477832) (xy 408.95964 -351.428228) (xy 408.989122 -351.382352)
			(xy 409.024833 -351.341138) (xy 409.066045 -351.305427) (xy 409.111921 -351.275944) (xy 409.161525 -351.253289)
			(xy 409.213848 -351.237925) (xy 409.267826 -351.230163) (xy 409.295092 -351.229676) (xy 410.158692 -351.229676)
			(xy 410.185966 -351.230063) (xy 410.239959 -351.237825) (xy 410.292298 -351.253192) (xy 410.341917 -351.275851)
			(xy 410.387806 -351.305342) (xy 410.429032 -351.341063) (xy 410.464753 -351.382287) (xy 410.494245 -351.428176)
			(xy 410.516905 -351.477794) (xy 410.532273 -351.530133) (xy 410.540036 -351.584126) (xy 410.540036 -351.638664)
			(xy 412.022862 -351.638664) (xy 412.022862 -351.584136) (xy 412.030622 -351.530162) (xy 412.045983 -351.477841)
			(xy 412.068634 -351.428239) (xy 412.098112 -351.382365) (xy 412.133819 -351.341153) (xy 412.175026 -351.305441)
			(xy 412.220897 -351.275957) (xy 412.270496 -351.2533) (xy 412.322815 -351.237932) (xy 412.376788 -351.230166)
			(xy 412.404052 -351.229676) (xy 413.267652 -351.229676) (xy 413.294928 -351.23006) (xy 413.348925 -351.237818)
			(xy 413.401269 -351.253181) (xy 413.450893 -351.275838) (xy 413.496787 -351.305328) (xy 413.538017 -351.341049)
			(xy 413.573744 -351.382274) (xy 413.603239 -351.428165) (xy 413.625902 -351.477786) (xy 413.641272 -351.530128)
			(xy 413.649036 -351.584124) (xy 413.649036 -351.638669) (xy 415.131739 -351.638669) (xy 415.131739 -351.584131)
			(xy 415.139501 -351.530149) (xy 415.154866 -351.47782) (xy 415.177523 -351.428211) (xy 415.207008 -351.382331)
			(xy 415.242724 -351.341115) (xy 415.283941 -351.305401) (xy 415.329822 -351.275917) (xy 415.379431 -351.253262)
			(xy 415.43176 -351.237899) (xy 415.485743 -351.230139) (xy 415.513012 -351.229676) (xy 416.376612 -351.229676)
			(xy 416.403884 -351.230087) (xy 416.457871 -351.237851) (xy 416.510204 -351.253219) (xy 416.559818 -351.275878)
			(xy 416.605702 -351.305367) (xy 416.646922 -351.341086) (xy 416.68264 -351.382308) (xy 416.712128 -351.428192)
			(xy 416.734785 -351.477807) (xy 416.750151 -351.530141) (xy 416.757914 -351.584128) (xy 416.757914 -351.638665)
			(xy 418.240762 -351.638665) (xy 418.240762 -351.584135) (xy 418.248522 -351.530159) (xy 418.263885 -351.477837)
			(xy 418.286537 -351.428233) (xy 418.316017 -351.382358) (xy 418.351726 -351.341146) (xy 418.392936 -351.305434)
			(xy 418.438809 -351.27595) (xy 418.48841 -351.253295) (xy 418.540731 -351.237928) (xy 418.594707 -351.230164)
			(xy 418.621972 -351.229676) (xy 419.485572 -351.229676) (xy 419.512847 -351.230062) (xy 419.566842 -351.237821)
			(xy 419.619184 -351.253187) (xy 419.668805 -351.275845) (xy 419.714697 -351.305335) (xy 419.755924 -351.341056)
			(xy 419.791648 -351.382281) (xy 419.821142 -351.42817) (xy 419.843803 -351.47779) (xy 419.859173 -351.53013)
			(xy 419.866936 -351.584125) (xy 419.866936 -351.63867) (xy 421.349639 -351.63867) (xy 421.349639 -351.58413)
			(xy 421.357402 -351.530146) (xy 421.372768 -351.477816) (xy 421.395426 -351.428206) (xy 421.424913 -351.382325)
			(xy 421.460631 -351.341108) (xy 421.501851 -351.305394) (xy 421.547734 -351.27591) (xy 421.597346 -351.253257)
			(xy 421.649677 -351.237895) (xy 421.703662 -351.230137) (xy 421.730932 -351.229676) (xy 422.594532 -351.229676)
			(xy 422.621803 -351.230089) (xy 422.675788 -351.237855) (xy 422.728119 -351.253224) (xy 422.77773 -351.275885)
			(xy 422.823612 -351.305374) (xy 422.864829 -351.341093) (xy 422.900545 -351.382314) (xy 422.930031 -351.428198)
			(xy 422.952687 -351.477811) (xy 422.968052 -351.530143) (xy 422.975814 -351.584129) (xy 422.975814 -351.638666)
			(xy 424.458662 -351.638666) (xy 424.458662 -351.584134) (xy 424.466423 -351.530156) (xy 424.481786 -351.477832)
			(xy 424.50444 -351.428228) (xy 424.533922 -351.382352) (xy 424.569633 -351.341138) (xy 424.610845 -351.305427)
			(xy 424.656721 -351.275944) (xy 424.706325 -351.253289) (xy 424.758648 -351.237925) (xy 424.812626 -351.230163)
			(xy 424.839892 -351.229676) (xy 425.703492 -351.229676) (xy 425.730766 -351.230063) (xy 425.784759 -351.237825)
			(xy 425.837098 -351.253192) (xy 425.886717 -351.275851) (xy 425.932606 -351.305342) (xy 425.973832 -351.341063)
			(xy 426.009553 -351.382287) (xy 426.039045 -351.428176) (xy 426.061705 -351.477794) (xy 426.077073 -351.530133)
			(xy 426.084836 -351.584126) (xy 426.084836 -351.638664) (xy 427.567662 -351.638664) (xy 427.567662 -351.584136)
			(xy 427.575422 -351.530162) (xy 427.590783 -351.477841) (xy 427.613434 -351.428239) (xy 427.642912 -351.382365)
			(xy 427.678619 -351.341153) (xy 427.719826 -351.305441) (xy 427.765697 -351.275957) (xy 427.815296 -351.2533)
			(xy 427.867615 -351.237932) (xy 427.921588 -351.230166) (xy 427.948852 -351.229676) (xy 428.812452 -351.229676)
			(xy 428.839728 -351.23006) (xy 428.893725 -351.237818) (xy 428.946069 -351.253181) (xy 428.995693 -351.275838)
			(xy 429.041587 -351.305328) (xy 429.082817 -351.341049) (xy 429.118544 -351.382274) (xy 429.148039 -351.428165)
			(xy 429.170702 -351.477786) (xy 429.186072 -351.530128) (xy 429.193836 -351.584124) (xy 429.193836 -351.638669)
			(xy 430.676539 -351.638669) (xy 430.676539 -351.584131) (xy 430.684301 -351.530149) (xy 430.699666 -351.47782)
			(xy 430.722323 -351.428211) (xy 430.751808 -351.382331) (xy 430.787524 -351.341115) (xy 430.828741 -351.305401)
			(xy 430.874622 -351.275917) (xy 430.924231 -351.253262) (xy 430.97656 -351.237899) (xy 431.030543 -351.230139)
			(xy 431.057812 -351.229676) (xy 431.921412 -351.229676) (xy 431.948684 -351.230087) (xy 432.002671 -351.237851)
			(xy 432.055004 -351.253219) (xy 432.104618 -351.275878) (xy 432.150502 -351.305367) (xy 432.191722 -351.341086)
			(xy 432.22744 -351.382308) (xy 432.256928 -351.428192) (xy 432.279585 -351.477807) (xy 432.294951 -351.530141)
			(xy 432.302714 -351.584128) (xy 432.302714 -351.638665) (xy 433.785562 -351.638665) (xy 433.785562 -351.584135)
			(xy 433.793322 -351.530159) (xy 433.808685 -351.477837) (xy 433.831337 -351.428233) (xy 433.860817 -351.382358)
			(xy 433.896526 -351.341146) (xy 433.937736 -351.305434) (xy 433.983609 -351.27595) (xy 434.03321 -351.253295)
			(xy 434.085531 -351.237928) (xy 434.139507 -351.230164) (xy 434.166772 -351.229676) (xy 435.030372 -351.229676)
			(xy 435.057647 -351.230062) (xy 435.111642 -351.237821) (xy 435.163984 -351.253187) (xy 435.213605 -351.275845)
			(xy 435.259497 -351.305335) (xy 435.300724 -351.341056) (xy 435.336448 -351.382281) (xy 435.365942 -351.42817)
			(xy 435.388603 -351.47779) (xy 435.403973 -351.53013) (xy 435.411736 -351.584125) (xy 435.411736 -351.63867)
			(xy 436.894439 -351.63867) (xy 436.894439 -351.58413) (xy 436.902202 -351.530146) (xy 436.917568 -351.477816)
			(xy 436.940226 -351.428206) (xy 436.969713 -351.382325) (xy 437.005431 -351.341108) (xy 437.046651 -351.305394)
			(xy 437.092534 -351.27591) (xy 437.142146 -351.253257) (xy 437.194477 -351.237895) (xy 437.248462 -351.230137)
			(xy 437.275732 -351.229676) (xy 438.139332 -351.229676) (xy 438.166603 -351.230089) (xy 438.220588 -351.237855)
			(xy 438.272919 -351.253224) (xy 438.32253 -351.275885) (xy 438.368412 -351.305374) (xy 438.409629 -351.341093)
			(xy 438.445345 -351.382314) (xy 438.474831 -351.428198) (xy 438.497487 -351.477811) (xy 438.512852 -351.530143)
			(xy 438.520614 -351.584129) (xy 438.520614 -351.638666) (xy 440.003462 -351.638666) (xy 440.003462 -351.584134)
			(xy 440.011223 -351.530156) (xy 440.026586 -351.477832) (xy 440.04924 -351.428228) (xy 440.078722 -351.382352)
			(xy 440.114433 -351.341138) (xy 440.155645 -351.305427) (xy 440.201521 -351.275944) (xy 440.251125 -351.253289)
			(xy 440.303448 -351.237925) (xy 440.357426 -351.230163) (xy 440.384692 -351.229676) (xy 441.248292 -351.229676)
			(xy 441.275566 -351.230063) (xy 441.329559 -351.237825) (xy 441.381898 -351.253192) (xy 441.431517 -351.275851)
			(xy 441.477406 -351.305342) (xy 441.518632 -351.341063) (xy 441.554353 -351.382287) (xy 441.583845 -351.428176)
			(xy 441.606505 -351.477794) (xy 441.621873 -351.530133) (xy 441.629636 -351.584126) (xy 441.629636 -351.638674)
			(xy 441.621873 -351.692667) (xy 441.606505 -351.745006) (xy 441.583845 -351.794624) (xy 441.554353 -351.840513)
			(xy 441.518632 -351.881737) (xy 441.477406 -351.917458) (xy 441.431517 -351.946949) (xy 441.381898 -351.969608)
			(xy 441.329559 -351.984975) (xy 441.275566 -351.992737) (xy 441.248292 -351.9932) (xy 440.384692 -351.9932)
			(xy 440.357426 -351.992637) (xy 440.303448 -351.984875) (xy 440.251125 -351.969511) (xy 440.201521 -351.946856)
			(xy 440.155645 -351.917373) (xy 440.114433 -351.881662) (xy 440.078722 -351.840448) (xy 440.04924 -351.794572)
			(xy 440.026586 -351.744968) (xy 440.011223 -351.692644) (xy 440.003462 -351.638666) (xy 438.520614 -351.638666)
			(xy 438.520614 -351.638671) (xy 438.512852 -351.692657) (xy 438.497487 -351.744989) (xy 438.474831 -351.794602)
			(xy 438.445345 -351.840486) (xy 438.409629 -351.881707) (xy 438.368412 -351.917426) (xy 438.32253 -351.946915)
			(xy 438.272919 -351.969576) (xy 438.220588 -351.984945) (xy 438.166603 -351.992711) (xy 438.139332 -351.9932)
			(xy 437.275732 -351.9932) (xy 437.248462 -351.992663) (xy 437.194477 -351.984905) (xy 437.142146 -351.969543)
			(xy 437.092534 -351.94689) (xy 437.046651 -351.917406) (xy 437.005431 -351.881692) (xy 436.969713 -351.840475)
			(xy 436.940226 -351.794594) (xy 436.917568 -351.744984) (xy 436.902202 -351.692654) (xy 436.894439 -351.63867)
			(xy 435.411736 -351.63867) (xy 435.411736 -351.638675) (xy 435.403973 -351.69267) (xy 435.388603 -351.74501)
			(xy 435.365942 -351.79463) (xy 435.336448 -351.840519) (xy 435.300724 -351.881744) (xy 435.259497 -351.917465)
			(xy 435.213605 -351.946955) (xy 435.163984 -351.969613) (xy 435.111642 -351.984979) (xy 435.057647 -351.992738)
			(xy 435.030372 -351.9932) (xy 434.166772 -351.9932) (xy 434.139507 -351.992636) (xy 434.085531 -351.984872)
			(xy 434.03321 -351.969505) (xy 433.983609 -351.94685) (xy 433.937736 -351.917366) (xy 433.896526 -351.881654)
			(xy 433.860817 -351.840442) (xy 433.831337 -351.794567) (xy 433.808685 -351.744963) (xy 433.793322 -351.692641)
			(xy 433.785562 -351.638665) (xy 432.302714 -351.638665) (xy 432.302714 -351.638672) (xy 432.294951 -351.692659)
			(xy 432.279585 -351.744993) (xy 432.256928 -351.794608) (xy 432.22744 -351.840492) (xy 432.191722 -351.881714)
			(xy 432.150502 -351.917433) (xy 432.104618 -351.946922) (xy 432.055004 -351.969581) (xy 432.002671 -351.984949)
			(xy 431.948684 -351.992713) (xy 431.921412 -351.9932) (xy 431.057812 -351.9932) (xy 431.030543 -351.992661)
			(xy 430.97656 -351.984901) (xy 430.924231 -351.969538) (xy 430.874622 -351.946883) (xy 430.828741 -351.917399)
			(xy 430.787524 -351.881685) (xy 430.751808 -351.840469) (xy 430.722323 -351.794589) (xy 430.699666 -351.74498)
			(xy 430.684301 -351.692651) (xy 430.676539 -351.638669) (xy 429.193836 -351.638669) (xy 429.193836 -351.638676)
			(xy 429.186072 -351.692672) (xy 429.170702 -351.745014) (xy 429.148039 -351.794635) (xy 429.118544 -351.840526)
			(xy 429.082817 -351.881751) (xy 429.041587 -351.917472) (xy 428.995693 -351.946962) (xy 428.946069 -351.969619)
			(xy 428.893725 -351.984982) (xy 428.839728 -351.99274) (xy 428.812452 -351.9932) (xy 427.948852 -351.9932)
			(xy 427.921588 -351.992634) (xy 427.867615 -351.984868) (xy 427.815296 -351.9695) (xy 427.765697 -351.946843)
			(xy 427.719826 -351.917359) (xy 427.678619 -351.881647) (xy 427.642912 -351.840435) (xy 427.613434 -351.794561)
			(xy 427.590783 -351.744959) (xy 427.575422 -351.692639) (xy 427.567662 -351.638664) (xy 426.084836 -351.638664)
			(xy 426.084836 -351.638674) (xy 426.077073 -351.692667) (xy 426.061705 -351.745006) (xy 426.039045 -351.794624)
			(xy 426.009553 -351.840513) (xy 425.973832 -351.881737) (xy 425.932606 -351.917458) (xy 425.886717 -351.946949)
			(xy 425.837098 -351.969608) (xy 425.784759 -351.984975) (xy 425.730766 -351.992737) (xy 425.703492 -351.9932)
			(xy 424.839892 -351.9932) (xy 424.812626 -351.992637) (xy 424.758648 -351.984875) (xy 424.706325 -351.969511)
			(xy 424.656721 -351.946856) (xy 424.610845 -351.917373) (xy 424.569633 -351.881662) (xy 424.533922 -351.840448)
			(xy 424.50444 -351.794572) (xy 424.481786 -351.744968) (xy 424.466423 -351.692644) (xy 424.458662 -351.638666)
			(xy 422.975814 -351.638666) (xy 422.975814 -351.638671) (xy 422.968052 -351.692657) (xy 422.952687 -351.744989)
			(xy 422.930031 -351.794602) (xy 422.900545 -351.840486) (xy 422.864829 -351.881707) (xy 422.823612 -351.917426)
			(xy 422.77773 -351.946915) (xy 422.728119 -351.969576) (xy 422.675788 -351.984945) (xy 422.621803 -351.992711)
			(xy 422.594532 -351.9932) (xy 421.730932 -351.9932) (xy 421.703662 -351.992663) (xy 421.649677 -351.984905)
			(xy 421.597346 -351.969543) (xy 421.547734 -351.94689) (xy 421.501851 -351.917406) (xy 421.460631 -351.881692)
			(xy 421.424913 -351.840475) (xy 421.395426 -351.794594) (xy 421.372768 -351.744984) (xy 421.357402 -351.692654)
			(xy 421.349639 -351.63867) (xy 419.866936 -351.63867) (xy 419.866936 -351.638675) (xy 419.859173 -351.69267)
			(xy 419.843803 -351.74501) (xy 419.821142 -351.79463) (xy 419.791648 -351.840519) (xy 419.755924 -351.881744)
			(xy 419.714697 -351.917465) (xy 419.668805 -351.946955) (xy 419.619184 -351.969613) (xy 419.566842 -351.984979)
			(xy 419.512847 -351.992738) (xy 419.485572 -351.9932) (xy 418.621972 -351.9932) (xy 418.594707 -351.992636)
			(xy 418.540731 -351.984872) (xy 418.48841 -351.969505) (xy 418.438809 -351.94685) (xy 418.392936 -351.917366)
			(xy 418.351726 -351.881654) (xy 418.316017 -351.840442) (xy 418.286537 -351.794567) (xy 418.263885 -351.744963)
			(xy 418.248522 -351.692641) (xy 418.240762 -351.638665) (xy 416.757914 -351.638665) (xy 416.757914 -351.638672)
			(xy 416.750151 -351.692659) (xy 416.734785 -351.744993) (xy 416.712128 -351.794608) (xy 416.68264 -351.840492)
			(xy 416.646922 -351.881714) (xy 416.605702 -351.917433) (xy 416.559818 -351.946922) (xy 416.510204 -351.969581)
			(xy 416.457871 -351.984949) (xy 416.403884 -351.992713) (xy 416.376612 -351.9932) (xy 415.513012 -351.9932)
			(xy 415.485743 -351.992661) (xy 415.43176 -351.984901) (xy 415.379431 -351.969538) (xy 415.329822 -351.946883)
			(xy 415.283941 -351.917399) (xy 415.242724 -351.881685) (xy 415.207008 -351.840469) (xy 415.177523 -351.794589)
			(xy 415.154866 -351.74498) (xy 415.139501 -351.692651) (xy 415.131739 -351.638669) (xy 413.649036 -351.638669)
			(xy 413.649036 -351.638676) (xy 413.641272 -351.692672) (xy 413.625902 -351.745014) (xy 413.603239 -351.794635)
			(xy 413.573744 -351.840526) (xy 413.538017 -351.881751) (xy 413.496787 -351.917472) (xy 413.450893 -351.946962)
			(xy 413.401269 -351.969619) (xy 413.348925 -351.984982) (xy 413.294928 -351.99274) (xy 413.267652 -351.9932)
			(xy 412.404052 -351.9932) (xy 412.376788 -351.992634) (xy 412.322815 -351.984868) (xy 412.270496 -351.9695)
			(xy 412.220897 -351.946843) (xy 412.175026 -351.917359) (xy 412.133819 -351.881647) (xy 412.098112 -351.840435)
			(xy 412.068634 -351.794561) (xy 412.045983 -351.744959) (xy 412.030622 -351.692639) (xy 412.022862 -351.638664)
			(xy 410.540036 -351.638664) (xy 410.540036 -351.638674) (xy 410.532273 -351.692667) (xy 410.516905 -351.745006)
			(xy 410.494245 -351.794624) (xy 410.464753 -351.840513) (xy 410.429032 -351.881737) (xy 410.387806 -351.917458)
			(xy 410.341917 -351.946949) (xy 410.292298 -351.969608) (xy 410.239959 -351.984975) (xy 410.185966 -351.992737)
			(xy 410.158692 -351.9932) (xy 409.295092 -351.9932) (xy 409.267826 -351.992637) (xy 409.213848 -351.984875)
			(xy 409.161525 -351.969511) (xy 409.111921 -351.946856) (xy 409.066045 -351.917373) (xy 409.024833 -351.881662)
			(xy 408.989122 -351.840448) (xy 408.95964 -351.794572) (xy 408.936986 -351.744968) (xy 408.921623 -351.692644)
			(xy 408.913862 -351.638666) (xy 403.522536 -351.638666) (xy 403.522536 -351.638675) (xy 403.514773 -351.692669)
			(xy 403.499404 -351.745008) (xy 403.476743 -351.794628) (xy 403.44725 -351.840517) (xy 403.411527 -351.881741)
			(xy 403.370301 -351.917462) (xy 403.32441 -351.946952) (xy 403.274789 -351.969611) (xy 403.222449 -351.984977)
			(xy 403.168455 -351.992738) (xy 403.14118 -351.9932) (xy 402.27758 -351.9932) (xy 402.250314 -351.992636)
			(xy 402.196338 -351.984873) (xy 402.144016 -351.969508) (xy 402.094414 -351.946852) (xy 402.04854 -351.917369)
			(xy 402.007329 -351.881657) (xy 401.971619 -351.840444) (xy 401.942138 -351.794569) (xy 401.919485 -351.744965)
			(xy 401.904123 -351.692642) (xy 401.896362 -351.638666) (xy 400.413514 -351.638666) (xy 400.413514 -351.638671)
			(xy 400.405752 -351.692658) (xy 400.390386 -351.744992) (xy 400.367729 -351.794605) (xy 400.338242 -351.84049)
			(xy 400.302525 -351.881711) (xy 400.261306 -351.91743) (xy 400.215423 -351.946919) (xy 400.16581 -351.969579)
			(xy 400.113478 -351.984947) (xy 400.059491 -351.992712) (xy 400.03222 -351.9932) (xy 399.16862 -351.9932)
			(xy 399.141351 -351.992662) (xy 399.087367 -351.984903) (xy 399.035037 -351.96954) (xy 398.985426 -351.946886)
			(xy 398.939545 -351.917402) (xy 398.898326 -351.881688) (xy 398.86261 -351.840471) (xy 398.833124 -351.794591)
			(xy 398.810467 -351.744982) (xy 398.795101 -351.692652) (xy 398.787339 -351.638669) (xy 397.304636 -351.638669)
			(xy 397.304636 -351.638676) (xy 397.296872 -351.692671) (xy 397.281503 -351.745012) (xy 397.25884 -351.794633)
			(xy 397.229346 -351.840523) (xy 397.19362 -351.881749) (xy 397.152391 -351.91747) (xy 397.106498 -351.946959)
			(xy 397.056875 -351.969617) (xy 397.004532 -351.984981) (xy 396.950536 -351.992739) (xy 396.92326 -351.9932)
			(xy 396.05966 -351.9932) (xy 396.032395 -351.992635) (xy 395.978421 -351.984869) (xy 395.926102 -351.969502)
			(xy 395.876502 -351.946846) (xy 395.83063 -351.917362) (xy 395.789421 -351.88165) (xy 395.753714 -351.840438)
			(xy 395.724235 -351.794563) (xy 395.701584 -351.744961) (xy 395.686222 -351.69264) (xy 395.678462 -351.638665)
			(xy 394.195613 -351.638665) (xy 394.195613 -351.638672) (xy 394.187851 -351.692661) (xy 394.172484 -351.744996)
			(xy 394.149826 -351.794611) (xy 394.120337 -351.840496) (xy 394.084618 -351.881718) (xy 394.043396 -351.917437)
			(xy 393.997511 -351.946926) (xy 393.947896 -351.969584) (xy 393.895561 -351.984951) (xy 393.841572 -351.992713)
			(xy 393.8143 -351.9932) (xy 392.9507 -351.9932) (xy 392.923433 -351.992638) (xy 392.869455 -351.984877)
			(xy 392.817131 -351.969513) (xy 392.767526 -351.946859) (xy 392.721649 -351.917376) (xy 392.680436 -351.881664)
			(xy 392.644724 -351.840451) (xy 392.615241 -351.794574) (xy 392.592587 -351.744969) (xy 392.577223 -351.692645)
			(xy 392.569462 -351.638667) (xy 391.086614 -351.638667) (xy 391.086614 -351.63867) (xy 391.078852 -351.692656)
			(xy 391.063487 -351.744987) (xy 391.040832 -351.7946) (xy 391.011347 -351.840483) (xy 390.975632 -351.881704)
			(xy 390.934415 -351.917423) (xy 390.888535 -351.946913) (xy 390.838925 -351.969573) (xy 390.786595 -351.984944)
			(xy 390.73261 -351.992711) (xy 390.70534 -351.9932) (xy 389.84174 -351.9932) (xy 389.81447 -351.992663)
			(xy 389.760484 -351.984907) (xy 389.708152 -351.969545) (xy 389.658538 -351.946892) (xy 389.612654 -351.917409)
			(xy 389.571434 -351.881695) (xy 389.535715 -351.840478) (xy 389.506227 -351.794597) (xy 389.483569 -351.744986)
			(xy 389.468202 -351.692655) (xy 389.46044 -351.63867) (xy 387.977736 -351.63867) (xy 387.977736 -351.638675)
			(xy 387.969973 -351.692669) (xy 387.954604 -351.745008) (xy 387.931943 -351.794628) (xy 387.90245 -351.840517)
			(xy 387.866727 -351.881741) (xy 387.825501 -351.917462) (xy 387.77961 -351.946952) (xy 387.729989 -351.969611)
			(xy 387.677649 -351.984977) (xy 387.623655 -351.992738) (xy 387.59638 -351.9932) (xy 386.73278 -351.9932)
			(xy 386.705514 -351.992636) (xy 386.651538 -351.984873) (xy 386.599216 -351.969508) (xy 386.549614 -351.946852)
			(xy 386.50374 -351.917369) (xy 386.462529 -351.881657) (xy 386.426819 -351.840444) (xy 386.397338 -351.794569)
			(xy 386.374685 -351.744965) (xy 386.359323 -351.692642) (xy 386.351562 -351.638666) (xy 384.868714 -351.638666)
			(xy 384.868714 -351.638671) (xy 384.860952 -351.692658) (xy 384.845586 -351.744992) (xy 384.822929 -351.794605)
			(xy 384.793442 -351.84049) (xy 384.757725 -351.881711) (xy 384.716506 -351.91743) (xy 384.670623 -351.946919)
			(xy 384.62101 -351.969579) (xy 384.568678 -351.984947) (xy 384.514691 -351.992712) (xy 384.48742 -351.9932)
			(xy 383.62382 -351.9932) (xy 383.596551 -351.992662) (xy 383.542567 -351.984903) (xy 383.490237 -351.96954)
			(xy 383.440626 -351.946886) (xy 383.394745 -351.917402) (xy 383.353526 -351.881688) (xy 383.31781 -351.840471)
			(xy 383.288324 -351.794591) (xy 383.265667 -351.744982) (xy 383.250301 -351.692652) (xy 383.242539 -351.638669)
			(xy 381.759836 -351.638669) (xy 381.759836 -351.638676) (xy 381.752072 -351.692671) (xy 381.736703 -351.745012)
			(xy 381.71404 -351.794633) (xy 381.684546 -351.840523) (xy 381.64882 -351.881749) (xy 381.607591 -351.91747)
			(xy 381.561698 -351.946959) (xy 381.512075 -351.969617) (xy 381.459732 -351.984981) (xy 381.405736 -351.992739)
			(xy 381.37846 -351.9932) (xy 380.51486 -351.9932) (xy 380.487595 -351.992635) (xy 380.433621 -351.984869)
			(xy 380.381302 -351.969502) (xy 380.331702 -351.946846) (xy 380.28583 -351.917362) (xy 380.244621 -351.88165)
			(xy 380.208914 -351.840438) (xy 380.179435 -351.794563) (xy 380.156784 -351.744961) (xy 380.141422 -351.69264)
			(xy 380.133662 -351.638665) (xy 378.650813 -351.638665) (xy 378.650813 -351.638672) (xy 378.643051 -351.692661)
			(xy 378.627684 -351.744996) (xy 378.605026 -351.794611) (xy 378.575537 -351.840496) (xy 378.539818 -351.881718)
			(xy 378.498596 -351.917437) (xy 378.452711 -351.946926) (xy 378.403096 -351.969584) (xy 378.350761 -351.984951)
			(xy 378.296772 -351.992713) (xy 378.2695 -351.9932) (xy 377.4059 -351.9932) (xy 377.378633 -351.992638)
			(xy 377.324655 -351.984877) (xy 377.272331 -351.969513) (xy 377.222726 -351.946859) (xy 377.176849 -351.917376)
			(xy 377.135636 -351.881664) (xy 377.099924 -351.840451) (xy 377.070441 -351.794574) (xy 377.047787 -351.744969)
			(xy 377.032423 -351.692645) (xy 377.024662 -351.638667) (xy 375.541814 -351.638667) (xy 375.541814 -351.63867)
			(xy 375.534052 -351.692656) (xy 375.518687 -351.744987) (xy 375.496032 -351.7946) (xy 375.466547 -351.840483)
			(xy 375.430832 -351.881704) (xy 375.389615 -351.917423) (xy 375.343735 -351.946913) (xy 375.294125 -351.969573)
			(xy 375.241795 -351.984944) (xy 375.18781 -351.992711) (xy 375.16054 -351.9932) (xy 374.29694 -351.9932)
			(xy 374.26967 -351.992663) (xy 374.215684 -351.984907) (xy 374.163352 -351.969545) (xy 374.113738 -351.946892)
			(xy 374.067854 -351.917409) (xy 374.026634 -351.881695) (xy 373.990915 -351.840478) (xy 373.961427 -351.794597)
			(xy 373.938769 -351.744986) (xy 373.923402 -351.692655) (xy 373.91564 -351.63867) (xy 372.432936 -351.63867)
			(xy 372.432936 -351.638675) (xy 372.425173 -351.692669) (xy 372.409804 -351.745008) (xy 372.387143 -351.794628)
			(xy 372.35765 -351.840517) (xy 372.321927 -351.881741) (xy 372.280701 -351.917462) (xy 372.23481 -351.946952)
			(xy 372.185189 -351.969611) (xy 372.132849 -351.984977) (xy 372.078855 -351.992738) (xy 372.05158 -351.9932)
			(xy 371.18798 -351.9932) (xy 371.160714 -351.992636) (xy 371.106738 -351.984873) (xy 371.054416 -351.969508)
			(xy 371.004814 -351.946852) (xy 370.95894 -351.917369) (xy 370.917729 -351.881657) (xy 370.882019 -351.840444)
			(xy 370.852538 -351.794569) (xy 370.829885 -351.744965) (xy 370.814523 -351.692642) (xy 370.806762 -351.638666)
			(xy 344.837313 -351.638666) (xy 344.837313 -351.638672) (xy 344.829551 -351.692661) (xy 344.814184 -351.744995)
			(xy 344.791526 -351.79461) (xy 344.762038 -351.840495) (xy 344.726319 -351.881717) (xy 344.685098 -351.917435)
			(xy 344.639213 -351.946924) (xy 344.589599 -351.969583) (xy 344.537264 -351.98495) (xy 344.483276 -351.992713)
			(xy 344.456004 -351.9932) (xy 343.592404 -351.9932) (xy 343.565136 -351.992661) (xy 343.511154 -351.9849)
			(xy 343.458826 -351.969536) (xy 343.409217 -351.94688) (xy 343.363337 -351.917396) (xy 343.322121 -351.881682)
			(xy 343.286407 -351.840466) (xy 343.256921 -351.794587) (xy 343.234266 -351.744978) (xy 343.218901 -351.69265)
			(xy 343.211139 -351.638668) (xy 341.728314 -351.638668) (xy 341.728314 -351.63867) (xy 341.720552 -351.692655)
			(xy 341.705188 -351.744986) (xy 341.682532 -351.794599) (xy 341.653048 -351.840482) (xy 341.617334 -351.881703)
			(xy 341.576117 -351.917421) (xy 341.530237 -351.946911) (xy 341.480628 -351.969572) (xy 341.428298 -351.984943)
			(xy 341.374314 -351.99271) (xy 341.347044 -351.9932) (xy 340.483444 -351.9932) (xy 340.456174 -351.992664)
			(xy 340.402187 -351.984907) (xy 340.349855 -351.969546) (xy 340.300241 -351.946894) (xy 340.254356 -351.91741)
			(xy 340.213135 -351.881696) (xy 340.177416 -351.840479) (xy 340.147928 -351.794598) (xy 340.125269 -351.744987)
			(xy 340.109902 -351.692656) (xy 340.10214 -351.63867) (xy 338.619436 -351.63867) (xy 338.619436 -351.638674)
			(xy 338.611673 -351.692668) (xy 338.596304 -351.745007) (xy 338.573643 -351.794626) (xy 338.544151 -351.840515)
			(xy 338.508429 -351.88174) (xy 338.467203 -351.917461) (xy 338.421312 -351.946951) (xy 338.371692 -351.96961)
			(xy 338.319352 -351.984976) (xy 338.265358 -351.992738) (xy 338.238084 -351.9932) (xy 337.374484 -351.9932)
			(xy 337.347218 -351.992637) (xy 337.293242 -351.984874) (xy 337.240919 -351.969509) (xy 337.191316 -351.946854)
			(xy 337.145442 -351.91737) (xy 337.10423 -351.881659) (xy 337.06852 -351.840446) (xy 337.039039 -351.79457)
			(xy 337.016386 -351.744966) (xy 337.001023 -351.692643) (xy 336.993262 -351.638666) (xy 335.510414 -351.638666)
			(xy 335.510414 -351.638671) (xy 335.502652 -351.692658) (xy 335.487286 -351.744991) (xy 335.464629 -351.794604)
			(xy 335.435143 -351.840488) (xy 335.399427 -351.88171) (xy 335.358208 -351.917428) (xy 335.312325 -351.946918)
			(xy 335.262713 -351.969578) (xy 335.210381 -351.984947) (xy 335.156395 -351.992712) (xy 335.129124 -351.9932)
			(xy 334.265524 -351.9932) (xy 334.238255 -351.992662) (xy 334.18427 -351.984904) (xy 334.13194 -351.969541)
			(xy 334.082329 -351.946887) (xy 334.036447 -351.917403) (xy 333.995228 -351.881689) (xy 333.959511 -351.840472)
			(xy 333.930024 -351.794592) (xy 333.907367 -351.744982) (xy 333.892001 -351.692653) (xy 333.884239 -351.638669)
			(xy 332.401536 -351.638669) (xy 332.401536 -351.638675) (xy 332.393772 -351.692671) (xy 332.378403 -351.745011)
			(xy 332.35574 -351.794632) (xy 332.326246 -351.840522) (xy 332.290522 -351.881747) (xy 332.249293 -351.917468)
			(xy 332.2034 -351.946958) (xy 332.153778 -351.969615) (xy 332.101436 -351.98498) (xy 332.047439 -351.992739)
			(xy 332.020164 -351.9932) (xy 331.156564 -351.9932) (xy 331.129299 -351.992635) (xy 331.075325 -351.98487)
			(xy 331.023005 -351.969503) (xy 330.973404 -351.946847) (xy 330.927532 -351.917363) (xy 330.886323 -351.881652)
			(xy 330.850615 -351.840439) (xy 330.821136 -351.794564) (xy 330.798484 -351.744962) (xy 330.783122 -351.69264)
			(xy 330.775362 -351.638665) (xy 329.292513 -351.638665) (xy 329.292513 -351.638672) (xy 329.284751 -351.692661)
			(xy 329.269384 -351.744995) (xy 329.246726 -351.79461) (xy 329.217238 -351.840495) (xy 329.181519 -351.881717)
			(xy 329.140298 -351.917435) (xy 329.094413 -351.946924) (xy 329.044799 -351.969583) (xy 328.992464 -351.98495)
			(xy 328.938476 -351.992713) (xy 328.911204 -351.9932) (xy 328.047604 -351.9932) (xy 328.020336 -351.992661)
			(xy 327.966354 -351.9849) (xy 327.914026 -351.969536) (xy 327.864417 -351.94688) (xy 327.818537 -351.917396)
			(xy 327.777321 -351.881682) (xy 327.741607 -351.840466) (xy 327.712121 -351.794587) (xy 327.689466 -351.744978)
			(xy 327.674101 -351.69265) (xy 327.666339 -351.638668) (xy 326.183514 -351.638668) (xy 326.183514 -351.63867)
			(xy 326.175752 -351.692655) (xy 326.160388 -351.744986) (xy 326.137732 -351.794599) (xy 326.108248 -351.840482)
			(xy 326.072534 -351.881703) (xy 326.031317 -351.917421) (xy 325.985437 -351.946911) (xy 325.935828 -351.969572)
			(xy 325.883498 -351.984943) (xy 325.829514 -351.99271) (xy 325.802244 -351.9932) (xy 324.938644 -351.9932)
			(xy 324.911374 -351.992664) (xy 324.857387 -351.984907) (xy 324.805055 -351.969546) (xy 324.755441 -351.946894)
			(xy 324.709556 -351.91741) (xy 324.668335 -351.881696) (xy 324.632616 -351.840479) (xy 324.603128 -351.794598)
			(xy 324.580469 -351.744987) (xy 324.565102 -351.692656) (xy 324.55734 -351.63867) (xy 323.074636 -351.63867)
			(xy 323.074636 -351.638674) (xy 323.066873 -351.692668) (xy 323.051504 -351.745007) (xy 323.028843 -351.794626)
			(xy 322.999351 -351.840515) (xy 322.963629 -351.88174) (xy 322.922403 -351.917461) (xy 322.876512 -351.946951)
			(xy 322.826892 -351.96961) (xy 322.774552 -351.984976) (xy 322.720558 -351.992738) (xy 322.693284 -351.9932)
			(xy 321.829684 -351.9932) (xy 321.802418 -351.992637) (xy 321.748442 -351.984874) (xy 321.696119 -351.969509)
			(xy 321.646516 -351.946854) (xy 321.600642 -351.91737) (xy 321.55943 -351.881659) (xy 321.52372 -351.840446)
			(xy 321.494239 -351.79457) (xy 321.471586 -351.744966) (xy 321.456223 -351.692643) (xy 321.448462 -351.638666)
			(xy 319.965614 -351.638666) (xy 319.965614 -351.638671) (xy 319.957852 -351.692658) (xy 319.942486 -351.744991)
			(xy 319.919829 -351.794604) (xy 319.890343 -351.840488) (xy 319.854627 -351.88171) (xy 319.813408 -351.917428)
			(xy 319.767525 -351.946918) (xy 319.717913 -351.969578) (xy 319.665581 -351.984947) (xy 319.611595 -351.992712)
			(xy 319.584324 -351.9932) (xy 318.720724 -351.9932) (xy 318.693455 -351.992662) (xy 318.63947 -351.984904)
			(xy 318.58714 -351.969541) (xy 318.537529 -351.946887) (xy 318.491647 -351.917403) (xy 318.450428 -351.881689)
			(xy 318.414711 -351.840472) (xy 318.385224 -351.794592) (xy 318.362567 -351.744982) (xy 318.347201 -351.692653)
			(xy 318.339439 -351.638669) (xy 316.856736 -351.638669) (xy 316.856736 -351.638675) (xy 316.848972 -351.692671)
			(xy 316.833603 -351.745011) (xy 316.81094 -351.794632) (xy 316.781446 -351.840522) (xy 316.745722 -351.881747)
			(xy 316.704493 -351.917468) (xy 316.6586 -351.946958) (xy 316.608978 -351.969615) (xy 316.556636 -351.98498)
			(xy 316.502639 -351.992739) (xy 316.475364 -351.9932) (xy 315.611764 -351.9932) (xy 315.584499 -351.992635)
			(xy 315.530525 -351.98487) (xy 315.478205 -351.969503) (xy 315.428604 -351.946847) (xy 315.382732 -351.917363)
			(xy 315.341523 -351.881652) (xy 315.305815 -351.840439) (xy 315.276336 -351.794564) (xy 315.253684 -351.744962)
			(xy 315.238322 -351.69264) (xy 315.230562 -351.638665) (xy 313.747713 -351.638665) (xy 313.747713 -351.638672)
			(xy 313.739951 -351.692661) (xy 313.724584 -351.744995) (xy 313.701926 -351.79461) (xy 313.672438 -351.840495)
			(xy 313.636719 -351.881717) (xy 313.595498 -351.917435) (xy 313.549613 -351.946924) (xy 313.499999 -351.969583)
			(xy 313.447664 -351.98495) (xy 313.393676 -351.992713) (xy 313.366404 -351.9932) (xy 312.502804 -351.9932)
			(xy 312.475536 -351.992661) (xy 312.421554 -351.9849) (xy 312.369226 -351.969536) (xy 312.319617 -351.94688)
			(xy 312.273737 -351.917396) (xy 312.232521 -351.881682) (xy 312.196807 -351.840466) (xy 312.167321 -351.794587)
			(xy 312.144666 -351.744978) (xy 312.129301 -351.69265) (xy 312.121539 -351.638668) (xy 300.231613 -351.638668)
			(xy 300.231613 -351.638672) (xy 300.223851 -351.692661) (xy 300.208484 -351.744995) (xy 300.185826 -351.79461)
			(xy 300.156337 -351.840496) (xy 300.120619 -351.881717) (xy 300.079397 -351.917436) (xy 300.033512 -351.946925)
			(xy 299.983897 -351.969584) (xy 299.931563 -351.984951) (xy 299.877574 -351.992713) (xy 299.850302 -351.9932)
			(xy 298.986702 -351.9932) (xy 298.959434 -351.992661) (xy 298.905452 -351.9849) (xy 298.853124 -351.969535)
			(xy 298.803516 -351.94688) (xy 298.757636 -351.917395) (xy 298.71642 -351.881681) (xy 298.680706 -351.840465)
			(xy 298.651221 -351.794586) (xy 298.628566 -351.744978) (xy 298.613201 -351.69265) (xy 298.605439 -351.638668)
			(xy 297.122614 -351.638668) (xy 297.122614 -351.63867) (xy 297.114852 -351.692655) (xy 297.099488 -351.744987)
			(xy 297.076832 -351.794599) (xy 297.047347 -351.840483) (xy 297.011633 -351.881703) (xy 296.970416 -351.917422)
			(xy 296.924536 -351.946912) (xy 296.874926 -351.969573) (xy 296.822597 -351.984943) (xy 296.768612 -351.992711)
			(xy 296.741342 -351.9932) (xy 295.877742 -351.9932) (xy 295.850472 -351.992663) (xy 295.796486 -351.984907)
			(xy 295.744153 -351.969546) (xy 295.69454 -351.946893) (xy 295.648655 -351.917409) (xy 295.607434 -351.881695)
			(xy 295.571716 -351.840478) (xy 295.542227 -351.794597) (xy 295.519569 -351.744986) (xy 295.504202 -351.692655)
			(xy 295.49644 -351.63867) (xy 294.013736 -351.63867) (xy 294.013736 -351.638675) (xy 294.005973 -351.692668)
			(xy 293.990604 -351.745008) (xy 293.967943 -351.794627) (xy 293.938451 -351.840516) (xy 293.902728 -351.881741)
			(xy 293.861502 -351.917462) (xy 293.815611 -351.946952) (xy 293.765991 -351.969611) (xy 293.713651 -351.984977)
			(xy 293.659657 -351.992738) (xy 293.632382 -351.9932) (xy 292.768782 -351.9932) (xy 292.741516 -351.992636)
			(xy 292.68754 -351.984873) (xy 292.635218 -351.969508) (xy 292.585615 -351.946853) (xy 292.539741 -351.91737)
			(xy 292.498529 -351.881658) (xy 292.46282 -351.840445) (xy 292.433338 -351.794569) (xy 292.410686 -351.744965)
			(xy 292.395323 -351.692642) (xy 292.387562 -351.638666) (xy 290.904714 -351.638666) (xy 290.904714 -351.638671)
			(xy 290.896952 -351.692658) (xy 290.881586 -351.744991) (xy 290.858929 -351.794605) (xy 290.829442 -351.840489)
			(xy 290.793726 -351.88171) (xy 290.752507 -351.917429) (xy 290.706624 -351.946919) (xy 290.657012 -351.969578)
			(xy 290.60468 -351.984947) (xy 290.550693 -351.992712) (xy 290.523422 -351.9932) (xy 289.659822 -351.9932)
			(xy 289.632553 -351.992662) (xy 289.578569 -351.984903) (xy 289.526239 -351.96954) (xy 289.476628 -351.946886)
			(xy 289.430746 -351.917402) (xy 289.389527 -351.881688) (xy 289.353811 -351.840472) (xy 289.324324 -351.794592)
			(xy 289.301667 -351.744982) (xy 289.286301 -351.692653) (xy 289.278539 -351.638669) (xy 287.795836 -351.638669)
			(xy 287.795836 -351.638675) (xy 287.788072 -351.692671) (xy 287.772703 -351.745012) (xy 287.75004 -351.794633)
			(xy 287.720546 -351.840523) (xy 287.684821 -351.881748) (xy 287.643592 -351.917469) (xy 287.597699 -351.946958)
			(xy 287.548076 -351.969616) (xy 287.495734 -351.98498) (xy 287.441737 -351.992739) (xy 287.414462 -351.9932)
			(xy 286.550862 -351.9932) (xy 286.523597 -351.992635) (xy 286.469623 -351.98487) (xy 286.417303 -351.969503)
			(xy 286.367703 -351.946847) (xy 286.321831 -351.917363) (xy 286.280622 -351.881651) (xy 286.244915 -351.840438)
			(xy 286.215435 -351.794564) (xy 286.192784 -351.744961) (xy 286.177422 -351.69264) (xy 286.169662 -351.638665)
			(xy 284.686813 -351.638665) (xy 284.686813 -351.638672) (xy 284.679051 -351.692661) (xy 284.663684 -351.744995)
			(xy 284.641026 -351.79461) (xy 284.611537 -351.840496) (xy 284.575819 -351.881717) (xy 284.534597 -351.917436)
			(xy 284.488712 -351.946925) (xy 284.439097 -351.969584) (xy 284.386763 -351.984951) (xy 284.332774 -351.992713)
			(xy 284.305502 -351.9932) (xy 283.441902 -351.9932) (xy 283.414634 -351.992661) (xy 283.360652 -351.9849)
			(xy 283.308324 -351.969535) (xy 283.258716 -351.94688) (xy 283.212836 -351.917395) (xy 283.17162 -351.881681)
			(xy 283.135906 -351.840465) (xy 283.106421 -351.794586) (xy 283.083766 -351.744978) (xy 283.068401 -351.69265)
			(xy 283.060639 -351.638668) (xy 281.577814 -351.638668) (xy 281.577814 -351.63867) (xy 281.570052 -351.692655)
			(xy 281.554688 -351.744987) (xy 281.532032 -351.794599) (xy 281.502547 -351.840483) (xy 281.466833 -351.881703)
			(xy 281.425616 -351.917422) (xy 281.379736 -351.946912) (xy 281.330126 -351.969573) (xy 281.277797 -351.984943)
			(xy 281.223812 -351.992711) (xy 281.196542 -351.9932) (xy 280.332942 -351.9932) (xy 280.305672 -351.992663)
			(xy 280.251686 -351.984907) (xy 280.199353 -351.969546) (xy 280.14974 -351.946893) (xy 280.103855 -351.917409)
			(xy 280.062634 -351.881695) (xy 280.026916 -351.840478) (xy 279.997427 -351.794597) (xy 279.974769 -351.744986)
			(xy 279.959402 -351.692655) (xy 279.95164 -351.63867) (xy 278.468936 -351.63867) (xy 278.468936 -351.638675)
			(xy 278.461173 -351.692668) (xy 278.445804 -351.745008) (xy 278.423143 -351.794627) (xy 278.393651 -351.840516)
			(xy 278.357928 -351.881741) (xy 278.316702 -351.917462) (xy 278.270811 -351.946952) (xy 278.221191 -351.969611)
			(xy 278.168851 -351.984977) (xy 278.114857 -351.992738) (xy 278.087582 -351.9932) (xy 277.223982 -351.9932)
			(xy 277.196716 -351.992636) (xy 277.14274 -351.984873) (xy 277.090418 -351.969508) (xy 277.040815 -351.946853)
			(xy 276.994941 -351.91737) (xy 276.953729 -351.881658) (xy 276.91802 -351.840445) (xy 276.888538 -351.794569)
			(xy 276.865886 -351.744965) (xy 276.850523 -351.692642) (xy 276.842762 -351.638666) (xy 275.359914 -351.638666)
			(xy 275.359914 -351.638671) (xy 275.352152 -351.692658) (xy 275.336786 -351.744991) (xy 275.314129 -351.794605)
			(xy 275.284642 -351.840489) (xy 275.248926 -351.88171) (xy 275.207707 -351.917429) (xy 275.161824 -351.946919)
			(xy 275.112212 -351.969578) (xy 275.05988 -351.984947) (xy 275.005893 -351.992712) (xy 274.978622 -351.9932)
			(xy 274.115022 -351.9932) (xy 274.087753 -351.992662) (xy 274.033769 -351.984903) (xy 273.981439 -351.96954)
			(xy 273.931828 -351.946886) (xy 273.885946 -351.917402) (xy 273.844727 -351.881688) (xy 273.809011 -351.840472)
			(xy 273.779524 -351.794592) (xy 273.756867 -351.744982) (xy 273.741501 -351.692653) (xy 273.733739 -351.638669)
			(xy 272.251036 -351.638669) (xy 272.251036 -351.638675) (xy 272.243272 -351.692671) (xy 272.227903 -351.745012)
			(xy 272.20524 -351.794633) (xy 272.175746 -351.840523) (xy 272.140021 -351.881748) (xy 272.098792 -351.917469)
			(xy 272.052899 -351.946958) (xy 272.003276 -351.969616) (xy 271.950934 -351.98498) (xy 271.896937 -351.992739)
			(xy 271.869662 -351.9932) (xy 271.006062 -351.9932) (xy 270.978797 -351.992635) (xy 270.924823 -351.98487)
			(xy 270.872503 -351.969503) (xy 270.822903 -351.946847) (xy 270.777031 -351.917363) (xy 270.735822 -351.881651)
			(xy 270.700115 -351.840438) (xy 270.670635 -351.794564) (xy 270.647984 -351.744961) (xy 270.632622 -351.69264)
			(xy 270.624862 -351.638665) (xy 269.142013 -351.638665) (xy 269.142013 -351.638672) (xy 269.134251 -351.692661)
			(xy 269.118884 -351.744995) (xy 269.096226 -351.79461) (xy 269.066737 -351.840496) (xy 269.031019 -351.881717)
			(xy 268.989797 -351.917436) (xy 268.943912 -351.946925) (xy 268.894297 -351.969584) (xy 268.841963 -351.984951)
			(xy 268.787974 -351.992713) (xy 268.760702 -351.9932) (xy 267.897102 -351.9932) (xy 267.869834 -351.992661)
			(xy 267.815852 -351.9849) (xy 267.763524 -351.969535) (xy 267.713916 -351.94688) (xy 267.668036 -351.917395)
			(xy 267.62682 -351.881681) (xy 267.591106 -351.840465) (xy 267.561621 -351.794586) (xy 267.538966 -351.744978)
			(xy 267.523601 -351.69265) (xy 267.515839 -351.638668) (xy 194.520614 -351.638668) (xy 194.520614 -351.638672)
			(xy 194.512851 -351.692659) (xy 194.497485 -351.744993) (xy 194.474828 -351.794608) (xy 194.44534 -351.840492)
			(xy 194.409622 -351.881714) (xy 194.368402 -351.917433) (xy 194.322518 -351.946922) (xy 194.272904 -351.969581)
			(xy 194.220571 -351.984949) (xy 194.166584 -351.992713) (xy 194.139312 -351.9932) (xy 193.275712 -351.9932)
			(xy 193.248443 -351.992661) (xy 193.19446 -351.984901) (xy 193.142131 -351.969538) (xy 193.092522 -351.946883)
			(xy 193.046641 -351.917399) (xy 193.005424 -351.881685) (xy 192.969708 -351.840469) (xy 192.940223 -351.794589)
			(xy 192.917566 -351.74498) (xy 192.902201 -351.692651) (xy 192.894439 -351.638669) (xy 191.411736 -351.638669)
			(xy 191.411736 -351.638676) (xy 191.403972 -351.692672) (xy 191.388602 -351.745014) (xy 191.365939 -351.794635)
			(xy 191.336444 -351.840526) (xy 191.300717 -351.881751) (xy 191.259487 -351.917472) (xy 191.213593 -351.946962)
			(xy 191.163969 -351.969619) (xy 191.111625 -351.984982) (xy 191.057628 -351.99274) (xy 191.030352 -351.9932)
			(xy 190.166752 -351.9932) (xy 190.139488 -351.992634) (xy 190.085515 -351.984868) (xy 190.033196 -351.9695)
			(xy 189.983597 -351.946843) (xy 189.937726 -351.917359) (xy 189.896519 -351.881647) (xy 189.860812 -351.840435)
			(xy 189.831334 -351.794561) (xy 189.808683 -351.744959) (xy 189.793322 -351.692639) (xy 189.785562 -351.638664)
			(xy 188.302736 -351.638664) (xy 188.302736 -351.638674) (xy 188.294973 -351.692667) (xy 188.279605 -351.745006)
			(xy 188.256945 -351.794624) (xy 188.227453 -351.840513) (xy 188.191732 -351.881737) (xy 188.150506 -351.917458)
			(xy 188.104617 -351.946949) (xy 188.054998 -351.969608) (xy 188.002659 -351.984975) (xy 187.948666 -351.992737)
			(xy 187.921392 -351.9932) (xy 187.057792 -351.9932) (xy 187.030526 -351.992637) (xy 186.976548 -351.984875)
			(xy 186.924225 -351.969511) (xy 186.874621 -351.946856) (xy 186.828745 -351.917373) (xy 186.787533 -351.881662)
			(xy 186.751822 -351.840448) (xy 186.72234 -351.794572) (xy 186.699686 -351.744968) (xy 186.684323 -351.692644)
			(xy 186.676562 -351.638666) (xy 185.193714 -351.638666) (xy 185.193714 -351.638671) (xy 185.185952 -351.692657)
			(xy 185.170587 -351.744989) (xy 185.147931 -351.794602) (xy 185.118445 -351.840486) (xy 185.082729 -351.881707)
			(xy 185.041512 -351.917426) (xy 184.99563 -351.946915) (xy 184.946019 -351.969576) (xy 184.893688 -351.984945)
			(xy 184.839703 -351.992711) (xy 184.812432 -351.9932) (xy 183.948832 -351.9932) (xy 183.921562 -351.992663)
			(xy 183.867577 -351.984905) (xy 183.815246 -351.969543) (xy 183.765634 -351.94689) (xy 183.719751 -351.917406)
			(xy 183.678531 -351.881692) (xy 183.642813 -351.840475) (xy 183.613326 -351.794594) (xy 183.590668 -351.744984)
			(xy 183.575302 -351.692654) (xy 183.567539 -351.63867) (xy 182.084836 -351.63867) (xy 182.084836 -351.638675)
			(xy 182.077073 -351.69267) (xy 182.061703 -351.74501) (xy 182.039042 -351.79463) (xy 182.009548 -351.840519)
			(xy 181.973824 -351.881744) (xy 181.932597 -351.917465) (xy 181.886705 -351.946955) (xy 181.837084 -351.969613)
			(xy 181.784742 -351.984979) (xy 181.730747 -351.992738) (xy 181.703472 -351.9932) (xy 180.839872 -351.9932)
			(xy 180.812607 -351.992636) (xy 180.758631 -351.984872) (xy 180.70631 -351.969505) (xy 180.656709 -351.94685)
			(xy 180.610836 -351.917366) (xy 180.569626 -351.881654) (xy 180.533917 -351.840442) (xy 180.504437 -351.794567)
			(xy 180.481785 -351.744963) (xy 180.466422 -351.692641) (xy 180.458662 -351.638665) (xy 178.975814 -351.638665)
			(xy 178.975814 -351.638672) (xy 178.968051 -351.692659) (xy 178.952685 -351.744993) (xy 178.930028 -351.794608)
			(xy 178.90054 -351.840492) (xy 178.864822 -351.881714) (xy 178.823602 -351.917433) (xy 178.777718 -351.946922)
			(xy 178.728104 -351.969581) (xy 178.675771 -351.984949) (xy 178.621784 -351.992713) (xy 178.594512 -351.9932)
			(xy 177.730912 -351.9932) (xy 177.703643 -351.992661) (xy 177.64966 -351.984901) (xy 177.597331 -351.969538)
			(xy 177.547722 -351.946883) (xy 177.501841 -351.917399) (xy 177.460624 -351.881685) (xy 177.424908 -351.840469)
			(xy 177.395423 -351.794589) (xy 177.372766 -351.74498) (xy 177.357401 -351.692651) (xy 177.349639 -351.638669)
			(xy 175.866936 -351.638669) (xy 175.866936 -351.638676) (xy 175.859172 -351.692672) (xy 175.843802 -351.745014)
			(xy 175.821139 -351.794635) (xy 175.791644 -351.840526) (xy 175.755917 -351.881751) (xy 175.714687 -351.917472)
			(xy 175.668793 -351.946962) (xy 175.619169 -351.969619) (xy 175.566825 -351.984982) (xy 175.512828 -351.99274)
			(xy 175.485552 -351.9932) (xy 174.621952 -351.9932) (xy 174.594688 -351.992634) (xy 174.540715 -351.984868)
			(xy 174.488396 -351.9695) (xy 174.438797 -351.946843) (xy 174.392926 -351.917359) (xy 174.351719 -351.881647)
			(xy 174.316012 -351.840435) (xy 174.286534 -351.794561) (xy 174.263883 -351.744959) (xy 174.248522 -351.692639)
			(xy 174.240762 -351.638664) (xy 172.757936 -351.638664) (xy 172.757936 -351.638674) (xy 172.750173 -351.692667)
			(xy 172.734805 -351.745006) (xy 172.712145 -351.794624) (xy 172.682653 -351.840513) (xy 172.646932 -351.881737)
			(xy 172.605706 -351.917458) (xy 172.559817 -351.946949) (xy 172.510198 -351.969608) (xy 172.457859 -351.984975)
			(xy 172.403866 -351.992737) (xy 172.376592 -351.9932) (xy 171.512992 -351.9932) (xy 171.485726 -351.992637)
			(xy 171.431748 -351.984875) (xy 171.379425 -351.969511) (xy 171.329821 -351.946856) (xy 171.283945 -351.917373)
			(xy 171.242733 -351.881662) (xy 171.207022 -351.840448) (xy 171.17754 -351.794572) (xy 171.154886 -351.744968)
			(xy 171.139523 -351.692644) (xy 171.131762 -351.638666) (xy 169.648914 -351.638666) (xy 169.648914 -351.638671)
			(xy 169.641152 -351.692657) (xy 169.625787 -351.744989) (xy 169.603131 -351.794602) (xy 169.573645 -351.840486)
			(xy 169.537929 -351.881707) (xy 169.496712 -351.917426) (xy 169.45083 -351.946915) (xy 169.401219 -351.969576)
			(xy 169.348888 -351.984945) (xy 169.294903 -351.992711) (xy 169.267632 -351.9932) (xy 168.404032 -351.9932)
			(xy 168.376762 -351.992663) (xy 168.322777 -351.984905) (xy 168.270446 -351.969543) (xy 168.220834 -351.94689)
			(xy 168.174951 -351.917406) (xy 168.133731 -351.881692) (xy 168.098013 -351.840475) (xy 168.068526 -351.794594)
			(xy 168.045868 -351.744984) (xy 168.030502 -351.692654) (xy 168.022739 -351.63867) (xy 166.540036 -351.63867)
			(xy 166.540036 -351.638675) (xy 166.532273 -351.69267) (xy 166.516903 -351.74501) (xy 166.494242 -351.79463)
			(xy 166.464748 -351.840519) (xy 166.429024 -351.881744) (xy 166.387797 -351.917465) (xy 166.341905 -351.946955)
			(xy 166.292284 -351.969613) (xy 166.239942 -351.984979) (xy 166.185947 -351.992738) (xy 166.158672 -351.9932)
			(xy 165.295072 -351.9932) (xy 165.267807 -351.992636) (xy 165.213831 -351.984872) (xy 165.16151 -351.969505)
			(xy 165.111909 -351.94685) (xy 165.066036 -351.917366) (xy 165.024826 -351.881654) (xy 164.989117 -351.840442)
			(xy 164.959637 -351.794567) (xy 164.936985 -351.744963) (xy 164.921622 -351.692641) (xy 164.913862 -351.638665)
			(xy 163.431014 -351.638665) (xy 163.431014 -351.638672) (xy 163.423251 -351.692659) (xy 163.407885 -351.744993)
			(xy 163.385228 -351.794608) (xy 163.35574 -351.840492) (xy 163.320022 -351.881714) (xy 163.278802 -351.917433)
			(xy 163.232918 -351.946922) (xy 163.183304 -351.969581) (xy 163.130971 -351.984949) (xy 163.076984 -351.992713)
			(xy 163.049712 -351.9932) (xy 162.186112 -351.9932) (xy 162.158843 -351.992661) (xy 162.10486 -351.984901)
			(xy 162.052531 -351.969538) (xy 162.002922 -351.946883) (xy 161.957041 -351.917399) (xy 161.915824 -351.881685)
			(xy 161.880108 -351.840469) (xy 161.850623 -351.794589) (xy 161.827966 -351.74498) (xy 161.812601 -351.692651)
			(xy 161.804839 -351.638669) (xy 144.196614 -351.638669) (xy 144.196614 -351.638672) (xy 144.188851 -351.69266)
			(xy 144.173485 -351.744994) (xy 144.150827 -351.794609) (xy 144.121339 -351.840494) (xy 144.085621 -351.881715)
			(xy 144.0444 -351.917434) (xy 143.998516 -351.946923) (xy 143.948902 -351.969582) (xy 143.896568 -351.98495)
			(xy 143.84258 -351.992713) (xy 143.815308 -351.9932) (xy 142.951708 -351.9932) (xy 142.924439 -351.992661)
			(xy 142.870457 -351.984901) (xy 142.818129 -351.969537) (xy 142.768519 -351.946882) (xy 142.722639 -351.917397)
			(xy 142.681422 -351.881683) (xy 142.645707 -351.840467) (xy 142.616222 -351.794588) (xy 142.593566 -351.744979)
			(xy 142.578201 -351.692651) (xy 142.570439 -351.638669) (xy 141.087614 -351.638669) (xy 141.087614 -351.63867)
			(xy 141.079852 -351.692655) (xy 141.064488 -351.744986) (xy 141.041833 -351.794597) (xy 141.012349 -351.840481)
			(xy 140.976635 -351.881701) (xy 140.935419 -351.91742) (xy 140.88954 -351.94691) (xy 140.839931 -351.969571)
			(xy 140.787602 -351.984942) (xy 140.733618 -351.99271) (xy 140.706348 -351.9932) (xy 139.842748 -351.9932)
			(xy 139.815477 -351.992664) (xy 139.761491 -351.984908) (xy 139.709158 -351.969547) (xy 139.659543 -351.946895)
			(xy 139.613658 -351.917411) (xy 139.572436 -351.881698) (xy 139.536717 -351.84048) (xy 139.507228 -351.794599)
			(xy 139.484569 -351.744987) (xy 139.469202 -351.692656) (xy 139.46144 -351.63867) (xy 137.978736 -351.63867)
			(xy 137.978736 -351.638674) (xy 137.970973 -351.692668) (xy 137.955605 -351.745006) (xy 137.932944 -351.794625)
			(xy 137.903452 -351.840514) (xy 137.86773 -351.881739) (xy 137.826504 -351.91746) (xy 137.780615 -351.94695)
			(xy 137.730995 -351.969609) (xy 137.678656 -351.984976) (xy 137.624662 -351.992737) (xy 137.597388 -351.9932)
			(xy 136.733788 -351.9932) (xy 136.706522 -351.992637) (xy 136.652545 -351.984875) (xy 136.600222 -351.96951)
			(xy 136.550618 -351.946855) (xy 136.504744 -351.917372) (xy 136.463531 -351.88166) (xy 136.427821 -351.840447)
			(xy 136.398339 -351.794571) (xy 136.375686 -351.744967) (xy 136.360323 -351.692643) (xy 136.352562 -351.638666)
			(xy 134.869714 -351.638666) (xy 134.869714 -351.638671) (xy 134.861952 -351.692657) (xy 134.846586 -351.74499)
			(xy 134.82393 -351.794603) (xy 134.794444 -351.840487) (xy 134.758728 -351.881708) (xy 134.71751 -351.917427)
			(xy 134.671628 -351.946917) (xy 134.622016 -351.969577) (xy 134.569685 -351.984946) (xy 134.515699 -351.992712)
			(xy 134.488428 -351.9932) (xy 133.624828 -351.9932) (xy 133.597558 -351.992663) (xy 133.543574 -351.984904)
			(xy 133.491243 -351.969542) (xy 133.441631 -351.946888) (xy 133.395749 -351.917404) (xy 133.354529 -351.881691)
			(xy 133.318812 -351.840474) (xy 133.289325 -351.794593) (xy 133.266668 -351.744983) (xy 133.251302 -351.692654)
			(xy 133.243539 -351.63867) (xy 131.760836 -351.63867) (xy 131.760836 -351.638675) (xy 131.753073 -351.69267)
			(xy 131.737703 -351.745011) (xy 131.715041 -351.794631) (xy 131.685547 -351.840521) (xy 131.649823 -351.881746)
			(xy 131.608595 -351.917467) (xy 131.562703 -351.946956) (xy 131.513081 -351.969614) (xy 131.460739 -351.984979)
			(xy 131.406743 -351.992739) (xy 131.379468 -351.9932) (xy 130.515868 -351.9932) (xy 130.488603 -351.992635)
			(xy 130.434628 -351.984871) (xy 130.382308 -351.969504) (xy 130.332706 -351.946849) (xy 130.286834 -351.917365)
			(xy 130.245624 -351.881653) (xy 130.209916 -351.84044) (xy 130.180436 -351.794566) (xy 130.157784 -351.744962)
			(xy 130.142422 -351.692641) (xy 130.134662 -351.638665) (xy 128.651814 -351.638665) (xy 128.651814 -351.638672)
			(xy 128.644051 -351.69266) (xy 128.628685 -351.744994) (xy 128.606027 -351.794609) (xy 128.576539 -351.840494)
			(xy 128.540821 -351.881715) (xy 128.4996 -351.917434) (xy 128.453716 -351.946923) (xy 128.404102 -351.969582)
			(xy 128.351768 -351.98495) (xy 128.29778 -351.992713) (xy 128.270508 -351.9932) (xy 127.406908 -351.9932)
			(xy 127.379639 -351.992661) (xy 127.325657 -351.984901) (xy 127.273329 -351.969537) (xy 127.223719 -351.946882)
			(xy 127.177839 -351.917397) (xy 127.136622 -351.881683) (xy 127.100907 -351.840467) (xy 127.071422 -351.794588)
			(xy 127.048766 -351.744979) (xy 127.033401 -351.692651) (xy 127.025639 -351.638669) (xy 125.542814 -351.638669)
			(xy 125.542814 -351.63867) (xy 125.535052 -351.692655) (xy 125.519688 -351.744986) (xy 125.497033 -351.794597)
			(xy 125.467549 -351.840481) (xy 125.431835 -351.881701) (xy 125.390619 -351.91742) (xy 125.34474 -351.94691)
			(xy 125.295131 -351.969571) (xy 125.242802 -351.984942) (xy 125.188818 -351.99271) (xy 125.161548 -351.9932)
			(xy 124.297948 -351.9932) (xy 124.270677 -351.992664) (xy 124.216691 -351.984908) (xy 124.164358 -351.969547)
			(xy 124.114743 -351.946895) (xy 124.068858 -351.917411) (xy 124.027636 -351.881698) (xy 123.991917 -351.84048)
			(xy 123.962428 -351.794599) (xy 123.939769 -351.744987) (xy 123.924402 -351.692656) (xy 123.91664 -351.63867)
			(xy 122.433936 -351.63867) (xy 122.433936 -351.638674) (xy 122.426173 -351.692668) (xy 122.410805 -351.745006)
			(xy 122.388144 -351.794625) (xy 122.358652 -351.840514) (xy 122.32293 -351.881739) (xy 122.281704 -351.91746)
			(xy 122.235815 -351.94695) (xy 122.186195 -351.969609) (xy 122.133856 -351.984976) (xy 122.079862 -351.992737)
			(xy 122.052588 -351.9932) (xy 121.188988 -351.9932) (xy 121.161722 -351.992637) (xy 121.107745 -351.984875)
			(xy 121.055422 -351.96951) (xy 121.005818 -351.946855) (xy 120.959944 -351.917372) (xy 120.918731 -351.88166)
			(xy 120.883021 -351.840447) (xy 120.853539 -351.794571) (xy 120.830886 -351.744967) (xy 120.815523 -351.692643)
			(xy 120.807762 -351.638666) (xy 119.324914 -351.638666) (xy 119.324914 -351.638671) (xy 119.317152 -351.692657)
			(xy 119.301786 -351.74499) (xy 119.27913 -351.794603) (xy 119.249644 -351.840487) (xy 119.213928 -351.881708)
			(xy 119.17271 -351.917427) (xy 119.126828 -351.946917) (xy 119.077216 -351.969577) (xy 119.024885 -351.984946)
			(xy 118.970899 -351.992712) (xy 118.943628 -351.9932) (xy 118.080028 -351.9932) (xy 118.052758 -351.992663)
			(xy 117.998774 -351.984904) (xy 117.946443 -351.969542) (xy 117.896831 -351.946888) (xy 117.850949 -351.917404)
			(xy 117.809729 -351.881691) (xy 117.774012 -351.840474) (xy 117.744525 -351.794593) (xy 117.721868 -351.744983)
			(xy 117.706502 -351.692654) (xy 117.698739 -351.63867) (xy 116.216036 -351.63867) (xy 116.216036 -351.638675)
			(xy 116.208273 -351.69267) (xy 116.192903 -351.745011) (xy 116.170241 -351.794631) (xy 116.140747 -351.840521)
			(xy 116.105023 -351.881746) (xy 116.063795 -351.917467) (xy 116.017903 -351.946956) (xy 115.968281 -351.969614)
			(xy 115.915939 -351.984979) (xy 115.861943 -351.992739) (xy 115.834668 -351.9932) (xy 114.971068 -351.9932)
			(xy 114.943803 -351.992635) (xy 114.889828 -351.984871) (xy 114.837508 -351.969504) (xy 114.787906 -351.946849)
			(xy 114.742034 -351.917365) (xy 114.700824 -351.881653) (xy 114.665116 -351.84044) (xy 114.635636 -351.794566)
			(xy 114.612984 -351.744962) (xy 114.597622 -351.692641) (xy 114.589862 -351.638665) (xy 113.107014 -351.638665)
			(xy 113.107014 -351.638672) (xy 113.099251 -351.69266) (xy 113.083885 -351.744994) (xy 113.061227 -351.794609)
			(xy 113.031739 -351.840494) (xy 112.996021 -351.881715) (xy 112.9548 -351.917434) (xy 112.908916 -351.946923)
			(xy 112.859302 -351.969582) (xy 112.806968 -351.98495) (xy 112.75298 -351.992713) (xy 112.725708 -351.9932)
			(xy 111.862108 -351.9932) (xy 111.834839 -351.992661) (xy 111.780857 -351.984901) (xy 111.728529 -351.969537)
			(xy 111.678919 -351.946882) (xy 111.633039 -351.917397) (xy 111.591822 -351.881683) (xy 111.556107 -351.840467)
			(xy 111.526622 -351.794588) (xy 111.503966 -351.744979) (xy 111.488601 -351.692651) (xy 111.480839 -351.638669)
			(xy 93.706714 -351.638669) (xy 93.706714 -351.63867) (xy 93.698952 -351.692655) (xy 93.683588 -351.744987)
			(xy 93.660932 -351.794599) (xy 93.631447 -351.840483) (xy 93.595733 -351.881703) (xy 93.554516 -351.917422)
			(xy 93.508636 -351.946912) (xy 93.459026 -351.969573) (xy 93.406697 -351.984943) (xy 93.352712 -351.992711)
			(xy 93.325442 -351.9932) (xy 92.461842 -351.9932) (xy 92.434572 -351.992663) (xy 92.380586 -351.984907)
			(xy 92.328253 -351.969546) (xy 92.27864 -351.946893) (xy 92.232755 -351.917409) (xy 92.191534 -351.881695)
			(xy 92.155816 -351.840478) (xy 92.126327 -351.794597) (xy 92.103669 -351.744986) (xy 92.088302 -351.692655)
			(xy 92.08054 -351.63867) (xy 90.597836 -351.63867) (xy 90.597836 -351.638675) (xy 90.590073 -351.692668)
			(xy 90.574704 -351.745008) (xy 90.552043 -351.794627) (xy 90.522551 -351.840516) (xy 90.486828 -351.881741)
			(xy 90.445602 -351.917462) (xy 90.399711 -351.946952) (xy 90.350091 -351.969611) (xy 90.297751 -351.984977)
			(xy 90.243757 -351.992738) (xy 90.216482 -351.9932) (xy 89.352882 -351.9932) (xy 89.325616 -351.992636)
			(xy 89.27164 -351.984873) (xy 89.219318 -351.969508) (xy 89.169715 -351.946853) (xy 89.123841 -351.91737)
			(xy 89.082629 -351.881658) (xy 89.04692 -351.840445) (xy 89.017438 -351.794569) (xy 88.994786 -351.744965)
			(xy 88.979423 -351.692642) (xy 88.971662 -351.638666) (xy 87.488814 -351.638666) (xy 87.488814 -351.638671)
			(xy 87.481052 -351.692658) (xy 87.465686 -351.744991) (xy 87.443029 -351.794605) (xy 87.413542 -351.840489)
			(xy 87.377826 -351.88171) (xy 87.336607 -351.917429) (xy 87.290724 -351.946919) (xy 87.241112 -351.969578)
			(xy 87.18878 -351.984947) (xy 87.134793 -351.992712) (xy 87.107522 -351.9932) (xy 86.243922 -351.9932)
			(xy 86.216653 -351.992662) (xy 86.162669 -351.984903) (xy 86.110339 -351.96954) (xy 86.060728 -351.946886)
			(xy 86.014846 -351.917402) (xy 85.973627 -351.881688) (xy 85.937911 -351.840472) (xy 85.908424 -351.794592)
			(xy 85.885767 -351.744982) (xy 85.870401 -351.692653) (xy 85.862639 -351.638669) (xy 84.379936 -351.638669)
			(xy 84.379936 -351.638675) (xy 84.372172 -351.692671) (xy 84.356803 -351.745012) (xy 84.33414 -351.794633)
			(xy 84.304646 -351.840523) (xy 84.268921 -351.881748) (xy 84.227692 -351.917469) (xy 84.181799 -351.946958)
			(xy 84.132176 -351.969616) (xy 84.079834 -351.98498) (xy 84.025837 -351.992739) (xy 83.998562 -351.9932)
			(xy 83.134962 -351.9932) (xy 83.107697 -351.992635) (xy 83.053723 -351.98487) (xy 83.001403 -351.969503)
			(xy 82.951803 -351.946847) (xy 82.905931 -351.917363) (xy 82.864722 -351.881651) (xy 82.829015 -351.840438)
			(xy 82.799535 -351.794564) (xy 82.776884 -351.744961) (xy 82.761522 -351.69264) (xy 82.753762 -351.638665)
			(xy 81.270913 -351.638665) (xy 81.270913 -351.638672) (xy 81.263151 -351.692661) (xy 81.247784 -351.744995)
			(xy 81.225126 -351.79461) (xy 81.195637 -351.840496) (xy 81.159919 -351.881717) (xy 81.118697 -351.917436)
			(xy 81.072812 -351.946925) (xy 81.023197 -351.969584) (xy 80.970863 -351.984951) (xy 80.916874 -351.992713)
			(xy 80.889602 -351.9932) (xy 80.026002 -351.9932) (xy 79.998734 -351.992661) (xy 79.944752 -351.9849)
			(xy 79.892424 -351.969535) (xy 79.842816 -351.94688) (xy 79.796936 -351.917395) (xy 79.75572 -351.881681)
			(xy 79.720006 -351.840465) (xy 79.690521 -351.794586) (xy 79.667866 -351.744978) (xy 79.652501 -351.69265)
			(xy 79.644739 -351.638668) (xy 78.161914 -351.638668) (xy 78.161914 -351.63867) (xy 78.154152 -351.692655)
			(xy 78.138788 -351.744987) (xy 78.116132 -351.794599) (xy 78.086647 -351.840483) (xy 78.050933 -351.881703)
			(xy 78.009716 -351.917422) (xy 77.963836 -351.946912) (xy 77.914226 -351.969573) (xy 77.861897 -351.984943)
			(xy 77.807912 -351.992711) (xy 77.780642 -351.9932) (xy 76.917042 -351.9932) (xy 76.889772 -351.992663)
			(xy 76.835786 -351.984907) (xy 76.783453 -351.969546) (xy 76.73384 -351.946893) (xy 76.687955 -351.917409)
			(xy 76.646734 -351.881695) (xy 76.611016 -351.840478) (xy 76.581527 -351.794597) (xy 76.558869 -351.744986)
			(xy 76.543502 -351.692655) (xy 76.53574 -351.63867) (xy 75.053036 -351.63867) (xy 75.053036 -351.638675)
			(xy 75.045273 -351.692668) (xy 75.029904 -351.745008) (xy 75.007243 -351.794627) (xy 74.977751 -351.840516)
			(xy 74.942028 -351.881741) (xy 74.900802 -351.917462) (xy 74.854911 -351.946952) (xy 74.805291 -351.969611)
			(xy 74.752951 -351.984977) (xy 74.698957 -351.992738) (xy 74.671682 -351.9932) (xy 73.808082 -351.9932)
			(xy 73.780816 -351.992636) (xy 73.72684 -351.984873) (xy 73.674518 -351.969508) (xy 73.624915 -351.946853)
			(xy 73.579041 -351.91737) (xy 73.537829 -351.881658) (xy 73.50212 -351.840445) (xy 73.472638 -351.794569)
			(xy 73.449986 -351.744965) (xy 73.434623 -351.692642) (xy 73.426862 -351.638666) (xy 71.944014 -351.638666)
			(xy 71.944014 -351.638671) (xy 71.936252 -351.692658) (xy 71.920886 -351.744991) (xy 71.898229 -351.794605)
			(xy 71.868742 -351.840489) (xy 71.833026 -351.88171) (xy 71.791807 -351.917429) (xy 71.745924 -351.946919)
			(xy 71.696312 -351.969578) (xy 71.64398 -351.984947) (xy 71.589993 -351.992712) (xy 71.562722 -351.9932)
			(xy 70.699122 -351.9932) (xy 70.671853 -351.992662) (xy 70.617869 -351.984903) (xy 70.565539 -351.96954)
			(xy 70.515928 -351.946886) (xy 70.470046 -351.917402) (xy 70.428827 -351.881688) (xy 70.393111 -351.840472)
			(xy 70.363624 -351.794592) (xy 70.340967 -351.744982) (xy 70.325601 -351.692653) (xy 70.317839 -351.638669)
			(xy 68.835136 -351.638669) (xy 68.835136 -351.638675) (xy 68.827372 -351.692671) (xy 68.812003 -351.745012)
			(xy 68.78934 -351.794633) (xy 68.759846 -351.840523) (xy 68.724121 -351.881748) (xy 68.682892 -351.917469)
			(xy 68.636999 -351.946958) (xy 68.587376 -351.969616) (xy 68.535034 -351.98498) (xy 68.481037 -351.992739)
			(xy 68.453762 -351.9932) (xy 67.590162 -351.9932) (xy 67.562897 -351.992635) (xy 67.508923 -351.98487)
			(xy 67.456603 -351.969503) (xy 67.407003 -351.946847) (xy 67.361131 -351.917363) (xy 67.319922 -351.881651)
			(xy 67.284215 -351.840438) (xy 67.254735 -351.794564) (xy 67.232084 -351.744961) (xy 67.216722 -351.69264)
			(xy 67.208962 -351.638665) (xy 65.726113 -351.638665) (xy 65.726113 -351.638672) (xy 65.718351 -351.692661)
			(xy 65.702984 -351.744995) (xy 65.680326 -351.79461) (xy 65.650837 -351.840496) (xy 65.615119 -351.881717)
			(xy 65.573897 -351.917436) (xy 65.528012 -351.946925) (xy 65.478397 -351.969584) (xy 65.426063 -351.984951)
			(xy 65.372074 -351.992713) (xy 65.344802 -351.9932) (xy 64.481202 -351.9932) (xy 64.453934 -351.992661)
			(xy 64.399952 -351.9849) (xy 64.347624 -351.969535) (xy 64.298016 -351.94688) (xy 64.252136 -351.917395)
			(xy 64.21092 -351.881681) (xy 64.175206 -351.840465) (xy 64.145721 -351.794586) (xy 64.123066 -351.744978)
			(xy 64.107701 -351.69265) (xy 64.099939 -351.638668) (xy 62.617114 -351.638668) (xy 62.617114 -351.63867)
			(xy 62.609352 -351.692655) (xy 62.593988 -351.744987) (xy 62.571332 -351.794599) (xy 62.541847 -351.840483)
			(xy 62.506133 -351.881703) (xy 62.464916 -351.917422) (xy 62.419036 -351.946912) (xy 62.369426 -351.969573)
			(xy 62.317097 -351.984943) (xy 62.263112 -351.992711) (xy 62.235842 -351.9932) (xy 61.372242 -351.9932)
			(xy 61.344972 -351.992663) (xy 61.290986 -351.984907) (xy 61.238653 -351.969546) (xy 61.18904 -351.946893)
			(xy 61.143155 -351.917409) (xy 61.101934 -351.881695) (xy 61.066216 -351.840478) (xy 61.036727 -351.794597)
			(xy 61.014069 -351.744986) (xy 60.998702 -351.692655) (xy 60.99094 -351.63867) (xy 51.666914 -351.63867)
			(xy 51.659152 -351.692655) (xy 51.643788 -351.744986) (xy 51.621133 -351.794597) (xy 51.591649 -351.840481)
			(xy 51.555935 -351.881701) (xy 51.514719 -351.91742) (xy 51.46884 -351.94691) (xy 51.419231 -351.969571)
			(xy 51.366902 -351.984942) (xy 51.312918 -351.99271) (xy 51.285648 -351.9932) (xy 50.422048 -351.9932)
			(xy 50.394777 -351.992664) (xy 50.340791 -351.984908) (xy 50.288458 -351.969547) (xy 50.238843 -351.946895)
			(xy 50.192958 -351.917411) (xy 50.151736 -351.881698) (xy 50.116017 -351.84048) (xy 50.086528 -351.794599)
			(xy 50.063869 -351.744987) (xy 50.048502 -351.692656) (xy 50.04074 -351.63867) (xy 48.558036 -351.63867)
			(xy 48.558036 -351.638674) (xy 48.550273 -351.692668) (xy 48.534905 -351.745006) (xy 48.512244 -351.794625)
			(xy 48.482752 -351.840514) (xy 48.44703 -351.881739) (xy 48.405804 -351.91746) (xy 48.359915 -351.94695)
			(xy 48.310295 -351.969609) (xy 48.257956 -351.984976) (xy 48.203962 -351.992737) (xy 48.176688 -351.9932)
			(xy 47.313088 -351.9932) (xy 47.285822 -351.992637) (xy 47.231845 -351.984875) (xy 47.179522 -351.96951)
			(xy 47.129918 -351.946855) (xy 47.084044 -351.917372) (xy 47.042831 -351.88166) (xy 47.007121 -351.840447)
			(xy 46.977639 -351.794571) (xy 46.954986 -351.744967) (xy 46.939623 -351.692643) (xy 46.931862 -351.638666)
			(xy 45.449014 -351.638666) (xy 45.449014 -351.638671) (xy 45.441252 -351.692657) (xy 45.425886 -351.74499)
			(xy 45.40323 -351.794603) (xy 45.373744 -351.840487) (xy 45.338028 -351.881708) (xy 45.29681 -351.917427)
			(xy 45.250928 -351.946917) (xy 45.201316 -351.969577) (xy 45.148985 -351.984946) (xy 45.094999 -351.992712)
			(xy 45.067728 -351.9932) (xy 44.204128 -351.9932) (xy 44.176858 -351.992663) (xy 44.122874 -351.984904)
			(xy 44.070543 -351.969542) (xy 44.020931 -351.946888) (xy 43.975049 -351.917404) (xy 43.933829 -351.881691)
			(xy 43.898112 -351.840474) (xy 43.868625 -351.794593) (xy 43.845968 -351.744983) (xy 43.830602 -351.692654)
			(xy 43.822839 -351.63867) (xy 42.340136 -351.63867) (xy 42.340136 -351.638675) (xy 42.332373 -351.69267)
			(xy 42.317003 -351.745011) (xy 42.294341 -351.794631) (xy 42.264847 -351.840521) (xy 42.229123 -351.881746)
			(xy 42.187895 -351.917467) (xy 42.142003 -351.946956) (xy 42.092381 -351.969614) (xy 42.040039 -351.984979)
			(xy 41.986043 -351.992739) (xy 41.958768 -351.9932) (xy 41.095168 -351.9932) (xy 41.067903 -351.992635)
			(xy 41.013928 -351.984871) (xy 40.961608 -351.969504) (xy 40.912006 -351.946849) (xy 40.866134 -351.917365)
			(xy 40.824924 -351.881653) (xy 40.789216 -351.84044) (xy 40.759736 -351.794566) (xy 40.737084 -351.744962)
			(xy 40.721722 -351.692641) (xy 40.713962 -351.638665) (xy 39.231114 -351.638665) (xy 39.231114 -351.638672)
			(xy 39.223351 -351.69266) (xy 39.207985 -351.744994) (xy 39.185327 -351.794609) (xy 39.155839 -351.840494)
			(xy 39.120121 -351.881715) (xy 39.0789 -351.917434) (xy 39.033016 -351.946923) (xy 38.983402 -351.969582)
			(xy 38.931068 -351.98495) (xy 38.87708 -351.992713) (xy 38.849808 -351.9932) (xy 37.986208 -351.9932)
			(xy 37.958939 -351.992661) (xy 37.904957 -351.984901) (xy 37.852629 -351.969537) (xy 37.803019 -351.946882)
			(xy 37.757139 -351.917397) (xy 37.715922 -351.881683) (xy 37.680207 -351.840467) (xy 37.650722 -351.794588)
			(xy 37.628066 -351.744979) (xy 37.612701 -351.692651) (xy 37.604939 -351.638669) (xy 36.122114 -351.638669)
			(xy 36.122114 -351.63867) (xy 36.114352 -351.692655) (xy 36.098988 -351.744986) (xy 36.076333 -351.794597)
			(xy 36.046849 -351.840481) (xy 36.011135 -351.881701) (xy 35.969919 -351.91742) (xy 35.92404 -351.94691)
			(xy 35.874431 -351.969571) (xy 35.822102 -351.984942) (xy 35.768118 -351.99271) (xy 35.740848 -351.9932)
			(xy 34.877248 -351.9932) (xy 34.849977 -351.992664) (xy 34.795991 -351.984908) (xy 34.743658 -351.969547)
			(xy 34.694043 -351.946895) (xy 34.648158 -351.917411) (xy 34.606936 -351.881698) (xy 34.571217 -351.84048)
			(xy 34.541728 -351.794599) (xy 34.519069 -351.744987) (xy 34.503702 -351.692656) (xy 34.49594 -351.63867)
			(xy 33.013236 -351.63867) (xy 33.013236 -351.638674) (xy 33.005473 -351.692668) (xy 32.990105 -351.745006)
			(xy 32.967444 -351.794625) (xy 32.937952 -351.840514) (xy 32.90223 -351.881739) (xy 32.861004 -351.91746)
			(xy 32.815115 -351.94695) (xy 32.765495 -351.969609) (xy 32.713156 -351.984976) (xy 32.659162 -351.992737)
			(xy 32.631888 -351.9932) (xy 31.768288 -351.9932) (xy 31.741022 -351.992637) (xy 31.687045 -351.984875)
			(xy 31.634722 -351.96951) (xy 31.585118 -351.946855) (xy 31.539244 -351.917372) (xy 31.498031 -351.88166)
			(xy 31.462321 -351.840447) (xy 31.432839 -351.794571) (xy 31.410186 -351.744967) (xy 31.394823 -351.692643)
			(xy 31.387062 -351.638666) (xy 29.904214 -351.638666) (xy 29.904214 -351.638671) (xy 29.896452 -351.692657)
			(xy 29.881086 -351.74499) (xy 29.85843 -351.794603) (xy 29.828944 -351.840487) (xy 29.793228 -351.881708)
			(xy 29.75201 -351.917427) (xy 29.706128 -351.946917) (xy 29.656516 -351.969577) (xy 29.604185 -351.984946)
			(xy 29.550199 -351.992712) (xy 29.522928 -351.9932) (xy 28.659328 -351.9932) (xy 28.632058 -351.992663)
			(xy 28.578074 -351.984904) (xy 28.525743 -351.969542) (xy 28.476131 -351.946888) (xy 28.430249 -351.917404)
			(xy 28.389029 -351.881691) (xy 28.353312 -351.840474) (xy 28.323825 -351.794593) (xy 28.301168 -351.744983)
			(xy 28.285802 -351.692654) (xy 28.278039 -351.63867) (xy 26.795336 -351.63867) (xy 26.795336 -351.638675)
			(xy 26.787573 -351.69267) (xy 26.772203 -351.745011) (xy 26.749541 -351.794631) (xy 26.720047 -351.840521)
			(xy 26.684323 -351.881746) (xy 26.643095 -351.917467) (xy 26.597203 -351.946956) (xy 26.547581 -351.969614)
			(xy 26.495239 -351.984979) (xy 26.441243 -351.992739) (xy 26.413968 -351.9932) (xy 25.550368 -351.9932)
			(xy 25.523103 -351.992635) (xy 25.469128 -351.984871) (xy 25.416808 -351.969504) (xy 25.367206 -351.946849)
			(xy 25.321334 -351.917365) (xy 25.280124 -351.881653) (xy 25.244416 -351.84044) (xy 25.214936 -351.794566)
			(xy 25.192284 -351.744962) (xy 25.176922 -351.692641) (xy 25.169162 -351.638665) (xy 23.686314 -351.638665)
			(xy 23.686314 -351.638672) (xy 23.678551 -351.69266) (xy 23.663185 -351.744994) (xy 23.640527 -351.794609)
			(xy 23.611039 -351.840494) (xy 23.575321 -351.881715) (xy 23.5341 -351.917434) (xy 23.488216 -351.946923)
			(xy 23.438602 -351.969582) (xy 23.386268 -351.98495) (xy 23.33228 -351.992713) (xy 23.305008 -351.9932)
			(xy 22.441408 -351.9932) (xy 22.414139 -351.992661) (xy 22.360157 -351.984901) (xy 22.307829 -351.969537)
			(xy 22.258219 -351.946882) (xy 22.212339 -351.917397) (xy 22.171122 -351.881683) (xy 22.135407 -351.840467)
			(xy 22.105922 -351.794588) (xy 22.083266 -351.744979) (xy 22.067901 -351.692651) (xy 22.060139 -351.638669)
			(xy 20.577347 -351.638669) (xy 20.577347 -351.638711) (xy 20.569584 -351.692698) (xy 20.554218 -351.74503)
			(xy 20.53156 -351.794643) (xy 20.502073 -351.840527) (xy 20.466355 -351.881747) (xy 20.425135 -351.917464)
			(xy 20.379252 -351.946951) (xy 20.329638 -351.969609) (xy 20.277306 -351.984975) (xy 20.223319 -351.992737)
			(xy 20.196048 -351.9932) (xy 19.332448 -351.9932) (xy 19.305179 -351.992717) (xy 19.251195 -351.984955)
			(xy 19.198865 -351.96959) (xy 19.149255 -351.946933) (xy 19.103374 -351.917447) (xy 19.062157 -351.881732)
			(xy 19.026441 -351.840514) (xy 18.996956 -351.794633) (xy 18.974299 -351.745023) (xy 18.958934 -351.692693)
			(xy 18.951172 -351.638709) (xy 0.508 -351.638709) (xy 0.508 -354.759373) (xy 22.060084 -354.759373)
			(xy 22.060084 -354.704827) (xy 22.067846 -354.650837) (xy 22.083214 -354.598501) (xy 22.105873 -354.548885)
			(xy 22.135363 -354.502999) (xy 22.171083 -354.461777) (xy 22.212306 -354.426058) (xy 22.258192 -354.396569)
			(xy 22.307809 -354.373911) (xy 22.360145 -354.358545) (xy 22.414135 -354.350783) (xy 22.441408 -354.35032)
			(xy 23.305008 -354.35032) (xy 23.332276 -354.350843) (xy 23.386256 -354.358605) (xy 23.438582 -354.37397)
			(xy 23.488189 -354.396626) (xy 23.534067 -354.426111) (xy 23.575281 -354.461824) (xy 23.610994 -354.50304)
			(xy 23.640478 -354.548918) (xy 23.663132 -354.598525) (xy 23.678497 -354.650852) (xy 23.686258 -354.704832)
			(xy 23.686258 -354.759368) (xy 23.686258 -354.759369) (xy 25.169106 -354.759369) (xy 25.169106 -354.704831)
			(xy 25.176868 -354.650847) (xy 25.192232 -354.598518) (xy 25.214887 -354.548908) (xy 25.244371 -354.503026)
			(xy 25.280085 -354.461807) (xy 25.3213 -354.42609) (xy 25.36718 -354.396602) (xy 25.416788 -354.373943)
			(xy 25.469116 -354.358574) (xy 25.523099 -354.350809) (xy 25.550368 -354.35032) (xy 26.413968 -354.35032)
			(xy 26.441239 -354.350817) (xy 26.495227 -354.358575) (xy 26.547561 -354.373938) (xy 26.597176 -354.396593)
			(xy 26.643061 -354.426078) (xy 26.684283 -354.461794) (xy 26.720003 -354.503013) (xy 26.749492 -354.548896)
			(xy 26.772151 -354.598509) (xy 26.787518 -354.650842) (xy 26.79528 -354.704829) (xy 26.79528 -354.759371)
			(xy 26.79528 -354.759374) (xy 28.277984 -354.759374) (xy 28.277984 -354.704826) (xy 28.285747 -354.650835)
			(xy 28.301115 -354.598497) (xy 28.323776 -354.54888) (xy 28.353268 -354.502993) (xy 28.38899 -354.46177)
			(xy 28.430215 -354.426051) (xy 28.476104 -354.396562) (xy 28.525723 -354.373905) (xy 28.578062 -354.358541)
			(xy 28.632054 -354.350782) (xy 28.659328 -354.35032) (xy 29.522928 -354.35032) (xy 29.550195 -354.350844)
			(xy 29.604173 -354.358609) (xy 29.656497 -354.373976) (xy 29.706101 -354.396633) (xy 29.751976 -354.426118)
			(xy 29.793188 -354.461831) (xy 29.828899 -354.503046) (xy 29.858381 -354.548924) (xy 29.881034 -354.59853)
			(xy 29.896397 -354.650855) (xy 29.904158 -354.704833) (xy 29.904158 -354.759367) (xy 29.904158 -354.75937)
			(xy 31.387006 -354.75937) (xy 31.387006 -354.70483) (xy 31.394768 -354.650845) (xy 31.410134 -354.598514)
			(xy 31.43279 -354.548902) (xy 31.462276 -354.50302) (xy 31.497992 -354.4618) (xy 31.53921 -354.426083)
			(xy 31.585091 -354.396596) (xy 31.634703 -354.373938) (xy 31.687033 -354.358571) (xy 31.741018 -354.350807)
			(xy 31.768288 -354.35032) (xy 32.631888 -354.35032) (xy 32.659158 -354.350819) (xy 32.713144 -354.358579)
			(xy 32.765476 -354.373944) (xy 32.815088 -354.396599) (xy 32.860971 -354.426085) (xy 32.902191 -354.461801)
			(xy 32.937908 -354.503019) (xy 32.967395 -354.548902) (xy 32.990052 -354.598513) (xy 33.005418 -354.650844)
			(xy 33.013181 -354.70483) (xy 33.013181 -354.75937) (xy 33.01318 -354.759374) (xy 34.495884 -354.759374)
			(xy 34.495884 -354.704826) (xy 34.503647 -354.650832) (xy 34.519017 -354.598493) (xy 34.541679 -354.548874)
			(xy 34.571172 -354.502986) (xy 34.606897 -354.461763) (xy 34.648125 -354.426044) (xy 34.694016 -354.396556)
			(xy 34.743638 -354.3739) (xy 34.795979 -354.358537) (xy 34.849973 -354.35078) (xy 34.877248 -354.35032)
			(xy 35.740848 -354.35032) (xy 35.768114 -354.350846) (xy 35.82209 -354.358613) (xy 35.874411 -354.373981)
			(xy 35.924013 -354.396639) (xy 35.969886 -354.426125) (xy 36.011095 -354.461839) (xy 36.046804 -354.503053)
			(xy 36.076284 -354.548929) (xy 36.098936 -354.598534) (xy 36.114298 -354.650857) (xy 36.122058 -354.704834)
			(xy 36.122058 -354.759366) (xy 36.122057 -354.759373) (xy 37.604884 -354.759373) (xy 37.604884 -354.704827)
			(xy 37.612646 -354.650837) (xy 37.628014 -354.598501) (xy 37.650673 -354.548885) (xy 37.680163 -354.502999)
			(xy 37.715883 -354.461777) (xy 37.757106 -354.426058) (xy 37.802992 -354.396569) (xy 37.852609 -354.373911)
			(xy 37.904945 -354.358545) (xy 37.958935 -354.350783) (xy 37.986208 -354.35032) (xy 38.849808 -354.35032)
			(xy 38.877076 -354.350843) (xy 38.931056 -354.358605) (xy 38.983382 -354.37397) (xy 39.032989 -354.396626)
			(xy 39.078867 -354.426111) (xy 39.120081 -354.461824) (xy 39.155794 -354.50304) (xy 39.185278 -354.548918)
			(xy 39.207932 -354.598525) (xy 39.223297 -354.650852) (xy 39.231058 -354.704832) (xy 39.231058 -354.759368)
			(xy 39.231058 -354.759369) (xy 40.713906 -354.759369) (xy 40.713906 -354.704831) (xy 40.721668 -354.650847)
			(xy 40.737032 -354.598518) (xy 40.759687 -354.548908) (xy 40.789171 -354.503026) (xy 40.824885 -354.461807)
			(xy 40.8661 -354.42609) (xy 40.91198 -354.396602) (xy 40.961588 -354.373943) (xy 41.013916 -354.358574)
			(xy 41.067899 -354.350809) (xy 41.095168 -354.35032) (xy 41.958768 -354.35032) (xy 41.986039 -354.350817)
			(xy 42.040027 -354.358575) (xy 42.092361 -354.373938) (xy 42.141976 -354.396593) (xy 42.187861 -354.426078)
			(xy 42.229083 -354.461794) (xy 42.264803 -354.503013) (xy 42.294292 -354.548896) (xy 42.316951 -354.598509)
			(xy 42.332318 -354.650842) (xy 42.34008 -354.704829) (xy 42.34008 -354.759371) (xy 42.34008 -354.759374)
			(xy 43.822784 -354.759374) (xy 43.822784 -354.704826) (xy 43.830547 -354.650835) (xy 43.845915 -354.598497)
			(xy 43.868576 -354.54888) (xy 43.898068 -354.502993) (xy 43.93379 -354.46177) (xy 43.975015 -354.426051)
			(xy 44.020904 -354.396562) (xy 44.070523 -354.373905) (xy 44.122862 -354.358541) (xy 44.176854 -354.350782)
			(xy 44.204128 -354.35032) (xy 45.067728 -354.35032) (xy 45.094995 -354.350844) (xy 45.148973 -354.358609)
			(xy 45.201297 -354.373976) (xy 45.250901 -354.396633) (xy 45.296776 -354.426118) (xy 45.337988 -354.461831)
			(xy 45.373699 -354.503046) (xy 45.403181 -354.548924) (xy 45.425834 -354.59853) (xy 45.441197 -354.650855)
			(xy 45.448958 -354.704833) (xy 45.448958 -354.759367) (xy 45.448958 -354.75937) (xy 46.931806 -354.75937)
			(xy 46.931806 -354.70483) (xy 46.939568 -354.650845) (xy 46.954934 -354.598514) (xy 46.97759 -354.548902)
			(xy 47.007076 -354.50302) (xy 47.042792 -354.4618) (xy 47.08401 -354.426083) (xy 47.129891 -354.396596)
			(xy 47.179503 -354.373938) (xy 47.231833 -354.358571) (xy 47.285818 -354.350807) (xy 47.313088 -354.35032)
			(xy 48.176688 -354.35032) (xy 48.203958 -354.350819) (xy 48.257944 -354.358579) (xy 48.310276 -354.373944)
			(xy 48.359888 -354.396599) (xy 48.405771 -354.426085) (xy 48.446991 -354.461801) (xy 48.482708 -354.503019)
			(xy 48.512195 -354.548902) (xy 48.534852 -354.598513) (xy 48.550218 -354.650844) (xy 48.557981 -354.70483)
			(xy 48.557981 -354.75937) (xy 48.55798 -354.759374) (xy 50.040684 -354.759374) (xy 50.040684 -354.704826)
			(xy 50.048447 -354.650832) (xy 50.063817 -354.598493) (xy 50.086479 -354.548874) (xy 50.115972 -354.502986)
			(xy 50.151697 -354.461763) (xy 50.192925 -354.426044) (xy 50.238816 -354.396556) (xy 50.288438 -354.3739)
			(xy 50.340779 -354.358537) (xy 50.394773 -354.35078) (xy 50.422048 -354.35032) (xy 51.285648 -354.35032)
			(xy 51.312914 -354.350846) (xy 51.36689 -354.358613) (xy 51.419211 -354.373981) (xy 51.468813 -354.396639)
			(xy 51.514686 -354.426125) (xy 51.555895 -354.461839) (xy 51.591604 -354.503053) (xy 51.621084 -354.548929)
			(xy 51.643736 -354.598534) (xy 51.659098 -354.650857) (xy 51.666858 -354.704834) (xy 51.666858 -354.759366)
			(xy 51.666857 -354.759372) (xy 64.099884 -354.759372) (xy 64.099884 -354.704828) (xy 64.107646 -354.650838)
			(xy 64.123013 -354.598503) (xy 64.145672 -354.548887) (xy 64.175161 -354.503001) (xy 64.210881 -354.461779)
			(xy 64.252103 -354.42606) (xy 64.297989 -354.396571) (xy 64.347605 -354.373912) (xy 64.39994 -354.358546)
			(xy 64.45393 -354.350783) (xy 64.481202 -354.35032) (xy 65.344802 -354.35032) (xy 65.37207 -354.350843)
			(xy 65.426051 -354.358604) (xy 65.478378 -354.373969) (xy 65.527985 -354.396624) (xy 65.573864 -354.426109)
			(xy 65.615079 -354.461822) (xy 65.650793 -354.503038) (xy 65.680277 -354.548917) (xy 65.702932 -354.598524)
			(xy 65.718296 -354.650851) (xy 65.726058 -354.704832) (xy 65.726058 -354.759368) (xy 65.726058 -354.759369)
			(xy 67.208906 -354.759369) (xy 67.208906 -354.704831) (xy 67.216667 -354.650848) (xy 67.232032 -354.598519)
			(xy 67.254686 -354.548909) (xy 67.28417 -354.503028) (xy 67.319883 -354.46181) (xy 67.361098 -354.426093)
			(xy 67.406976 -354.396604) (xy 67.456584 -354.373945) (xy 67.508911 -354.358575) (xy 67.562893 -354.350809)
			(xy 67.590162 -354.35032) (xy 68.453762 -354.35032) (xy 68.481033 -354.350817) (xy 68.535022 -354.358574)
			(xy 68.587357 -354.373936) (xy 68.636972 -354.396591) (xy 68.682859 -354.426076) (xy 68.724081 -354.461792)
			(xy 68.759801 -354.503011) (xy 68.789291 -354.548894) (xy 68.81195 -354.598508) (xy 68.827318 -354.650841)
			(xy 68.83508 -354.704829) (xy 68.83508 -354.759371) (xy 68.83508 -354.759373) (xy 70.317784 -354.759373)
			(xy 70.317784 -354.704827) (xy 70.325547 -354.650835) (xy 70.340915 -354.598498) (xy 70.363575 -354.548882)
			(xy 70.393066 -354.502995) (xy 70.428788 -354.461772) (xy 70.470012 -354.426053) (xy 70.515901 -354.396564)
			(xy 70.565519 -354.373907) (xy 70.617857 -354.358542) (xy 70.671849 -354.350782) (xy 70.699122 -354.35032)
			(xy 71.562722 -354.35032) (xy 71.589989 -354.350844) (xy 71.643968 -354.358608) (xy 71.696292 -354.373974)
			(xy 71.745897 -354.396631) (xy 71.791773 -354.426116) (xy 71.832986 -354.461829) (xy 71.868697 -354.503044)
			(xy 71.89818 -354.548922) (xy 71.920833 -354.598528) (xy 71.936197 -354.650854) (xy 71.943958 -354.704833)
			(xy 71.943958 -354.759367) (xy 71.943958 -354.75937) (xy 73.426806 -354.75937) (xy 73.426806 -354.70483)
			(xy 73.434568 -354.650846) (xy 73.449933 -354.598515) (xy 73.472589 -354.548904) (xy 73.502075 -354.503022)
			(xy 73.53779 -354.461802) (xy 73.579007 -354.426085) (xy 73.624888 -354.396598) (xy 73.674498 -354.373939)
			(xy 73.726828 -354.358572) (xy 73.780812 -354.350808) (xy 73.808082 -354.35032) (xy 74.671682 -354.35032)
			(xy 74.698953 -354.350818) (xy 74.752939 -354.358578) (xy 74.805271 -354.373942) (xy 74.854884 -354.396597)
			(xy 74.900768 -354.426083) (xy 74.941988 -354.461799) (xy 74.977706 -354.503018) (xy 75.007194 -354.5489)
			(xy 75.029852 -354.598512) (xy 75.045218 -354.650844) (xy 75.052981 -354.704829) (xy 75.052981 -354.759371)
			(xy 75.052981 -354.759374) (xy 76.535684 -354.759374) (xy 76.535684 -354.704826) (xy 76.543447 -354.650833)
			(xy 76.558816 -354.598494) (xy 76.581478 -354.548876) (xy 76.610971 -354.502988) (xy 76.646695 -354.461765)
			(xy 76.687922 -354.426046) (xy 76.733813 -354.396558) (xy 76.783434 -354.373902) (xy 76.835774 -354.358538)
			(xy 76.889768 -354.350781) (xy 76.917042 -354.35032) (xy 77.780642 -354.35032) (xy 77.807908 -354.350845)
			(xy 77.861885 -354.358611) (xy 77.914207 -354.37398) (xy 77.963809 -354.396637) (xy 78.009683 -354.426123)
			(xy 78.050893 -354.461836) (xy 78.086602 -354.503051) (xy 78.116083 -354.548928) (xy 78.138735 -354.598533)
			(xy 78.154098 -354.650856) (xy 78.161858 -354.704834) (xy 78.161858 -354.759366) (xy 78.161857 -354.759372)
			(xy 79.644684 -354.759372) (xy 79.644684 -354.704828) (xy 79.652446 -354.650838) (xy 79.667813 -354.598503)
			(xy 79.690472 -354.548887) (xy 79.719961 -354.503001) (xy 79.755681 -354.461779) (xy 79.796903 -354.42606)
			(xy 79.842789 -354.396571) (xy 79.892405 -354.373912) (xy 79.94474 -354.358546) (xy 79.99873 -354.350783)
			(xy 80.026002 -354.35032) (xy 80.889602 -354.35032) (xy 80.91687 -354.350843) (xy 80.970851 -354.358604)
			(xy 81.023178 -354.373969) (xy 81.072785 -354.396624) (xy 81.118664 -354.426109) (xy 81.159879 -354.461822)
			(xy 81.195593 -354.503038) (xy 81.225077 -354.548917) (xy 81.247732 -354.598524) (xy 81.263096 -354.650851)
			(xy 81.270858 -354.704832) (xy 81.270858 -354.759368) (xy 81.270858 -354.759369) (xy 82.753706 -354.759369)
			(xy 82.753706 -354.704831) (xy 82.761467 -354.650848) (xy 82.776832 -354.598519) (xy 82.799486 -354.548909)
			(xy 82.82897 -354.503028) (xy 82.864683 -354.46181) (xy 82.905898 -354.426093) (xy 82.951776 -354.396604)
			(xy 83.001384 -354.373945) (xy 83.053711 -354.358575) (xy 83.107693 -354.350809) (xy 83.134962 -354.35032)
			(xy 83.998562 -354.35032) (xy 84.025833 -354.350817) (xy 84.079822 -354.358574) (xy 84.132157 -354.373936)
			(xy 84.181772 -354.396591) (xy 84.227659 -354.426076) (xy 84.268881 -354.461792) (xy 84.304601 -354.503011)
			(xy 84.334091 -354.548894) (xy 84.35675 -354.598508) (xy 84.372118 -354.650841) (xy 84.37988 -354.704829)
			(xy 84.37988 -354.759371) (xy 84.37988 -354.759373) (xy 85.862584 -354.759373) (xy 85.862584 -354.704827)
			(xy 85.870347 -354.650835) (xy 85.885715 -354.598498) (xy 85.908375 -354.548882) (xy 85.937866 -354.502995)
			(xy 85.973588 -354.461772) (xy 86.014812 -354.426053) (xy 86.060701 -354.396564) (xy 86.110319 -354.373907)
			(xy 86.162657 -354.358542) (xy 86.216649 -354.350782) (xy 86.243922 -354.35032) (xy 87.107522 -354.35032)
			(xy 87.134789 -354.350844) (xy 87.188768 -354.358608) (xy 87.241092 -354.373974) (xy 87.290697 -354.396631)
			(xy 87.336573 -354.426116) (xy 87.377786 -354.461829) (xy 87.413497 -354.503044) (xy 87.44298 -354.548922)
			(xy 87.465633 -354.598528) (xy 87.480997 -354.650854) (xy 87.488758 -354.704833) (xy 87.488758 -354.759367)
			(xy 87.488758 -354.75937) (xy 88.971606 -354.75937) (xy 88.971606 -354.70483) (xy 88.979368 -354.650846)
			(xy 88.994733 -354.598515) (xy 89.017389 -354.548904) (xy 89.046875 -354.503022) (xy 89.08259 -354.461802)
			(xy 89.123807 -354.426085) (xy 89.169688 -354.396598) (xy 89.219298 -354.373939) (xy 89.271628 -354.358572)
			(xy 89.325612 -354.350808) (xy 89.352882 -354.35032) (xy 90.216482 -354.35032) (xy 90.243753 -354.350818)
			(xy 90.297739 -354.358578) (xy 90.350071 -354.373942) (xy 90.399684 -354.396597) (xy 90.445568 -354.426083)
			(xy 90.486788 -354.461799) (xy 90.522506 -354.503018) (xy 90.551994 -354.5489) (xy 90.574652 -354.598512)
			(xy 90.590018 -354.650844) (xy 90.597781 -354.704829) (xy 90.597781 -354.759371) (xy 90.597781 -354.759374)
			(xy 92.080484 -354.759374) (xy 92.080484 -354.704826) (xy 92.088247 -354.650833) (xy 92.103616 -354.598494)
			(xy 92.126278 -354.548876) (xy 92.155771 -354.502988) (xy 92.191495 -354.461765) (xy 92.232722 -354.426046)
			(xy 92.278613 -354.396558) (xy 92.328234 -354.373902) (xy 92.380574 -354.358538) (xy 92.434568 -354.350781)
			(xy 92.461842 -354.35032) (xy 93.325442 -354.35032) (xy 93.352708 -354.350845) (xy 93.406685 -354.358611)
			(xy 93.459007 -354.37398) (xy 93.508609 -354.396637) (xy 93.554483 -354.426123) (xy 93.595693 -354.461836)
			(xy 93.631402 -354.503051) (xy 93.660883 -354.548928) (xy 93.683535 -354.598533) (xy 93.698898 -354.650856)
			(xy 93.706658 -354.704834) (xy 93.706658 -354.759366) (xy 93.706658 -354.759369) (xy 114.589806 -354.759369)
			(xy 114.589806 -354.704831) (xy 114.597568 -354.650847) (xy 114.612932 -354.598518) (xy 114.635587 -354.548908)
			(xy 114.665071 -354.503026) (xy 114.700785 -354.461807) (xy 114.742 -354.42609) (xy 114.78788 -354.396602)
			(xy 114.837488 -354.373943) (xy 114.889816 -354.358574) (xy 114.943799 -354.350809) (xy 114.971068 -354.35032)
			(xy 115.834668 -354.35032) (xy 115.861939 -354.350817) (xy 115.915927 -354.358575) (xy 115.968261 -354.373938)
			(xy 116.017876 -354.396593) (xy 116.063761 -354.426078) (xy 116.104983 -354.461794) (xy 116.140703 -354.503013)
			(xy 116.170192 -354.548896) (xy 116.192851 -354.598509) (xy 116.208218 -354.650842) (xy 116.21598 -354.704829)
			(xy 116.21598 -354.759371) (xy 116.21598 -354.759374) (xy 117.698684 -354.759374) (xy 117.698684 -354.704826)
			(xy 117.706447 -354.650835) (xy 117.721815 -354.598497) (xy 117.744476 -354.54888) (xy 117.773968 -354.502993)
			(xy 117.80969 -354.46177) (xy 117.850915 -354.426051) (xy 117.896804 -354.396562) (xy 117.946423 -354.373905)
			(xy 117.998762 -354.358541) (xy 118.052754 -354.350782) (xy 118.080028 -354.35032) (xy 118.943628 -354.35032)
			(xy 118.970895 -354.350844) (xy 119.024873 -354.358609) (xy 119.077197 -354.373976) (xy 119.126801 -354.396633)
			(xy 119.172676 -354.426118) (xy 119.213888 -354.461831) (xy 119.249599 -354.503046) (xy 119.279081 -354.548924)
			(xy 119.301734 -354.59853) (xy 119.317097 -354.650855) (xy 119.324858 -354.704833) (xy 119.324858 -354.759367)
			(xy 119.324858 -354.75937) (xy 120.807706 -354.75937) (xy 120.807706 -354.70483) (xy 120.815468 -354.650845)
			(xy 120.830834 -354.598514) (xy 120.85349 -354.548902) (xy 120.882976 -354.50302) (xy 120.918692 -354.4618)
			(xy 120.95991 -354.426083) (xy 121.005791 -354.396596) (xy 121.055403 -354.373938) (xy 121.107733 -354.358571)
			(xy 121.161718 -354.350807) (xy 121.188988 -354.35032) (xy 122.052588 -354.35032) (xy 122.079858 -354.350819)
			(xy 122.133844 -354.358579) (xy 122.186176 -354.373944) (xy 122.235788 -354.396599) (xy 122.281671 -354.426085)
			(xy 122.322891 -354.461801) (xy 122.358608 -354.503019) (xy 122.388095 -354.548902) (xy 122.410752 -354.598513)
			(xy 122.426118 -354.650844) (xy 122.433881 -354.70483) (xy 122.433881 -354.75937) (xy 122.43388 -354.759374)
			(xy 123.916584 -354.759374) (xy 123.916584 -354.704826) (xy 123.924347 -354.650832) (xy 123.939717 -354.598493)
			(xy 123.962379 -354.548874) (xy 123.991872 -354.502986) (xy 124.027597 -354.461763) (xy 124.068825 -354.426044)
			(xy 124.114716 -354.396556) (xy 124.164338 -354.3739) (xy 124.216679 -354.358537) (xy 124.270673 -354.35078)
			(xy 124.297948 -354.35032) (xy 125.161548 -354.35032) (xy 125.188814 -354.350846) (xy 125.24279 -354.358613)
			(xy 125.295111 -354.373981) (xy 125.344713 -354.396639) (xy 125.390586 -354.426125) (xy 125.431795 -354.461839)
			(xy 125.467504 -354.503053) (xy 125.496984 -354.548929) (xy 125.519636 -354.598534) (xy 125.534998 -354.650857)
			(xy 125.542758 -354.704834) (xy 125.542758 -354.759366) (xy 125.542757 -354.759373) (xy 127.025584 -354.759373)
			(xy 127.025584 -354.704827) (xy 127.033346 -354.650837) (xy 127.048714 -354.598501) (xy 127.071373 -354.548885)
			(xy 127.100863 -354.502999) (xy 127.136583 -354.461777) (xy 127.177806 -354.426058) (xy 127.223692 -354.396569)
			(xy 127.273309 -354.373911) (xy 127.325645 -354.358545) (xy 127.379635 -354.350783) (xy 127.406908 -354.35032)
			(xy 128.270508 -354.35032) (xy 128.297776 -354.350843) (xy 128.351756 -354.358605) (xy 128.404082 -354.37397)
			(xy 128.453689 -354.396626) (xy 128.499567 -354.426111) (xy 128.540781 -354.461824) (xy 128.576494 -354.50304)
			(xy 128.605978 -354.548918) (xy 128.628632 -354.598525) (xy 128.643997 -354.650852) (xy 128.651758 -354.704832)
			(xy 128.651758 -354.759368) (xy 128.651758 -354.759369) (xy 130.134606 -354.759369) (xy 130.134606 -354.704831)
			(xy 130.142368 -354.650847) (xy 130.157732 -354.598518) (xy 130.180387 -354.548908) (xy 130.209871 -354.503026)
			(xy 130.245585 -354.461807) (xy 130.2868 -354.42609) (xy 130.33268 -354.396602) (xy 130.382288 -354.373943)
			(xy 130.434616 -354.358574) (xy 130.488599 -354.350809) (xy 130.515868 -354.35032) (xy 131.379468 -354.35032)
			(xy 131.406739 -354.350817) (xy 131.460727 -354.358575) (xy 131.513061 -354.373938) (xy 131.562676 -354.396593)
			(xy 131.608561 -354.426078) (xy 131.649783 -354.461794) (xy 131.685503 -354.503013) (xy 131.714992 -354.548896)
			(xy 131.737651 -354.598509) (xy 131.753018 -354.650842) (xy 131.76078 -354.704829) (xy 131.76078 -354.759371)
			(xy 131.76078 -354.759374) (xy 133.243484 -354.759374) (xy 133.243484 -354.704826) (xy 133.251247 -354.650835)
			(xy 133.266615 -354.598497) (xy 133.289276 -354.54888) (xy 133.318768 -354.502993) (xy 133.35449 -354.46177)
			(xy 133.395715 -354.426051) (xy 133.441604 -354.396562) (xy 133.491223 -354.373905) (xy 133.543562 -354.358541)
			(xy 133.597554 -354.350782) (xy 133.624828 -354.35032) (xy 134.488428 -354.35032) (xy 134.515695 -354.350844)
			(xy 134.569673 -354.358609) (xy 134.621997 -354.373976) (xy 134.671601 -354.396633) (xy 134.717476 -354.426118)
			(xy 134.758688 -354.461831) (xy 134.794399 -354.503046) (xy 134.823881 -354.548924) (xy 134.846534 -354.59853)
			(xy 134.861897 -354.650855) (xy 134.869658 -354.704833) (xy 134.869658 -354.759367) (xy 134.869658 -354.75937)
			(xy 136.352506 -354.75937) (xy 136.352506 -354.70483) (xy 136.360268 -354.650845) (xy 136.375634 -354.598514)
			(xy 136.39829 -354.548902) (xy 136.427776 -354.50302) (xy 136.463492 -354.4618) (xy 136.50471 -354.426083)
			(xy 136.550591 -354.396596) (xy 136.600203 -354.373938) (xy 136.652533 -354.358571) (xy 136.706518 -354.350807)
			(xy 136.733788 -354.35032) (xy 137.597388 -354.35032) (xy 137.624658 -354.350819) (xy 137.678644 -354.358579)
			(xy 137.730976 -354.373944) (xy 137.780588 -354.396599) (xy 137.826471 -354.426085) (xy 137.867691 -354.461801)
			(xy 137.903408 -354.503019) (xy 137.932895 -354.548902) (xy 137.955552 -354.598513) (xy 137.970918 -354.650844)
			(xy 137.978681 -354.70483) (xy 137.978681 -354.75937) (xy 137.97868 -354.759374) (xy 139.461384 -354.759374)
			(xy 139.461384 -354.704826) (xy 139.469147 -354.650832) (xy 139.484517 -354.598493) (xy 139.507179 -354.548874)
			(xy 139.536672 -354.502986) (xy 139.572397 -354.461763) (xy 139.613625 -354.426044) (xy 139.659516 -354.396556)
			(xy 139.709138 -354.3739) (xy 139.761479 -354.358537) (xy 139.815473 -354.35078) (xy 139.842748 -354.35032)
			(xy 140.706348 -354.35032) (xy 140.733614 -354.350846) (xy 140.78759 -354.358613) (xy 140.839911 -354.373981)
			(xy 140.889513 -354.396639) (xy 140.935386 -354.426125) (xy 140.976595 -354.461839) (xy 141.012304 -354.503053)
			(xy 141.041784 -354.548929) (xy 141.064436 -354.598534) (xy 141.079798 -354.650857) (xy 141.087558 -354.704834)
			(xy 141.087558 -354.759366) (xy 141.087557 -354.759373) (xy 142.570384 -354.759373) (xy 142.570384 -354.704827)
			(xy 142.578146 -354.650837) (xy 142.593514 -354.598501) (xy 142.616173 -354.548885) (xy 142.645663 -354.502999)
			(xy 142.681383 -354.461777) (xy 142.722606 -354.426058) (xy 142.768492 -354.396569) (xy 142.818109 -354.373911)
			(xy 142.870445 -354.358545) (xy 142.924435 -354.350783) (xy 142.951708 -354.35032) (xy 143.815308 -354.35032)
			(xy 143.842576 -354.350843) (xy 143.896556 -354.358605) (xy 143.948882 -354.37397) (xy 143.998489 -354.396626)
			(xy 144.044367 -354.426111) (xy 144.085581 -354.461824) (xy 144.121294 -354.50304) (xy 144.150778 -354.548918)
			(xy 144.173432 -354.598525) (xy 144.188797 -354.650852) (xy 144.196558 -354.704832) (xy 144.196558 -354.759368)
			(xy 158.695906 -354.759368) (xy 158.695906 -354.704832) (xy 158.703667 -354.65085) (xy 158.719031 -354.598521)
			(xy 158.741685 -354.548912) (xy 158.771167 -354.503031) (xy 158.806879 -354.461813) (xy 158.848093 -354.426096)
			(xy 158.89397 -354.396608) (xy 158.943576 -354.373948) (xy 158.995903 -354.358577) (xy 159.049884 -354.35081)
			(xy 159.077152 -354.35032) (xy 159.940752 -354.35032) (xy 159.968024 -354.350816) (xy 160.022013 -354.358572)
			(xy 160.074349 -354.373934) (xy 160.123966 -354.396588) (xy 160.169854 -354.426072) (xy 160.211078 -354.461788)
			(xy 160.246799 -354.503008) (xy 160.276289 -354.548891) (xy 160.298949 -354.598506) (xy 160.314317 -354.65084)
			(xy 160.32208 -354.704828) (xy 160.32208 -354.759372) (xy 160.32208 -354.759373) (xy 161.804784 -354.759373)
			(xy 161.804784 -354.704827) (xy 161.812546 -354.650837) (xy 161.827914 -354.598501) (xy 161.850573 -354.548884)
			(xy 161.880064 -354.502998) (xy 161.915784 -354.461776) (xy 161.957008 -354.426056) (xy 162.002895 -354.396568)
			(xy 162.052512 -354.37391) (xy 162.104848 -354.358544) (xy 162.158839 -354.350783) (xy 162.186112 -354.35032)
			(xy 163.049712 -354.35032) (xy 163.07698 -354.350843) (xy 163.130959 -354.358606) (xy 163.183285 -354.373972)
			(xy 163.232891 -354.396627) (xy 163.278768 -354.426112) (xy 163.319983 -354.461826) (xy 163.355695 -354.503041)
			(xy 163.385178 -354.548919) (xy 163.407833 -354.598526) (xy 163.423197 -354.650852) (xy 163.430958 -354.704832)
			(xy 163.430958 -354.759368) (xy 163.430958 -354.759369) (xy 164.913806 -354.759369) (xy 164.913806 -354.704831)
			(xy 164.921568 -354.650847) (xy 164.936932 -354.598517) (xy 164.959588 -354.548907) (xy 164.989072 -354.503025)
			(xy 165.024786 -354.461806) (xy 165.066002 -354.426089) (xy 165.111882 -354.396601) (xy 165.161491 -354.373942)
			(xy 165.21382 -354.358574) (xy 165.267803 -354.350808) (xy 165.295072 -354.35032) (xy 166.158672 -354.35032)
			(xy 166.185943 -354.350818) (xy 166.23993 -354.358576) (xy 166.292264 -354.373939) (xy 166.341878 -354.396594)
			(xy 166.387763 -354.42608) (xy 166.428985 -354.461795) (xy 166.464704 -354.503014) (xy 166.494192 -354.548897)
			(xy 166.516851 -354.59851) (xy 166.532218 -354.650842) (xy 166.53998 -354.704829) (xy 166.53998 -354.759371)
			(xy 166.53998 -354.759374) (xy 168.022684 -354.759374) (xy 168.022684 -354.704826) (xy 168.030447 -354.650834)
			(xy 168.045816 -354.598496) (xy 168.068477 -354.548879) (xy 168.097969 -354.502991) (xy 168.133691 -354.461768)
			(xy 168.174917 -354.426049) (xy 168.220807 -354.396561) (xy 168.270426 -354.373904) (xy 168.322765 -354.35854)
			(xy 168.376758 -354.350781) (xy 168.404032 -354.35032) (xy 169.267632 -354.35032) (xy 169.294899 -354.350845)
			(xy 169.348876 -354.35861) (xy 169.401199 -354.373977) (xy 169.450803 -354.396634) (xy 169.496678 -354.426119)
			(xy 169.53789 -354.461833) (xy 169.5736 -354.503048) (xy 169.603081 -354.548925) (xy 169.625734 -354.598531)
			(xy 169.641097 -354.650855) (xy 169.648858 -354.704833) (xy 169.648858 -354.759367) (xy 169.648858 -354.75937)
			(xy 171.131706 -354.75937) (xy 171.131706 -354.70483) (xy 171.139468 -354.650844) (xy 171.154834 -354.598513)
			(xy 171.177491 -354.548901) (xy 171.206977 -354.503018) (xy 171.242693 -354.461799) (xy 171.283912 -354.426082)
			(xy 171.329794 -354.396594) (xy 171.379405 -354.373937) (xy 171.431736 -354.35857) (xy 171.485722 -354.350807)
			(xy 171.512992 -354.35032) (xy 172.376592 -354.35032) (xy 172.403862 -354.350819) (xy 172.457847 -354.35858)
			(xy 172.510178 -354.373945) (xy 172.55979 -354.396601) (xy 172.605673 -354.426087) (xy 172.646892 -354.461802)
			(xy 172.682609 -354.503021) (xy 172.712096 -354.548903) (xy 172.734753 -354.598514) (xy 172.750119 -354.650845)
			(xy 172.757881 -354.70483) (xy 172.757881 -354.759368) (xy 174.240706 -354.759368) (xy 174.240706 -354.704832)
			(xy 174.248467 -354.65085) (xy 174.263831 -354.598521) (xy 174.286485 -354.548912) (xy 174.315967 -354.503031)
			(xy 174.351679 -354.461813) (xy 174.392893 -354.426096) (xy 174.43877 -354.396608) (xy 174.488376 -354.373948)
			(xy 174.540703 -354.358577) (xy 174.594684 -354.35081) (xy 174.621952 -354.35032) (xy 175.485552 -354.35032)
			(xy 175.512824 -354.350816) (xy 175.566813 -354.358572) (xy 175.619149 -354.373934) (xy 175.668766 -354.396588)
			(xy 175.714654 -354.426072) (xy 175.755878 -354.461788) (xy 175.791599 -354.503008) (xy 175.821089 -354.548891)
			(xy 175.843749 -354.598506) (xy 175.859117 -354.65084) (xy 175.86688 -354.704828) (xy 175.86688 -354.759372)
			(xy 175.86688 -354.759373) (xy 177.349584 -354.759373) (xy 177.349584 -354.704827) (xy 177.357346 -354.650837)
			(xy 177.372714 -354.598501) (xy 177.395373 -354.548884) (xy 177.424864 -354.502998) (xy 177.460584 -354.461776)
			(xy 177.501808 -354.426056) (xy 177.547695 -354.396568) (xy 177.597312 -354.37391) (xy 177.649648 -354.358544)
			(xy 177.703639 -354.350783) (xy 177.730912 -354.35032) (xy 178.594512 -354.35032) (xy 178.62178 -354.350843)
			(xy 178.675759 -354.358606) (xy 178.728085 -354.373972) (xy 178.777691 -354.396627) (xy 178.823568 -354.426112)
			(xy 178.864783 -354.461826) (xy 178.900495 -354.503041) (xy 178.929978 -354.548919) (xy 178.952633 -354.598526)
			(xy 178.967997 -354.650852) (xy 178.975758 -354.704832) (xy 178.975758 -354.759368) (xy 178.975758 -354.759369)
			(xy 180.458606 -354.759369) (xy 180.458606 -354.704831) (xy 180.466368 -354.650847) (xy 180.481732 -354.598517)
			(xy 180.504388 -354.548907) (xy 180.533872 -354.503025) (xy 180.569586 -354.461806) (xy 180.610802 -354.426089)
			(xy 180.656682 -354.396601) (xy 180.706291 -354.373942) (xy 180.75862 -354.358574) (xy 180.812603 -354.350808)
			(xy 180.839872 -354.35032) (xy 181.703472 -354.35032) (xy 181.730743 -354.350818) (xy 181.78473 -354.358576)
			(xy 181.837064 -354.373939) (xy 181.886678 -354.396594) (xy 181.932563 -354.42608) (xy 181.973785 -354.461795)
			(xy 182.009504 -354.503014) (xy 182.038992 -354.548897) (xy 182.061651 -354.59851) (xy 182.077018 -354.650842)
			(xy 182.08478 -354.704829) (xy 182.08478 -354.735472) (xy 183.567508 -354.735472) (xy 183.567508 -354.680928)
			(xy 183.57527 -354.626939) (xy 183.590638 -354.574605) (xy 183.613298 -354.52499) (xy 183.642788 -354.479106)
			(xy 183.678508 -354.437885) (xy 183.719731 -354.402169) (xy 183.765618 -354.372682) (xy 183.815235 -354.350027)
			(xy 183.86757 -354.334664) (xy 183.92156 -354.326905) (xy 183.948832 -354.326444) (xy 184.812432 -354.326444)
			(xy 184.8397 -354.326921) (xy 184.893681 -354.334686) (xy 184.946008 -354.350054) (xy 184.995615 -354.372713)
			(xy 185.041492 -354.4022) (xy 185.082707 -354.437916) (xy 185.118419 -354.479133) (xy 185.147903 -354.525013)
			(xy 185.170557 -354.574622) (xy 185.185921 -354.62695) (xy 185.193682 -354.680932) (xy 185.193682 -354.735468)
			(xy 185.193682 -354.735469) (xy 186.67653 -354.735469) (xy 186.67653 -354.680931) (xy 186.684292 -354.626949)
			(xy 186.699656 -354.574621) (xy 186.722312 -354.525012) (xy 186.751796 -354.479133) (xy 186.78751 -354.437916)
			(xy 186.828726 -354.402201) (xy 186.874605 -354.372716) (xy 186.924214 -354.350059) (xy 186.976542 -354.334693)
			(xy 187.030523 -354.326931) (xy 187.057792 -354.326444) (xy 187.921392 -354.326444) (xy 187.948664 -354.326895)
			(xy 188.002652 -354.334656) (xy 188.054987 -354.350022) (xy 188.104602 -354.37268) (xy 188.150487 -354.402167)
			(xy 188.191709 -354.437885) (xy 188.227428 -354.479106) (xy 188.256917 -354.524991) (xy 188.279575 -354.574606)
			(xy 188.294942 -354.62694) (xy 188.302704 -354.680928) (xy 188.302704 -354.735472) (xy 188.299268 -354.759369)
			(xy 270.624806 -354.759369) (xy 270.624806 -354.704831) (xy 270.632567 -354.650848) (xy 270.647932 -354.598519)
			(xy 270.670586 -354.548909) (xy 270.70007 -354.503028) (xy 270.735783 -354.46181) (xy 270.776998 -354.426093)
			(xy 270.822876 -354.396604) (xy 270.872484 -354.373945) (xy 270.924811 -354.358575) (xy 270.978793 -354.350809)
			(xy 271.006062 -354.35032) (xy 271.869662 -354.35032) (xy 271.896933 -354.350817) (xy 271.950922 -354.358574)
			(xy 272.003257 -354.373936) (xy 272.052872 -354.396591) (xy 272.098759 -354.426076) (xy 272.139981 -354.461792)
			(xy 272.175701 -354.503011) (xy 272.205191 -354.548894) (xy 272.22785 -354.598508) (xy 272.243218 -354.650841)
			(xy 272.25098 -354.704829) (xy 272.25098 -354.759371) (xy 272.25098 -354.759373) (xy 273.733684 -354.759373)
			(xy 273.733684 -354.704827) (xy 273.741447 -354.650835) (xy 273.756815 -354.598498) (xy 273.779475 -354.548882)
			(xy 273.808966 -354.502995) (xy 273.844688 -354.461772) (xy 273.885912 -354.426053) (xy 273.931801 -354.396564)
			(xy 273.981419 -354.373907) (xy 274.033757 -354.358542) (xy 274.087749 -354.350782) (xy 274.115022 -354.35032)
			(xy 274.978622 -354.35032) (xy 275.005889 -354.350844) (xy 275.059868 -354.358608) (xy 275.112192 -354.373974)
			(xy 275.161797 -354.396631) (xy 275.207673 -354.426116) (xy 275.248886 -354.461829) (xy 275.284597 -354.503044)
			(xy 275.31408 -354.548922) (xy 275.336733 -354.598528) (xy 275.352097 -354.650854) (xy 275.359858 -354.704833)
			(xy 275.359858 -354.759367) (xy 275.359858 -354.75937) (xy 276.842706 -354.75937) (xy 276.842706 -354.70483)
			(xy 276.850468 -354.650846) (xy 276.865833 -354.598515) (xy 276.888489 -354.548904) (xy 276.917975 -354.503022)
			(xy 276.95369 -354.461802) (xy 276.994907 -354.426085) (xy 277.040788 -354.396598) (xy 277.090398 -354.373939)
			(xy 277.142728 -354.358572) (xy 277.196712 -354.350808) (xy 277.223982 -354.35032) (xy 278.087582 -354.35032)
			(xy 278.114853 -354.350818) (xy 278.168839 -354.358578) (xy 278.221171 -354.373942) (xy 278.270784 -354.396597)
			(xy 278.316668 -354.426083) (xy 278.357888 -354.461799) (xy 278.393606 -354.503018) (xy 278.423094 -354.5489)
			(xy 278.445752 -354.598512) (xy 278.461118 -354.650844) (xy 278.468881 -354.704829) (xy 278.468881 -354.759371)
			(xy 278.468881 -354.759374) (xy 279.951584 -354.759374) (xy 279.951584 -354.704826) (xy 279.959347 -354.650833)
			(xy 279.974716 -354.598494) (xy 279.997378 -354.548876) (xy 280.026871 -354.502988) (xy 280.062595 -354.461765)
			(xy 280.103822 -354.426046) (xy 280.149713 -354.396558) (xy 280.199334 -354.373902) (xy 280.251674 -354.358538)
			(xy 280.305668 -354.350781) (xy 280.332942 -354.35032) (xy 281.196542 -354.35032) (xy 281.223808 -354.350845)
			(xy 281.277785 -354.358611) (xy 281.330107 -354.37398) (xy 281.379709 -354.396637) (xy 281.425583 -354.426123)
			(xy 281.466793 -354.461836) (xy 281.502502 -354.503051) (xy 281.531983 -354.548928) (xy 281.554635 -354.598533)
			(xy 281.569998 -354.650856) (xy 281.577758 -354.704834) (xy 281.577758 -354.759366) (xy 281.577757 -354.759372)
			(xy 283.060584 -354.759372) (xy 283.060584 -354.704828) (xy 283.068346 -354.650838) (xy 283.083713 -354.598503)
			(xy 283.106372 -354.548887) (xy 283.135861 -354.503001) (xy 283.171581 -354.461779) (xy 283.212803 -354.42606)
			(xy 283.258689 -354.396571) (xy 283.308305 -354.373912) (xy 283.36064 -354.358546) (xy 283.41463 -354.350783)
			(xy 283.441902 -354.35032) (xy 284.305502 -354.35032) (xy 284.33277 -354.350843) (xy 284.386751 -354.358604)
			(xy 284.439078 -354.373969) (xy 284.488685 -354.396624) (xy 284.534564 -354.426109) (xy 284.575779 -354.461822)
			(xy 284.611493 -354.503038) (xy 284.640977 -354.548917) (xy 284.663632 -354.598524) (xy 284.678996 -354.650851)
			(xy 284.686758 -354.704832) (xy 284.686758 -354.759368) (xy 284.686758 -354.759369) (xy 286.169606 -354.759369)
			(xy 286.169606 -354.704831) (xy 286.177367 -354.650848) (xy 286.192732 -354.598519) (xy 286.215386 -354.548909)
			(xy 286.24487 -354.503028) (xy 286.280583 -354.46181) (xy 286.321798 -354.426093) (xy 286.367676 -354.396604)
			(xy 286.417284 -354.373945) (xy 286.469611 -354.358575) (xy 286.523593 -354.350809) (xy 286.550862 -354.35032)
			(xy 287.414462 -354.35032) (xy 287.441733 -354.350817) (xy 287.495722 -354.358574) (xy 287.548057 -354.373936)
			(xy 287.597672 -354.396591) (xy 287.643559 -354.426076) (xy 287.684781 -354.461792) (xy 287.720501 -354.503011)
			(xy 287.749991 -354.548894) (xy 287.77265 -354.598508) (xy 287.788018 -354.650841) (xy 287.79578 -354.704829)
			(xy 287.79578 -354.759371) (xy 287.79578 -354.759373) (xy 289.278484 -354.759373) (xy 289.278484 -354.704827)
			(xy 289.286247 -354.650835) (xy 289.301615 -354.598498) (xy 289.324275 -354.548882) (xy 289.353766 -354.502995)
			(xy 289.389488 -354.461772) (xy 289.430712 -354.426053) (xy 289.476601 -354.396564) (xy 289.526219 -354.373907)
			(xy 289.578557 -354.358542) (xy 289.632549 -354.350782) (xy 289.659822 -354.35032) (xy 290.523422 -354.35032)
			(xy 290.550689 -354.350844) (xy 290.604668 -354.358608) (xy 290.656992 -354.373974) (xy 290.706597 -354.396631)
			(xy 290.752473 -354.426116) (xy 290.793686 -354.461829) (xy 290.829397 -354.503044) (xy 290.85888 -354.548922)
			(xy 290.881533 -354.598528) (xy 290.896897 -354.650854) (xy 290.904658 -354.704833) (xy 290.904658 -354.759367)
			(xy 290.904658 -354.75937) (xy 292.387506 -354.75937) (xy 292.387506 -354.70483) (xy 292.395268 -354.650846)
			(xy 292.410633 -354.598515) (xy 292.433289 -354.548904) (xy 292.462775 -354.503022) (xy 292.49849 -354.461802)
			(xy 292.539707 -354.426085) (xy 292.585588 -354.396598) (xy 292.635198 -354.373939) (xy 292.687528 -354.358572)
			(xy 292.741512 -354.350808) (xy 292.768782 -354.35032) (xy 293.632382 -354.35032) (xy 293.659653 -354.350818)
			(xy 293.713639 -354.358578) (xy 293.765971 -354.373942) (xy 293.815584 -354.396597) (xy 293.861468 -354.426083)
			(xy 293.902688 -354.461799) (xy 293.938406 -354.503018) (xy 293.967894 -354.5489) (xy 293.990552 -354.598512)
			(xy 294.005918 -354.650844) (xy 294.013681 -354.704829) (xy 294.013681 -354.759371) (xy 294.013681 -354.759374)
			(xy 295.496384 -354.759374) (xy 295.496384 -354.704826) (xy 295.504147 -354.650833) (xy 295.519516 -354.598494)
			(xy 295.542178 -354.548876) (xy 295.571671 -354.502988) (xy 295.607395 -354.461765) (xy 295.648622 -354.426046)
			(xy 295.694513 -354.396558) (xy 295.744134 -354.373902) (xy 295.796474 -354.358538) (xy 295.850468 -354.350781)
			(xy 295.877742 -354.35032) (xy 296.741342 -354.35032) (xy 296.768608 -354.350845) (xy 296.822585 -354.358611)
			(xy 296.874907 -354.37398) (xy 296.924509 -354.396637) (xy 296.970383 -354.426123) (xy 297.011593 -354.461836)
			(xy 297.047302 -354.503051) (xy 297.076783 -354.548928) (xy 297.099435 -354.598533) (xy 297.114798 -354.650856)
			(xy 297.122558 -354.704834) (xy 297.122558 -354.759366) (xy 297.122557 -354.759372) (xy 298.605384 -354.759372)
			(xy 298.605384 -354.704828) (xy 298.613146 -354.650838) (xy 298.628513 -354.598503) (xy 298.651172 -354.548887)
			(xy 298.680661 -354.503001) (xy 298.716381 -354.461779) (xy 298.757603 -354.42606) (xy 298.803489 -354.396571)
			(xy 298.853105 -354.373912) (xy 298.90544 -354.358546) (xy 298.95943 -354.350783) (xy 298.986702 -354.35032)
			(xy 299.850302 -354.35032) (xy 299.87757 -354.350843) (xy 299.931551 -354.358604) (xy 299.983878 -354.373969)
			(xy 300.033485 -354.396624) (xy 300.079364 -354.426109) (xy 300.120579 -354.461822) (xy 300.156293 -354.503038)
			(xy 300.185777 -354.548917) (xy 300.208432 -354.598524) (xy 300.223796 -354.650851) (xy 300.231558 -354.704832)
			(xy 300.231558 -354.759368) (xy 300.231558 -354.759369) (xy 315.230506 -354.759369) (xy 315.230506 -354.704831)
			(xy 315.238267 -354.650848) (xy 315.253632 -354.598519) (xy 315.276286 -354.548909) (xy 315.30577 -354.503027)
			(xy 315.341483 -354.461809) (xy 315.382699 -354.426092) (xy 315.428577 -354.396604) (xy 315.478185 -354.373944)
			(xy 315.530513 -354.358575) (xy 315.584495 -354.350809) (xy 315.611764 -354.35032) (xy 316.475364 -354.35032)
			(xy 316.502635 -354.350817) (xy 316.556624 -354.358575) (xy 316.608958 -354.373937) (xy 316.658574 -354.396591)
			(xy 316.70446 -354.426077) (xy 316.745682 -354.461793) (xy 316.781402 -354.503012) (xy 316.810891 -354.548895)
			(xy 316.83355 -354.598508) (xy 316.848918 -354.650841) (xy 316.85668 -354.704829) (xy 316.85668 -354.759371)
			(xy 316.85668 -354.759373) (xy 318.339384 -354.759373) (xy 318.339384 -354.704827) (xy 318.347147 -354.650835)
			(xy 318.362515 -354.598498) (xy 318.385175 -354.548881) (xy 318.414667 -354.502994) (xy 318.450388 -354.461771)
			(xy 318.491613 -354.426052) (xy 318.537502 -354.396564) (xy 318.587121 -354.373907) (xy 318.639459 -354.358542)
			(xy 318.693451 -354.350782) (xy 318.720724 -354.35032) (xy 319.584324 -354.35032) (xy 319.611591 -354.350844)
			(xy 319.665569 -354.358608) (xy 319.717894 -354.373975) (xy 319.767498 -354.396631) (xy 319.813374 -354.426116)
			(xy 319.854587 -354.46183) (xy 319.890298 -354.503045) (xy 319.91978 -354.548923) (xy 319.942434 -354.598529)
			(xy 319.957797 -354.650854) (xy 319.965558 -354.704833) (xy 319.965558 -354.759367) (xy 319.965558 -354.75937)
			(xy 321.448406 -354.75937) (xy 321.448406 -354.70483) (xy 321.456168 -354.650845) (xy 321.471533 -354.598515)
			(xy 321.494189 -354.548903) (xy 321.523675 -354.503021) (xy 321.55939 -354.461802) (xy 321.600608 -354.426085)
			(xy 321.646489 -354.396597) (xy 321.6961 -354.373939) (xy 321.74843 -354.358571) (xy 321.802414 -354.350808)
			(xy 321.829684 -354.35032) (xy 322.693284 -354.35032) (xy 322.720554 -354.350818) (xy 322.774541 -354.358578)
			(xy 322.826873 -354.373942) (xy 322.876485 -354.396598) (xy 322.922369 -354.426084) (xy 322.963589 -354.4618)
			(xy 322.999307 -354.503018) (xy 323.028794 -354.5489) (xy 323.051452 -354.598512) (xy 323.066818 -354.650844)
			(xy 323.074581 -354.70483) (xy 323.074581 -354.75937) (xy 323.07458 -354.759374) (xy 324.557284 -354.759374)
			(xy 324.557284 -354.704826) (xy 324.565047 -354.650832) (xy 324.580417 -354.598494) (xy 324.603078 -354.548875)
			(xy 324.632571 -354.502987) (xy 324.668295 -354.461764) (xy 324.709523 -354.426045) (xy 324.755414 -354.396557)
			(xy 324.805035 -354.373901) (xy 324.857375 -354.358538) (xy 324.91137 -354.350781) (xy 324.938644 -354.35032)
			(xy 325.802244 -354.35032) (xy 325.82951 -354.350845) (xy 325.883486 -354.358612) (xy 325.935808 -354.37398)
			(xy 325.98541 -354.396638) (xy 326.031284 -354.426124) (xy 326.072494 -354.461837) (xy 326.108203 -354.503052)
			(xy 326.137683 -354.548928) (xy 326.160335 -354.598533) (xy 326.175698 -354.650857) (xy 326.183458 -354.704834)
			(xy 326.183458 -354.759366) (xy 326.183457 -354.759372) (xy 327.666284 -354.759372) (xy 327.666284 -354.704828)
			(xy 327.674046 -354.650838) (xy 327.689413 -354.598502) (xy 327.712072 -354.548887) (xy 327.741562 -354.503001)
			(xy 327.777281 -354.461778) (xy 327.818504 -354.426059) (xy 327.86439 -354.39657) (xy 327.914006 -354.373912)
			(xy 327.966342 -354.358545) (xy 328.020332 -354.350783) (xy 328.047604 -354.35032) (xy 328.911204 -354.35032)
			(xy 328.938472 -354.350843) (xy 328.992453 -354.358604) (xy 329.044779 -354.373969) (xy 329.094386 -354.396625)
			(xy 329.140265 -354.426109) (xy 329.18148 -354.461823) (xy 329.217193 -354.503039) (xy 329.246677 -354.548917)
			(xy 329.269332 -354.598525) (xy 329.284696 -354.650851) (xy 329.292458 -354.704832) (xy 329.292458 -354.759368)
			(xy 329.292458 -354.759369) (xy 330.775306 -354.759369) (xy 330.775306 -354.704831) (xy 330.783067 -354.650848)
			(xy 330.798432 -354.598519) (xy 330.821086 -354.548909) (xy 330.85057 -354.503027) (xy 330.886283 -354.461809)
			(xy 330.927499 -354.426092) (xy 330.973377 -354.396604) (xy 331.022985 -354.373944) (xy 331.075313 -354.358575)
			(xy 331.129295 -354.350809) (xy 331.156564 -354.35032) (xy 332.020164 -354.35032) (xy 332.047435 -354.350817)
			(xy 332.101424 -354.358575) (xy 332.153758 -354.373937) (xy 332.203374 -354.396591) (xy 332.24926 -354.426077)
			(xy 332.290482 -354.461793) (xy 332.326202 -354.503012) (xy 332.355691 -354.548895) (xy 332.37835 -354.598508)
			(xy 332.393718 -354.650841) (xy 332.40148 -354.704829) (xy 332.40148 -354.759371) (xy 332.40148 -354.759373)
			(xy 333.884184 -354.759373) (xy 333.884184 -354.704827) (xy 333.891947 -354.650835) (xy 333.907315 -354.598498)
			(xy 333.929975 -354.548881) (xy 333.959467 -354.502994) (xy 333.995188 -354.461771) (xy 334.036413 -354.426052)
			(xy 334.082302 -354.396564) (xy 334.131921 -354.373907) (xy 334.184259 -354.358542) (xy 334.238251 -354.350782)
			(xy 334.265524 -354.35032) (xy 335.129124 -354.35032) (xy 335.156391 -354.350844) (xy 335.210369 -354.358608)
			(xy 335.262694 -354.373975) (xy 335.312298 -354.396631) (xy 335.358174 -354.426116) (xy 335.399387 -354.46183)
			(xy 335.435098 -354.503045) (xy 335.46458 -354.548923) (xy 335.487234 -354.598529) (xy 335.502597 -354.650854)
			(xy 335.510358 -354.704833) (xy 335.510358 -354.759367) (xy 335.510358 -354.75937) (xy 336.993206 -354.75937)
			(xy 336.993206 -354.70483) (xy 337.000968 -354.650845) (xy 337.016333 -354.598515) (xy 337.038989 -354.548903)
			(xy 337.068475 -354.503021) (xy 337.10419 -354.461802) (xy 337.145408 -354.426085) (xy 337.191289 -354.396597)
			(xy 337.2409 -354.373939) (xy 337.29323 -354.358571) (xy 337.347214 -354.350808) (xy 337.374484 -354.35032)
			(xy 338.238084 -354.35032) (xy 338.265354 -354.350818) (xy 338.319341 -354.358578) (xy 338.371673 -354.373942)
			(xy 338.421285 -354.396598) (xy 338.467169 -354.426084) (xy 338.508389 -354.4618) (xy 338.544107 -354.503018)
			(xy 338.573594 -354.5489) (xy 338.596252 -354.598512) (xy 338.611618 -354.650844) (xy 338.619381 -354.70483)
			(xy 338.619381 -354.75937) (xy 338.61938 -354.759374) (xy 340.102084 -354.759374) (xy 340.102084 -354.704826)
			(xy 340.109847 -354.650832) (xy 340.125217 -354.598494) (xy 340.147878 -354.548875) (xy 340.177371 -354.502987)
			(xy 340.213095 -354.461764) (xy 340.254323 -354.426045) (xy 340.300214 -354.396557) (xy 340.349835 -354.373901)
			(xy 340.402175 -354.358538) (xy 340.45617 -354.350781) (xy 340.483444 -354.35032) (xy 341.347044 -354.35032)
			(xy 341.37431 -354.350845) (xy 341.428286 -354.358612) (xy 341.480608 -354.37398) (xy 341.53021 -354.396638)
			(xy 341.576084 -354.426124) (xy 341.617294 -354.461837) (xy 341.653003 -354.503052) (xy 341.682483 -354.548928)
			(xy 341.705135 -354.598533) (xy 341.720498 -354.650857) (xy 341.728258 -354.704834) (xy 341.728258 -354.759366)
			(xy 341.728257 -354.759372) (xy 343.211084 -354.759372) (xy 343.211084 -354.704828) (xy 343.218846 -354.650838)
			(xy 343.234213 -354.598502) (xy 343.256872 -354.548887) (xy 343.286362 -354.503001) (xy 343.322081 -354.461778)
			(xy 343.363304 -354.426059) (xy 343.40919 -354.39657) (xy 343.458806 -354.373912) (xy 343.511142 -354.358545)
			(xy 343.565132 -354.350783) (xy 343.592404 -354.35032) (xy 344.456004 -354.35032) (xy 344.483272 -354.350843)
			(xy 344.537253 -354.358604) (xy 344.589579 -354.373969) (xy 344.639186 -354.396625) (xy 344.685065 -354.426109)
			(xy 344.72628 -354.461823) (xy 344.761993 -354.503039) (xy 344.791477 -354.548917) (xy 344.814132 -354.598525)
			(xy 344.829496 -354.650851) (xy 344.837258 -354.704832) (xy 344.837258 -354.759368) (xy 344.837257 -354.759374)
			(xy 373.915584 -354.759374) (xy 373.915584 -354.704826) (xy 373.923347 -354.650833) (xy 373.938716 -354.598495)
			(xy 373.961378 -354.548876) (xy 373.990871 -354.502989) (xy 374.026594 -354.461766) (xy 374.067821 -354.426047)
			(xy 374.113712 -354.396559) (xy 374.163332 -354.373902) (xy 374.215672 -354.358539) (xy 374.269666 -354.350781)
			(xy 374.29694 -354.35032) (xy 375.16054 -354.35032) (xy 375.187806 -354.350845) (xy 375.241783 -354.358611)
			(xy 375.294105 -354.373979) (xy 375.343708 -354.396637) (xy 375.389582 -354.426122) (xy 375.430793 -354.461836)
			(xy 375.466502 -354.50305) (xy 375.495983 -354.548927) (xy 375.518635 -354.598532) (xy 375.533997 -354.650856)
			(xy 375.541758 -354.704834) (xy 375.541758 -354.759366) (xy 375.541757 -354.759371) (xy 377.024606 -354.759371)
			(xy 377.024606 -354.704829) (xy 377.032369 -354.650843) (xy 377.047735 -354.598511) (xy 377.070392 -354.548899)
			(xy 377.099879 -354.503016) (xy 377.135596 -354.461796) (xy 377.176816 -354.426079) (xy 377.222699 -354.396592)
			(xy 377.272311 -354.373935) (xy 377.324643 -354.358569) (xy 377.378629 -354.350806) (xy 377.4059 -354.35032)
			(xy 378.2695 -354.35032) (xy 378.296768 -354.350842) (xy 378.350749 -354.358604) (xy 378.403076 -354.373968)
			(xy 378.452684 -354.396623) (xy 378.498563 -354.426108) (xy 378.539778 -354.461822) (xy 378.575492 -354.503037)
			(xy 378.604977 -354.548916) (xy 378.627632 -354.598524) (xy 378.642996 -354.650851) (xy 378.650758 -354.704832)
			(xy 378.650758 -354.759368) (xy 378.650758 -354.759369) (xy 380.133606 -354.759369) (xy 380.133606 -354.704831)
			(xy 380.141367 -354.650849) (xy 380.156731 -354.59852) (xy 380.179386 -354.54891) (xy 380.208869 -354.503029)
			(xy 380.244582 -354.46181) (xy 380.285797 -354.426093) (xy 380.331675 -354.396605) (xy 380.381282 -354.373945)
			(xy 380.433609 -354.358576) (xy 380.487591 -354.350809) (xy 380.51486 -354.35032) (xy 381.37846 -354.35032)
			(xy 381.405732 -354.350817) (xy 381.45972 -354.358574) (xy 381.512055 -354.373936) (xy 381.561671 -354.39659)
			(xy 381.607558 -354.426075) (xy 381.648781 -354.461791) (xy 381.684501 -354.50301) (xy 381.713991 -354.548894)
			(xy 381.73665 -354.598507) (xy 381.752018 -354.650841) (xy 381.75978 -354.704828) (xy 381.75978 -354.759372)
			(xy 381.75978 -354.759373) (xy 383.242484 -354.759373) (xy 383.242484 -354.704827) (xy 383.250247 -354.650836)
			(xy 383.265615 -354.598499) (xy 383.288275 -354.548882) (xy 383.317766 -354.502995) (xy 383.353487 -354.461773)
			(xy 383.394711 -354.426054) (xy 383.4406 -354.396565) (xy 383.490218 -354.373908) (xy 383.542555 -354.358542)
			(xy 383.596547 -354.350782) (xy 383.62382 -354.35032) (xy 384.48742 -354.35032) (xy 384.514687 -354.350844)
			(xy 384.568666 -354.358607) (xy 384.620991 -354.373974) (xy 384.670596 -354.39663) (xy 384.716472 -354.426115)
			(xy 384.757686 -354.461829) (xy 384.793397 -354.503044) (xy 384.82288 -354.548922) (xy 384.845533 -354.598528)
			(xy 384.860897 -354.650854) (xy 384.868658 -354.704833) (xy 384.868658 -354.759367) (xy 384.868658 -354.75937)
			(xy 386.351506 -354.75937) (xy 386.351506 -354.70483) (xy 386.359268 -354.650846) (xy 386.374633 -354.598515)
			(xy 386.397289 -354.548904) (xy 386.426774 -354.503022) (xy 386.462489 -354.461803) (xy 386.503706 -354.426086)
			(xy 386.549587 -354.396598) (xy 386.599197 -354.37394) (xy 386.651526 -354.358572) (xy 386.70551 -354.350808)
			(xy 386.73278 -354.35032) (xy 387.59638 -354.35032) (xy 387.623651 -354.350818) (xy 387.677637 -354.358578)
			(xy 387.72997 -354.373941) (xy 387.779583 -354.396597) (xy 387.825467 -354.426082) (xy 387.866688 -354.461798)
			(xy 387.902406 -354.503017) (xy 387.931894 -354.548899) (xy 387.954552 -354.598511) (xy 387.969918 -354.650843)
			(xy 387.97768 -354.704829) (xy 387.97768 -354.759371) (xy 387.97768 -354.759374) (xy 389.460384 -354.759374)
			(xy 389.460384 -354.704826) (xy 389.468147 -354.650833) (xy 389.483516 -354.598495) (xy 389.506178 -354.548876)
			(xy 389.535671 -354.502989) (xy 389.571394 -354.461766) (xy 389.612621 -354.426047) (xy 389.658512 -354.396559)
			(xy 389.708132 -354.373902) (xy 389.760472 -354.358539) (xy 389.814466 -354.350781) (xy 389.84174 -354.35032)
			(xy 390.70534 -354.35032) (xy 390.732606 -354.350845) (xy 390.786583 -354.358611) (xy 390.838905 -354.373979)
			(xy 390.888508 -354.396637) (xy 390.934382 -354.426122) (xy 390.975593 -354.461836) (xy 391.011302 -354.50305)
			(xy 391.040783 -354.548927) (xy 391.063435 -354.598532) (xy 391.078797 -354.650856) (xy 391.086558 -354.704834)
			(xy 391.086558 -354.759366) (xy 391.086557 -354.759371) (xy 392.569406 -354.759371) (xy 392.569406 -354.704829)
			(xy 392.577169 -354.650843) (xy 392.592535 -354.598511) (xy 392.615192 -354.548899) (xy 392.644679 -354.503016)
			(xy 392.680396 -354.461796) (xy 392.721616 -354.426079) (xy 392.767499 -354.396592) (xy 392.817111 -354.373935)
			(xy 392.869443 -354.358569) (xy 392.923429 -354.350806) (xy 392.9507 -354.35032) (xy 393.8143 -354.35032)
			(xy 393.841568 -354.350842) (xy 393.895549 -354.358604) (xy 393.947876 -354.373968) (xy 393.997484 -354.396623)
			(xy 394.043363 -354.426108) (xy 394.084578 -354.461822) (xy 394.120292 -354.503037) (xy 394.149777 -354.548916)
			(xy 394.172432 -354.598524) (xy 394.187796 -354.650851) (xy 394.195558 -354.704832) (xy 394.195558 -354.759368)
			(xy 394.195558 -354.759369) (xy 395.678406 -354.759369) (xy 395.678406 -354.704831) (xy 395.686167 -354.650849)
			(xy 395.701531 -354.59852) (xy 395.724186 -354.54891) (xy 395.753669 -354.503029) (xy 395.789382 -354.46181)
			(xy 395.830597 -354.426093) (xy 395.876475 -354.396605) (xy 395.926082 -354.373945) (xy 395.978409 -354.358576)
			(xy 396.032391 -354.350809) (xy 396.05966 -354.35032) (xy 396.92326 -354.35032) (xy 396.950532 -354.350817)
			(xy 397.00452 -354.358574) (xy 397.056855 -354.373936) (xy 397.106471 -354.39659) (xy 397.152358 -354.426075)
			(xy 397.193581 -354.461791) (xy 397.229301 -354.50301) (xy 397.258791 -354.548894) (xy 397.28145 -354.598507)
			(xy 397.296818 -354.650841) (xy 397.30458 -354.704828) (xy 397.30458 -354.759372) (xy 397.30458 -354.759373)
			(xy 398.787284 -354.759373) (xy 398.787284 -354.704827) (xy 398.795047 -354.650836) (xy 398.810415 -354.598499)
			(xy 398.833075 -354.548882) (xy 398.862566 -354.502995) (xy 398.898287 -354.461773) (xy 398.939511 -354.426054)
			(xy 398.9854 -354.396565) (xy 399.035018 -354.373908) (xy 399.087355 -354.358542) (xy 399.141347 -354.350782)
			(xy 399.16862 -354.35032) (xy 400.03222 -354.35032) (xy 400.059487 -354.350844) (xy 400.113466 -354.358607)
			(xy 400.165791 -354.373974) (xy 400.215396 -354.39663) (xy 400.261272 -354.426115) (xy 400.302486 -354.461829)
			(xy 400.338197 -354.503044) (xy 400.36768 -354.548922) (xy 400.390333 -354.598528) (xy 400.405697 -354.650854)
			(xy 400.413458 -354.704833) (xy 400.413458 -354.759367) (xy 400.413458 -354.75937) (xy 401.896306 -354.75937)
			(xy 401.896306 -354.70483) (xy 401.904068 -354.650846) (xy 401.919433 -354.598515) (xy 401.942089 -354.548904)
			(xy 401.971574 -354.503022) (xy 402.007289 -354.461803) (xy 402.048506 -354.426086) (xy 402.094387 -354.396598)
			(xy 402.143997 -354.37394) (xy 402.196326 -354.358572) (xy 402.25031 -354.350808) (xy 402.27758 -354.35032)
			(xy 403.14118 -354.35032) (xy 403.168451 -354.350818) (xy 403.222437 -354.358578) (xy 403.27477 -354.373941)
			(xy 403.324383 -354.396597) (xy 403.370267 -354.426082) (xy 403.411488 -354.461798) (xy 403.447206 -354.503017)
			(xy 403.476694 -354.548899) (xy 403.499352 -354.598511) (xy 403.514718 -354.650843) (xy 403.52248 -354.704829)
			(xy 403.52248 -354.759368) (xy 412.022806 -354.759368) (xy 412.022806 -354.704832) (xy 412.030567 -354.65085)
			(xy 412.045931 -354.598521) (xy 412.068585 -354.548912) (xy 412.098067 -354.503031) (xy 412.133779 -354.461813)
			(xy 412.174993 -354.426096) (xy 412.22087 -354.396608) (xy 412.270476 -354.373948) (xy 412.322803 -354.358577)
			(xy 412.376784 -354.35081) (xy 412.404052 -354.35032) (xy 413.267652 -354.35032) (xy 413.294924 -354.350816)
			(xy 413.348913 -354.358572) (xy 413.401249 -354.373934) (xy 413.450866 -354.396588) (xy 413.496754 -354.426072)
			(xy 413.537978 -354.461788) (xy 413.573699 -354.503008) (xy 413.603189 -354.548891) (xy 413.625849 -354.598506)
			(xy 413.641217 -354.65084) (xy 413.64898 -354.704828) (xy 413.64898 -354.759372) (xy 413.64898 -354.759373)
			(xy 415.131684 -354.759373) (xy 415.131684 -354.704827) (xy 415.139446 -354.650837) (xy 415.154814 -354.598501)
			(xy 415.177473 -354.548884) (xy 415.206964 -354.502998) (xy 415.242684 -354.461776) (xy 415.283908 -354.426056)
			(xy 415.329795 -354.396568) (xy 415.379412 -354.37391) (xy 415.431748 -354.358544) (xy 415.485739 -354.350783)
			(xy 415.513012 -354.35032) (xy 416.376612 -354.35032) (xy 416.40388 -354.350843) (xy 416.457859 -354.358606)
			(xy 416.510185 -354.373972) (xy 416.559791 -354.396627) (xy 416.605668 -354.426112) (xy 416.646883 -354.461826)
			(xy 416.682595 -354.503041) (xy 416.712078 -354.548919) (xy 416.734733 -354.598526) (xy 416.750097 -354.650852)
			(xy 416.757858 -354.704832) (xy 416.757858 -354.759368) (xy 416.757858 -354.759369) (xy 418.240706 -354.759369)
			(xy 418.240706 -354.704831) (xy 418.248468 -354.650847) (xy 418.263832 -354.598517) (xy 418.286488 -354.548907)
			(xy 418.315972 -354.503025) (xy 418.351686 -354.461806) (xy 418.392902 -354.426089) (xy 418.438782 -354.396601)
			(xy 418.488391 -354.373942) (xy 418.54072 -354.358574) (xy 418.594703 -354.350808) (xy 418.621972 -354.35032)
			(xy 419.485572 -354.35032) (xy 419.512843 -354.350818) (xy 419.56683 -354.358576) (xy 419.619164 -354.373939)
			(xy 419.668778 -354.396594) (xy 419.714663 -354.42608) (xy 419.755885 -354.461795) (xy 419.791604 -354.503014)
			(xy 419.821092 -354.548897) (xy 419.843751 -354.59851) (xy 419.859118 -354.650842) (xy 419.86688 -354.704829)
			(xy 419.86688 -354.759371) (xy 419.86688 -354.759374) (xy 421.349584 -354.759374) (xy 421.349584 -354.704826)
			(xy 421.357347 -354.650834) (xy 421.372716 -354.598496) (xy 421.395377 -354.548879) (xy 421.424869 -354.502991)
			(xy 421.460591 -354.461768) (xy 421.501817 -354.426049) (xy 421.547707 -354.396561) (xy 421.597326 -354.373904)
			(xy 421.649665 -354.35854) (xy 421.703658 -354.350781) (xy 421.730932 -354.35032) (xy 422.594532 -354.35032)
			(xy 422.621799 -354.350845) (xy 422.675776 -354.35861) (xy 422.728099 -354.373977) (xy 422.777703 -354.396634)
			(xy 422.823578 -354.426119) (xy 422.86479 -354.461833) (xy 422.9005 -354.503048) (xy 422.929981 -354.548925)
			(xy 422.952634 -354.598531) (xy 422.967997 -354.650855) (xy 422.975758 -354.704833) (xy 422.975758 -354.759367)
			(xy 422.975758 -354.75937) (xy 424.458606 -354.75937) (xy 424.458606 -354.70483) (xy 424.466368 -354.650844)
			(xy 424.481734 -354.598513) (xy 424.504391 -354.548901) (xy 424.533877 -354.503018) (xy 424.569593 -354.461799)
			(xy 424.610812 -354.426082) (xy 424.656694 -354.396594) (xy 424.706305 -354.373937) (xy 424.758636 -354.35857)
			(xy 424.812622 -354.350807) (xy 424.839892 -354.35032) (xy 425.703492 -354.35032) (xy 425.730762 -354.350819)
			(xy 425.784747 -354.35858) (xy 425.837078 -354.373945) (xy 425.88669 -354.396601) (xy 425.932573 -354.426087)
			(xy 425.973792 -354.461802) (xy 426.009509 -354.503021) (xy 426.038996 -354.548903) (xy 426.061653 -354.598514)
			(xy 426.077019 -354.650845) (xy 426.084781 -354.70483) (xy 426.084781 -354.759368) (xy 427.567606 -354.759368)
			(xy 427.567606 -354.704832) (xy 427.575367 -354.65085) (xy 427.590731 -354.598521) (xy 427.613385 -354.548912)
			(xy 427.642867 -354.503031) (xy 427.678579 -354.461813) (xy 427.719793 -354.426096) (xy 427.76567 -354.396608)
			(xy 427.815276 -354.373948) (xy 427.867603 -354.358577) (xy 427.921584 -354.35081) (xy 427.948852 -354.35032)
			(xy 428.812452 -354.35032) (xy 428.839724 -354.350816) (xy 428.893713 -354.358572) (xy 428.946049 -354.373934)
			(xy 428.995666 -354.396588) (xy 429.041554 -354.426072) (xy 429.082778 -354.461788) (xy 429.118499 -354.503008)
			(xy 429.147989 -354.548891) (xy 429.170649 -354.598506) (xy 429.186017 -354.65084) (xy 429.19378 -354.704828)
			(xy 429.19378 -354.759372) (xy 429.19378 -354.759373) (xy 430.676484 -354.759373) (xy 430.676484 -354.704827)
			(xy 430.684246 -354.650837) (xy 430.699614 -354.598501) (xy 430.722273 -354.548884) (xy 430.751764 -354.502998)
			(xy 430.787484 -354.461776) (xy 430.828708 -354.426056) (xy 430.874595 -354.396568) (xy 430.924212 -354.37391)
			(xy 430.976548 -354.358544) (xy 431.030539 -354.350783) (xy 431.057812 -354.35032) (xy 431.921412 -354.35032)
			(xy 431.94868 -354.350843) (xy 432.002659 -354.358606) (xy 432.054985 -354.373972) (xy 432.104591 -354.396627)
			(xy 432.150468 -354.426112) (xy 432.191683 -354.461826) (xy 432.227395 -354.503041) (xy 432.256878 -354.548919)
			(xy 432.279533 -354.598526) (xy 432.294897 -354.650852) (xy 432.302658 -354.704832) (xy 432.302658 -354.759368)
			(xy 432.302658 -354.759369) (xy 433.785506 -354.759369) (xy 433.785506 -354.704831) (xy 433.793268 -354.650847)
			(xy 433.808632 -354.598517) (xy 433.831288 -354.548907) (xy 433.860772 -354.503025) (xy 433.896486 -354.461806)
			(xy 433.937702 -354.426089) (xy 433.983582 -354.396601) (xy 434.033191 -354.373942) (xy 434.08552 -354.358574)
			(xy 434.139503 -354.350808) (xy 434.166772 -354.35032) (xy 435.030372 -354.35032) (xy 435.057643 -354.350818)
			(xy 435.11163 -354.358576) (xy 435.163964 -354.373939) (xy 435.213578 -354.396594) (xy 435.259463 -354.42608)
			(xy 435.300685 -354.461795) (xy 435.336404 -354.503014) (xy 435.365892 -354.548897) (xy 435.388551 -354.59851)
			(xy 435.403918 -354.650842) (xy 435.41168 -354.704829) (xy 435.41168 -354.759371) (xy 435.41168 -354.759374)
			(xy 436.894384 -354.759374) (xy 436.894384 -354.704826) (xy 436.902147 -354.650834) (xy 436.917516 -354.598496)
			(xy 436.940177 -354.548879) (xy 436.969669 -354.502991) (xy 437.005391 -354.461768) (xy 437.046617 -354.426049)
			(xy 437.092507 -354.396561) (xy 437.142126 -354.373904) (xy 437.194465 -354.35854) (xy 437.248458 -354.350781)
			(xy 437.275732 -354.35032) (xy 438.139332 -354.35032) (xy 438.166599 -354.350845) (xy 438.220576 -354.35861)
			(xy 438.272899 -354.373977) (xy 438.322503 -354.396634) (xy 438.368378 -354.426119) (xy 438.40959 -354.461833)
			(xy 438.4453 -354.503048) (xy 438.474781 -354.548925) (xy 438.497434 -354.598531) (xy 438.512797 -354.650855)
			(xy 438.520558 -354.704833) (xy 438.520558 -354.759367) (xy 438.520558 -354.75937) (xy 440.003406 -354.75937)
			(xy 440.003406 -354.70483) (xy 440.011168 -354.650844) (xy 440.026534 -354.598513) (xy 440.049191 -354.548901)
			(xy 440.078677 -354.503018) (xy 440.114393 -354.461799) (xy 440.155612 -354.426082) (xy 440.201494 -354.396594)
			(xy 440.251105 -354.373937) (xy 440.303436 -354.35857) (xy 440.357422 -354.350807) (xy 440.384692 -354.35032)
			(xy 441.248292 -354.35032) (xy 441.275562 -354.350819) (xy 441.329547 -354.35858) (xy 441.381878 -354.373945)
			(xy 441.43149 -354.396601) (xy 441.477373 -354.426087) (xy 441.518592 -354.461802) (xy 441.554309 -354.503021)
			(xy 441.583796 -354.548903) (xy 441.606453 -354.598514) (xy 441.621819 -354.650845) (xy 441.629581 -354.70483)
			(xy 441.629581 -354.75937) (xy 441.621819 -354.813355) (xy 441.606453 -354.865686) (xy 441.583796 -354.915297)
			(xy 441.554309 -354.961179) (xy 441.518592 -355.002398) (xy 441.477373 -355.038113) (xy 441.43149 -355.067599)
			(xy 441.381878 -355.090255) (xy 441.329547 -355.10562) (xy 441.275562 -355.113381) (xy 441.248292 -355.113844)
			(xy 440.384692 -355.113844) (xy 440.357422 -355.113393) (xy 440.303436 -355.10563) (xy 440.251105 -355.090263)
			(xy 440.201494 -355.067606) (xy 440.155612 -355.038118) (xy 440.114393 -355.002401) (xy 440.078677 -354.961182)
			(xy 440.049191 -354.915299) (xy 440.026534 -354.865687) (xy 440.011168 -354.813356) (xy 440.003406 -354.75937)
			(xy 438.520558 -354.75937) (xy 438.512797 -354.813345) (xy 438.497434 -354.865669) (xy 438.474781 -354.915275)
			(xy 438.4453 -354.961152) (xy 438.40959 -355.002367) (xy 438.368378 -355.038081) (xy 438.322503 -355.067566)
			(xy 438.272899 -355.090223) (xy 438.220576 -355.10559) (xy 438.166599 -355.113355) (xy 438.139332 -355.113844)
			(xy 437.275732 -355.113844) (xy 437.248458 -355.113419) (xy 437.194465 -355.10566) (xy 437.142126 -355.090296)
			(xy 437.092507 -355.067639) (xy 437.046617 -355.038151) (xy 437.005391 -355.002432) (xy 436.969669 -354.961209)
			(xy 436.940177 -354.915321) (xy 436.917516 -354.865704) (xy 436.902147 -354.813366) (xy 436.894384 -354.759374)
			(xy 435.41168 -354.759374) (xy 435.403918 -354.813358) (xy 435.388551 -354.86569) (xy 435.365892 -354.915303)
			(xy 435.336404 -354.961186) (xy 435.300685 -355.002405) (xy 435.259463 -355.03812) (xy 435.213578 -355.067606)
			(xy 435.163964 -355.090261) (xy 435.11163 -355.105624) (xy 435.057643 -355.113382) (xy 435.030372 -355.113844)
			(xy 434.166772 -355.113844) (xy 434.139503 -355.113392) (xy 434.08552 -355.105626) (xy 434.033191 -355.090258)
			(xy 433.983582 -355.067599) (xy 433.937702 -355.038111) (xy 433.896486 -355.002394) (xy 433.860772 -354.961175)
			(xy 433.831288 -354.915293) (xy 433.808632 -354.865683) (xy 433.793268 -354.813353) (xy 433.785506 -354.759369)
			(xy 432.302658 -354.759369) (xy 432.294897 -354.813348) (xy 432.279533 -354.865674) (xy 432.256878 -354.915281)
			(xy 432.227395 -354.961159) (xy 432.191683 -355.002374) (xy 432.150468 -355.038088) (xy 432.104591 -355.067573)
			(xy 432.054985 -355.090228) (xy 432.002659 -355.105594) (xy 431.94868 -355.113357) (xy 431.921412 -355.113844)
			(xy 431.057812 -355.113844) (xy 431.030539 -355.113417) (xy 430.976548 -355.105656) (xy 430.924212 -355.09029)
			(xy 430.874595 -355.067632) (xy 430.828708 -355.038144) (xy 430.787484 -355.002424) (xy 430.751764 -354.961202)
			(xy 430.722273 -354.915316) (xy 430.699614 -354.865699) (xy 430.684246 -354.813363) (xy 430.676484 -354.759373)
			(xy 429.19378 -354.759373) (xy 429.186017 -354.81336) (xy 429.170649 -354.865694) (xy 429.147989 -354.915309)
			(xy 429.118499 -354.961192) (xy 429.082778 -355.002412) (xy 429.041554 -355.038128) (xy 428.995666 -355.067612)
			(xy 428.946049 -355.090266) (xy 428.893713 -355.105628) (xy 428.839724 -355.113384) (xy 428.812452 -355.113844)
			(xy 427.948852 -355.113844) (xy 427.921584 -355.11339) (xy 427.867603 -355.105623) (xy 427.815276 -355.090252)
			(xy 427.76567 -355.067592) (xy 427.719793 -355.038104) (xy 427.678579 -355.002387) (xy 427.642867 -354.961169)
			(xy 427.613385 -354.915288) (xy 427.590731 -354.865679) (xy 427.575367 -354.81335) (xy 427.567606 -354.759368)
			(xy 426.084781 -354.759368) (xy 426.084781 -354.75937) (xy 426.077019 -354.813355) (xy 426.061653 -354.865686)
			(xy 426.038996 -354.915297) (xy 426.009509 -354.961179) (xy 425.973792 -355.002398) (xy 425.932573 -355.038113)
			(xy 425.88669 -355.067599) (xy 425.837078 -355.090255) (xy 425.784747 -355.10562) (xy 425.730762 -355.113381)
			(xy 425.703492 -355.113844) (xy 424.839892 -355.113844) (xy 424.812622 -355.113393) (xy 424.758636 -355.10563)
			(xy 424.706305 -355.090263) (xy 424.656694 -355.067606) (xy 424.610812 -355.038118) (xy 424.569593 -355.002401)
			(xy 424.533877 -354.961182) (xy 424.504391 -354.915299) (xy 424.481734 -354.865687) (xy 424.466368 -354.813356)
			(xy 424.458606 -354.75937) (xy 422.975758 -354.75937) (xy 422.967997 -354.813345) (xy 422.952634 -354.865669)
			(xy 422.929981 -354.915275) (xy 422.9005 -354.961152) (xy 422.86479 -355.002367) (xy 422.823578 -355.038081)
			(xy 422.777703 -355.067566) (xy 422.728099 -355.090223) (xy 422.675776 -355.10559) (xy 422.621799 -355.113355)
			(xy 422.594532 -355.113844) (xy 421.730932 -355.113844) (xy 421.703658 -355.113419) (xy 421.649665 -355.10566)
			(xy 421.597326 -355.090296) (xy 421.547707 -355.067639) (xy 421.501817 -355.038151) (xy 421.460591 -355.002432)
			(xy 421.424869 -354.961209) (xy 421.395377 -354.915321) (xy 421.372716 -354.865704) (xy 421.357347 -354.813366)
			(xy 421.349584 -354.759374) (xy 419.86688 -354.759374) (xy 419.859118 -354.813358) (xy 419.843751 -354.86569)
			(xy 419.821092 -354.915303) (xy 419.791604 -354.961186) (xy 419.755885 -355.002405) (xy 419.714663 -355.03812)
			(xy 419.668778 -355.067606) (xy 419.619164 -355.090261) (xy 419.56683 -355.105624) (xy 419.512843 -355.113382)
			(xy 419.485572 -355.113844) (xy 418.621972 -355.113844) (xy 418.594703 -355.113392) (xy 418.54072 -355.105626)
			(xy 418.488391 -355.090258) (xy 418.438782 -355.067599) (xy 418.392902 -355.038111) (xy 418.351686 -355.002394)
			(xy 418.315972 -354.961175) (xy 418.286488 -354.915293) (xy 418.263832 -354.865683) (xy 418.248468 -354.813353)
			(xy 418.240706 -354.759369) (xy 416.757858 -354.759369) (xy 416.750097 -354.813348) (xy 416.734733 -354.865674)
			(xy 416.712078 -354.915281) (xy 416.682595 -354.961159) (xy 416.646883 -355.002374) (xy 416.605668 -355.038088)
			(xy 416.559791 -355.067573) (xy 416.510185 -355.090228) (xy 416.457859 -355.105594) (xy 416.40388 -355.113357)
			(xy 416.376612 -355.113844) (xy 415.513012 -355.113844) (xy 415.485739 -355.113417) (xy 415.431748 -355.105656)
			(xy 415.379412 -355.09029) (xy 415.329795 -355.067632) (xy 415.283908 -355.038144) (xy 415.242684 -355.002424)
			(xy 415.206964 -354.961202) (xy 415.177473 -354.915316) (xy 415.154814 -354.865699) (xy 415.139446 -354.813363)
			(xy 415.131684 -354.759373) (xy 413.64898 -354.759373) (xy 413.641217 -354.81336) (xy 413.625849 -354.865694)
			(xy 413.603189 -354.915309) (xy 413.573699 -354.961192) (xy 413.537978 -355.002412) (xy 413.496754 -355.038128)
			(xy 413.450866 -355.067612) (xy 413.401249 -355.090266) (xy 413.348913 -355.105628) (xy 413.294924 -355.113384)
			(xy 413.267652 -355.113844) (xy 412.404052 -355.113844) (xy 412.376784 -355.11339) (xy 412.322803 -355.105623)
			(xy 412.270476 -355.090252) (xy 412.22087 -355.067592) (xy 412.174993 -355.038104) (xy 412.133779 -355.002387)
			(xy 412.098067 -354.961169) (xy 412.068585 -354.915288) (xy 412.045931 -354.865679) (xy 412.030567 -354.81335)
			(xy 412.022806 -354.759368) (xy 403.52248 -354.759368) (xy 403.52248 -354.759371) (xy 403.514718 -354.813357)
			(xy 403.499352 -354.865689) (xy 403.476694 -354.915301) (xy 403.447206 -354.961183) (xy 403.411488 -355.002402)
			(xy 403.370267 -355.038118) (xy 403.324383 -355.067603) (xy 403.27477 -355.090259) (xy 403.222437 -355.105622)
			(xy 403.168451 -355.113382) (xy 403.14118 -355.113844) (xy 402.27758 -355.113844) (xy 402.25031 -355.113392)
			(xy 402.196326 -355.105628) (xy 402.143997 -355.09026) (xy 402.094387 -355.067602) (xy 402.048506 -355.038114)
			(xy 402.007289 -355.002397) (xy 401.971574 -354.961178) (xy 401.942089 -354.915296) (xy 401.919433 -354.865685)
			(xy 401.904068 -354.813354) (xy 401.896306 -354.75937) (xy 400.413458 -354.75937) (xy 400.405697 -354.813346)
			(xy 400.390333 -354.865672) (xy 400.36768 -354.915278) (xy 400.338197 -354.961156) (xy 400.302486 -355.002371)
			(xy 400.261272 -355.038085) (xy 400.215396 -355.06757) (xy 400.165791 -355.090226) (xy 400.113466 -355.105593)
			(xy 400.059487 -355.113356) (xy 400.03222 -355.113844) (xy 399.16862 -355.113844) (xy 399.141347 -355.113418)
			(xy 399.087355 -355.105658) (xy 399.035018 -355.090292) (xy 398.9854 -355.067635) (xy 398.939511 -355.038146)
			(xy 398.898287 -355.002427) (xy 398.862566 -354.961205) (xy 398.833075 -354.915318) (xy 398.810415 -354.865701)
			(xy 398.795047 -354.813364) (xy 398.787284 -354.759373) (xy 397.30458 -354.759373) (xy 397.296818 -354.813359)
			(xy 397.28145 -354.865693) (xy 397.258791 -354.915306) (xy 397.229301 -354.96119) (xy 397.193581 -355.002409)
			(xy 397.152358 -355.038125) (xy 397.106471 -355.06761) (xy 397.056855 -355.090264) (xy 397.00452 -355.105626)
			(xy 396.950532 -355.113383) (xy 396.92326 -355.113844) (xy 396.05966 -355.113844) (xy 396.032391 -355.113391)
			(xy 395.978409 -355.105624) (xy 395.926082 -355.090255) (xy 395.876475 -355.067595) (xy 395.830597 -355.038107)
			(xy 395.789382 -355.00239) (xy 395.753669 -354.961171) (xy 395.724186 -354.91529) (xy 395.701531 -354.86568)
			(xy 395.686167 -354.813351) (xy 395.678406 -354.759369) (xy 394.195558 -354.759369) (xy 394.187796 -354.813349)
			(xy 394.172432 -354.865676) (xy 394.149777 -354.915284) (xy 394.120292 -354.961163) (xy 394.084578 -355.002378)
			(xy 394.043363 -355.038092) (xy 393.997484 -355.067577) (xy 393.947876 -355.090232) (xy 393.895549 -355.105596)
			(xy 393.841568 -355.113358) (xy 393.8143 -355.113844) (xy 392.9507 -355.113844) (xy 392.923429 -355.113394)
			(xy 392.869443 -355.105631) (xy 392.817111 -355.090265) (xy 392.767499 -355.067608) (xy 392.721616 -355.038121)
			(xy 392.680396 -355.002404) (xy 392.644679 -354.961184) (xy 392.615192 -354.915301) (xy 392.592535 -354.865689)
			(xy 392.577169 -354.813357) (xy 392.569406 -354.759371) (xy 391.086557 -354.759371) (xy 391.078797 -354.813344)
			(xy 391.063435 -354.865668) (xy 391.040783 -354.915273) (xy 391.011302 -354.96115) (xy 390.975593 -355.002364)
			(xy 390.934382 -355.038078) (xy 390.888508 -355.067563) (xy 390.838905 -355.090221) (xy 390.786583 -355.105589)
			(xy 390.732606 -355.113355) (xy 390.70534 -355.113844) (xy 389.84174 -355.113844) (xy 389.814466 -355.113419)
			(xy 389.760472 -355.105661) (xy 389.708132 -355.090298) (xy 389.658512 -355.067641) (xy 389.612621 -355.038153)
			(xy 389.571394 -355.002434) (xy 389.535671 -354.961211) (xy 389.506178 -354.915324) (xy 389.483516 -354.865705)
			(xy 389.468147 -354.813367) (xy 389.460384 -354.759374) (xy 387.97768 -354.759374) (xy 387.969918 -354.813357)
			(xy 387.954552 -354.865689) (xy 387.931894 -354.915301) (xy 387.902406 -354.961183) (xy 387.866688 -355.002402)
			(xy 387.825467 -355.038118) (xy 387.779583 -355.067603) (xy 387.72997 -355.090259) (xy 387.677637 -355.105622)
			(xy 387.623651 -355.113382) (xy 387.59638 -355.113844) (xy 386.73278 -355.113844) (xy 386.70551 -355.113392)
			(xy 386.651526 -355.105628) (xy 386.599197 -355.09026) (xy 386.549587 -355.067602) (xy 386.503706 -355.038114)
			(xy 386.462489 -355.002397) (xy 386.426774 -354.961178) (xy 386.397289 -354.915296) (xy 386.374633 -354.865685)
			(xy 386.359268 -354.813354) (xy 386.351506 -354.75937) (xy 384.868658 -354.75937) (xy 384.860897 -354.813346)
			(xy 384.845533 -354.865672) (xy 384.82288 -354.915278) (xy 384.793397 -354.961156) (xy 384.757686 -355.002371)
			(xy 384.716472 -355.038085) (xy 384.670596 -355.06757) (xy 384.620991 -355.090226) (xy 384.568666 -355.105593)
			(xy 384.514687 -355.113356) (xy 384.48742 -355.113844) (xy 383.62382 -355.113844) (xy 383.596547 -355.113418)
			(xy 383.542555 -355.105658) (xy 383.490218 -355.090292) (xy 383.4406 -355.067635) (xy 383.394711 -355.038146)
			(xy 383.353487 -355.002427) (xy 383.317766 -354.961205) (xy 383.288275 -354.915318) (xy 383.265615 -354.865701)
			(xy 383.250247 -354.813364) (xy 383.242484 -354.759373) (xy 381.75978 -354.759373) (xy 381.752018 -354.813359)
			(xy 381.73665 -354.865693) (xy 381.713991 -354.915306) (xy 381.684501 -354.96119) (xy 381.648781 -355.002409)
			(xy 381.607558 -355.038125) (xy 381.561671 -355.06761) (xy 381.512055 -355.090264) (xy 381.45972 -355.105626)
			(xy 381.405732 -355.113383) (xy 381.37846 -355.113844) (xy 380.51486 -355.113844) (xy 380.487591 -355.113391)
			(xy 380.433609 -355.105624) (xy 380.381282 -355.090255) (xy 380.331675 -355.067595) (xy 380.285797 -355.038107)
			(xy 380.244582 -355.00239) (xy 380.208869 -354.961171) (xy 380.179386 -354.91529) (xy 380.156731 -354.86568)
			(xy 380.141367 -354.813351) (xy 380.133606 -354.759369) (xy 378.650758 -354.759369) (xy 378.642996 -354.813349)
			(xy 378.627632 -354.865676) (xy 378.604977 -354.915284) (xy 378.575492 -354.961163) (xy 378.539778 -355.002378)
			(xy 378.498563 -355.038092) (xy 378.452684 -355.067577) (xy 378.403076 -355.090232) (xy 378.350749 -355.105596)
			(xy 378.296768 -355.113358) (xy 378.2695 -355.113844) (xy 377.4059 -355.113844) (xy 377.378629 -355.113394)
			(xy 377.324643 -355.105631) (xy 377.272311 -355.090265) (xy 377.222699 -355.067608) (xy 377.176816 -355.038121)
			(xy 377.135596 -355.002404) (xy 377.099879 -354.961184) (xy 377.070392 -354.915301) (xy 377.047735 -354.865689)
			(xy 377.032369 -354.813357) (xy 377.024606 -354.759371) (xy 375.541757 -354.759371) (xy 375.533997 -354.813344)
			(xy 375.518635 -354.865668) (xy 375.495983 -354.915273) (xy 375.466502 -354.96115) (xy 375.430793 -355.002364)
			(xy 375.389582 -355.038078) (xy 375.343708 -355.067563) (xy 375.294105 -355.090221) (xy 375.241783 -355.105589)
			(xy 375.187806 -355.113355) (xy 375.16054 -355.113844) (xy 374.29694 -355.113844) (xy 374.269666 -355.113419)
			(xy 374.215672 -355.105661) (xy 374.163332 -355.090298) (xy 374.113712 -355.067641) (xy 374.067821 -355.038153)
			(xy 374.026594 -355.002434) (xy 373.990871 -354.961211) (xy 373.961378 -354.915324) (xy 373.938716 -354.865705)
			(xy 373.923347 -354.813367) (xy 373.915584 -354.759374) (xy 344.837257 -354.759374) (xy 344.829496 -354.813349)
			(xy 344.814132 -354.865675) (xy 344.791477 -354.915283) (xy 344.761993 -354.961161) (xy 344.72628 -355.002377)
			(xy 344.685065 -355.038091) (xy 344.639186 -355.067575) (xy 344.589579 -355.090231) (xy 344.537253 -355.105596)
			(xy 344.483272 -355.113357) (xy 344.456004 -355.113844) (xy 343.592404 -355.113844) (xy 343.565132 -355.113417)
			(xy 343.511142 -355.105655) (xy 343.458806 -355.090288) (xy 343.40919 -355.06763) (xy 343.363304 -355.038141)
			(xy 343.322081 -355.002422) (xy 343.286362 -354.961199) (xy 343.256872 -354.915313) (xy 343.234213 -354.865698)
			(xy 343.218846 -354.813362) (xy 343.211084 -354.759372) (xy 341.728257 -354.759372) (xy 341.720498 -354.813343)
			(xy 341.705135 -354.865667) (xy 341.682483 -354.915272) (xy 341.653003 -354.961148) (xy 341.617294 -355.002363)
			(xy 341.576084 -355.038076) (xy 341.53021 -355.067562) (xy 341.480608 -355.09022) (xy 341.428286 -355.105588)
			(xy 341.37431 -355.113355) (xy 341.347044 -355.113844) (xy 340.483444 -355.113844) (xy 340.45617 -355.113419)
			(xy 340.402175 -355.105662) (xy 340.349835 -355.090299) (xy 340.300214 -355.067643) (xy 340.254323 -355.038155)
			(xy 340.213095 -355.002436) (xy 340.177371 -354.961213) (xy 340.147878 -354.915325) (xy 340.125217 -354.865706)
			(xy 340.109847 -354.813368) (xy 340.102084 -354.759374) (xy 338.61938 -354.759374) (xy 338.611618 -354.813356)
			(xy 338.596252 -354.865688) (xy 338.573594 -354.9153) (xy 338.544107 -354.961182) (xy 338.508389 -355.0024)
			(xy 338.467169 -355.038116) (xy 338.421285 -355.067602) (xy 338.371673 -355.090258) (xy 338.319341 -355.105622)
			(xy 338.265354 -355.113382) (xy 338.238084 -355.113844) (xy 337.374484 -355.113844) (xy 337.347214 -355.113392)
			(xy 337.29323 -355.105629) (xy 337.2409 -355.090261) (xy 337.191289 -355.067603) (xy 337.145408 -355.038115)
			(xy 337.10419 -355.002398) (xy 337.068475 -354.961179) (xy 337.038989 -354.915297) (xy 337.016333 -354.865685)
			(xy 337.000968 -354.813355) (xy 336.993206 -354.75937) (xy 335.510358 -354.75937) (xy 335.502597 -354.813346)
			(xy 335.487234 -354.865671) (xy 335.46458 -354.915277) (xy 335.435098 -354.961155) (xy 335.399387 -355.00237)
			(xy 335.358174 -355.038084) (xy 335.312298 -355.067569) (xy 335.262694 -355.090225) (xy 335.210369 -355.105592)
			(xy 335.156391 -355.113356) (xy 335.129124 -355.113844) (xy 334.265524 -355.113844) (xy 334.238251 -355.113418)
			(xy 334.184259 -355.105658) (xy 334.131921 -355.090293) (xy 334.082302 -355.067636) (xy 334.036413 -355.038148)
			(xy 333.995188 -355.002429) (xy 333.959467 -354.961206) (xy 333.929975 -354.915319) (xy 333.907315 -354.865702)
			(xy 333.891947 -354.813365) (xy 333.884184 -354.759373) (xy 332.40148 -354.759373) (xy 332.393718 -354.813359)
			(xy 332.37835 -354.865692) (xy 332.355691 -354.915305) (xy 332.326202 -354.961188) (xy 332.290482 -355.002407)
			(xy 332.24926 -355.038123) (xy 332.203374 -355.067609) (xy 332.153758 -355.090263) (xy 332.101424 -355.105625)
			(xy 332.047435 -355.113383) (xy 332.020164 -355.113844) (xy 331.156564 -355.113844) (xy 331.129295 -355.113391)
			(xy 331.075313 -355.105625) (xy 331.022985 -355.090256) (xy 330.973377 -355.067596) (xy 330.927499 -355.038108)
			(xy 330.886283 -355.002391) (xy 330.85057 -354.961173) (xy 330.821086 -354.915291) (xy 330.798432 -354.865681)
			(xy 330.783067 -354.813352) (xy 330.775306 -354.759369) (xy 329.292458 -354.759369) (xy 329.284696 -354.813349)
			(xy 329.269332 -354.865675) (xy 329.246677 -354.915283) (xy 329.217193 -354.961161) (xy 329.18148 -355.002377)
			(xy 329.140265 -355.038091) (xy 329.094386 -355.067575) (xy 329.044779 -355.090231) (xy 328.992453 -355.105596)
			(xy 328.938472 -355.113357) (xy 328.911204 -355.113844) (xy 328.047604 -355.113844) (xy 328.020332 -355.113417)
			(xy 327.966342 -355.105655) (xy 327.914006 -355.090288) (xy 327.86439 -355.06763) (xy 327.818504 -355.038141)
			(xy 327.777281 -355.002422) (xy 327.741562 -354.961199) (xy 327.712072 -354.915313) (xy 327.689413 -354.865698)
			(xy 327.674046 -354.813362) (xy 327.666284 -354.759372) (xy 326.183457 -354.759372) (xy 326.175698 -354.813343)
			(xy 326.160335 -354.865667) (xy 326.137683 -354.915272) (xy 326.108203 -354.961148) (xy 326.072494 -355.002363)
			(xy 326.031284 -355.038076) (xy 325.98541 -355.067562) (xy 325.935808 -355.09022) (xy 325.883486 -355.105588)
			(xy 325.82951 -355.113355) (xy 325.802244 -355.113844) (xy 324.938644 -355.113844) (xy 324.91137 -355.113419)
			(xy 324.857375 -355.105662) (xy 324.805035 -355.090299) (xy 324.755414 -355.067643) (xy 324.709523 -355.038155)
			(xy 324.668295 -355.002436) (xy 324.632571 -354.961213) (xy 324.603078 -354.915325) (xy 324.580417 -354.865706)
			(xy 324.565047 -354.813368) (xy 324.557284 -354.759374) (xy 323.07458 -354.759374) (xy 323.066818 -354.813356)
			(xy 323.051452 -354.865688) (xy 323.028794 -354.9153) (xy 322.999307 -354.961182) (xy 322.963589 -355.0024)
			(xy 322.922369 -355.038116) (xy 322.876485 -355.067602) (xy 322.826873 -355.090258) (xy 322.774541 -355.105622)
			(xy 322.720554 -355.113382) (xy 322.693284 -355.113844) (xy 321.829684 -355.113844) (xy 321.802414 -355.113392)
			(xy 321.74843 -355.105629) (xy 321.6961 -355.090261) (xy 321.646489 -355.067603) (xy 321.600608 -355.038115)
			(xy 321.55939 -355.002398) (xy 321.523675 -354.961179) (xy 321.494189 -354.915297) (xy 321.471533 -354.865685)
			(xy 321.456168 -354.813355) (xy 321.448406 -354.75937) (xy 319.965558 -354.75937) (xy 319.957797 -354.813346)
			(xy 319.942434 -354.865671) (xy 319.91978 -354.915277) (xy 319.890298 -354.961155) (xy 319.854587 -355.00237)
			(xy 319.813374 -355.038084) (xy 319.767498 -355.067569) (xy 319.717894 -355.090225) (xy 319.665569 -355.105592)
			(xy 319.611591 -355.113356) (xy 319.584324 -355.113844) (xy 318.720724 -355.113844) (xy 318.693451 -355.113418)
			(xy 318.639459 -355.105658) (xy 318.587121 -355.090293) (xy 318.537502 -355.067636) (xy 318.491613 -355.038148)
			(xy 318.450388 -355.002429) (xy 318.414667 -354.961206) (xy 318.385175 -354.915319) (xy 318.362515 -354.865702)
			(xy 318.347147 -354.813365) (xy 318.339384 -354.759373) (xy 316.85668 -354.759373) (xy 316.848918 -354.813359)
			(xy 316.83355 -354.865692) (xy 316.810891 -354.915305) (xy 316.781402 -354.961188) (xy 316.745682 -355.002407)
			(xy 316.70446 -355.038123) (xy 316.658574 -355.067609) (xy 316.608958 -355.090263) (xy 316.556624 -355.105625)
			(xy 316.502635 -355.113383) (xy 316.475364 -355.113844) (xy 315.611764 -355.113844) (xy 315.584495 -355.113391)
			(xy 315.530513 -355.105625) (xy 315.478185 -355.090256) (xy 315.428577 -355.067596) (xy 315.382699 -355.038108)
			(xy 315.341483 -355.002391) (xy 315.30577 -354.961173) (xy 315.276286 -354.915291) (xy 315.253632 -354.865681)
			(xy 315.238267 -354.813352) (xy 315.230506 -354.759369) (xy 300.231558 -354.759369) (xy 300.223796 -354.813349)
			(xy 300.208432 -354.865676) (xy 300.185777 -354.915283) (xy 300.156293 -354.961162) (xy 300.120579 -355.002378)
			(xy 300.079364 -355.038091) (xy 300.033485 -355.067576) (xy 299.983878 -355.090231) (xy 299.931551 -355.105596)
			(xy 299.87757 -355.113357) (xy 299.850302 -355.113844) (xy 298.986702 -355.113844) (xy 298.95943 -355.113417)
			(xy 298.90544 -355.105654) (xy 298.853105 -355.090288) (xy 298.803489 -355.067629) (xy 298.757603 -355.03814)
			(xy 298.716381 -355.002421) (xy 298.680661 -354.961199) (xy 298.651172 -354.915313) (xy 298.628513 -354.865697)
			(xy 298.613146 -354.813362) (xy 298.605384 -354.759372) (xy 297.122557 -354.759372) (xy 297.114798 -354.813344)
			(xy 297.099435 -354.865667) (xy 297.076783 -354.915272) (xy 297.047302 -354.961149) (xy 297.011593 -355.002364)
			(xy 296.970383 -355.038077) (xy 296.924509 -355.067563) (xy 296.874907 -355.09022) (xy 296.822585 -355.105589)
			(xy 296.768608 -355.113355) (xy 296.741342 -355.113844) (xy 295.877742 -355.113844) (xy 295.850468 -355.113419)
			(xy 295.796474 -355.105662) (xy 295.744134 -355.090298) (xy 295.694513 -355.067642) (xy 295.648622 -355.038154)
			(xy 295.607395 -355.002435) (xy 295.571671 -354.961212) (xy 295.542178 -354.915324) (xy 295.519516 -354.865706)
			(xy 295.504147 -354.813367) (xy 295.496384 -354.759374) (xy 294.013681 -354.759374) (xy 294.005918 -354.813356)
			(xy 293.990552 -354.865688) (xy 293.967894 -354.9153) (xy 293.938406 -354.961182) (xy 293.902688 -355.002401)
			(xy 293.861468 -355.038117) (xy 293.815584 -355.067603) (xy 293.765971 -355.090258) (xy 293.713639 -355.105622)
			(xy 293.659653 -355.113382) (xy 293.632382 -355.113844) (xy 292.768782 -355.113844) (xy 292.741512 -355.113392)
			(xy 292.687528 -355.105628) (xy 292.635198 -355.090261) (xy 292.585588 -355.067602) (xy 292.539707 -355.038115)
			(xy 292.49849 -355.002398) (xy 292.462775 -354.961178) (xy 292.433289 -354.915296) (xy 292.410633 -354.865685)
			(xy 292.395268 -354.813354) (xy 292.387506 -354.75937) (xy 290.904658 -354.75937) (xy 290.896897 -354.813346)
			(xy 290.881533 -354.865672) (xy 290.85888 -354.915278) (xy 290.829397 -354.961156) (xy 290.793686 -355.002371)
			(xy 290.752473 -355.038084) (xy 290.706597 -355.067569) (xy 290.656992 -355.090226) (xy 290.604668 -355.105592)
			(xy 290.550689 -355.113356) (xy 290.523422 -355.113844) (xy 289.659822 -355.113844) (xy 289.632549 -355.113418)
			(xy 289.578557 -355.105658) (xy 289.526219 -355.090293) (xy 289.476601 -355.067636) (xy 289.430712 -355.038147)
			(xy 289.389488 -355.002428) (xy 289.353766 -354.961205) (xy 289.324275 -354.915318) (xy 289.301615 -354.865702)
			(xy 289.286247 -354.813365) (xy 289.278484 -354.759373) (xy 287.79578 -354.759373) (xy 287.788018 -354.813359)
			(xy 287.77265 -354.865692) (xy 287.749991 -354.915306) (xy 287.720501 -354.961189) (xy 287.684781 -355.002408)
			(xy 287.643559 -355.038124) (xy 287.597672 -355.067609) (xy 287.548057 -355.090264) (xy 287.495722 -355.105626)
			(xy 287.441733 -355.113383) (xy 287.414462 -355.113844) (xy 286.550862 -355.113844) (xy 286.523593 -355.113391)
			(xy 286.469611 -355.105625) (xy 286.417284 -355.090255) (xy 286.367676 -355.067596) (xy 286.321798 -355.038107)
			(xy 286.280583 -355.00239) (xy 286.24487 -354.961172) (xy 286.215386 -354.915291) (xy 286.192732 -354.865681)
			(xy 286.177367 -354.813352) (xy 286.169606 -354.759369) (xy 284.686758 -354.759369) (xy 284.678996 -354.813349)
			(xy 284.663632 -354.865676) (xy 284.640977 -354.915283) (xy 284.611493 -354.961162) (xy 284.575779 -355.002378)
			(xy 284.534564 -355.038091) (xy 284.488685 -355.067576) (xy 284.439078 -355.090231) (xy 284.386751 -355.105596)
			(xy 284.33277 -355.113357) (xy 284.305502 -355.113844) (xy 283.441902 -355.113844) (xy 283.41463 -355.113417)
			(xy 283.36064 -355.105654) (xy 283.308305 -355.090288) (xy 283.258689 -355.067629) (xy 283.212803 -355.03814)
			(xy 283.171581 -355.002421) (xy 283.135861 -354.961199) (xy 283.106372 -354.915313) (xy 283.083713 -354.865697)
			(xy 283.068346 -354.813362) (xy 283.060584 -354.759372) (xy 281.577757 -354.759372) (xy 281.569998 -354.813344)
			(xy 281.554635 -354.865667) (xy 281.531983 -354.915272) (xy 281.502502 -354.961149) (xy 281.466793 -355.002364)
			(xy 281.425583 -355.038077) (xy 281.379709 -355.067563) (xy 281.330107 -355.09022) (xy 281.277785 -355.105589)
			(xy 281.223808 -355.113355) (xy 281.196542 -355.113844) (xy 280.332942 -355.113844) (xy 280.305668 -355.113419)
			(xy 280.251674 -355.105662) (xy 280.199334 -355.090298) (xy 280.149713 -355.067642) (xy 280.103822 -355.038154)
			(xy 280.062595 -355.002435) (xy 280.026871 -354.961212) (xy 279.997378 -354.915324) (xy 279.974716 -354.865706)
			(xy 279.959347 -354.813367) (xy 279.951584 -354.759374) (xy 278.468881 -354.759374) (xy 278.461118 -354.813356)
			(xy 278.445752 -354.865688) (xy 278.423094 -354.9153) (xy 278.393606 -354.961182) (xy 278.357888 -355.002401)
			(xy 278.316668 -355.038117) (xy 278.270784 -355.067603) (xy 278.221171 -355.090258) (xy 278.168839 -355.105622)
			(xy 278.114853 -355.113382) (xy 278.087582 -355.113844) (xy 277.223982 -355.113844) (xy 277.196712 -355.113392)
			(xy 277.142728 -355.105628) (xy 277.090398 -355.090261) (xy 277.040788 -355.067602) (xy 276.994907 -355.038115)
			(xy 276.95369 -355.002398) (xy 276.917975 -354.961178) (xy 276.888489 -354.915296) (xy 276.865833 -354.865685)
			(xy 276.850468 -354.813354) (xy 276.842706 -354.75937) (xy 275.359858 -354.75937) (xy 275.352097 -354.813346)
			(xy 275.336733 -354.865672) (xy 275.31408 -354.915278) (xy 275.284597 -354.961156) (xy 275.248886 -355.002371)
			(xy 275.207673 -355.038084) (xy 275.161797 -355.067569) (xy 275.112192 -355.090226) (xy 275.059868 -355.105592)
			(xy 275.005889 -355.113356) (xy 274.978622 -355.113844) (xy 274.115022 -355.113844) (xy 274.087749 -355.113418)
			(xy 274.033757 -355.105658) (xy 273.981419 -355.090293) (xy 273.931801 -355.067636) (xy 273.885912 -355.038147)
			(xy 273.844688 -355.002428) (xy 273.808966 -354.961205) (xy 273.779475 -354.915318) (xy 273.756815 -354.865702)
			(xy 273.741447 -354.813365) (xy 273.733684 -354.759373) (xy 272.25098 -354.759373) (xy 272.243218 -354.813359)
			(xy 272.22785 -354.865692) (xy 272.205191 -354.915306) (xy 272.175701 -354.961189) (xy 272.139981 -355.002408)
			(xy 272.098759 -355.038124) (xy 272.052872 -355.067609) (xy 272.003257 -355.090264) (xy 271.950922 -355.105626)
			(xy 271.896933 -355.113383) (xy 271.869662 -355.113844) (xy 271.006062 -355.113844) (xy 270.978793 -355.113391)
			(xy 270.924811 -355.105625) (xy 270.872484 -355.090255) (xy 270.822876 -355.067596) (xy 270.776998 -355.038107)
			(xy 270.735783 -355.00239) (xy 270.70007 -354.961172) (xy 270.670586 -354.915291) (xy 270.647932 -354.865681)
			(xy 270.632567 -354.813352) (xy 270.624806 -354.759369) (xy 188.299268 -354.759369) (xy 188.294942 -354.78946)
			(xy 188.279575 -354.841794) (xy 188.256917 -354.891409) (xy 188.227428 -354.937294) (xy 188.191709 -354.978515)
			(xy 188.150487 -355.014233) (xy 188.104602 -355.04372) (xy 188.054987 -355.066378) (xy 188.002652 -355.081744)
			(xy 187.948664 -355.089505) (xy 187.921392 -355.089968) (xy 187.057792 -355.089968) (xy 187.030523 -355.089469)
			(xy 186.976542 -355.081707) (xy 186.924214 -355.066341) (xy 186.874605 -355.043684) (xy 186.828726 -355.014199)
			(xy 186.78751 -354.978484) (xy 186.751796 -354.937267) (xy 186.722312 -354.891388) (xy 186.699656 -354.841779)
			(xy 186.684292 -354.789451) (xy 186.67653 -354.735469) (xy 185.193682 -354.735469) (xy 185.185921 -354.78945)
			(xy 185.170557 -354.841778) (xy 185.147903 -354.891387) (xy 185.118419 -354.937267) (xy 185.082707 -354.978484)
			(xy 185.041492 -355.0142) (xy 184.995615 -355.043687) (xy 184.946008 -355.066346) (xy 184.893681 -355.081714)
			(xy 184.8397 -355.089479) (xy 184.812432 -355.089968) (xy 183.948832 -355.089968) (xy 183.92156 -355.089495)
			(xy 183.86757 -355.081736) (xy 183.815235 -355.066373) (xy 183.765618 -355.043718) (xy 183.719731 -355.014231)
			(xy 183.678508 -354.978515) (xy 183.642788 -354.937294) (xy 183.613298 -354.89141) (xy 183.590638 -354.841795)
			(xy 183.57527 -354.789461) (xy 183.567508 -354.735472) (xy 182.08478 -354.735472) (xy 182.08478 -354.759371)
			(xy 182.077018 -354.813358) (xy 182.061651 -354.86569) (xy 182.038992 -354.915303) (xy 182.009504 -354.961186)
			(xy 181.973785 -355.002405) (xy 181.932563 -355.03812) (xy 181.886678 -355.067606) (xy 181.837064 -355.090261)
			(xy 181.78473 -355.105624) (xy 181.730743 -355.113382) (xy 181.703472 -355.113844) (xy 180.839872 -355.113844)
			(xy 180.812603 -355.113392) (xy 180.75862 -355.105626) (xy 180.706291 -355.090258) (xy 180.656682 -355.067599)
			(xy 180.610802 -355.038111) (xy 180.569586 -355.002394) (xy 180.533872 -354.961175) (xy 180.504388 -354.915293)
			(xy 180.481732 -354.865683) (xy 180.466368 -354.813353) (xy 180.458606 -354.759369) (xy 178.975758 -354.759369)
			(xy 178.967997 -354.813348) (xy 178.952633 -354.865674) (xy 178.929978 -354.915281) (xy 178.900495 -354.961159)
			(xy 178.864783 -355.002374) (xy 178.823568 -355.038088) (xy 178.777691 -355.067573) (xy 178.728085 -355.090228)
			(xy 178.675759 -355.105594) (xy 178.62178 -355.113357) (xy 178.594512 -355.113844) (xy 177.730912 -355.113844)
			(xy 177.703639 -355.113417) (xy 177.649648 -355.105656) (xy 177.597312 -355.09029) (xy 177.547695 -355.067632)
			(xy 177.501808 -355.038144) (xy 177.460584 -355.002424) (xy 177.424864 -354.961202) (xy 177.395373 -354.915316)
			(xy 177.372714 -354.865699) (xy 177.357346 -354.813363) (xy 177.349584 -354.759373) (xy 175.86688 -354.759373)
			(xy 175.859117 -354.81336) (xy 175.843749 -354.865694) (xy 175.821089 -354.915309) (xy 175.791599 -354.961192)
			(xy 175.755878 -355.002412) (xy 175.714654 -355.038128) (xy 175.668766 -355.067612) (xy 175.619149 -355.090266)
			(xy 175.566813 -355.105628) (xy 175.512824 -355.113384) (xy 175.485552 -355.113844) (xy 174.621952 -355.113844)
			(xy 174.594684 -355.11339) (xy 174.540703 -355.105623) (xy 174.488376 -355.090252) (xy 174.43877 -355.067592)
			(xy 174.392893 -355.038104) (xy 174.351679 -355.002387) (xy 174.315967 -354.961169) (xy 174.286485 -354.915288)
			(xy 174.263831 -354.865679) (xy 174.248467 -354.81335) (xy 174.240706 -354.759368) (xy 172.757881 -354.759368)
			(xy 172.757881 -354.75937) (xy 172.750119 -354.813355) (xy 172.734753 -354.865686) (xy 172.712096 -354.915297)
			(xy 172.682609 -354.961179) (xy 172.646892 -355.002398) (xy 172.605673 -355.038113) (xy 172.55979 -355.067599)
			(xy 172.510178 -355.090255) (xy 172.457847 -355.10562) (xy 172.403862 -355.113381) (xy 172.376592 -355.113844)
			(xy 171.512992 -355.113844) (xy 171.485722 -355.113393) (xy 171.431736 -355.10563) (xy 171.379405 -355.090263)
			(xy 171.329794 -355.067606) (xy 171.283912 -355.038118) (xy 171.242693 -355.002401) (xy 171.206977 -354.961182)
			(xy 171.177491 -354.915299) (xy 171.154834 -354.865687) (xy 171.139468 -354.813356) (xy 171.131706 -354.75937)
			(xy 169.648858 -354.75937) (xy 169.641097 -354.813345) (xy 169.625734 -354.865669) (xy 169.603081 -354.915275)
			(xy 169.5736 -354.961152) (xy 169.53789 -355.002367) (xy 169.496678 -355.038081) (xy 169.450803 -355.067566)
			(xy 169.401199 -355.090223) (xy 169.348876 -355.10559) (xy 169.294899 -355.113355) (xy 169.267632 -355.113844)
			(xy 168.404032 -355.113844) (xy 168.376758 -355.113419) (xy 168.322765 -355.10566) (xy 168.270426 -355.090296)
			(xy 168.220807 -355.067639) (xy 168.174917 -355.038151) (xy 168.133691 -355.002432) (xy 168.097969 -354.961209)
			(xy 168.068477 -354.915321) (xy 168.045816 -354.865704) (xy 168.030447 -354.813366) (xy 168.022684 -354.759374)
			(xy 166.53998 -354.759374) (xy 166.532218 -354.813358) (xy 166.516851 -354.86569) (xy 166.494192 -354.915303)
			(xy 166.464704 -354.961186) (xy 166.428985 -355.002405) (xy 166.387763 -355.03812) (xy 166.341878 -355.067606)
			(xy 166.292264 -355.090261) (xy 166.23993 -355.105624) (xy 166.185943 -355.113382) (xy 166.158672 -355.113844)
			(xy 165.295072 -355.113844) (xy 165.267803 -355.113392) (xy 165.21382 -355.105626) (xy 165.161491 -355.090258)
			(xy 165.111882 -355.067599) (xy 165.066002 -355.038111) (xy 165.024786 -355.002394) (xy 164.989072 -354.961175)
			(xy 164.959588 -354.915293) (xy 164.936932 -354.865683) (xy 164.921568 -354.813353) (xy 164.913806 -354.759369)
			(xy 163.430958 -354.759369) (xy 163.423197 -354.813348) (xy 163.407833 -354.865674) (xy 163.385178 -354.915281)
			(xy 163.355695 -354.961159) (xy 163.319983 -355.002374) (xy 163.278768 -355.038088) (xy 163.232891 -355.067573)
			(xy 163.183285 -355.090228) (xy 163.130959 -355.105594) (xy 163.07698 -355.113357) (xy 163.049712 -355.113844)
			(xy 162.186112 -355.113844) (xy 162.158839 -355.113417) (xy 162.104848 -355.105656) (xy 162.052512 -355.09029)
			(xy 162.002895 -355.067632) (xy 161.957008 -355.038144) (xy 161.915784 -355.002424) (xy 161.880064 -354.961202)
			(xy 161.850573 -354.915316) (xy 161.827914 -354.865699) (xy 161.812546 -354.813363) (xy 161.804784 -354.759373)
			(xy 160.32208 -354.759373) (xy 160.314317 -354.81336) (xy 160.298949 -354.865694) (xy 160.276289 -354.915309)
			(xy 160.246799 -354.961192) (xy 160.211078 -355.002412) (xy 160.169854 -355.038128) (xy 160.123966 -355.067612)
			(xy 160.074349 -355.090266) (xy 160.022013 -355.105628) (xy 159.968024 -355.113384) (xy 159.940752 -355.113844)
			(xy 159.077152 -355.113844) (xy 159.049884 -355.11339) (xy 158.995903 -355.105623) (xy 158.943576 -355.090252)
			(xy 158.89397 -355.067592) (xy 158.848093 -355.038104) (xy 158.806879 -355.002387) (xy 158.771167 -354.961169)
			(xy 158.741685 -354.915288) (xy 158.719031 -354.865679) (xy 158.703667 -354.81335) (xy 158.695906 -354.759368)
			(xy 144.196558 -354.759368) (xy 144.188797 -354.813348) (xy 144.173432 -354.865675) (xy 144.150778 -354.915282)
			(xy 144.121294 -354.96116) (xy 144.085581 -355.002376) (xy 144.044367 -355.038089) (xy 143.998489 -355.067574)
			(xy 143.948882 -355.09023) (xy 143.896556 -355.105595) (xy 143.842576 -355.113357) (xy 143.815308 -355.113844)
			(xy 142.951708 -355.113844) (xy 142.924435 -355.113417) (xy 142.870445 -355.105655) (xy 142.818109 -355.090289)
			(xy 142.768492 -355.067631) (xy 142.722606 -355.038142) (xy 142.681383 -355.002423) (xy 142.645663 -354.961201)
			(xy 142.616173 -354.915315) (xy 142.593514 -354.865699) (xy 142.578146 -354.813363) (xy 142.570384 -354.759373)
			(xy 141.087557 -354.759373) (xy 141.079798 -354.813343) (xy 141.064436 -354.865666) (xy 141.041784 -354.915271)
			(xy 141.012304 -354.961147) (xy 140.976595 -355.002361) (xy 140.935386 -355.038075) (xy 140.889513 -355.067561)
			(xy 140.839911 -355.090219) (xy 140.78759 -355.105587) (xy 140.733614 -355.113354) (xy 140.706348 -355.113844)
			(xy 139.842748 -355.113844) (xy 139.815473 -355.11342) (xy 139.761479 -355.105663) (xy 139.709138 -355.0903)
			(xy 139.659516 -355.067644) (xy 139.613625 -355.038156) (xy 139.572397 -355.002437) (xy 139.536672 -354.961214)
			(xy 139.507179 -354.915326) (xy 139.484517 -354.865707) (xy 139.469147 -354.813368) (xy 139.461384 -354.759374)
			(xy 137.97868 -354.759374) (xy 137.970918 -354.813356) (xy 137.955552 -354.865687) (xy 137.932895 -354.915298)
			(xy 137.903408 -354.961181) (xy 137.867691 -355.002399) (xy 137.826471 -355.038115) (xy 137.780588 -355.067601)
			(xy 137.730976 -355.090256) (xy 137.678644 -355.105621) (xy 137.624658 -355.113381) (xy 137.597388 -355.113844)
			(xy 136.733788 -355.113844) (xy 136.706518 -355.113393) (xy 136.652533 -355.105629) (xy 136.600203 -355.090262)
			(xy 136.550591 -355.067604) (xy 136.50471 -355.038117) (xy 136.463492 -355.0024) (xy 136.427776 -354.96118)
			(xy 136.39829 -354.915298) (xy 136.375634 -354.865686) (xy 136.360268 -354.813355) (xy 136.352506 -354.75937)
			(xy 134.869658 -354.75937) (xy 134.861897 -354.813345) (xy 134.846534 -354.86567) (xy 134.823881 -354.915276)
			(xy 134.794399 -354.961154) (xy 134.758688 -355.002369) (xy 134.717476 -355.038082) (xy 134.671601 -355.067567)
			(xy 134.621997 -355.090224) (xy 134.569673 -355.105591) (xy 134.515695 -355.113356) (xy 134.488428 -355.113844)
			(xy 133.624828 -355.113844) (xy 133.597554 -355.113418) (xy 133.543562 -355.105659) (xy 133.491223 -355.090295)
			(xy 133.441604 -355.067638) (xy 133.395715 -355.038149) (xy 133.35449 -355.00243) (xy 133.318768 -354.961207)
			(xy 133.289276 -354.91532) (xy 133.266615 -354.865703) (xy 133.251247 -354.813365) (xy 133.243484 -354.759374)
			(xy 131.76078 -354.759374) (xy 131.753018 -354.813358) (xy 131.737651 -354.865691) (xy 131.714992 -354.915304)
			(xy 131.685503 -354.961187) (xy 131.649783 -355.002406) (xy 131.608561 -355.038122) (xy 131.562676 -355.067607)
			(xy 131.513061 -355.090262) (xy 131.460727 -355.105625) (xy 131.406739 -355.113383) (xy 131.379468 -355.113844)
			(xy 130.515868 -355.113844) (xy 130.488599 -355.113391) (xy 130.434616 -355.105626) (xy 130.382288 -355.090257)
			(xy 130.33268 -355.067598) (xy 130.2868 -355.03811) (xy 130.245585 -355.002393) (xy 130.209871 -354.961174)
			(xy 130.180387 -354.915292) (xy 130.157732 -354.865682) (xy 130.142368 -354.813353) (xy 130.134606 -354.759369)
			(xy 128.651758 -354.759369) (xy 128.643997 -354.813348) (xy 128.628632 -354.865675) (xy 128.605978 -354.915282)
			(xy 128.576494 -354.96116) (xy 128.540781 -355.002376) (xy 128.499567 -355.038089) (xy 128.453689 -355.067574)
			(xy 128.404082 -355.09023) (xy 128.351756 -355.105595) (xy 128.297776 -355.113357) (xy 128.270508 -355.113844)
			(xy 127.406908 -355.113844) (xy 127.379635 -355.113417) (xy 127.325645 -355.105655) (xy 127.273309 -355.090289)
			(xy 127.223692 -355.067631) (xy 127.177806 -355.038142) (xy 127.136583 -355.002423) (xy 127.100863 -354.961201)
			(xy 127.071373 -354.915315) (xy 127.048714 -354.865699) (xy 127.033346 -354.813363) (xy 127.025584 -354.759373)
			(xy 125.542757 -354.759373) (xy 125.534998 -354.813343) (xy 125.519636 -354.865666) (xy 125.496984 -354.915271)
			(xy 125.467504 -354.961147) (xy 125.431795 -355.002361) (xy 125.390586 -355.038075) (xy 125.344713 -355.067561)
			(xy 125.295111 -355.090219) (xy 125.24279 -355.105587) (xy 125.188814 -355.113354) (xy 125.161548 -355.113844)
			(xy 124.297948 -355.113844) (xy 124.270673 -355.11342) (xy 124.216679 -355.105663) (xy 124.164338 -355.0903)
			(xy 124.114716 -355.067644) (xy 124.068825 -355.038156) (xy 124.027597 -355.002437) (xy 123.991872 -354.961214)
			(xy 123.962379 -354.915326) (xy 123.939717 -354.865707) (xy 123.924347 -354.813368) (xy 123.916584 -354.759374)
			(xy 122.43388 -354.759374) (xy 122.426118 -354.813356) (xy 122.410752 -354.865687) (xy 122.388095 -354.915298)
			(xy 122.358608 -354.961181) (xy 122.322891 -355.002399) (xy 122.281671 -355.038115) (xy 122.235788 -355.067601)
			(xy 122.186176 -355.090256) (xy 122.133844 -355.105621) (xy 122.079858 -355.113381) (xy 122.052588 -355.113844)
			(xy 121.188988 -355.113844) (xy 121.161718 -355.113393) (xy 121.107733 -355.105629) (xy 121.055403 -355.090262)
			(xy 121.005791 -355.067604) (xy 120.95991 -355.038117) (xy 120.918692 -355.0024) (xy 120.882976 -354.96118)
			(xy 120.85349 -354.915298) (xy 120.830834 -354.865686) (xy 120.815468 -354.813355) (xy 120.807706 -354.75937)
			(xy 119.324858 -354.75937) (xy 119.317097 -354.813345) (xy 119.301734 -354.86567) (xy 119.279081 -354.915276)
			(xy 119.249599 -354.961154) (xy 119.213888 -355.002369) (xy 119.172676 -355.038082) (xy 119.126801 -355.067567)
			(xy 119.077197 -355.090224) (xy 119.024873 -355.105591) (xy 118.970895 -355.113356) (xy 118.943628 -355.113844)
			(xy 118.080028 -355.113844) (xy 118.052754 -355.113418) (xy 117.998762 -355.105659) (xy 117.946423 -355.090295)
			(xy 117.896804 -355.067638) (xy 117.850915 -355.038149) (xy 117.80969 -355.00243) (xy 117.773968 -354.961207)
			(xy 117.744476 -354.91532) (xy 117.721815 -354.865703) (xy 117.706447 -354.813365) (xy 117.698684 -354.759374)
			(xy 116.21598 -354.759374) (xy 116.208218 -354.813358) (xy 116.192851 -354.865691) (xy 116.170192 -354.915304)
			(xy 116.140703 -354.961187) (xy 116.104983 -355.002406) (xy 116.063761 -355.038122) (xy 116.017876 -355.067607)
			(xy 115.968261 -355.090262) (xy 115.915927 -355.105625) (xy 115.861939 -355.113383) (xy 115.834668 -355.113844)
			(xy 114.971068 -355.113844) (xy 114.943799 -355.113391) (xy 114.889816 -355.105626) (xy 114.837488 -355.090257)
			(xy 114.78788 -355.067598) (xy 114.742 -355.03811) (xy 114.700785 -355.002393) (xy 114.665071 -354.961174)
			(xy 114.635587 -354.915292) (xy 114.612932 -354.865682) (xy 114.597568 -354.813353) (xy 114.589806 -354.759369)
			(xy 93.706658 -354.759369) (xy 93.698898 -354.813344) (xy 93.683535 -354.865667) (xy 93.660883 -354.915272)
			(xy 93.631402 -354.961149) (xy 93.595693 -355.002364) (xy 93.554483 -355.038077) (xy 93.508609 -355.067563)
			(xy 93.459007 -355.09022) (xy 93.406685 -355.105589) (xy 93.352708 -355.113355) (xy 93.325442 -355.113844)
			(xy 92.461842 -355.113844) (xy 92.434568 -355.113419) (xy 92.380574 -355.105662) (xy 92.328234 -355.090298)
			(xy 92.278613 -355.067642) (xy 92.232722 -355.038154) (xy 92.191495 -355.002435) (xy 92.155771 -354.961212)
			(xy 92.126278 -354.915324) (xy 92.103616 -354.865706) (xy 92.088247 -354.813367) (xy 92.080484 -354.759374)
			(xy 90.597781 -354.759374) (xy 90.590018 -354.813356) (xy 90.574652 -354.865688) (xy 90.551994 -354.9153)
			(xy 90.522506 -354.961182) (xy 90.486788 -355.002401) (xy 90.445568 -355.038117) (xy 90.399684 -355.067603)
			(xy 90.350071 -355.090258) (xy 90.297739 -355.105622) (xy 90.243753 -355.113382) (xy 90.216482 -355.113844)
			(xy 89.352882 -355.113844) (xy 89.325612 -355.113392) (xy 89.271628 -355.105628) (xy 89.219298 -355.090261)
			(xy 89.169688 -355.067602) (xy 89.123807 -355.038115) (xy 89.08259 -355.002398) (xy 89.046875 -354.961178)
			(xy 89.017389 -354.915296) (xy 88.994733 -354.865685) (xy 88.979368 -354.813354) (xy 88.971606 -354.75937)
			(xy 87.488758 -354.75937) (xy 87.480997 -354.813346) (xy 87.465633 -354.865672) (xy 87.44298 -354.915278)
			(xy 87.413497 -354.961156) (xy 87.377786 -355.002371) (xy 87.336573 -355.038084) (xy 87.290697 -355.067569)
			(xy 87.241092 -355.090226) (xy 87.188768 -355.105592) (xy 87.134789 -355.113356) (xy 87.107522 -355.113844)
			(xy 86.243922 -355.113844) (xy 86.216649 -355.113418) (xy 86.162657 -355.105658) (xy 86.110319 -355.090293)
			(xy 86.060701 -355.067636) (xy 86.014812 -355.038147) (xy 85.973588 -355.002428) (xy 85.937866 -354.961205)
			(xy 85.908375 -354.915318) (xy 85.885715 -354.865702) (xy 85.870347 -354.813365) (xy 85.862584 -354.759373)
			(xy 84.37988 -354.759373) (xy 84.372118 -354.813359) (xy 84.35675 -354.865692) (xy 84.334091 -354.915306)
			(xy 84.304601 -354.961189) (xy 84.268881 -355.002408) (xy 84.227659 -355.038124) (xy 84.181772 -355.067609)
			(xy 84.132157 -355.090264) (xy 84.079822 -355.105626) (xy 84.025833 -355.113383) (xy 83.998562 -355.113844)
			(xy 83.134962 -355.113844) (xy 83.107693 -355.113391) (xy 83.053711 -355.105625) (xy 83.001384 -355.090255)
			(xy 82.951776 -355.067596) (xy 82.905898 -355.038107) (xy 82.864683 -355.00239) (xy 82.82897 -354.961172)
			(xy 82.799486 -354.915291) (xy 82.776832 -354.865681) (xy 82.761467 -354.813352) (xy 82.753706 -354.759369)
			(xy 81.270858 -354.759369) (xy 81.263096 -354.813349) (xy 81.247732 -354.865676) (xy 81.225077 -354.915283)
			(xy 81.195593 -354.961162) (xy 81.159879 -355.002378) (xy 81.118664 -355.038091) (xy 81.072785 -355.067576)
			(xy 81.023178 -355.090231) (xy 80.970851 -355.105596) (xy 80.91687 -355.113357) (xy 80.889602 -355.113844)
			(xy 80.026002 -355.113844) (xy 79.99873 -355.113417) (xy 79.94474 -355.105654) (xy 79.892405 -355.090288)
			(xy 79.842789 -355.067629) (xy 79.796903 -355.03814) (xy 79.755681 -355.002421) (xy 79.719961 -354.961199)
			(xy 79.690472 -354.915313) (xy 79.667813 -354.865697) (xy 79.652446 -354.813362) (xy 79.644684 -354.759372)
			(xy 78.161857 -354.759372) (xy 78.154098 -354.813344) (xy 78.138735 -354.865667) (xy 78.116083 -354.915272)
			(xy 78.086602 -354.961149) (xy 78.050893 -355.002364) (xy 78.009683 -355.038077) (xy 77.963809 -355.067563)
			(xy 77.914207 -355.09022) (xy 77.861885 -355.105589) (xy 77.807908 -355.113355) (xy 77.780642 -355.113844)
			(xy 76.917042 -355.113844) (xy 76.889768 -355.113419) (xy 76.835774 -355.105662) (xy 76.783434 -355.090298)
			(xy 76.733813 -355.067642) (xy 76.687922 -355.038154) (xy 76.646695 -355.002435) (xy 76.610971 -354.961212)
			(xy 76.581478 -354.915324) (xy 76.558816 -354.865706) (xy 76.543447 -354.813367) (xy 76.535684 -354.759374)
			(xy 75.052981 -354.759374) (xy 75.045218 -354.813356) (xy 75.029852 -354.865688) (xy 75.007194 -354.9153)
			(xy 74.977706 -354.961182) (xy 74.941988 -355.002401) (xy 74.900768 -355.038117) (xy 74.854884 -355.067603)
			(xy 74.805271 -355.090258) (xy 74.752939 -355.105622) (xy 74.698953 -355.113382) (xy 74.671682 -355.113844)
			(xy 73.808082 -355.113844) (xy 73.780812 -355.113392) (xy 73.726828 -355.105628) (xy 73.674498 -355.090261)
			(xy 73.624888 -355.067602) (xy 73.579007 -355.038115) (xy 73.53779 -355.002398) (xy 73.502075 -354.961178)
			(xy 73.472589 -354.915296) (xy 73.449933 -354.865685) (xy 73.434568 -354.813354) (xy 73.426806 -354.75937)
			(xy 71.943958 -354.75937) (xy 71.936197 -354.813346) (xy 71.920833 -354.865672) (xy 71.89818 -354.915278)
			(xy 71.868697 -354.961156) (xy 71.832986 -355.002371) (xy 71.791773 -355.038084) (xy 71.745897 -355.067569)
			(xy 71.696292 -355.090226) (xy 71.643968 -355.105592) (xy 71.589989 -355.113356) (xy 71.562722 -355.113844)
			(xy 70.699122 -355.113844) (xy 70.671849 -355.113418) (xy 70.617857 -355.105658) (xy 70.565519 -355.090293)
			(xy 70.515901 -355.067636) (xy 70.470012 -355.038147) (xy 70.428788 -355.002428) (xy 70.393066 -354.961205)
			(xy 70.363575 -354.915318) (xy 70.340915 -354.865702) (xy 70.325547 -354.813365) (xy 70.317784 -354.759373)
			(xy 68.83508 -354.759373) (xy 68.827318 -354.813359) (xy 68.81195 -354.865692) (xy 68.789291 -354.915306)
			(xy 68.759801 -354.961189) (xy 68.724081 -355.002408) (xy 68.682859 -355.038124) (xy 68.636972 -355.067609)
			(xy 68.587357 -355.090264) (xy 68.535022 -355.105626) (xy 68.481033 -355.113383) (xy 68.453762 -355.113844)
			(xy 67.590162 -355.113844) (xy 67.562893 -355.113391) (xy 67.508911 -355.105625) (xy 67.456584 -355.090255)
			(xy 67.406976 -355.067596) (xy 67.361098 -355.038107) (xy 67.319883 -355.00239) (xy 67.28417 -354.961172)
			(xy 67.254686 -354.915291) (xy 67.232032 -354.865681) (xy 67.216667 -354.813352) (xy 67.208906 -354.759369)
			(xy 65.726058 -354.759369) (xy 65.718296 -354.813349) (xy 65.702932 -354.865676) (xy 65.680277 -354.915283)
			(xy 65.650793 -354.961162) (xy 65.615079 -355.002378) (xy 65.573864 -355.038091) (xy 65.527985 -355.067576)
			(xy 65.478378 -355.090231) (xy 65.426051 -355.105596) (xy 65.37207 -355.113357) (xy 65.344802 -355.113844)
			(xy 64.481202 -355.113844) (xy 64.45393 -355.113417) (xy 64.39994 -355.105654) (xy 64.347605 -355.090288)
			(xy 64.297989 -355.067629) (xy 64.252103 -355.03814) (xy 64.210881 -355.002421) (xy 64.175161 -354.961199)
			(xy 64.145672 -354.915313) (xy 64.123013 -354.865697) (xy 64.107646 -354.813362) (xy 64.099884 -354.759372)
			(xy 51.666857 -354.759372) (xy 51.659098 -354.813343) (xy 51.643736 -354.865666) (xy 51.621084 -354.915271)
			(xy 51.591604 -354.961147) (xy 51.555895 -355.002361) (xy 51.514686 -355.038075) (xy 51.468813 -355.067561)
			(xy 51.419211 -355.090219) (xy 51.36689 -355.105587) (xy 51.312914 -355.113354) (xy 51.285648 -355.113844)
			(xy 50.422048 -355.113844) (xy 50.394773 -355.11342) (xy 50.340779 -355.105663) (xy 50.288438 -355.0903)
			(xy 50.238816 -355.067644) (xy 50.192925 -355.038156) (xy 50.151697 -355.002437) (xy 50.115972 -354.961214)
			(xy 50.086479 -354.915326) (xy 50.063817 -354.865707) (xy 50.048447 -354.813368) (xy 50.040684 -354.759374)
			(xy 48.55798 -354.759374) (xy 48.550218 -354.813356) (xy 48.534852 -354.865687) (xy 48.512195 -354.915298)
			(xy 48.482708 -354.961181) (xy 48.446991 -355.002399) (xy 48.405771 -355.038115) (xy 48.359888 -355.067601)
			(xy 48.310276 -355.090256) (xy 48.257944 -355.105621) (xy 48.203958 -355.113381) (xy 48.176688 -355.113844)
			(xy 47.313088 -355.113844) (xy 47.285818 -355.113393) (xy 47.231833 -355.105629) (xy 47.179503 -355.090262)
			(xy 47.129891 -355.067604) (xy 47.08401 -355.038117) (xy 47.042792 -355.0024) (xy 47.007076 -354.96118)
			(xy 46.97759 -354.915298) (xy 46.954934 -354.865686) (xy 46.939568 -354.813355) (xy 46.931806 -354.75937)
			(xy 45.448958 -354.75937) (xy 45.441197 -354.813345) (xy 45.425834 -354.86567) (xy 45.403181 -354.915276)
			(xy 45.373699 -354.961154) (xy 45.337988 -355.002369) (xy 45.296776 -355.038082) (xy 45.250901 -355.067567)
			(xy 45.201297 -355.090224) (xy 45.148973 -355.105591) (xy 45.094995 -355.113356) (xy 45.067728 -355.113844)
			(xy 44.204128 -355.113844) (xy 44.176854 -355.113418) (xy 44.122862 -355.105659) (xy 44.070523 -355.090295)
			(xy 44.020904 -355.067638) (xy 43.975015 -355.038149) (xy 43.93379 -355.00243) (xy 43.898068 -354.961207)
			(xy 43.868576 -354.91532) (xy 43.845915 -354.865703) (xy 43.830547 -354.813365) (xy 43.822784 -354.759374)
			(xy 42.34008 -354.759374) (xy 42.332318 -354.813358) (xy 42.316951 -354.865691) (xy 42.294292 -354.915304)
			(xy 42.264803 -354.961187) (xy 42.229083 -355.002406) (xy 42.187861 -355.038122) (xy 42.141976 -355.067607)
			(xy 42.092361 -355.090262) (xy 42.040027 -355.105625) (xy 41.986039 -355.113383) (xy 41.958768 -355.113844)
			(xy 41.095168 -355.113844) (xy 41.067899 -355.113391) (xy 41.013916 -355.105626) (xy 40.961588 -355.090257)
			(xy 40.91198 -355.067598) (xy 40.8661 -355.03811) (xy 40.824885 -355.002393) (xy 40.789171 -354.961174)
			(xy 40.759687 -354.915292) (xy 40.737032 -354.865682) (xy 40.721668 -354.813353) (xy 40.713906 -354.759369)
			(xy 39.231058 -354.759369) (xy 39.223297 -354.813348) (xy 39.207932 -354.865675) (xy 39.185278 -354.915282)
			(xy 39.155794 -354.96116) (xy 39.120081 -355.002376) (xy 39.078867 -355.038089) (xy 39.032989 -355.067574)
			(xy 38.983382 -355.09023) (xy 38.931056 -355.105595) (xy 38.877076 -355.113357) (xy 38.849808 -355.113844)
			(xy 37.986208 -355.113844) (xy 37.958935 -355.113417) (xy 37.904945 -355.105655) (xy 37.852609 -355.090289)
			(xy 37.802992 -355.067631) (xy 37.757106 -355.038142) (xy 37.715883 -355.002423) (xy 37.680163 -354.961201)
			(xy 37.650673 -354.915315) (xy 37.628014 -354.865699) (xy 37.612646 -354.813363) (xy 37.604884 -354.759373)
			(xy 36.122057 -354.759373) (xy 36.114298 -354.813343) (xy 36.098936 -354.865666) (xy 36.076284 -354.915271)
			(xy 36.046804 -354.961147) (xy 36.011095 -355.002361) (xy 35.969886 -355.038075) (xy 35.924013 -355.067561)
			(xy 35.874411 -355.090219) (xy 35.82209 -355.105587) (xy 35.768114 -355.113354) (xy 35.740848 -355.113844)
			(xy 34.877248 -355.113844) (xy 34.849973 -355.11342) (xy 34.795979 -355.105663) (xy 34.743638 -355.0903)
			(xy 34.694016 -355.067644) (xy 34.648125 -355.038156) (xy 34.606897 -355.002437) (xy 34.571172 -354.961214)
			(xy 34.541679 -354.915326) (xy 34.519017 -354.865707) (xy 34.503647 -354.813368) (xy 34.495884 -354.759374)
			(xy 33.01318 -354.759374) (xy 33.005418 -354.813356) (xy 32.990052 -354.865687) (xy 32.967395 -354.915298)
			(xy 32.937908 -354.961181) (xy 32.902191 -355.002399) (xy 32.860971 -355.038115) (xy 32.815088 -355.067601)
			(xy 32.765476 -355.090256) (xy 32.713144 -355.105621) (xy 32.659158 -355.113381) (xy 32.631888 -355.113844)
			(xy 31.768288 -355.113844) (xy 31.741018 -355.113393) (xy 31.687033 -355.105629) (xy 31.634703 -355.090262)
			(xy 31.585091 -355.067604) (xy 31.53921 -355.038117) (xy 31.497992 -355.0024) (xy 31.462276 -354.96118)
			(xy 31.43279 -354.915298) (xy 31.410134 -354.865686) (xy 31.394768 -354.813355) (xy 31.387006 -354.75937)
			(xy 29.904158 -354.75937) (xy 29.896397 -354.813345) (xy 29.881034 -354.86567) (xy 29.858381 -354.915276)
			(xy 29.828899 -354.961154) (xy 29.793188 -355.002369) (xy 29.751976 -355.038082) (xy 29.706101 -355.067567)
			(xy 29.656497 -355.090224) (xy 29.604173 -355.105591) (xy 29.550195 -355.113356) (xy 29.522928 -355.113844)
			(xy 28.659328 -355.113844) (xy 28.632054 -355.113418) (xy 28.578062 -355.105659) (xy 28.525723 -355.090295)
			(xy 28.476104 -355.067638) (xy 28.430215 -355.038149) (xy 28.38899 -355.00243) (xy 28.353268 -354.961207)
			(xy 28.323776 -354.91532) (xy 28.301115 -354.865703) (xy 28.285747 -354.813365) (xy 28.277984 -354.759374)
			(xy 26.79528 -354.759374) (xy 26.787518 -354.813358) (xy 26.772151 -354.865691) (xy 26.749492 -354.915304)
			(xy 26.720003 -354.961187) (xy 26.684283 -355.002406) (xy 26.643061 -355.038122) (xy 26.597176 -355.067607)
			(xy 26.547561 -355.090262) (xy 26.495227 -355.105625) (xy 26.441239 -355.113383) (xy 26.413968 -355.113844)
			(xy 25.550368 -355.113844) (xy 25.523099 -355.113391) (xy 25.469116 -355.105626) (xy 25.416788 -355.090257)
			(xy 25.36718 -355.067598) (xy 25.3213 -355.03811) (xy 25.280085 -355.002393) (xy 25.244371 -354.961174)
			(xy 25.214887 -354.915292) (xy 25.192232 -354.865682) (xy 25.176868 -354.813353) (xy 25.169106 -354.759369)
			(xy 23.686258 -354.759369) (xy 23.678497 -354.813348) (xy 23.663132 -354.865675) (xy 23.640478 -354.915282)
			(xy 23.610994 -354.96116) (xy 23.575281 -355.002376) (xy 23.534067 -355.038089) (xy 23.488189 -355.067574)
			(xy 23.438582 -355.09023) (xy 23.386256 -355.105595) (xy 23.332276 -355.113357) (xy 23.305008 -355.113844)
			(xy 22.441408 -355.113844) (xy 22.414135 -355.113417) (xy 22.360145 -355.105655) (xy 22.307809 -355.090289)
			(xy 22.258192 -355.067631) (xy 22.212306 -355.038142) (xy 22.171083 -355.002423) (xy 22.135363 -354.961201)
			(xy 22.105873 -354.915315) (xy 22.083214 -354.865699) (xy 22.067846 -354.813363) (xy 22.060084 -354.759373)
			(xy 0.508 -354.759373) (xy 0.508 -357.784969) (xy 22.060131 -357.784969) (xy 22.060131 -357.730431)
			(xy 22.067893 -357.676447) (xy 22.083259 -357.624118) (xy 22.105915 -357.574508) (xy 22.135401 -357.528628)
			(xy 22.171117 -357.487411) (xy 22.212334 -357.451696) (xy 22.258215 -357.422211) (xy 22.307826 -357.399556)
			(xy 22.360155 -357.384191) (xy 22.414139 -357.376431) (xy 22.441408 -357.375968) (xy 23.305008 -357.375968)
			(xy 23.332279 -357.376395) (xy 23.386266 -357.384158) (xy 23.438599 -357.399525) (xy 23.488212 -357.422184)
			(xy 23.534095 -357.451672) (xy 23.575315 -357.48739) (xy 23.611032 -357.528611) (xy 23.64052 -357.574495)
			(xy 23.663177 -357.624109) (xy 23.678543 -357.676442) (xy 23.686306 -357.730429) (xy 23.686306 -357.784966)
			(xy 25.169154 -357.784966) (xy 25.169154 -357.730434) (xy 25.176914 -357.676458) (xy 25.192277 -357.624135)
			(xy 25.214929 -357.574531) (xy 25.24441 -357.528655) (xy 25.280119 -357.487441) (xy 25.321329 -357.451729)
			(xy 25.367203 -357.422244) (xy 25.416805 -357.399588) (xy 25.469126 -357.384221) (xy 25.523102 -357.376457)
			(xy 25.550368 -357.375968) (xy 26.413968 -357.375968) (xy 26.441243 -357.376369) (xy 26.495237 -357.384128)
			(xy 26.547578 -357.399493) (xy 26.597199 -357.422151) (xy 26.64309 -357.45164) (xy 26.684317 -357.48736)
			(xy 26.720041 -357.528584) (xy 26.749534 -357.574473) (xy 26.772196 -357.624092) (xy 26.787565 -357.676431)
			(xy 26.795328 -357.730425) (xy 26.795328 -357.78497) (xy 28.278031 -357.78497) (xy 28.278032 -357.73043)
			(xy 28.285794 -357.676445) (xy 28.30116 -357.624114) (xy 28.323818 -357.574503) (xy 28.353306 -357.528621)
			(xy 28.389024 -357.487404) (xy 28.430244 -357.451689) (xy 28.476127 -357.422205) (xy 28.52574 -357.39955)
			(xy 28.578072 -357.384188) (xy 28.632058 -357.37643) (xy 28.659328 -357.375968) (xy 29.522928 -357.375968)
			(xy 29.550198 -357.376396) (xy 29.604183 -357.384162) (xy 29.656513 -357.399531) (xy 29.706124 -357.42219)
			(xy 29.752005 -357.451679) (xy 29.793222 -357.487397) (xy 29.828937 -357.528618) (xy 29.858423 -357.574501)
			(xy 29.881079 -357.624113) (xy 29.896444 -357.676444) (xy 29.904206 -357.73043) (xy 29.904206 -357.784967)
			(xy 31.387054 -357.784967) (xy 31.387054 -357.730433) (xy 31.394815 -357.676455) (xy 31.410179 -357.624131)
			(xy 31.432832 -357.574525) (xy 31.462315 -357.528648) (xy 31.498026 -357.487434) (xy 31.539239 -357.451722)
			(xy 31.585115 -357.422238) (xy 31.634719 -357.399583) (xy 31.687043 -357.384218) (xy 31.741021 -357.376455)
			(xy 31.768288 -357.375968) (xy 32.631888 -357.375968) (xy 32.659162 -357.376371) (xy 32.713154 -357.384132)
			(xy 32.765492 -357.399499) (xy 32.815111 -357.422157) (xy 32.861 -357.451647) (xy 32.902224 -357.487367)
			(xy 32.937946 -357.528591) (xy 32.967437 -357.574479) (xy 32.990097 -357.624096) (xy 33.005465 -357.676434)
			(xy 33.013228 -357.730426) (xy 33.013228 -357.784971) (xy 34.495932 -357.784971) (xy 34.495932 -357.730429)
			(xy 34.503694 -357.676442) (xy 34.519062 -357.62411) (xy 34.541721 -357.574497) (xy 34.571211 -357.528615)
			(xy 34.606931 -357.487397) (xy 34.648153 -357.451682) (xy 34.694039 -357.422198) (xy 34.743655 -357.399545)
			(xy 34.795989 -357.384184) (xy 34.849977 -357.376428) (xy 34.877248 -357.375968) (xy 35.740848 -357.375968)
			(xy 35.768117 -357.376398) (xy 35.8221 -357.384166) (xy 35.874428 -357.399536) (xy 35.924036 -357.422197)
			(xy 35.969914 -357.451687) (xy 36.011129 -357.487405) (xy 36.046842 -357.528624) (xy 36.076326 -357.574506)
			(xy 36.09898 -357.624117) (xy 36.114345 -357.676447) (xy 36.122106 -357.730431) (xy 36.122106 -357.784969)
			(xy 37.604931 -357.784969) (xy 37.604931 -357.730431) (xy 37.612693 -357.676447) (xy 37.628059 -357.624118)
			(xy 37.650715 -357.574508) (xy 37.680201 -357.528628) (xy 37.715917 -357.487411) (xy 37.757134 -357.451696)
			(xy 37.803015 -357.422211) (xy 37.852626 -357.399556) (xy 37.904955 -357.384191) (xy 37.958939 -357.376431)
			(xy 37.986208 -357.375968) (xy 38.849808 -357.375968) (xy 38.877079 -357.376395) (xy 38.931066 -357.384158)
			(xy 38.983399 -357.399525) (xy 39.033012 -357.422184) (xy 39.078895 -357.451672) (xy 39.120115 -357.48739)
			(xy 39.155832 -357.528611) (xy 39.18532 -357.574495) (xy 39.207977 -357.624109) (xy 39.223343 -357.676442)
			(xy 39.231106 -357.730429) (xy 39.231106 -357.784966) (xy 40.713954 -357.784966) (xy 40.713954 -357.730434)
			(xy 40.721714 -357.676458) (xy 40.737077 -357.624135) (xy 40.759729 -357.574531) (xy 40.78921 -357.528655)
			(xy 40.824919 -357.487441) (xy 40.866129 -357.451729) (xy 40.912003 -357.422244) (xy 40.961605 -357.399588)
			(xy 41.013926 -357.384221) (xy 41.067902 -357.376457) (xy 41.095168 -357.375968) (xy 41.958768 -357.375968)
			(xy 41.986043 -357.376369) (xy 42.040037 -357.384128) (xy 42.092378 -357.399493) (xy 42.141999 -357.422151)
			(xy 42.18789 -357.45164) (xy 42.229117 -357.48736) (xy 42.264841 -357.528584) (xy 42.294334 -357.574473)
			(xy 42.316996 -357.624092) (xy 42.332365 -357.676431) (xy 42.340128 -357.730425) (xy 42.340128 -357.78497)
			(xy 43.822831 -357.78497) (xy 43.822832 -357.73043) (xy 43.830594 -357.676445) (xy 43.84596 -357.624114)
			(xy 43.868618 -357.574503) (xy 43.898106 -357.528621) (xy 43.933824 -357.487404) (xy 43.975044 -357.451689)
			(xy 44.020927 -357.422205) (xy 44.07054 -357.39955) (xy 44.122872 -357.384188) (xy 44.176858 -357.37643)
			(xy 44.204128 -357.375968) (xy 45.067728 -357.375968) (xy 45.094998 -357.376396) (xy 45.148983 -357.384162)
			(xy 45.201313 -357.399531) (xy 45.250924 -357.42219) (xy 45.296805 -357.451679) (xy 45.338022 -357.487397)
			(xy 45.373737 -357.528618) (xy 45.403223 -357.574501) (xy 45.425879 -357.624113) (xy 45.441244 -357.676444)
			(xy 45.449006 -357.73043) (xy 45.449006 -357.784967) (xy 46.931854 -357.784967) (xy 46.931854 -357.730433)
			(xy 46.939615 -357.676455) (xy 46.954979 -357.624131) (xy 46.977632 -357.574525) (xy 47.007115 -357.528648)
			(xy 47.042826 -357.487434) (xy 47.084039 -357.451722) (xy 47.129915 -357.422238) (xy 47.179519 -357.399583)
			(xy 47.231843 -357.384218) (xy 47.285821 -357.376455) (xy 47.313088 -357.375968) (xy 48.176688 -357.375968)
			(xy 48.203962 -357.376371) (xy 48.257954 -357.384132) (xy 48.310292 -357.399499) (xy 48.359911 -357.422157)
			(xy 48.4058 -357.451647) (xy 48.447024 -357.487367) (xy 48.482746 -357.528591) (xy 48.512237 -357.574479)
			(xy 48.534897 -357.624096) (xy 48.550265 -357.676434) (xy 48.558028 -357.730426) (xy 48.558028 -357.784971)
			(xy 50.040732 -357.784971) (xy 50.040732 -357.730429) (xy 50.048494 -357.676442) (xy 50.063862 -357.62411)
			(xy 50.086521 -357.574497) (xy 50.116011 -357.528615) (xy 50.151731 -357.487397) (xy 50.192953 -357.451682)
			(xy 50.238839 -357.422198) (xy 50.288455 -357.399545) (xy 50.340789 -357.384184) (xy 50.394777 -357.376428)
			(xy 50.422048 -357.375968) (xy 51.285648 -357.375968) (xy 51.312917 -357.376398) (xy 51.3669 -357.384166)
			(xy 51.419228 -357.399536) (xy 51.468836 -357.422197) (xy 51.514714 -357.451687) (xy 51.555929 -357.487405)
			(xy 51.591642 -357.528624) (xy 51.621126 -357.574506) (xy 51.64378 -357.624117) (xy 51.659145 -357.676447)
			(xy 51.666906 -357.730431) (xy 51.666906 -357.784969) (xy 64.099931 -357.784969) (xy 64.099931 -357.730431)
			(xy 64.107693 -357.676448) (xy 64.123058 -357.62412) (xy 64.145714 -357.57451) (xy 64.1752 -357.52863)
			(xy 64.210914 -357.487413) (xy 64.252132 -357.451698) (xy 64.298012 -357.422213) (xy 64.347621 -357.399557)
			(xy 64.39995 -357.384193) (xy 64.453933 -357.376431) (xy 64.481202 -357.375968) (xy 65.344802 -357.375968)
			(xy 65.372073 -357.376395) (xy 65.426061 -357.384157) (xy 65.478394 -357.399524) (xy 65.528008 -357.422182)
			(xy 65.573893 -357.45167) (xy 65.615113 -357.487388) (xy 65.650831 -357.528609) (xy 65.680319 -357.574493)
			(xy 65.702977 -357.624107) (xy 65.718343 -357.676441) (xy 65.726106 -357.730429) (xy 65.726106 -357.784966)
			(xy 67.208954 -357.784966) (xy 67.208954 -357.730435) (xy 67.216714 -357.676458) (xy 67.232077 -357.624136)
			(xy 67.254728 -357.574532) (xy 67.284208 -357.528657) (xy 67.319917 -357.487443) (xy 67.361126 -357.451731)
			(xy 67.406999 -357.422246) (xy 67.4566 -357.39959) (xy 67.508921 -357.384222) (xy 67.562897 -357.376457)
			(xy 67.590162 -357.375968) (xy 68.453762 -357.375968) (xy 68.481037 -357.376369) (xy 68.535032 -357.384127)
			(xy 68.587373 -357.399491) (xy 68.636995 -357.422149) (xy 68.682887 -357.451638) (xy 68.724115 -357.487358)
			(xy 68.75984 -357.528582) (xy 68.789333 -357.574471) (xy 68.811995 -357.624091) (xy 68.827365 -357.676431)
			(xy 68.835128 -357.730425) (xy 68.835128 -357.78497) (xy 70.317831 -357.78497) (xy 70.317831 -357.73043)
			(xy 70.325594 -357.676446) (xy 70.34096 -357.624115) (xy 70.363617 -357.574505) (xy 70.393105 -357.528623)
			(xy 70.428822 -357.487406) (xy 70.470041 -357.451691) (xy 70.515924 -357.422207) (xy 70.565536 -357.399552)
			(xy 70.617867 -357.384189) (xy 70.671852 -357.37643) (xy 70.699122 -357.375968) (xy 71.562722 -357.375968)
			(xy 71.589992 -357.376396) (xy 71.643978 -357.384161) (xy 71.696309 -357.399529) (xy 71.74592 -357.422189)
			(xy 71.791802 -357.451677) (xy 71.83302 -357.487395) (xy 71.868736 -357.528616) (xy 71.898222 -357.574499)
			(xy 71.920878 -357.624112) (xy 71.936244 -357.676444) (xy 71.944006 -357.730429) (xy 71.944006 -357.784966)
			(xy 73.426854 -357.784966) (xy 73.426854 -357.730434) (xy 73.434615 -357.676456) (xy 73.449978 -357.624132)
			(xy 73.472631 -357.574527) (xy 73.502113 -357.52865) (xy 73.537824 -357.487436) (xy 73.579036 -357.451724)
			(xy 73.624911 -357.42224) (xy 73.674515 -357.399584) (xy 73.726838 -357.384219) (xy 73.780816 -357.376456)
			(xy 73.808082 -357.375968) (xy 74.671682 -357.375968) (xy 74.698956 -357.37637) (xy 74.752949 -357.384131)
			(xy 74.805288 -357.399497) (xy 74.854907 -357.422155) (xy 74.900797 -357.451645) (xy 74.942022 -357.487365)
			(xy 74.977744 -357.528589) (xy 75.007236 -357.574477) (xy 75.029897 -357.624095) (xy 75.045265 -357.676433)
			(xy 75.053028 -357.730426) (xy 75.053028 -357.784971) (xy 76.535732 -357.784971) (xy 76.535732 -357.730429)
			(xy 76.543494 -357.676443) (xy 76.558861 -357.624111) (xy 76.58152 -357.574499) (xy 76.611009 -357.528617)
			(xy 76.646729 -357.487399) (xy 76.687951 -357.451684) (xy 76.733836 -357.4222) (xy 76.78345 -357.399547)
			(xy 76.835784 -357.384185) (xy 76.889771 -357.376429) (xy 76.917042 -357.375968) (xy 77.780642 -357.375968)
			(xy 77.807912 -357.376397) (xy 77.861895 -357.384165) (xy 77.914223 -357.399535) (xy 77.963832 -357.422195)
			(xy 78.009711 -357.451684) (xy 78.050927 -357.487402) (xy 78.086641 -357.528622) (xy 78.116125 -357.574505)
			(xy 78.13878 -357.624116) (xy 78.154144 -357.676446) (xy 78.161906 -357.73043) (xy 78.161906 -357.784969)
			(xy 79.644731 -357.784969) (xy 79.644731 -357.730431) (xy 79.652493 -357.676448) (xy 79.667858 -357.62412)
			(xy 79.690514 -357.57451) (xy 79.72 -357.52863) (xy 79.755714 -357.487413) (xy 79.796932 -357.451698)
			(xy 79.842812 -357.422213) (xy 79.892421 -357.399557) (xy 79.94475 -357.384193) (xy 79.998733 -357.376431)
			(xy 80.026002 -357.375968) (xy 80.889602 -357.375968) (xy 80.916873 -357.376395) (xy 80.970861 -357.384157)
			(xy 81.023194 -357.399524) (xy 81.072808 -357.422182) (xy 81.118693 -357.45167) (xy 81.159913 -357.487388)
			(xy 81.195631 -357.528609) (xy 81.225119 -357.574493) (xy 81.247777 -357.624107) (xy 81.263143 -357.676441)
			(xy 81.270906 -357.730429) (xy 81.270906 -357.784966) (xy 82.753754 -357.784966) (xy 82.753754 -357.730435)
			(xy 82.761514 -357.676458) (xy 82.776877 -357.624136) (xy 82.799528 -357.574532) (xy 82.829008 -357.528657)
			(xy 82.864717 -357.487443) (xy 82.905926 -357.451731) (xy 82.951799 -357.422246) (xy 83.0014 -357.39959)
			(xy 83.053721 -357.384222) (xy 83.107697 -357.376457) (xy 83.134962 -357.375968) (xy 83.998562 -357.375968)
			(xy 84.025837 -357.376369) (xy 84.079832 -357.384127) (xy 84.132173 -357.399491) (xy 84.181795 -357.422149)
			(xy 84.227687 -357.451638) (xy 84.268915 -357.487358) (xy 84.30464 -357.528582) (xy 84.334133 -357.574471)
			(xy 84.356795 -357.624091) (xy 84.372165 -357.676431) (xy 84.379928 -357.730425) (xy 84.379928 -357.78497)
			(xy 85.862631 -357.78497) (xy 85.862631 -357.73043) (xy 85.870394 -357.676446) (xy 85.88576 -357.624115)
			(xy 85.908417 -357.574505) (xy 85.937905 -357.528623) (xy 85.973622 -357.487406) (xy 86.014841 -357.451691)
			(xy 86.060724 -357.422207) (xy 86.110336 -357.399552) (xy 86.162667 -357.384189) (xy 86.216652 -357.37643)
			(xy 86.243922 -357.375968) (xy 87.107522 -357.375968) (xy 87.134792 -357.376396) (xy 87.188778 -357.384161)
			(xy 87.241109 -357.399529) (xy 87.29072 -357.422189) (xy 87.336602 -357.451677) (xy 87.37782 -357.487395)
			(xy 87.413536 -357.528616) (xy 87.443022 -357.574499) (xy 87.465678 -357.624112) (xy 87.481044 -357.676444)
			(xy 87.488806 -357.730429) (xy 87.488806 -357.784966) (xy 88.971654 -357.784966) (xy 88.971654 -357.730434)
			(xy 88.979415 -357.676456) (xy 88.994778 -357.624132) (xy 89.017431 -357.574527) (xy 89.046913 -357.52865)
			(xy 89.082624 -357.487436) (xy 89.123836 -357.451724) (xy 89.169711 -357.42224) (xy 89.219315 -357.399584)
			(xy 89.271638 -357.384219) (xy 89.325616 -357.376456) (xy 89.352882 -357.375968) (xy 90.216482 -357.375968)
			(xy 90.243756 -357.37637) (xy 90.297749 -357.384131) (xy 90.350088 -357.399497) (xy 90.399707 -357.422155)
			(xy 90.445597 -357.451645) (xy 90.486822 -357.487365) (xy 90.522544 -357.528589) (xy 90.552036 -357.574477)
			(xy 90.574697 -357.624095) (xy 90.590065 -357.676433) (xy 90.597828 -357.730426) (xy 90.597828 -357.784971)
			(xy 92.080532 -357.784971) (xy 92.080532 -357.730429) (xy 92.088294 -357.676443) (xy 92.103661 -357.624111)
			(xy 92.12632 -357.574499) (xy 92.155809 -357.528617) (xy 92.191529 -357.487399) (xy 92.232751 -357.451684)
			(xy 92.278636 -357.4222) (xy 92.32825 -357.399547) (xy 92.380584 -357.384185) (xy 92.434571 -357.376429)
			(xy 92.461842 -357.375968) (xy 93.325442 -357.375968) (xy 93.352712 -357.376397) (xy 93.406695 -357.384165)
			(xy 93.459023 -357.399535) (xy 93.508632 -357.422195) (xy 93.554511 -357.451684) (xy 93.595727 -357.487402)
			(xy 93.631441 -357.528622) (xy 93.660925 -357.574505) (xy 93.68358 -357.624116) (xy 93.698944 -357.676446)
			(xy 93.706706 -357.73043) (xy 93.706706 -357.784966) (xy 114.589854 -357.784966) (xy 114.589854 -357.730434)
			(xy 114.597614 -357.676458) (xy 114.612977 -357.624135) (xy 114.635629 -357.574531) (xy 114.66511 -357.528655)
			(xy 114.700819 -357.487441) (xy 114.742029 -357.451729) (xy 114.787903 -357.422244) (xy 114.837505 -357.399588)
			(xy 114.889826 -357.384221) (xy 114.943802 -357.376457) (xy 114.971068 -357.375968) (xy 115.834668 -357.375968)
			(xy 115.861943 -357.376369) (xy 115.915937 -357.384128) (xy 115.968278 -357.399493) (xy 116.017899 -357.422151)
			(xy 116.06379 -357.45164) (xy 116.105017 -357.48736) (xy 116.140741 -357.528584) (xy 116.170234 -357.574473)
			(xy 116.192896 -357.624092) (xy 116.208265 -357.676431) (xy 116.216028 -357.730425) (xy 116.216028 -357.78497)
			(xy 117.698731 -357.78497) (xy 117.698732 -357.73043) (xy 117.706494 -357.676445) (xy 117.72186 -357.624114)
			(xy 117.744518 -357.574503) (xy 117.774006 -357.528621) (xy 117.809724 -357.487404) (xy 117.850944 -357.451689)
			(xy 117.896827 -357.422205) (xy 117.94644 -357.39955) (xy 117.998772 -357.384188) (xy 118.052758 -357.37643)
			(xy 118.080028 -357.375968) (xy 118.943628 -357.375968) (xy 118.970898 -357.376396) (xy 119.024883 -357.384162)
			(xy 119.077213 -357.399531) (xy 119.126824 -357.42219) (xy 119.172705 -357.451679) (xy 119.213922 -357.487397)
			(xy 119.249637 -357.528618) (xy 119.279123 -357.574501) (xy 119.301779 -357.624113) (xy 119.317144 -357.676444)
			(xy 119.324906 -357.73043) (xy 119.324906 -357.784967) (xy 120.807754 -357.784967) (xy 120.807754 -357.730433)
			(xy 120.815515 -357.676455) (xy 120.830879 -357.624131) (xy 120.853532 -357.574525) (xy 120.883015 -357.528648)
			(xy 120.918726 -357.487434) (xy 120.959939 -357.451722) (xy 121.005815 -357.422238) (xy 121.055419 -357.399583)
			(xy 121.107743 -357.384218) (xy 121.161721 -357.376455) (xy 121.188988 -357.375968) (xy 122.052588 -357.375968)
			(xy 122.079862 -357.376371) (xy 122.133854 -357.384132) (xy 122.186192 -357.399499) (xy 122.235811 -357.422157)
			(xy 122.2817 -357.451647) (xy 122.322924 -357.487367) (xy 122.358646 -357.528591) (xy 122.388137 -357.574479)
			(xy 122.410797 -357.624096) (xy 122.426165 -357.676434) (xy 122.433928 -357.730426) (xy 122.433928 -357.784971)
			(xy 123.916632 -357.784971) (xy 123.916632 -357.730429) (xy 123.924394 -357.676442) (xy 123.939762 -357.62411)
			(xy 123.962421 -357.574497) (xy 123.991911 -357.528615) (xy 124.027631 -357.487397) (xy 124.068853 -357.451682)
			(xy 124.114739 -357.422198) (xy 124.164355 -357.399545) (xy 124.216689 -357.384184) (xy 124.270677 -357.376428)
			(xy 124.297948 -357.375968) (xy 125.161548 -357.375968) (xy 125.188817 -357.376398) (xy 125.2428 -357.384166)
			(xy 125.295128 -357.399536) (xy 125.344736 -357.422197) (xy 125.390614 -357.451687) (xy 125.431829 -357.487405)
			(xy 125.467542 -357.528624) (xy 125.497026 -357.574506) (xy 125.51968 -357.624117) (xy 125.535045 -357.676447)
			(xy 125.542806 -357.730431) (xy 125.542806 -357.784969) (xy 127.025631 -357.784969) (xy 127.025631 -357.730431)
			(xy 127.033393 -357.676447) (xy 127.048759 -357.624118) (xy 127.071415 -357.574508) (xy 127.100901 -357.528628)
			(xy 127.136617 -357.487411) (xy 127.177834 -357.451696) (xy 127.223715 -357.422211) (xy 127.273326 -357.399556)
			(xy 127.325655 -357.384191) (xy 127.379639 -357.376431) (xy 127.406908 -357.375968) (xy 128.270508 -357.375968)
			(xy 128.297779 -357.376395) (xy 128.351766 -357.384158) (xy 128.404099 -357.399525) (xy 128.453712 -357.422184)
			(xy 128.499595 -357.451672) (xy 128.540815 -357.48739) (xy 128.576532 -357.528611) (xy 128.60602 -357.574495)
			(xy 128.628677 -357.624109) (xy 128.644043 -357.676442) (xy 128.651806 -357.730429) (xy 128.651806 -357.784966)
			(xy 130.134654 -357.784966) (xy 130.134654 -357.730434) (xy 130.142414 -357.676458) (xy 130.157777 -357.624135)
			(xy 130.180429 -357.574531) (xy 130.20991 -357.528655) (xy 130.245619 -357.487441) (xy 130.286829 -357.451729)
			(xy 130.332703 -357.422244) (xy 130.382305 -357.399588) (xy 130.434626 -357.384221) (xy 130.488602 -357.376457)
			(xy 130.515868 -357.375968) (xy 131.379468 -357.375968) (xy 131.406743 -357.376369) (xy 131.460737 -357.384128)
			(xy 131.513078 -357.399493) (xy 131.562699 -357.422151) (xy 131.60859 -357.45164) (xy 131.649817 -357.48736)
			(xy 131.685541 -357.528584) (xy 131.715034 -357.574473) (xy 131.737696 -357.624092) (xy 131.753065 -357.676431)
			(xy 131.760828 -357.730425) (xy 131.760828 -357.78497) (xy 133.243531 -357.78497) (xy 133.243532 -357.73043)
			(xy 133.251294 -357.676445) (xy 133.26666 -357.624114) (xy 133.289318 -357.574503) (xy 133.318806 -357.528621)
			(xy 133.354524 -357.487404) (xy 133.395744 -357.451689) (xy 133.441627 -357.422205) (xy 133.49124 -357.39955)
			(xy 133.543572 -357.384188) (xy 133.597558 -357.37643) (xy 133.624828 -357.375968) (xy 134.488428 -357.375968)
			(xy 134.515698 -357.376396) (xy 134.569683 -357.384162) (xy 134.622013 -357.399531) (xy 134.671624 -357.42219)
			(xy 134.717505 -357.451679) (xy 134.758722 -357.487397) (xy 134.794437 -357.528618) (xy 134.823923 -357.574501)
			(xy 134.846579 -357.624113) (xy 134.861944 -357.676444) (xy 134.869706 -357.73043) (xy 134.869706 -357.784967)
			(xy 136.352554 -357.784967) (xy 136.352554 -357.730433) (xy 136.360315 -357.676455) (xy 136.375679 -357.624131)
			(xy 136.398332 -357.574525) (xy 136.427815 -357.528648) (xy 136.463526 -357.487434) (xy 136.504739 -357.451722)
			(xy 136.550615 -357.422238) (xy 136.600219 -357.399583) (xy 136.652543 -357.384218) (xy 136.706521 -357.376455)
			(xy 136.733788 -357.375968) (xy 137.597388 -357.375968) (xy 137.624662 -357.376371) (xy 137.678654 -357.384132)
			(xy 137.730992 -357.399499) (xy 137.780611 -357.422157) (xy 137.8265 -357.451647) (xy 137.867724 -357.487367)
			(xy 137.903446 -357.528591) (xy 137.932937 -357.574479) (xy 137.955597 -357.624096) (xy 137.970965 -357.676434)
			(xy 137.978728 -357.730426) (xy 137.978728 -357.784971) (xy 139.461432 -357.784971) (xy 139.461432 -357.730429)
			(xy 139.469194 -357.676442) (xy 139.484562 -357.62411) (xy 139.507221 -357.574497) (xy 139.536711 -357.528615)
			(xy 139.572431 -357.487397) (xy 139.613653 -357.451682) (xy 139.659539 -357.422198) (xy 139.709155 -357.399545)
			(xy 139.761489 -357.384184) (xy 139.815477 -357.376428) (xy 139.842748 -357.375968) (xy 140.706348 -357.375968)
			(xy 140.733617 -357.376398) (xy 140.7876 -357.384166) (xy 140.839928 -357.399536) (xy 140.889536 -357.422197)
			(xy 140.935414 -357.451687) (xy 140.976629 -357.487405) (xy 141.012342 -357.528624) (xy 141.041826 -357.574506)
			(xy 141.06448 -357.624117) (xy 141.079845 -357.676447) (xy 141.087606 -357.730431) (xy 141.087606 -357.784969)
			(xy 142.570431 -357.784969) (xy 142.570431 -357.730431) (xy 142.578193 -357.676447) (xy 142.593559 -357.624118)
			(xy 142.616215 -357.574508) (xy 142.645701 -357.528628) (xy 142.681417 -357.487411) (xy 142.722634 -357.451696)
			(xy 142.768515 -357.422211) (xy 142.818126 -357.399556) (xy 142.870455 -357.384191) (xy 142.924439 -357.376431)
			(xy 142.951708 -357.375968) (xy 143.815308 -357.375968) (xy 143.842579 -357.376395) (xy 143.896566 -357.384158)
			(xy 143.948899 -357.399525) (xy 143.998512 -357.422184) (xy 144.044395 -357.451672) (xy 144.085615 -357.48739)
			(xy 144.121332 -357.528611) (xy 144.15082 -357.574495) (xy 144.173477 -357.624109) (xy 144.188843 -357.676442)
			(xy 144.196606 -357.730429) (xy 144.196606 -357.784965) (xy 158.695954 -357.784965) (xy 158.695954 -357.730435)
			(xy 158.703714 -357.67646) (xy 158.719076 -357.624138) (xy 158.741727 -357.574535) (xy 158.771206 -357.52866)
			(xy 158.806913 -357.487447) (xy 158.848122 -357.451735) (xy 158.893993 -357.42225) (xy 158.943593 -357.399593)
			(xy 158.995913 -357.384224) (xy 159.049887 -357.376458) (xy 159.077152 -357.375968) (xy 159.940752 -357.375968)
			(xy 159.968027 -357.376368) (xy 160.022024 -357.384125) (xy 160.074366 -357.399489) (xy 160.123989 -357.422145)
			(xy 160.169883 -357.451634) (xy 160.211112 -357.487354) (xy 160.246837 -357.528579) (xy 160.276332 -357.574468)
			(xy 160.298994 -357.624089) (xy 160.314364 -357.676429) (xy 160.322128 -357.730425) (xy 160.322128 -357.784969)
			(xy 161.804831 -357.784969) (xy 161.804831 -357.730431) (xy 161.812593 -357.676447) (xy 161.827959 -357.624117)
			(xy 161.850616 -357.574507) (xy 161.880102 -357.528627) (xy 161.915818 -357.487409) (xy 161.957036 -357.451695)
			(xy 162.002918 -357.42221) (xy 162.052529 -357.399555) (xy 162.104859 -357.384191) (xy 162.158843 -357.376431)
			(xy 162.186112 -357.375968) (xy 163.049712 -357.375968) (xy 163.076983 -357.376395) (xy 163.130969 -357.384159)
			(xy 163.183302 -357.399527) (xy 163.232914 -357.422185) (xy 163.278797 -357.451674) (xy 163.320017 -357.487392)
			(xy 163.355733 -357.528612) (xy 163.385221 -357.574496) (xy 163.407878 -357.62411) (xy 163.423244 -357.676442)
			(xy 163.431006 -357.730429) (xy 163.431006 -357.784966) (xy 164.913854 -357.784966) (xy 164.913854 -357.730434)
			(xy 164.921615 -357.676457) (xy 164.936977 -357.624134) (xy 164.95963 -357.57453) (xy 164.989111 -357.528654)
			(xy 165.02482 -357.48744) (xy 165.066031 -357.451727) (xy 165.111905 -357.422243) (xy 165.161508 -357.399587)
			(xy 165.21383 -357.384221) (xy 165.267806 -357.376456) (xy 165.295072 -357.375968) (xy 166.158672 -357.375968)
			(xy 166.185946 -357.37637) (xy 166.239941 -357.384129) (xy 166.292281 -357.399494) (xy 166.341901 -357.422152)
			(xy 166.387792 -357.451641) (xy 166.429019 -357.487361) (xy 166.464742 -357.528585) (xy 166.494235 -357.574474)
			(xy 166.516896 -357.624093) (xy 166.532265 -357.676432) (xy 166.540028 -357.730426) (xy 166.540028 -357.78497)
			(xy 168.022732 -357.78497) (xy 168.022732 -357.73043) (xy 168.030494 -357.676444) (xy 168.045861 -357.624113)
			(xy 168.068519 -357.574502) (xy 168.098007 -357.52862) (xy 168.133725 -357.487402) (xy 168.174946 -357.451688)
			(xy 168.22083 -357.422203) (xy 168.270443 -357.399549) (xy 168.322776 -357.384187) (xy 168.376762 -357.376429)
			(xy 168.404032 -357.375968) (xy 169.267632 -357.375968) (xy 169.294902 -357.376397) (xy 169.348886 -357.384163)
			(xy 169.401216 -357.399532) (xy 169.450826 -357.422192) (xy 169.496707 -357.451681) (xy 169.537924 -357.487399)
			(xy 169.573638 -357.528619) (xy 169.603124 -357.574502) (xy 169.625779 -357.624114) (xy 169.641144 -357.676445)
			(xy 169.648906 -357.73043) (xy 169.648906 -357.784967) (xy 171.131754 -357.784967) (xy 171.131754 -357.730433)
			(xy 171.139515 -357.676454) (xy 171.154879 -357.62413) (xy 171.177533 -357.574524) (xy 171.207016 -357.528647)
			(xy 171.242727 -357.487433) (xy 171.283941 -357.45172) (xy 171.329817 -357.422237) (xy 171.379422 -357.399582)
			(xy 171.431747 -357.384217) (xy 171.485725 -357.376455) (xy 171.512992 -357.375968) (xy 172.376592 -357.375968)
			(xy 172.403866 -357.376371) (xy 172.457857 -357.384133) (xy 172.510195 -357.3995) (xy 172.559813 -357.422159)
			(xy 172.605702 -357.451648) (xy 172.646926 -357.487368) (xy 172.682647 -357.528592) (xy 172.712138 -357.57448)
			(xy 172.734798 -357.624097) (xy 172.750165 -357.676435) (xy 172.757928 -357.730426) (xy 172.757928 -357.784965)
			(xy 174.240754 -357.784965) (xy 174.240754 -357.730435) (xy 174.248514 -357.67646) (xy 174.263876 -357.624138)
			(xy 174.286527 -357.574535) (xy 174.316006 -357.52866) (xy 174.351713 -357.487447) (xy 174.392922 -357.451735)
			(xy 174.438793 -357.42225) (xy 174.488393 -357.399593) (xy 174.540713 -357.384224) (xy 174.594687 -357.376458)
			(xy 174.621952 -357.375968) (xy 175.485552 -357.375968) (xy 175.512827 -357.376368) (xy 175.566824 -357.384125)
			(xy 175.619166 -357.399489) (xy 175.668789 -357.422145) (xy 175.714683 -357.451634) (xy 175.755912 -357.487354)
			(xy 175.791637 -357.528579) (xy 175.821132 -357.574468) (xy 175.843794 -357.624089) (xy 175.859164 -357.676429)
			(xy 175.866928 -357.730425) (xy 175.866928 -357.784969) (xy 177.349631 -357.784969) (xy 177.349631 -357.730431)
			(xy 177.357393 -357.676447) (xy 177.372759 -357.624117) (xy 177.395416 -357.574507) (xy 177.424902 -357.528627)
			(xy 177.460618 -357.487409) (xy 177.501836 -357.451695) (xy 177.547718 -357.42221) (xy 177.597329 -357.399555)
			(xy 177.649659 -357.384191) (xy 177.703643 -357.376431) (xy 177.730912 -357.375968) (xy 178.594512 -357.375968)
			(xy 178.621783 -357.376395) (xy 178.675769 -357.384159) (xy 178.728102 -357.399527) (xy 178.777714 -357.422185)
			(xy 178.823597 -357.451674) (xy 178.864817 -357.487392) (xy 178.900533 -357.528612) (xy 178.930021 -357.574496)
			(xy 178.952678 -357.62411) (xy 178.968044 -357.676442) (xy 178.975806 -357.730429) (xy 178.975806 -357.784966)
			(xy 180.458654 -357.784966) (xy 180.458654 -357.730434) (xy 180.466415 -357.676457) (xy 180.481777 -357.624134)
			(xy 180.50443 -357.57453) (xy 180.533911 -357.528654) (xy 180.56962 -357.48744) (xy 180.610831 -357.451727)
			(xy 180.656705 -357.422243) (xy 180.706308 -357.399587) (xy 180.75863 -357.384221) (xy 180.812606 -357.376456)
			(xy 180.839872 -357.375968) (xy 181.703472 -357.375968) (xy 181.730746 -357.37637) (xy 181.784741 -357.384129)
			(xy 181.837081 -357.399494) (xy 181.886701 -357.422152) (xy 181.932592 -357.451641) (xy 181.973819 -357.487361)
			(xy 182.009542 -357.528585) (xy 182.039035 -357.574474) (xy 182.061696 -357.624093) (xy 182.077065 -357.676432)
			(xy 182.084828 -357.730426) (xy 182.084828 -357.761176) (xy 183.567456 -357.761176) (xy 183.567456 -357.706624)
			(xy 183.57522 -357.652628) (xy 183.590589 -357.600287) (xy 183.613252 -357.550665) (xy 183.642746 -357.504775)
			(xy 183.678471 -357.463549) (xy 183.7197 -357.427827) (xy 183.765593 -357.398337) (xy 183.815217 -357.375678)
			(xy 183.867559 -357.360313) (xy 183.921556 -357.352553) (xy 183.948832 -357.352092) (xy 184.812432 -357.352092)
			(xy 184.839697 -357.352672) (xy 184.89367 -357.360437) (xy 184.94599 -357.375803) (xy 184.99559 -357.398458)
			(xy 185.041461 -357.427942) (xy 185.08267 -357.463653) (xy 185.118378 -357.504864) (xy 185.147857 -357.550738)
			(xy 185.170508 -357.60034) (xy 185.18587 -357.652661) (xy 185.19363 -357.706635) (xy 185.19363 -357.761165)
			(xy 185.193629 -357.761172) (xy 186.676479 -357.761172) (xy 186.676479 -357.706628) (xy 186.684241 -357.652638)
			(xy 186.699608 -357.600303) (xy 186.722266 -357.550688) (xy 186.751755 -357.504801) (xy 186.787473 -357.463579)
			(xy 186.828695 -357.42786) (xy 186.87458 -357.39837) (xy 186.924196 -357.37571) (xy 186.97653 -357.360343)
			(xy 187.03052 -357.352579) (xy 187.057792 -357.352092) (xy 187.921392 -357.352092) (xy 187.94866 -357.352647)
			(xy 188.002641 -357.360407) (xy 188.054969 -357.375771) (xy 188.104577 -357.398425) (xy 188.150456 -357.427909)
			(xy 188.191672 -357.463622) (xy 188.227386 -357.504838) (xy 188.256871 -357.550716) (xy 188.279526 -357.600324)
			(xy 188.294891 -357.652651) (xy 188.302653 -357.706632) (xy 188.302653 -357.761168) (xy 188.294891 -357.815149)
			(xy 188.279526 -357.867476) (xy 188.256871 -357.917084) (xy 188.227386 -357.962962) (xy 188.223925 -357.966956)
			(xy 245.50903 -357.966956) (xy 245.50903 -357.88226) (xy 245.517081 -357.797946) (xy 245.53311 -357.71478)
			(xy 245.556971 -357.633513) (xy 245.58845 -357.554883) (xy 245.627261 -357.479602) (xy 245.673051 -357.40835)
			(xy 245.725407 -357.341774) (xy 245.783855 -357.280476) (xy 245.847865 -357.225011) (xy 245.916857 -357.175882)
			(xy 245.990207 -357.133533) (xy 246.06725 -357.098349) (xy 246.147289 -357.070647) (xy 246.229598 -357.050679)
			(xy 246.313433 -357.038626) (xy 246.398034 -357.034596) (xy 246.482635 -357.038626) (xy 246.56647 -357.050679)
			(xy 246.648779 -357.070647) (xy 246.728818 -357.098349) (xy 246.805861 -357.133533) (xy 246.879211 -357.175882)
			(xy 246.948203 -357.225011) (xy 247.012213 -357.280476) (xy 247.070661 -357.341774) (xy 247.123017 -357.40835)
			(xy 247.168807 -357.479602) (xy 247.207618 -357.554883) (xy 247.239097 -357.633513) (xy 247.262958 -357.71478)
			(xy 247.276485 -357.784966) (xy 270.624854 -357.784966) (xy 270.624854 -357.730435) (xy 270.632614 -357.676458)
			(xy 270.647977 -357.624136) (xy 270.670628 -357.574532) (xy 270.700108 -357.528657) (xy 270.735817 -357.487443)
			(xy 270.777026 -357.451731) (xy 270.822899 -357.422246) (xy 270.8725 -357.39959) (xy 270.924821 -357.384222)
			(xy 270.978797 -357.376457) (xy 271.006062 -357.375968) (xy 271.869662 -357.375968) (xy 271.896937 -357.376369)
			(xy 271.950932 -357.384127) (xy 272.003273 -357.399491) (xy 272.052895 -357.422149) (xy 272.098787 -357.451638)
			(xy 272.140015 -357.487358) (xy 272.17574 -357.528582) (xy 272.205233 -357.574471) (xy 272.227895 -357.624091)
			(xy 272.243265 -357.676431) (xy 272.251028 -357.730425) (xy 272.251028 -357.78497) (xy 273.733731 -357.78497)
			(xy 273.733731 -357.73043) (xy 273.741494 -357.676446) (xy 273.75686 -357.624115) (xy 273.779517 -357.574505)
			(xy 273.809005 -357.528623) (xy 273.844722 -357.487406) (xy 273.885941 -357.451691) (xy 273.931824 -357.422207)
			(xy 273.981436 -357.399552) (xy 274.033767 -357.384189) (xy 274.087752 -357.37643) (xy 274.115022 -357.375968)
			(xy 274.978622 -357.375968) (xy 275.005892 -357.376396) (xy 275.059878 -357.384161) (xy 275.112209 -357.399529)
			(xy 275.16182 -357.422189) (xy 275.207702 -357.451677) (xy 275.24892 -357.487395) (xy 275.284636 -357.528616)
			(xy 275.314122 -357.574499) (xy 275.336778 -357.624112) (xy 275.352144 -357.676444) (xy 275.359906 -357.730429)
			(xy 275.359906 -357.784966) (xy 276.842754 -357.784966) (xy 276.842754 -357.730434) (xy 276.850515 -357.676456)
			(xy 276.865878 -357.624132) (xy 276.888531 -357.574527) (xy 276.918013 -357.52865) (xy 276.953724 -357.487436)
			(xy 276.994936 -357.451724) (xy 277.040811 -357.42224) (xy 277.090415 -357.399584) (xy 277.142738 -357.384219)
			(xy 277.196716 -357.376456) (xy 277.223982 -357.375968) (xy 278.087582 -357.375968) (xy 278.114856 -357.37637)
			(xy 278.168849 -357.384131) (xy 278.221188 -357.399497) (xy 278.270807 -357.422155) (xy 278.316697 -357.451645)
			(xy 278.357922 -357.487365) (xy 278.393644 -357.528589) (xy 278.423136 -357.574477) (xy 278.445797 -357.624095)
			(xy 278.461165 -357.676433) (xy 278.468928 -357.730426) (xy 278.468928 -357.784971) (xy 279.951632 -357.784971)
			(xy 279.951632 -357.730429) (xy 279.959394 -357.676443) (xy 279.974761 -357.624111) (xy 279.99742 -357.574499)
			(xy 280.026909 -357.528617) (xy 280.062629 -357.487399) (xy 280.103851 -357.451684) (xy 280.149736 -357.4222)
			(xy 280.19935 -357.399547) (xy 280.251684 -357.384185) (xy 280.305671 -357.376429) (xy 280.332942 -357.375968)
			(xy 281.196542 -357.375968) (xy 281.223812 -357.376397) (xy 281.277795 -357.384165) (xy 281.330123 -357.399535)
			(xy 281.379732 -357.422195) (xy 281.425611 -357.451684) (xy 281.466827 -357.487402) (xy 281.502541 -357.528622)
			(xy 281.532025 -357.574505) (xy 281.55468 -357.624116) (xy 281.570044 -357.676446) (xy 281.577806 -357.73043)
			(xy 281.577806 -357.784969) (xy 283.060631 -357.784969) (xy 283.060631 -357.730431) (xy 283.068393 -357.676448)
			(xy 283.083758 -357.62412) (xy 283.106414 -357.57451) (xy 283.1359 -357.52863) (xy 283.171614 -357.487413)
			(xy 283.212832 -357.451698) (xy 283.258712 -357.422213) (xy 283.308321 -357.399557) (xy 283.36065 -357.384193)
			(xy 283.414633 -357.376431) (xy 283.441902 -357.375968) (xy 284.305502 -357.375968) (xy 284.332773 -357.376395)
			(xy 284.386761 -357.384157) (xy 284.439094 -357.399524) (xy 284.488708 -357.422182) (xy 284.534593 -357.45167)
			(xy 284.575813 -357.487388) (xy 284.611531 -357.528609) (xy 284.641019 -357.574493) (xy 284.663677 -357.624107)
			(xy 284.679043 -357.676441) (xy 284.686806 -357.730429) (xy 284.686806 -357.784966) (xy 286.169654 -357.784966)
			(xy 286.169654 -357.730435) (xy 286.177414 -357.676458) (xy 286.192777 -357.624136) (xy 286.215428 -357.574532)
			(xy 286.244908 -357.528657) (xy 286.280617 -357.487443) (xy 286.321826 -357.451731) (xy 286.367699 -357.422246)
			(xy 286.4173 -357.39959) (xy 286.469621 -357.384222) (xy 286.523597 -357.376457) (xy 286.550862 -357.375968)
			(xy 287.414462 -357.375968) (xy 287.441737 -357.376369) (xy 287.495732 -357.384127) (xy 287.548073 -357.399491)
			(xy 287.597695 -357.422149) (xy 287.643587 -357.451638) (xy 287.684815 -357.487358) (xy 287.72054 -357.528582)
			(xy 287.750033 -357.574471) (xy 287.772695 -357.624091) (xy 287.788065 -357.676431) (xy 287.795828 -357.730425)
			(xy 287.795828 -357.78497) (xy 289.278531 -357.78497) (xy 289.278531 -357.73043) (xy 289.286294 -357.676446)
			(xy 289.30166 -357.624115) (xy 289.324317 -357.574505) (xy 289.353805 -357.528623) (xy 289.389522 -357.487406)
			(xy 289.430741 -357.451691) (xy 289.476624 -357.422207) (xy 289.526236 -357.399552) (xy 289.578567 -357.384189)
			(xy 289.632552 -357.37643) (xy 289.659822 -357.375968) (xy 290.523422 -357.375968) (xy 290.550692 -357.376396)
			(xy 290.604678 -357.384161) (xy 290.657009 -357.399529) (xy 290.70662 -357.422189) (xy 290.752502 -357.451677)
			(xy 290.79372 -357.487395) (xy 290.829436 -357.528616) (xy 290.858922 -357.574499) (xy 290.881578 -357.624112)
			(xy 290.896944 -357.676444) (xy 290.904706 -357.730429) (xy 290.904706 -357.784966) (xy 292.387554 -357.784966)
			(xy 292.387554 -357.730434) (xy 292.395315 -357.676456) (xy 292.410678 -357.624132) (xy 292.433331 -357.574527)
			(xy 292.462813 -357.52865) (xy 292.498524 -357.487436) (xy 292.539736 -357.451724) (xy 292.585611 -357.42224)
			(xy 292.635215 -357.399584) (xy 292.687538 -357.384219) (xy 292.741516 -357.376456) (xy 292.768782 -357.375968)
			(xy 293.632382 -357.375968) (xy 293.659656 -357.37637) (xy 293.713649 -357.384131) (xy 293.765988 -357.399497)
			(xy 293.815607 -357.422155) (xy 293.861497 -357.451645) (xy 293.902722 -357.487365) (xy 293.938444 -357.528589)
			(xy 293.967936 -357.574477) (xy 293.990597 -357.624095) (xy 294.005965 -357.676433) (xy 294.013728 -357.730426)
			(xy 294.013728 -357.784971) (xy 295.496432 -357.784971) (xy 295.496432 -357.730429) (xy 295.504194 -357.676443)
			(xy 295.519561 -357.624111) (xy 295.54222 -357.574499) (xy 295.571709 -357.528617) (xy 295.607429 -357.487399)
			(xy 295.648651 -357.451684) (xy 295.694536 -357.4222) (xy 295.74415 -357.399547) (xy 295.796484 -357.384185)
			(xy 295.850471 -357.376429) (xy 295.877742 -357.375968) (xy 296.741342 -357.375968) (xy 296.768612 -357.376397)
			(xy 296.822595 -357.384165) (xy 296.874923 -357.399535) (xy 296.924532 -357.422195) (xy 296.970411 -357.451684)
			(xy 297.011627 -357.487402) (xy 297.047341 -357.528622) (xy 297.076825 -357.574505) (xy 297.09948 -357.624116)
			(xy 297.114844 -357.676446) (xy 297.122606 -357.73043) (xy 297.122606 -357.784969) (xy 298.605431 -357.784969)
			(xy 298.605431 -357.730431) (xy 298.613193 -357.676448) (xy 298.628558 -357.62412) (xy 298.651214 -357.57451)
			(xy 298.6807 -357.52863) (xy 298.716414 -357.487413) (xy 298.757632 -357.451698) (xy 298.803512 -357.422213)
			(xy 298.853121 -357.399557) (xy 298.90545 -357.384193) (xy 298.959433 -357.376431) (xy 298.986702 -357.375968)
			(xy 299.850302 -357.375968) (xy 299.877573 -357.376395) (xy 299.931561 -357.384157) (xy 299.983894 -357.399524)
			(xy 300.033508 -357.422182) (xy 300.079393 -357.45167) (xy 300.120613 -357.487388) (xy 300.156331 -357.528609)
			(xy 300.185819 -357.574493) (xy 300.208477 -357.624107) (xy 300.223843 -357.676441) (xy 300.231606 -357.730429)
			(xy 300.231606 -357.784966) (xy 315.230554 -357.784966) (xy 315.230554 -357.730434) (xy 315.238314 -357.676458)
			(xy 315.253677 -357.624136) (xy 315.276328 -357.574532) (xy 315.305809 -357.528656) (xy 315.341517 -357.487443)
			(xy 315.382727 -357.45173) (xy 315.4286 -357.422246) (xy 315.478202 -357.399589) (xy 315.530523 -357.384222)
			(xy 315.584498 -357.376457) (xy 315.611764 -357.375968) (xy 316.475364 -357.375968) (xy 316.502639 -357.376369)
			(xy 316.556634 -357.384128) (xy 316.608975 -357.399492) (xy 316.658597 -357.422149) (xy 316.704488 -357.451638)
			(xy 316.745716 -357.487359) (xy 316.78144 -357.528583) (xy 316.810933 -357.574472) (xy 316.833595 -357.624091)
			(xy 316.848965 -357.676431) (xy 316.856728 -357.730425) (xy 316.856728 -357.78497) (xy 318.339431 -357.78497)
			(xy 318.339431 -357.73043) (xy 318.347194 -357.676445) (xy 318.36256 -357.624115) (xy 318.385217 -357.574504)
			(xy 318.414705 -357.528623) (xy 318.450422 -357.487405) (xy 318.491642 -357.451691) (xy 318.537525 -357.422206)
			(xy 318.587137 -357.399552) (xy 318.639469 -357.384189) (xy 318.693454 -357.37643) (xy 318.720724 -357.375968)
			(xy 319.584324 -357.375968) (xy 319.611594 -357.376396) (xy 319.66558 -357.384161) (xy 319.71791 -357.39953)
			(xy 319.767521 -357.422189) (xy 319.813403 -357.451678) (xy 319.854621 -357.487396) (xy 319.890336 -357.528616)
			(xy 319.919822 -357.5745) (xy 319.942479 -357.624112) (xy 319.957844 -357.676444) (xy 319.965606 -357.73043)
			(xy 319.965606 -357.784967) (xy 321.448454 -357.784967) (xy 321.448454 -357.730434) (xy 321.456215 -357.676456)
			(xy 321.471578 -357.624131) (xy 321.494232 -357.574526) (xy 321.523714 -357.52865) (xy 321.559424 -357.487436)
			(xy 321.600637 -357.451723) (xy 321.646512 -357.422239) (xy 321.696116 -357.399584) (xy 321.74844 -357.384218)
			(xy 321.802418 -357.376455) (xy 321.829684 -357.375968) (xy 322.693284 -357.375968) (xy 322.720558 -357.37637)
			(xy 322.774551 -357.384131) (xy 322.826889 -357.399497) (xy 322.876508 -357.422156) (xy 322.922398 -357.451645)
			(xy 322.963623 -357.487366) (xy 322.999345 -357.528589) (xy 323.028836 -357.574477) (xy 323.051497 -357.624096)
			(xy 323.066865 -357.676434) (xy 323.074628 -357.730426) (xy 323.074628 -357.784971) (xy 324.557332 -357.784971)
			(xy 324.557332 -357.730429) (xy 324.565094 -357.676443) (xy 324.580461 -357.624111) (xy 324.603121 -357.574498)
			(xy 324.63261 -357.528616) (xy 324.668329 -357.487398) (xy 324.709551 -357.451684) (xy 324.755437 -357.422199)
			(xy 324.805052 -357.399546) (xy 324.857386 -357.384185) (xy 324.911373 -357.376428) (xy 324.938644 -357.375968)
			(xy 325.802244 -357.375968) (xy 325.829513 -357.376398) (xy 325.883497 -357.384165) (xy 325.935825 -357.399535)
			(xy 325.985433 -357.422196) (xy 326.031312 -357.451685) (xy 326.072528 -357.487403) (xy 326.108241 -357.528623)
			(xy 326.137725 -357.574505) (xy 326.16038 -357.624116) (xy 326.175744 -357.676447) (xy 326.183506 -357.73043)
			(xy 326.183506 -357.784969) (xy 327.666331 -357.784969) (xy 327.666331 -357.730431) (xy 327.674093 -357.676448)
			(xy 327.689458 -357.624119) (xy 327.712114 -357.57451) (xy 327.7416 -357.528629) (xy 327.777315 -357.487412)
			(xy 327.818533 -357.451698) (xy 327.864413 -357.422212) (xy 327.914023 -357.399557) (xy 327.966352 -357.384192)
			(xy 328.020335 -357.376431) (xy 328.047604 -357.375968) (xy 328.911204 -357.375968) (xy 328.938475 -357.376395)
			(xy 328.992463 -357.384158) (xy 329.044796 -357.399524) (xy 329.094409 -357.422183) (xy 329.140293 -357.451671)
			(xy 329.181514 -357.487389) (xy 329.217231 -357.52861) (xy 329.246719 -357.574494) (xy 329.269377 -357.624108)
			(xy 329.284743 -357.676441) (xy 329.292506 -357.730429) (xy 329.292506 -357.784966) (xy 330.775354 -357.784966)
			(xy 330.775354 -357.730434) (xy 330.783114 -357.676458) (xy 330.798477 -357.624136) (xy 330.821128 -357.574532)
			(xy 330.850609 -357.528656) (xy 330.886317 -357.487443) (xy 330.927527 -357.45173) (xy 330.9734 -357.422246)
			(xy 331.023002 -357.399589) (xy 331.075323 -357.384222) (xy 331.129298 -357.376457) (xy 331.156564 -357.375968)
			(xy 332.020164 -357.375968) (xy 332.047439 -357.376369) (xy 332.101434 -357.384128) (xy 332.153775 -357.399492)
			(xy 332.203397 -357.422149) (xy 332.249288 -357.451638) (xy 332.290516 -357.487359) (xy 332.32624 -357.528583)
			(xy 332.355733 -357.574472) (xy 332.378395 -357.624091) (xy 332.393765 -357.676431) (xy 332.401528 -357.730425)
			(xy 332.401528 -357.78497) (xy 333.884231 -357.78497) (xy 333.884231 -357.73043) (xy 333.891994 -357.676445)
			(xy 333.90736 -357.624115) (xy 333.930017 -357.574504) (xy 333.959505 -357.528623) (xy 333.995222 -357.487405)
			(xy 334.036442 -357.451691) (xy 334.082325 -357.422206) (xy 334.131937 -357.399552) (xy 334.184269 -357.384189)
			(xy 334.238254 -357.37643) (xy 334.265524 -357.375968) (xy 335.129124 -357.375968) (xy 335.156394 -357.376396)
			(xy 335.21038 -357.384161) (xy 335.26271 -357.39953) (xy 335.312321 -357.422189) (xy 335.358203 -357.451678)
			(xy 335.399421 -357.487396) (xy 335.435136 -357.528616) (xy 335.464622 -357.5745) (xy 335.487279 -357.624112)
			(xy 335.502644 -357.676444) (xy 335.510406 -357.73043) (xy 335.510406 -357.784967) (xy 336.993254 -357.784967)
			(xy 336.993254 -357.730434) (xy 337.001015 -357.676456) (xy 337.016378 -357.624131) (xy 337.039032 -357.574526)
			(xy 337.068514 -357.52865) (xy 337.104224 -357.487436) (xy 337.145437 -357.451723) (xy 337.191312 -357.422239)
			(xy 337.240916 -357.399584) (xy 337.29324 -357.384218) (xy 337.347218 -357.376455) (xy 337.374484 -357.375968)
			(xy 338.238084 -357.375968) (xy 338.265358 -357.37637) (xy 338.319351 -357.384131) (xy 338.371689 -357.399497)
			(xy 338.421308 -357.422156) (xy 338.467198 -357.451645) (xy 338.508423 -357.487366) (xy 338.544145 -357.528589)
			(xy 338.573636 -357.574477) (xy 338.596297 -357.624096) (xy 338.611665 -357.676434) (xy 338.619428 -357.730426)
			(xy 338.619428 -357.784971) (xy 340.102132 -357.784971) (xy 340.102132 -357.730429) (xy 340.109894 -357.676443)
			(xy 340.125261 -357.624111) (xy 340.147921 -357.574498) (xy 340.17741 -357.528616) (xy 340.213129 -357.487398)
			(xy 340.254351 -357.451684) (xy 340.300237 -357.422199) (xy 340.349852 -357.399546) (xy 340.402186 -357.384185)
			(xy 340.456173 -357.376428) (xy 340.483444 -357.375968) (xy 341.347044 -357.375968) (xy 341.374313 -357.376398)
			(xy 341.428297 -357.384165) (xy 341.480625 -357.399535) (xy 341.530233 -357.422196) (xy 341.576112 -357.451685)
			(xy 341.617328 -357.487403) (xy 341.653041 -357.528623) (xy 341.682525 -357.574505) (xy 341.70518 -357.624116)
			(xy 341.720544 -357.676447) (xy 341.728306 -357.73043) (xy 341.728306 -357.784969) (xy 343.211131 -357.784969)
			(xy 343.211131 -357.730431) (xy 343.218893 -357.676448) (xy 343.234258 -357.624119) (xy 343.256914 -357.57451)
			(xy 343.2864 -357.528629) (xy 343.322115 -357.487412) (xy 343.363333 -357.451698) (xy 343.409213 -357.422212)
			(xy 343.458823 -357.399557) (xy 343.511152 -357.384192) (xy 343.565135 -357.376431) (xy 343.592404 -357.375968)
			(xy 344.456004 -357.375968) (xy 344.483275 -357.376395) (xy 344.537263 -357.384158) (xy 344.589596 -357.399524)
			(xy 344.639209 -357.422183) (xy 344.685093 -357.451671) (xy 344.726314 -357.487389) (xy 344.762031 -357.52861)
			(xy 344.791519 -357.574494) (xy 344.814177 -357.624108) (xy 344.829543 -357.676441) (xy 344.837306 -357.730429)
			(xy 344.837306 -357.784971) (xy 373.915632 -357.784971) (xy 373.915632 -357.730429) (xy 373.923394 -357.676443)
			(xy 373.938761 -357.624111) (xy 373.96142 -357.574499) (xy 373.990909 -357.528617) (xy 374.026628 -357.4874)
			(xy 374.06785 -357.451685) (xy 374.113735 -357.422201) (xy 374.163349 -357.399547) (xy 374.215682 -357.384186)
			(xy 374.269669 -357.376429) (xy 374.29694 -357.375968) (xy 375.16054 -357.375968) (xy 375.18781 -357.376397)
			(xy 375.241793 -357.384164) (xy 375.294122 -357.399534) (xy 375.343731 -357.422194) (xy 375.389611 -357.451684)
			(xy 375.430827 -357.487402) (xy 375.46654 -357.528622) (xy 375.496025 -357.574504) (xy 375.51868 -357.624116)
			(xy 375.534044 -357.676446) (xy 375.541806 -357.73043) (xy 375.541806 -357.784967) (xy 377.024654 -357.784967)
			(xy 377.024654 -357.730433) (xy 377.032415 -357.676453) (xy 377.04778 -357.624128) (xy 377.070434 -357.574522)
			(xy 377.099918 -357.528644) (xy 377.13563 -357.48743) (xy 377.176844 -357.451718) (xy 377.222722 -357.422234)
			(xy 377.272328 -357.39958) (xy 377.324653 -357.384215) (xy 377.378633 -357.376454) (xy 377.4059 -357.375968)
			(xy 378.2695 -357.375968) (xy 378.296772 -357.376395) (xy 378.350759 -357.384157) (xy 378.403093 -357.399523)
			(xy 378.452707 -357.422181) (xy 378.498592 -357.451669) (xy 378.539812 -357.487388) (xy 378.575531 -357.528608)
			(xy 378.605019 -357.574493) (xy 378.627677 -357.624107) (xy 378.643043 -357.676441) (xy 378.650805 -357.730428)
			(xy 378.650805 -357.784965) (xy 380.133654 -357.784965) (xy 380.133654 -357.730435) (xy 380.141414 -357.676459)
			(xy 380.156776 -357.624137) (xy 380.179428 -357.574533) (xy 380.208908 -357.528658) (xy 380.244616 -357.487444)
			(xy 380.285825 -357.451732) (xy 380.331698 -357.422247) (xy 380.381299 -357.39959) (xy 380.43362 -357.384223)
			(xy 380.487595 -357.376457) (xy 380.51486 -357.375968) (xy 381.37846 -357.375968) (xy 381.405735 -357.376369)
			(xy 381.45973 -357.384127) (xy 381.512072 -357.399491) (xy 381.561694 -357.422148) (xy 381.607586 -357.451637)
			(xy 381.648815 -357.487357) (xy 381.684539 -357.528582) (xy 381.714033 -357.574471) (xy 381.736695 -357.62409)
			(xy 381.752065 -357.67643) (xy 381.759828 -357.730425) (xy 381.759828 -357.78497) (xy 383.242531 -357.78497)
			(xy 383.242531 -357.73043) (xy 383.250294 -357.676446) (xy 383.26566 -357.624116) (xy 383.288317 -357.574505)
			(xy 383.317804 -357.528624) (xy 383.353521 -357.487407) (xy 383.39474 -357.451692) (xy 383.440623 -357.422207)
			(xy 383.490234 -357.399553) (xy 383.542565 -357.384189) (xy 383.59655 -357.37643) (xy 383.62382 -357.375968)
			(xy 384.48742 -357.375968) (xy 384.514691 -357.376396) (xy 384.568676 -357.38416) (xy 384.621007 -357.399529)
			(xy 384.670619 -357.422188) (xy 384.716501 -357.451677) (xy 384.75772 -357.487395) (xy 384.793435 -357.528615)
			(xy 384.822922 -357.574499) (xy 384.845578 -357.624111) (xy 384.860944 -357.676443) (xy 384.868706 -357.730429)
			(xy 384.868706 -357.784966) (xy 386.351554 -357.784966) (xy 386.351554 -357.730434) (xy 386.359315 -357.676456)
			(xy 386.374678 -357.624132) (xy 386.397331 -357.574527) (xy 386.426813 -357.528651) (xy 386.462523 -357.487437)
			(xy 386.503735 -357.451725) (xy 386.54961 -357.422241) (xy 386.599213 -357.399585) (xy 386.651537 -357.384219)
			(xy 386.705514 -357.376456) (xy 386.73278 -357.375968) (xy 387.59638 -357.375968) (xy 387.623654 -357.37637)
			(xy 387.677647 -357.384131) (xy 387.729987 -357.399496) (xy 387.779606 -357.422155) (xy 387.825496 -357.451644)
			(xy 387.866722 -357.487364) (xy 387.902444 -357.528588) (xy 387.931936 -357.574476) (xy 387.954597 -357.624095)
			(xy 387.969965 -357.676433) (xy 387.977728 -357.730426) (xy 387.977728 -357.784971) (xy 389.460432 -357.784971)
			(xy 389.460432 -357.730429) (xy 389.468194 -357.676443) (xy 389.483561 -357.624111) (xy 389.50622 -357.574499)
			(xy 389.535709 -357.528617) (xy 389.571428 -357.4874) (xy 389.61265 -357.451685) (xy 389.658535 -357.422201)
			(xy 389.708149 -357.399547) (xy 389.760482 -357.384186) (xy 389.814469 -357.376429) (xy 389.84174 -357.375968)
			(xy 390.70534 -357.375968) (xy 390.73261 -357.376397) (xy 390.786593 -357.384164) (xy 390.838922 -357.399534)
			(xy 390.888531 -357.422194) (xy 390.934411 -357.451684) (xy 390.975627 -357.487402) (xy 391.01134 -357.528622)
			(xy 391.040825 -357.574504) (xy 391.06348 -357.624116) (xy 391.078844 -357.676446) (xy 391.086606 -357.73043)
			(xy 391.086606 -357.784967) (xy 392.569454 -357.784967) (xy 392.569454 -357.730433) (xy 392.577215 -357.676453)
			(xy 392.59258 -357.624128) (xy 392.615234 -357.574522) (xy 392.644718 -357.528644) (xy 392.68043 -357.48743)
			(xy 392.721644 -357.451718) (xy 392.767522 -357.422234) (xy 392.817128 -357.39958) (xy 392.869453 -357.384215)
			(xy 392.923433 -357.376454) (xy 392.9507 -357.375968) (xy 393.8143 -357.375968) (xy 393.841572 -357.376395)
			(xy 393.895559 -357.384157) (xy 393.947893 -357.399523) (xy 393.997507 -357.422181) (xy 394.043392 -357.451669)
			(xy 394.084612 -357.487388) (xy 394.120331 -357.528608) (xy 394.149819 -357.574493) (xy 394.172477 -357.624107)
			(xy 394.187843 -357.676441) (xy 394.195605 -357.730428) (xy 394.195605 -357.784965) (xy 395.678454 -357.784965)
			(xy 395.678454 -357.730435) (xy 395.686214 -357.676459) (xy 395.701576 -357.624137) (xy 395.724228 -357.574533)
			(xy 395.753708 -357.528658) (xy 395.789416 -357.487444) (xy 395.830625 -357.451732) (xy 395.876498 -357.422247)
			(xy 395.926099 -357.39959) (xy 395.97842 -357.384223) (xy 396.032395 -357.376457) (xy 396.05966 -357.375968)
			(xy 396.92326 -357.375968) (xy 396.950535 -357.376369) (xy 397.00453 -357.384127) (xy 397.056872 -357.399491)
			(xy 397.106494 -357.422148) (xy 397.152386 -357.451637) (xy 397.193615 -357.487357) (xy 397.229339 -357.528582)
			(xy 397.258833 -357.574471) (xy 397.281495 -357.62409) (xy 397.296865 -357.67643) (xy 397.304628 -357.730425)
			(xy 397.304628 -357.78497) (xy 398.787331 -357.78497) (xy 398.787331 -357.73043) (xy 398.795094 -357.676446)
			(xy 398.81046 -357.624116) (xy 398.833117 -357.574505) (xy 398.862604 -357.528624) (xy 398.898321 -357.487407)
			(xy 398.93954 -357.451692) (xy 398.985423 -357.422207) (xy 399.035034 -357.399553) (xy 399.087365 -357.384189)
			(xy 399.14135 -357.37643) (xy 399.16862 -357.375968) (xy 400.03222 -357.375968) (xy 400.059491 -357.376396)
			(xy 400.113476 -357.38416) (xy 400.165807 -357.399529) (xy 400.215419 -357.422188) (xy 400.261301 -357.451677)
			(xy 400.30252 -357.487395) (xy 400.338235 -357.528615) (xy 400.367722 -357.574499) (xy 400.390378 -357.624111)
			(xy 400.405744 -357.676443) (xy 400.413506 -357.730429) (xy 400.413506 -357.784966) (xy 401.896354 -357.784966)
			(xy 401.896354 -357.730434) (xy 401.904115 -357.676456) (xy 401.919478 -357.624132) (xy 401.942131 -357.574527)
			(xy 401.971613 -357.528651) (xy 402.007323 -357.487437) (xy 402.048535 -357.451725) (xy 402.09441 -357.422241)
			(xy 402.144013 -357.399585) (xy 402.196337 -357.384219) (xy 402.250314 -357.376456) (xy 402.27758 -357.375968)
			(xy 403.14118 -357.375968) (xy 403.168454 -357.37637) (xy 403.222447 -357.384131) (xy 403.274787 -357.399496)
			(xy 403.324406 -357.422155) (xy 403.370296 -357.451644) (xy 403.411522 -357.487364) (xy 403.447244 -357.528588)
			(xy 403.476736 -357.574476) (xy 403.499397 -357.624095) (xy 403.514765 -357.676433) (xy 403.522528 -357.730426)
			(xy 403.522528 -357.784965) (xy 412.022854 -357.784965) (xy 412.022854 -357.730435) (xy 412.030614 -357.67646)
			(xy 412.045976 -357.624138) (xy 412.068627 -357.574535) (xy 412.098106 -357.52866) (xy 412.133813 -357.487447)
			(xy 412.175022 -357.451735) (xy 412.220893 -357.42225) (xy 412.270493 -357.399593) (xy 412.322813 -357.384224)
			(xy 412.376787 -357.376458) (xy 412.404052 -357.375968) (xy 413.267652 -357.375968) (xy 413.294927 -357.376368)
			(xy 413.348924 -357.384125) (xy 413.401266 -357.399489) (xy 413.450889 -357.422145) (xy 413.496783 -357.451634)
			(xy 413.538012 -357.487354) (xy 413.573737 -357.528579) (xy 413.603232 -357.574468) (xy 413.625894 -357.624089)
			(xy 413.641264 -357.676429) (xy 413.649028 -357.730425) (xy 413.649028 -357.784969) (xy 415.131731 -357.784969)
			(xy 415.131731 -357.730431) (xy 415.139493 -357.676447) (xy 415.154859 -357.624117) (xy 415.177516 -357.574507)
			(xy 415.207002 -357.528627) (xy 415.242718 -357.487409) (xy 415.283936 -357.451695) (xy 415.329818 -357.42221)
			(xy 415.379429 -357.399555) (xy 415.431759 -357.384191) (xy 415.485743 -357.376431) (xy 415.513012 -357.375968)
			(xy 416.376612 -357.375968) (xy 416.403883 -357.376395) (xy 416.457869 -357.384159) (xy 416.510202 -357.399527)
			(xy 416.559814 -357.422185) (xy 416.605697 -357.451674) (xy 416.646917 -357.487392) (xy 416.682633 -357.528612)
			(xy 416.712121 -357.574496) (xy 416.734778 -357.62411) (xy 416.750144 -357.676442) (xy 416.757906 -357.730429)
			(xy 416.757906 -357.784966) (xy 418.240754 -357.784966) (xy 418.240754 -357.730434) (xy 418.248515 -357.676457)
			(xy 418.263877 -357.624134) (xy 418.28653 -357.57453) (xy 418.316011 -357.528654) (xy 418.35172 -357.48744)
			(xy 418.392931 -357.451727) (xy 418.438805 -357.422243) (xy 418.488408 -357.399587) (xy 418.54073 -357.384221)
			(xy 418.594706 -357.376456) (xy 418.621972 -357.375968) (xy 419.485572 -357.375968) (xy 419.512846 -357.37637)
			(xy 419.566841 -357.384129) (xy 419.619181 -357.399494) (xy 419.668801 -357.422152) (xy 419.714692 -357.451641)
			(xy 419.755919 -357.487361) (xy 419.791642 -357.528585) (xy 419.821135 -357.574474) (xy 419.843796 -357.624093)
			(xy 419.859165 -357.676432) (xy 419.866928 -357.730426) (xy 419.866928 -357.78497) (xy 421.349632 -357.78497)
			(xy 421.349632 -357.73043) (xy 421.357394 -357.676444) (xy 421.372761 -357.624113) (xy 421.395419 -357.574502)
			(xy 421.424907 -357.52862) (xy 421.460625 -357.487402) (xy 421.501846 -357.451688) (xy 421.54773 -357.422203)
			(xy 421.597343 -357.399549) (xy 421.649676 -357.384187) (xy 421.703662 -357.376429) (xy 421.730932 -357.375968)
			(xy 422.594532 -357.375968) (xy 422.621802 -357.376397) (xy 422.675786 -357.384163) (xy 422.728116 -357.399532)
			(xy 422.777726 -357.422192) (xy 422.823607 -357.451681) (xy 422.864824 -357.487399) (xy 422.900538 -357.528619)
			(xy 422.930024 -357.574502) (xy 422.952679 -357.624114) (xy 422.968044 -357.676445) (xy 422.975806 -357.73043)
			(xy 422.975806 -357.784967) (xy 424.458654 -357.784967) (xy 424.458654 -357.730433) (xy 424.466415 -357.676454)
			(xy 424.481779 -357.62413) (xy 424.504433 -357.574524) (xy 424.533916 -357.528647) (xy 424.569627 -357.487433)
			(xy 424.610841 -357.45172) (xy 424.656717 -357.422237) (xy 424.706322 -357.399582) (xy 424.758647 -357.384217)
			(xy 424.812625 -357.376455) (xy 424.839892 -357.375968) (xy 425.703492 -357.375968) (xy 425.730766 -357.376371)
			(xy 425.784757 -357.384133) (xy 425.837095 -357.3995) (xy 425.886713 -357.422159) (xy 425.932602 -357.451648)
			(xy 425.973826 -357.487368) (xy 426.009547 -357.528592) (xy 426.039038 -357.57448) (xy 426.061698 -357.624097)
			(xy 426.077065 -357.676435) (xy 426.084828 -357.730426) (xy 426.084828 -357.784965) (xy 427.567654 -357.784965)
			(xy 427.567654 -357.730435) (xy 427.575414 -357.67646) (xy 427.590776 -357.624138) (xy 427.613427 -357.574535)
			(xy 427.642906 -357.52866) (xy 427.678613 -357.487447) (xy 427.719822 -357.451735) (xy 427.765693 -357.42225)
			(xy 427.815293 -357.399593) (xy 427.867613 -357.384224) (xy 427.921587 -357.376458) (xy 427.948852 -357.375968)
			(xy 428.812452 -357.375968) (xy 428.839727 -357.376368) (xy 428.893724 -357.384125) (xy 428.946066 -357.399489)
			(xy 428.995689 -357.422145) (xy 429.041583 -357.451634) (xy 429.082812 -357.487354) (xy 429.118537 -357.528579)
			(xy 429.148032 -357.574468) (xy 429.170694 -357.624089) (xy 429.186064 -357.676429) (xy 429.193828 -357.730425)
			(xy 429.193828 -357.784969) (xy 430.676531 -357.784969) (xy 430.676531 -357.730431) (xy 430.684293 -357.676447)
			(xy 430.699659 -357.624117) (xy 430.722316 -357.574507) (xy 430.751802 -357.528627) (xy 430.787518 -357.487409)
			(xy 430.828736 -357.451695) (xy 430.874618 -357.42221) (xy 430.924229 -357.399555) (xy 430.976559 -357.384191)
			(xy 431.030543 -357.376431) (xy 431.057812 -357.375968) (xy 431.921412 -357.375968) (xy 431.948683 -357.376395)
			(xy 432.002669 -357.384159) (xy 432.055002 -357.399527) (xy 432.104614 -357.422185) (xy 432.150497 -357.451674)
			(xy 432.191717 -357.487392) (xy 432.227433 -357.528612) (xy 432.256921 -357.574496) (xy 432.279578 -357.62411)
			(xy 432.294944 -357.676442) (xy 432.302706 -357.730429) (xy 432.302706 -357.784966) (xy 433.785554 -357.784966)
			(xy 433.785554 -357.730434) (xy 433.793315 -357.676457) (xy 433.808677 -357.624134) (xy 433.83133 -357.57453)
			(xy 433.860811 -357.528654) (xy 433.89652 -357.48744) (xy 433.937731 -357.451727) (xy 433.983605 -357.422243)
			(xy 434.033208 -357.399587) (xy 434.08553 -357.384221) (xy 434.139506 -357.376456) (xy 434.166772 -357.375968)
			(xy 435.030372 -357.375968) (xy 435.057646 -357.37637) (xy 435.111641 -357.384129) (xy 435.163981 -357.399494)
			(xy 435.213601 -357.422152) (xy 435.259492 -357.451641) (xy 435.300719 -357.487361) (xy 435.336442 -357.528585)
			(xy 435.365935 -357.574474) (xy 435.388596 -357.624093) (xy 435.403965 -357.676432) (xy 435.411728 -357.730426)
			(xy 435.411728 -357.78497) (xy 436.894432 -357.78497) (xy 436.894432 -357.73043) (xy 436.902194 -357.676444)
			(xy 436.917561 -357.624113) (xy 436.940219 -357.574502) (xy 436.969707 -357.52862) (xy 437.005425 -357.487402)
			(xy 437.046646 -357.451688) (xy 437.09253 -357.422203) (xy 437.142143 -357.399549) (xy 437.194476 -357.384187)
			(xy 437.248462 -357.376429) (xy 437.275732 -357.375968) (xy 438.139332 -357.375968) (xy 438.166602 -357.376397)
			(xy 438.220586 -357.384163) (xy 438.272916 -357.399532) (xy 438.322526 -357.422192) (xy 438.368407 -357.451681)
			(xy 438.409624 -357.487399) (xy 438.445338 -357.528619) (xy 438.474824 -357.574502) (xy 438.497479 -357.624114)
			(xy 438.512844 -357.676445) (xy 438.520606 -357.73043) (xy 438.520606 -357.784967) (xy 440.003454 -357.784967)
			(xy 440.003454 -357.730433) (xy 440.011215 -357.676454) (xy 440.026579 -357.62413) (xy 440.049233 -357.574524)
			(xy 440.078716 -357.528647) (xy 440.114427 -357.487433) (xy 440.155641 -357.45172) (xy 440.201517 -357.422237)
			(xy 440.251122 -357.399582) (xy 440.303447 -357.384217) (xy 440.357425 -357.376455) (xy 440.384692 -357.375968)
			(xy 441.248292 -357.375968) (xy 441.275566 -357.376371) (xy 441.329557 -357.384133) (xy 441.381895 -357.3995)
			(xy 441.431513 -357.422159) (xy 441.477402 -357.451648) (xy 441.518626 -357.487368) (xy 441.554347 -357.528592)
			(xy 441.583838 -357.57448) (xy 441.606498 -357.624097) (xy 441.621865 -357.676435) (xy 441.629628 -357.730426)
			(xy 441.629628 -357.784974) (xy 441.621865 -357.838965) (xy 441.606498 -357.891303) (xy 441.583838 -357.94092)
			(xy 441.554347 -357.986808) (xy 441.518626 -358.028032) (xy 441.477402 -358.063752) (xy 441.431513 -358.093241)
			(xy 441.381895 -358.1159) (xy 441.329557 -358.131267) (xy 441.275566 -358.139029) (xy 441.248292 -358.139492)
			(xy 440.384692 -358.139492) (xy 440.357425 -358.138945) (xy 440.303447 -358.131183) (xy 440.251122 -358.115818)
			(xy 440.201517 -358.093163) (xy 440.155641 -358.06368) (xy 440.114427 -358.027967) (xy 440.078716 -357.986753)
			(xy 440.049233 -357.940876) (xy 440.026579 -357.89127) (xy 440.011215 -357.838946) (xy 440.003454 -357.784967)
			(xy 438.520606 -357.784967) (xy 438.520606 -357.78497) (xy 438.512844 -357.838955) (xy 438.497479 -357.891286)
			(xy 438.474824 -357.940898) (xy 438.445338 -357.986781) (xy 438.409624 -358.028001) (xy 438.368407 -358.063719)
			(xy 438.322526 -358.093208) (xy 438.272916 -358.115868) (xy 438.220586 -358.131237) (xy 438.166602 -358.139003)
			(xy 438.139332 -358.139492) (xy 437.275732 -358.139492) (xy 437.248462 -358.138971) (xy 437.194476 -358.131213)
			(xy 437.142143 -358.115851) (xy 437.09253 -358.093197) (xy 437.046646 -358.063712) (xy 437.005425 -358.027998)
			(xy 436.969707 -357.98678) (xy 436.940219 -357.940898) (xy 436.917561 -357.891287) (xy 436.902194 -357.838956)
			(xy 436.894432 -357.78497) (xy 435.411728 -357.78497) (xy 435.411728 -357.784974) (xy 435.403965 -357.838968)
			(xy 435.388596 -357.891307) (xy 435.365935 -357.940926) (xy 435.336442 -357.986815) (xy 435.300719 -358.028039)
			(xy 435.259492 -358.063759) (xy 435.213601 -358.093248) (xy 435.163981 -358.115906) (xy 435.111641 -358.131271)
			(xy 435.057646 -358.13903) (xy 435.030372 -358.139492) (xy 434.166772 -358.139492) (xy 434.139506 -358.138944)
			(xy 434.08553 -358.131179) (xy 434.033208 -358.115813) (xy 433.983605 -358.093157) (xy 433.937731 -358.063673)
			(xy 433.89652 -358.02796) (xy 433.860811 -357.986746) (xy 433.83133 -357.94087) (xy 433.808677 -357.891266)
			(xy 433.793315 -357.838943) (xy 433.785554 -357.784966) (xy 432.302706 -357.784966) (xy 432.302706 -357.784971)
			(xy 432.294944 -357.838958) (xy 432.279578 -357.89129) (xy 432.256921 -357.940904) (xy 432.227433 -357.986788)
			(xy 432.191717 -358.028008) (xy 432.150497 -358.063726) (xy 432.104614 -358.093215) (xy 432.055002 -358.115873)
			(xy 432.002669 -358.131241) (xy 431.948683 -358.139005) (xy 431.921412 -358.139492) (xy 431.057812 -358.139492)
			(xy 431.030543 -358.138969) (xy 430.976559 -358.131209) (xy 430.924229 -358.115845) (xy 430.874618 -358.09319)
			(xy 430.828736 -358.063705) (xy 430.787518 -358.027991) (xy 430.751802 -357.986773) (xy 430.722316 -357.940893)
			(xy 430.699659 -357.891283) (xy 430.684293 -357.838953) (xy 430.676531 -357.784969) (xy 429.193828 -357.784969)
			(xy 429.193828 -357.784975) (xy 429.186064 -357.838971) (xy 429.170694 -357.891311) (xy 429.148032 -357.940932)
			(xy 429.118537 -357.986821) (xy 429.082812 -358.028046) (xy 429.041583 -358.063766) (xy 428.995689 -358.093255)
			(xy 428.946066 -358.115911) (xy 428.893724 -358.131275) (xy 428.839727 -358.139032) (xy 428.812452 -358.139492)
			(xy 427.948852 -358.139492) (xy 427.921587 -358.138942) (xy 427.867613 -358.131176) (xy 427.815293 -358.115807)
			(xy 427.765693 -358.09315) (xy 427.719822 -358.063665) (xy 427.678613 -358.027953) (xy 427.642906 -357.98674)
			(xy 427.613427 -357.940865) (xy 427.590776 -357.891262) (xy 427.575414 -357.83894) (xy 427.567654 -357.784965)
			(xy 426.084828 -357.784965) (xy 426.084828 -357.784974) (xy 426.077065 -357.838965) (xy 426.061698 -357.891303)
			(xy 426.039038 -357.94092) (xy 426.009547 -357.986808) (xy 425.973826 -358.028032) (xy 425.932602 -358.063752)
			(xy 425.886713 -358.093241) (xy 425.837095 -358.1159) (xy 425.784757 -358.131267) (xy 425.730766 -358.139029)
			(xy 425.703492 -358.139492) (xy 424.839892 -358.139492) (xy 424.812625 -358.138945) (xy 424.758647 -358.131183)
			(xy 424.706322 -358.115818) (xy 424.656717 -358.093163) (xy 424.610841 -358.06368) (xy 424.569627 -358.027967)
			(xy 424.533916 -357.986753) (xy 424.504433 -357.940876) (xy 424.481779 -357.89127) (xy 424.466415 -357.838946)
			(xy 424.458654 -357.784967) (xy 422.975806 -357.784967) (xy 422.975806 -357.78497) (xy 422.968044 -357.838955)
			(xy 422.952679 -357.891286) (xy 422.930024 -357.940898) (xy 422.900538 -357.986781) (xy 422.864824 -358.028001)
			(xy 422.823607 -358.063719) (xy 422.777726 -358.093208) (xy 422.728116 -358.115868) (xy 422.675786 -358.131237)
			(xy 422.621802 -358.139003) (xy 422.594532 -358.139492) (xy 421.730932 -358.139492) (xy 421.703662 -358.138971)
			(xy 421.649676 -358.131213) (xy 421.597343 -358.115851) (xy 421.54773 -358.093197) (xy 421.501846 -358.063712)
			(xy 421.460625 -358.027998) (xy 421.424907 -357.98678) (xy 421.395419 -357.940898) (xy 421.372761 -357.891287)
			(xy 421.357394 -357.838956) (xy 421.349632 -357.78497) (xy 419.866928 -357.78497) (xy 419.866928 -357.784974)
			(xy 419.859165 -357.838968) (xy 419.843796 -357.891307) (xy 419.821135 -357.940926) (xy 419.791642 -357.986815)
			(xy 419.755919 -358.028039) (xy 419.714692 -358.063759) (xy 419.668801 -358.093248) (xy 419.619181 -358.115906)
			(xy 419.566841 -358.131271) (xy 419.512846 -358.13903) (xy 419.485572 -358.139492) (xy 418.621972 -358.139492)
			(xy 418.594706 -358.138944) (xy 418.54073 -358.131179) (xy 418.488408 -358.115813) (xy 418.438805 -358.093157)
			(xy 418.392931 -358.063673) (xy 418.35172 -358.02796) (xy 418.316011 -357.986746) (xy 418.28653 -357.94087)
			(xy 418.263877 -357.891266) (xy 418.248515 -357.838943) (xy 418.240754 -357.784966) (xy 416.757906 -357.784966)
			(xy 416.757906 -357.784971) (xy 416.750144 -357.838958) (xy 416.734778 -357.89129) (xy 416.712121 -357.940904)
			(xy 416.682633 -357.986788) (xy 416.646917 -358.028008) (xy 416.605697 -358.063726) (xy 416.559814 -358.093215)
			(xy 416.510202 -358.115873) (xy 416.457869 -358.131241) (xy 416.403883 -358.139005) (xy 416.376612 -358.139492)
			(xy 415.513012 -358.139492) (xy 415.485743 -358.138969) (xy 415.431759 -358.131209) (xy 415.379429 -358.115845)
			(xy 415.329818 -358.09319) (xy 415.283936 -358.063705) (xy 415.242718 -358.027991) (xy 415.207002 -357.986773)
			(xy 415.177516 -357.940893) (xy 415.154859 -357.891283) (xy 415.139493 -357.838953) (xy 415.131731 -357.784969)
			(xy 413.649028 -357.784969) (xy 413.649028 -357.784975) (xy 413.641264 -357.838971) (xy 413.625894 -357.891311)
			(xy 413.603232 -357.940932) (xy 413.573737 -357.986821) (xy 413.538012 -358.028046) (xy 413.496783 -358.063766)
			(xy 413.450889 -358.093255) (xy 413.401266 -358.115911) (xy 413.348924 -358.131275) (xy 413.294927 -358.139032)
			(xy 413.267652 -358.139492) (xy 412.404052 -358.139492) (xy 412.376787 -358.138942) (xy 412.322813 -358.131176)
			(xy 412.270493 -358.115807) (xy 412.220893 -358.09315) (xy 412.175022 -358.063665) (xy 412.133813 -358.027953)
			(xy 412.098106 -357.98674) (xy 412.068627 -357.940865) (xy 412.045976 -357.891262) (xy 412.030614 -357.83894)
			(xy 412.022854 -357.784965) (xy 403.522528 -357.784965) (xy 403.522528 -357.784974) (xy 403.514765 -357.838967)
			(xy 403.499397 -357.891305) (xy 403.476736 -357.940924) (xy 403.447244 -357.986812) (xy 403.411522 -358.028036)
			(xy 403.370296 -358.063756) (xy 403.324406 -358.093245) (xy 403.274787 -358.115904) (xy 403.222447 -358.131269)
			(xy 403.168454 -358.13903) (xy 403.14118 -358.139492) (xy 402.27758 -358.139492) (xy 402.250314 -358.138944)
			(xy 402.196337 -358.131181) (xy 402.144013 -358.115815) (xy 402.09441 -358.093159) (xy 402.048535 -358.063675)
			(xy 402.007323 -358.027963) (xy 401.971613 -357.986749) (xy 401.942131 -357.940873) (xy 401.919478 -357.891268)
			(xy 401.904115 -357.838944) (xy 401.896354 -357.784966) (xy 400.413506 -357.784966) (xy 400.413506 -357.784971)
			(xy 400.405744 -357.838957) (xy 400.390378 -357.891289) (xy 400.367722 -357.940901) (xy 400.338235 -357.986785)
			(xy 400.30252 -358.028005) (xy 400.261301 -358.063723) (xy 400.215419 -358.093212) (xy 400.165807 -358.115871)
			(xy 400.113476 -358.13124) (xy 400.059491 -358.139004) (xy 400.03222 -358.139492) (xy 399.16862 -358.139492)
			(xy 399.14135 -358.13897) (xy 399.087365 -358.131211) (xy 399.035034 -358.115847) (xy 398.985423 -358.093193)
			(xy 398.93954 -358.063708) (xy 398.898321 -358.027993) (xy 398.862604 -357.986776) (xy 398.833117 -357.940895)
			(xy 398.81046 -357.891284) (xy 398.795094 -357.838954) (xy 398.787331 -357.78497) (xy 397.304628 -357.78497)
			(xy 397.304628 -357.784975) (xy 397.296865 -357.83897) (xy 397.281495 -357.89131) (xy 397.258833 -357.940929)
			(xy 397.229339 -357.986818) (xy 397.193615 -358.028043) (xy 397.152386 -358.063763) (xy 397.106494 -358.093252)
			(xy 397.056872 -358.115909) (xy 397.00453 -358.131273) (xy 396.950535 -358.139031) (xy 396.92326 -358.139492)
			(xy 396.05966 -358.139492) (xy 396.032395 -358.138943) (xy 395.97842 -358.131177) (xy 395.926099 -358.11581)
			(xy 395.876498 -358.093153) (xy 395.830625 -358.063668) (xy 395.789416 -358.027956) (xy 395.753708 -357.986742)
			(xy 395.724228 -357.940867) (xy 395.701576 -357.891263) (xy 395.686214 -357.838941) (xy 395.678454 -357.784965)
			(xy 394.195605 -357.784965) (xy 394.195605 -357.784972) (xy 394.187843 -357.838959) (xy 394.172477 -357.891293)
			(xy 394.149819 -357.940907) (xy 394.120331 -357.986792) (xy 394.084612 -358.028012) (xy 394.043392 -358.063731)
			(xy 393.997507 -358.093219) (xy 393.947893 -358.115877) (xy 393.895559 -358.131243) (xy 393.841572 -358.139005)
			(xy 393.8143 -358.139492) (xy 392.9507 -358.139492) (xy 392.923433 -358.138946) (xy 392.869453 -358.131185)
			(xy 392.817128 -358.11582) (xy 392.767522 -358.093166) (xy 392.721644 -358.063682) (xy 392.68043 -358.02797)
			(xy 392.644718 -357.986756) (xy 392.615234 -357.940878) (xy 392.59258 -357.891272) (xy 392.577215 -357.838947)
			(xy 392.569454 -357.784967) (xy 391.086606 -357.784967) (xy 391.086606 -357.78497) (xy 391.078844 -357.838954)
			(xy 391.06348 -357.891284) (xy 391.040825 -357.940896) (xy 391.01134 -357.986778) (xy 390.975627 -358.027998)
			(xy 390.934411 -358.063716) (xy 390.888531 -358.093206) (xy 390.838922 -358.115866) (xy 390.786593 -358.131236)
			(xy 390.73261 -358.139003) (xy 390.70534 -358.139492) (xy 389.84174 -358.139492) (xy 389.814469 -358.138971)
			(xy 389.760482 -358.131214) (xy 389.708149 -358.115853) (xy 389.658535 -358.093199) (xy 389.61265 -358.063715)
			(xy 389.571428 -358.028) (xy 389.535709 -357.986783) (xy 389.50622 -357.940901) (xy 389.483561 -357.891289)
			(xy 389.468194 -357.838957) (xy 389.460432 -357.784971) (xy 387.977728 -357.784971) (xy 387.977728 -357.784974)
			(xy 387.969965 -357.838967) (xy 387.954597 -357.891305) (xy 387.931936 -357.940924) (xy 387.902444 -357.986812)
			(xy 387.866722 -358.028036) (xy 387.825496 -358.063756) (xy 387.779606 -358.093245) (xy 387.729987 -358.115904)
			(xy 387.677647 -358.131269) (xy 387.623654 -358.13903) (xy 387.59638 -358.139492) (xy 386.73278 -358.139492)
			(xy 386.705514 -358.138944) (xy 386.651537 -358.131181) (xy 386.599213 -358.115815) (xy 386.54961 -358.093159)
			(xy 386.503735 -358.063675) (xy 386.462523 -358.027963) (xy 386.426813 -357.986749) (xy 386.397331 -357.940873)
			(xy 386.374678 -357.891268) (xy 386.359315 -357.838944) (xy 386.351554 -357.784966) (xy 384.868706 -357.784966)
			(xy 384.868706 -357.784971) (xy 384.860944 -357.838957) (xy 384.845578 -357.891289) (xy 384.822922 -357.940901)
			(xy 384.793435 -357.986785) (xy 384.75772 -358.028005) (xy 384.716501 -358.063723) (xy 384.670619 -358.093212)
			(xy 384.621007 -358.115871) (xy 384.568676 -358.13124) (xy 384.514691 -358.139004) (xy 384.48742 -358.139492)
			(xy 383.62382 -358.139492) (xy 383.59655 -358.13897) (xy 383.542565 -358.131211) (xy 383.490234 -358.115847)
			(xy 383.440623 -358.093193) (xy 383.39474 -358.063708) (xy 383.353521 -358.027993) (xy 383.317804 -357.986776)
			(xy 383.288317 -357.940895) (xy 383.26566 -357.891284) (xy 383.250294 -357.838954) (xy 383.242531 -357.78497)
			(xy 381.759828 -357.78497) (xy 381.759828 -357.784975) (xy 381.752065 -357.83897) (xy 381.736695 -357.89131)
			(xy 381.714033 -357.940929) (xy 381.684539 -357.986818) (xy 381.648815 -358.028043) (xy 381.607586 -358.063763)
			(xy 381.561694 -358.093252) (xy 381.512072 -358.115909) (xy 381.45973 -358.131273) (xy 381.405735 -358.139031)
			(xy 381.37846 -358.139492) (xy 380.51486 -358.139492) (xy 380.487595 -358.138943) (xy 380.43362 -358.131177)
			(xy 380.381299 -358.11581) (xy 380.331698 -358.093153) (xy 380.285825 -358.063668) (xy 380.244616 -358.027956)
			(xy 380.208908 -357.986742) (xy 380.179428 -357.940867) (xy 380.156776 -357.891263) (xy 380.141414 -357.838941)
			(xy 380.133654 -357.784965) (xy 378.650805 -357.784965) (xy 378.650805 -357.784972) (xy 378.643043 -357.838959)
			(xy 378.627677 -357.891293) (xy 378.605019 -357.940907) (xy 378.575531 -357.986792) (xy 378.539812 -358.028012)
			(xy 378.498592 -358.063731) (xy 378.452707 -358.093219) (xy 378.403093 -358.115877) (xy 378.350759 -358.131243)
			(xy 378.296772 -358.139005) (xy 378.2695 -358.139492) (xy 377.4059 -358.139492) (xy 377.378633 -358.138946)
			(xy 377.324653 -358.131185) (xy 377.272328 -358.11582) (xy 377.222722 -358.093166) (xy 377.176844 -358.063682)
			(xy 377.13563 -358.02797) (xy 377.099918 -357.986756) (xy 377.070434 -357.940878) (xy 377.04778 -357.891272)
			(xy 377.032415 -357.838947) (xy 377.024654 -357.784967) (xy 375.541806 -357.784967) (xy 375.541806 -357.78497)
			(xy 375.534044 -357.838954) (xy 375.51868 -357.891284) (xy 375.496025 -357.940896) (xy 375.46654 -357.986778)
			(xy 375.430827 -358.027998) (xy 375.389611 -358.063716) (xy 375.343731 -358.093206) (xy 375.294122 -358.115866)
			(xy 375.241793 -358.131236) (xy 375.18781 -358.139003) (xy 375.16054 -358.139492) (xy 374.29694 -358.139492)
			(xy 374.269669 -358.138971) (xy 374.215682 -358.131214) (xy 374.163349 -358.115853) (xy 374.113735 -358.093199)
			(xy 374.06785 -358.063715) (xy 374.026628 -358.028) (xy 373.990909 -357.986783) (xy 373.96142 -357.940901)
			(xy 373.938761 -357.891289) (xy 373.923394 -357.838957) (xy 373.915632 -357.784971) (xy 344.837306 -357.784971)
			(xy 344.829543 -357.838959) (xy 344.814177 -357.891292) (xy 344.791519 -357.940906) (xy 344.762031 -357.98679)
			(xy 344.726314 -358.028011) (xy 344.685093 -358.063729) (xy 344.639209 -358.093217) (xy 344.589596 -358.115876)
			(xy 344.537263 -358.131242) (xy 344.483275 -358.139005) (xy 344.456004 -358.139492) (xy 343.592404 -358.139492)
			(xy 343.565135 -358.138969) (xy 343.511152 -358.131208) (xy 343.458823 -358.115843) (xy 343.409213 -358.093188)
			(xy 343.363333 -358.063702) (xy 343.322115 -358.027988) (xy 343.2864 -357.986771) (xy 343.256914 -357.94089)
			(xy 343.234258 -357.891281) (xy 343.218893 -357.838952) (xy 343.211131 -357.784969) (xy 341.728306 -357.784969)
			(xy 341.728306 -357.78497) (xy 341.720544 -357.838953) (xy 341.70518 -357.891284) (xy 341.682525 -357.940895)
			(xy 341.653041 -357.986777) (xy 341.617328 -358.027997) (xy 341.576112 -358.063715) (xy 341.530233 -358.093204)
			(xy 341.480625 -358.115865) (xy 341.428297 -358.131235) (xy 341.374313 -358.139002) (xy 341.347044 -358.139492)
			(xy 340.483444 -358.139492) (xy 340.456173 -358.138972) (xy 340.402186 -358.131215) (xy 340.349852 -358.115854)
			(xy 340.300237 -358.093201) (xy 340.254351 -358.063716) (xy 340.213129 -358.028002) (xy 340.17741 -357.986784)
			(xy 340.147921 -357.940902) (xy 340.125261 -357.891289) (xy 340.109894 -357.838957) (xy 340.102132 -357.784971)
			(xy 338.619428 -357.784971) (xy 338.619428 -357.784974) (xy 338.611665 -357.838966) (xy 338.596297 -357.891304)
			(xy 338.573636 -357.940923) (xy 338.544145 -357.986811) (xy 338.508423 -358.028034) (xy 338.467198 -358.063755)
			(xy 338.421308 -358.093244) (xy 338.371689 -358.115903) (xy 338.319351 -358.131269) (xy 338.265358 -358.13903)
			(xy 338.238084 -358.139492) (xy 337.374484 -358.139492) (xy 337.347218 -358.138945) (xy 337.29324 -358.131182)
			(xy 337.240916 -358.115816) (xy 337.191312 -358.093161) (xy 337.145437 -358.063677) (xy 337.104224 -358.027964)
			(xy 337.068514 -357.98675) (xy 337.039032 -357.940874) (xy 337.016378 -357.891269) (xy 337.001015 -357.838944)
			(xy 336.993254 -357.784967) (xy 335.510406 -357.784967) (xy 335.510406 -357.78497) (xy 335.502644 -357.838956)
			(xy 335.487279 -357.891288) (xy 335.464622 -357.9409) (xy 335.435136 -357.986784) (xy 335.399421 -358.028004)
			(xy 335.358203 -358.063722) (xy 335.312321 -358.093211) (xy 335.26271 -358.11587) (xy 335.21038 -358.131239)
			(xy 335.156394 -358.139004) (xy 335.129124 -358.139492) (xy 334.265524 -358.139492) (xy 334.238254 -358.13897)
			(xy 334.184269 -358.131211) (xy 334.131937 -358.115848) (xy 334.082325 -358.093194) (xy 334.036442 -358.063709)
			(xy 333.995222 -358.027995) (xy 333.959505 -357.986777) (xy 333.930017 -357.940896) (xy 333.90736 -357.891285)
			(xy 333.891994 -357.838955) (xy 333.884231 -357.78497) (xy 332.401528 -357.78497) (xy 332.401528 -357.784975)
			(xy 332.393765 -357.838969) (xy 332.378395 -357.891309) (xy 332.355733 -357.940928) (xy 332.32624 -357.986817)
			(xy 332.290516 -358.028041) (xy 332.249288 -358.063762) (xy 332.203397 -358.093251) (xy 332.153775 -358.115908)
			(xy 332.101434 -358.131272) (xy 332.047439 -358.139031) (xy 332.020164 -358.139492) (xy 331.156564 -358.139492)
			(xy 331.129298 -358.138943) (xy 331.075323 -358.131178) (xy 331.023002 -358.115811) (xy 330.9734 -358.093154)
			(xy 330.927527 -358.06367) (xy 330.886317 -358.027957) (xy 330.850609 -357.986744) (xy 330.821128 -357.940868)
			(xy 330.798477 -357.891264) (xy 330.783114 -357.838942) (xy 330.775354 -357.784966) (xy 329.292506 -357.784966)
			(xy 329.292506 -357.784971) (xy 329.284743 -357.838959) (xy 329.269377 -357.891292) (xy 329.246719 -357.940906)
			(xy 329.217231 -357.98679) (xy 329.181514 -358.028011) (xy 329.140293 -358.063729) (xy 329.094409 -358.093217)
			(xy 329.044796 -358.115876) (xy 328.992463 -358.131242) (xy 328.938475 -358.139005) (xy 328.911204 -358.139492)
			(xy 328.047604 -358.139492) (xy 328.020335 -358.138969) (xy 327.966352 -358.131208) (xy 327.914023 -358.115843)
			(xy 327.864413 -358.093188) (xy 327.818533 -358.063702) (xy 327.777315 -358.027988) (xy 327.7416 -357.986771)
			(xy 327.712114 -357.94089) (xy 327.689458 -357.891281) (xy 327.674093 -357.838952) (xy 327.666331 -357.784969)
			(xy 326.183506 -357.784969) (xy 326.183506 -357.78497) (xy 326.175744 -357.838953) (xy 326.16038 -357.891284)
			(xy 326.137725 -357.940895) (xy 326.108241 -357.986777) (xy 326.072528 -358.027997) (xy 326.031312 -358.063715)
			(xy 325.985433 -358.093204) (xy 325.935825 -358.115865) (xy 325.883497 -358.131235) (xy 325.829513 -358.139002)
			(xy 325.802244 -358.139492) (xy 324.938644 -358.139492) (xy 324.911373 -358.138972) (xy 324.857386 -358.131215)
			(xy 324.805052 -358.115854) (xy 324.755437 -358.093201) (xy 324.709551 -358.063716) (xy 324.668329 -358.028002)
			(xy 324.63261 -357.986784) (xy 324.603121 -357.940902) (xy 324.580461 -357.891289) (xy 324.565094 -357.838957)
			(xy 324.557332 -357.784971) (xy 323.074628 -357.784971) (xy 323.074628 -357.784974) (xy 323.066865 -357.838966)
			(xy 323.051497 -357.891304) (xy 323.028836 -357.940923) (xy 322.999345 -357.986811) (xy 322.963623 -358.028034)
			(xy 322.922398 -358.063755) (xy 322.876508 -358.093244) (xy 322.826889 -358.115903) (xy 322.774551 -358.131269)
			(xy 322.720558 -358.13903) (xy 322.693284 -358.139492) (xy 321.829684 -358.139492) (xy 321.802418 -358.138945)
			(xy 321.74844 -358.131182) (xy 321.696116 -358.115816) (xy 321.646512 -358.093161) (xy 321.600637 -358.063677)
			(xy 321.559424 -358.027964) (xy 321.523714 -357.98675) (xy 321.494232 -357.940874) (xy 321.471578 -357.891269)
			(xy 321.456215 -357.838944) (xy 321.448454 -357.784967) (xy 319.965606 -357.784967) (xy 319.965606 -357.78497)
			(xy 319.957844 -357.838956) (xy 319.942479 -357.891288) (xy 319.919822 -357.9409) (xy 319.890336 -357.986784)
			(xy 319.854621 -358.028004) (xy 319.813403 -358.063722) (xy 319.767521 -358.093211) (xy 319.71791 -358.11587)
			(xy 319.66558 -358.131239) (xy 319.611594 -358.139004) (xy 319.584324 -358.139492) (xy 318.720724 -358.139492)
			(xy 318.693454 -358.13897) (xy 318.639469 -358.131211) (xy 318.587137 -358.115848) (xy 318.537525 -358.093194)
			(xy 318.491642 -358.063709) (xy 318.450422 -358.027995) (xy 318.414705 -357.986777) (xy 318.385217 -357.940896)
			(xy 318.36256 -357.891285) (xy 318.347194 -357.838955) (xy 318.339431 -357.78497) (xy 316.856728 -357.78497)
			(xy 316.856728 -357.784975) (xy 316.848965 -357.838969) (xy 316.833595 -357.891309) (xy 316.810933 -357.940928)
			(xy 316.78144 -357.986817) (xy 316.745716 -358.028041) (xy 316.704488 -358.063762) (xy 316.658597 -358.093251)
			(xy 316.608975 -358.115908) (xy 316.556634 -358.131272) (xy 316.502639 -358.139031) (xy 316.475364 -358.139492)
			(xy 315.611764 -358.139492) (xy 315.584498 -358.138943) (xy 315.530523 -358.131178) (xy 315.478202 -358.115811)
			(xy 315.4286 -358.093154) (xy 315.382727 -358.06367) (xy 315.341517 -358.027957) (xy 315.305809 -357.986744)
			(xy 315.276328 -357.940868) (xy 315.253677 -357.891264) (xy 315.238314 -357.838942) (xy 315.230554 -357.784966)
			(xy 300.231606 -357.784966) (xy 300.231606 -357.784971) (xy 300.223843 -357.838959) (xy 300.208477 -357.891293)
			(xy 300.185819 -357.940907) (xy 300.156331 -357.986791) (xy 300.120613 -358.028012) (xy 300.079393 -358.06373)
			(xy 300.033508 -358.093218) (xy 299.983894 -358.115876) (xy 299.931561 -358.131243) (xy 299.877573 -358.139005)
			(xy 299.850302 -358.139492) (xy 298.986702 -358.139492) (xy 298.959433 -358.138969) (xy 298.90545 -358.131207)
			(xy 298.853121 -358.115843) (xy 298.803512 -358.093187) (xy 298.757632 -358.063702) (xy 298.716414 -358.027987)
			(xy 298.6807 -357.98677) (xy 298.651214 -357.94089) (xy 298.628558 -357.89128) (xy 298.613193 -357.838952)
			(xy 298.605431 -357.784969) (xy 297.122606 -357.784969) (xy 297.122606 -357.78497) (xy 297.114844 -357.838954)
			(xy 297.09948 -357.891284) (xy 297.076825 -357.940895) (xy 297.047341 -357.986778) (xy 297.011627 -358.027998)
			(xy 296.970411 -358.063716) (xy 296.924532 -358.093205) (xy 296.874923 -358.115865) (xy 296.822595 -358.131235)
			(xy 296.768612 -358.139003) (xy 296.741342 -358.139492) (xy 295.877742 -358.139492) (xy 295.850471 -358.138971)
			(xy 295.796484 -358.131215) (xy 295.74415 -358.115853) (xy 295.694536 -358.0932) (xy 295.64865 -358.063716)
			(xy 295.607429 -358.028001) (xy 295.571709 -357.986783) (xy 295.54222 -357.940901) (xy 295.519561 -357.891289)
			(xy 295.504194 -357.838957) (xy 295.496432 -357.784971) (xy 294.013728 -357.784971) (xy 294.013728 -357.784974)
			(xy 294.005965 -357.838967) (xy 293.990597 -357.891305) (xy 293.967936 -357.940923) (xy 293.938444 -357.986811)
			(xy 293.902722 -358.028035) (xy 293.861497 -358.063755) (xy 293.815607 -358.093245) (xy 293.765988 -358.115903)
			(xy 293.713649 -358.131269) (xy 293.659656 -358.13903) (xy 293.632382 -358.139492) (xy 292.768782 -358.139492)
			(xy 292.741516 -358.138944) (xy 292.687538 -358.131181) (xy 292.635215 -358.115816) (xy 292.585611 -358.09316)
			(xy 292.539736 -358.063676) (xy 292.498524 -358.027964) (xy 292.462813 -357.98675) (xy 292.433331 -357.940873)
			(xy 292.410678 -357.891268) (xy 292.395315 -357.838944) (xy 292.387554 -357.784966) (xy 290.904706 -357.784966)
			(xy 290.904706 -357.784971) (xy 290.896944 -357.838956) (xy 290.881578 -357.891288) (xy 290.858922 -357.940901)
			(xy 290.829436 -357.986784) (xy 290.79372 -358.028005) (xy 290.752502 -358.063723) (xy 290.70662 -358.093211)
			(xy 290.657009 -358.115871) (xy 290.604678 -358.131239) (xy 290.550692 -358.139004) (xy 290.523422 -358.139492)
			(xy 289.659822 -358.139492) (xy 289.632552 -358.13897) (xy 289.578567 -358.131211) (xy 289.526236 -358.115848)
			(xy 289.476624 -358.093193) (xy 289.430741 -358.063709) (xy 289.389522 -358.027994) (xy 289.353805 -357.986777)
			(xy 289.324317 -357.940895) (xy 289.30166 -357.891285) (xy 289.286294 -357.838954) (xy 289.278531 -357.78497)
			(xy 287.795828 -357.78497) (xy 287.795828 -357.784975) (xy 287.788065 -357.838969) (xy 287.772695 -357.891309)
			(xy 287.750033 -357.940929) (xy 287.72054 -357.986818) (xy 287.684815 -358.028042) (xy 287.643587 -358.063762)
			(xy 287.597695 -358.093251) (xy 287.548073 -358.115908) (xy 287.495732 -358.131273) (xy 287.441737 -358.139031)
			(xy 287.414462 -358.139492) (xy 286.550862 -358.139492) (xy 286.523597 -358.138943) (xy 286.469621 -358.131178)
			(xy 286.4173 -358.11581) (xy 286.367699 -358.093154) (xy 286.321826 -358.063669) (xy 286.280617 -358.027957)
			(xy 286.244908 -357.986743) (xy 286.215428 -357.940868) (xy 286.192777 -357.891264) (xy 286.177414 -357.838942)
			(xy 286.169654 -357.784966) (xy 284.686806 -357.784966) (xy 284.686806 -357.784971) (xy 284.679043 -357.838959)
			(xy 284.663677 -357.891293) (xy 284.641019 -357.940907) (xy 284.611531 -357.986791) (xy 284.575813 -358.028012)
			(xy 284.534593 -358.06373) (xy 284.488708 -358.093218) (xy 284.439094 -358.115876) (xy 284.386761 -358.131243)
			(xy 284.332773 -358.139005) (xy 284.305502 -358.139492) (xy 283.441902 -358.139492) (xy 283.414633 -358.138969)
			(xy 283.36065 -358.131207) (xy 283.308321 -358.115843) (xy 283.258712 -358.093187) (xy 283.212832 -358.063702)
			(xy 283.171614 -358.027987) (xy 283.1359 -357.98677) (xy 283.106414 -357.94089) (xy 283.083758 -357.89128)
			(xy 283.068393 -357.838952) (xy 283.060631 -357.784969) (xy 281.577806 -357.784969) (xy 281.577806 -357.78497)
			(xy 281.570044 -357.838954) (xy 281.55468 -357.891284) (xy 281.532025 -357.940895) (xy 281.502541 -357.986778)
			(xy 281.466827 -358.027998) (xy 281.425611 -358.063716) (xy 281.379732 -358.093205) (xy 281.330123 -358.115865)
			(xy 281.277795 -358.131235) (xy 281.223812 -358.139003) (xy 281.196542 -358.139492) (xy 280.332942 -358.139492)
			(xy 280.305671 -358.138971) (xy 280.251684 -358.131215) (xy 280.19935 -358.115853) (xy 280.149736 -358.0932)
			(xy 280.10385 -358.063716) (xy 280.062629 -358.028001) (xy 280.026909 -357.986783) (xy 279.99742 -357.940901)
			(xy 279.974761 -357.891289) (xy 279.959394 -357.838957) (xy 279.951632 -357.784971) (xy 278.468928 -357.784971)
			(xy 278.468928 -357.784974) (xy 278.461165 -357.838967) (xy 278.445797 -357.891305) (xy 278.423136 -357.940923)
			(xy 278.393644 -357.986811) (xy 278.357922 -358.028035) (xy 278.316697 -358.063755) (xy 278.270807 -358.093245)
			(xy 278.221188 -358.115903) (xy 278.168849 -358.131269) (xy 278.114856 -358.13903) (xy 278.087582 -358.139492)
			(xy 277.223982 -358.139492) (xy 277.196716 -358.138944) (xy 277.142738 -358.131181) (xy 277.090415 -358.115816)
			(xy 277.040811 -358.09316) (xy 276.994936 -358.063676) (xy 276.953724 -358.027964) (xy 276.918013 -357.98675)
			(xy 276.888531 -357.940873) (xy 276.865878 -357.891268) (xy 276.850515 -357.838944) (xy 276.842754 -357.784966)
			(xy 275.359906 -357.784966) (xy 275.359906 -357.784971) (xy 275.352144 -357.838956) (xy 275.336778 -357.891288)
			(xy 275.314122 -357.940901) (xy 275.284636 -357.986784) (xy 275.24892 -358.028005) (xy 275.207702 -358.063723)
			(xy 275.16182 -358.093211) (xy 275.112209 -358.115871) (xy 275.059878 -358.131239) (xy 275.005892 -358.139004)
			(xy 274.978622 -358.139492) (xy 274.115022 -358.139492) (xy 274.087752 -358.13897) (xy 274.033767 -358.131211)
			(xy 273.981436 -358.115848) (xy 273.931824 -358.093193) (xy 273.885941 -358.063709) (xy 273.844722 -358.027994)
			(xy 273.809005 -357.986777) (xy 273.779517 -357.940895) (xy 273.75686 -357.891285) (xy 273.741494 -357.838954)
			(xy 273.733731 -357.78497) (xy 272.251028 -357.78497) (xy 272.251028 -357.784975) (xy 272.243265 -357.838969)
			(xy 272.227895 -357.891309) (xy 272.205233 -357.940929) (xy 272.17574 -357.986818) (xy 272.140015 -358.028042)
			(xy 272.098787 -358.063762) (xy 272.052895 -358.093251) (xy 272.003273 -358.115908) (xy 271.950932 -358.131273)
			(xy 271.896937 -358.139031) (xy 271.869662 -358.139492) (xy 271.006062 -358.139492) (xy 270.978797 -358.138943)
			(xy 270.924821 -358.131178) (xy 270.8725 -358.11581) (xy 270.822899 -358.093154) (xy 270.777026 -358.063669)
			(xy 270.735817 -358.027957) (xy 270.700108 -357.986743) (xy 270.670628 -357.940868) (xy 270.647977 -357.891264)
			(xy 270.632614 -357.838942) (xy 270.624854 -357.784966) (xy 247.276485 -357.784966) (xy 247.278987 -357.797946)
			(xy 247.287038 -357.88226) (xy 247.287542 -357.924608) (xy 247.287038 -357.966956) (xy 247.278987 -358.05127)
			(xy 247.262958 -358.134436) (xy 247.239097 -358.215703) (xy 247.207618 -358.294333) (xy 247.168807 -358.369614)
			(xy 247.123017 -358.440866) (xy 247.070661 -358.507442) (xy 247.012213 -358.56874) (xy 246.948203 -358.624205)
			(xy 246.879211 -358.673334) (xy 246.805861 -358.715683) (xy 246.728818 -358.750867) (xy 246.648779 -358.778569)
			(xy 246.56647 -358.798537) (xy 246.482635 -358.81059) (xy 246.398034 -358.814621) (xy 246.313433 -358.81059)
			(xy 246.229598 -358.798537) (xy 246.147289 -358.778569) (xy 246.06725 -358.750867) (xy 245.990207 -358.715683)
			(xy 245.916857 -358.673334) (xy 245.847865 -358.624205) (xy 245.783855 -358.56874) (xy 245.725407 -358.507442)
			(xy 245.673051 -358.440866) (xy 245.627261 -358.369614) (xy 245.58845 -358.294333) (xy 245.556971 -358.215703)
			(xy 245.53311 -358.134436) (xy 245.517081 -358.05127) (xy 245.50903 -357.966956) (xy 188.223925 -357.966956)
			(xy 188.191672 -358.004178) (xy 188.150456 -358.039891) (xy 188.104577 -358.069375) (xy 188.054969 -358.092029)
			(xy 188.002641 -358.107393) (xy 187.94866 -358.115153) (xy 187.921392 -358.115616) (xy 187.057792 -358.115616)
			(xy 187.03052 -358.115221) (xy 186.97653 -358.107457) (xy 186.924196 -358.092089) (xy 186.87458 -358.06943)
			(xy 186.828695 -358.03994) (xy 186.787473 -358.004221) (xy 186.751755 -357.962999) (xy 186.722266 -357.917112)
			(xy 186.699608 -357.867497) (xy 186.684241 -357.815162) (xy 186.676479 -357.761172) (xy 185.193629 -357.761172)
			(xy 185.18587 -357.815139) (xy 185.170508 -357.86746) (xy 185.147857 -357.917062) (xy 185.118378 -357.962936)
			(xy 185.08267 -358.004147) (xy 185.041461 -358.039858) (xy 184.99559 -358.069342) (xy 184.94599 -358.091997)
			(xy 184.89367 -358.107363) (xy 184.839697 -358.115128) (xy 184.812432 -358.115616) (xy 183.948832 -358.115616)
			(xy 183.921556 -358.115247) (xy 183.867559 -358.107487) (xy 183.815217 -358.092122) (xy 183.765593 -358.069463)
			(xy 183.7197 -358.039973) (xy 183.678471 -358.004251) (xy 183.642746 -357.963025) (xy 183.613252 -357.917135)
			(xy 183.590589 -357.867513) (xy 183.57522 -357.815172) (xy 183.567456 -357.761176) (xy 182.084828 -357.761176)
			(xy 182.084828 -357.784974) (xy 182.077065 -357.838968) (xy 182.061696 -357.891307) (xy 182.039035 -357.940926)
			(xy 182.009542 -357.986815) (xy 181.973819 -358.028039) (xy 181.932592 -358.063759) (xy 181.886701 -358.093248)
			(xy 181.837081 -358.115906) (xy 181.784741 -358.131271) (xy 181.730746 -358.13903) (xy 181.703472 -358.139492)
			(xy 180.839872 -358.139492) (xy 180.812606 -358.138944) (xy 180.75863 -358.131179) (xy 180.706308 -358.115813)
			(xy 180.656705 -358.093157) (xy 180.610831 -358.063673) (xy 180.56962 -358.02796) (xy 180.533911 -357.986746)
			(xy 180.50443 -357.94087) (xy 180.481777 -357.891266) (xy 180.466415 -357.838943) (xy 180.458654 -357.784966)
			(xy 178.975806 -357.784966) (xy 178.975806 -357.784971) (xy 178.968044 -357.838958) (xy 178.952678 -357.89129)
			(xy 178.930021 -357.940904) (xy 178.900533 -357.986788) (xy 178.864817 -358.028008) (xy 178.823597 -358.063726)
			(xy 178.777714 -358.093215) (xy 178.728102 -358.115873) (xy 178.675769 -358.131241) (xy 178.621783 -358.139005)
			(xy 178.594512 -358.139492) (xy 177.730912 -358.139492) (xy 177.703643 -358.138969) (xy 177.649659 -358.131209)
			(xy 177.597329 -358.115845) (xy 177.547718 -358.09319) (xy 177.501836 -358.063705) (xy 177.460618 -358.027991)
			(xy 177.424902 -357.986773) (xy 177.395416 -357.940893) (xy 177.372759 -357.891283) (xy 177.357393 -357.838953)
			(xy 177.349631 -357.784969) (xy 175.866928 -357.784969) (xy 175.866928 -357.784975) (xy 175.859164 -357.838971)
			(xy 175.843794 -357.891311) (xy 175.821132 -357.940932) (xy 175.791637 -357.986821) (xy 175.755912 -358.028046)
			(xy 175.714683 -358.063766) (xy 175.668789 -358.093255) (xy 175.619166 -358.115911) (xy 175.566824 -358.131275)
			(xy 175.512827 -358.139032) (xy 175.485552 -358.139492) (xy 174.621952 -358.139492) (xy 174.594687 -358.138942)
			(xy 174.540713 -358.131176) (xy 174.488393 -358.115807) (xy 174.438793 -358.09315) (xy 174.392922 -358.063665)
			(xy 174.351713 -358.027953) (xy 174.316006 -357.98674) (xy 174.286527 -357.940865) (xy 174.263876 -357.891262)
			(xy 174.248514 -357.83894) (xy 174.240754 -357.784965) (xy 172.757928 -357.784965) (xy 172.757928 -357.784974)
			(xy 172.750165 -357.838965) (xy 172.734798 -357.891303) (xy 172.712138 -357.94092) (xy 172.682647 -357.986808)
			(xy 172.646926 -358.028032) (xy 172.605702 -358.063752) (xy 172.559813 -358.093241) (xy 172.510195 -358.1159)
			(xy 172.457857 -358.131267) (xy 172.403866 -358.139029) (xy 172.376592 -358.139492) (xy 171.512992 -358.139492)
			(xy 171.485725 -358.138945) (xy 171.431747 -358.131183) (xy 171.379422 -358.115818) (xy 171.329817 -358.093163)
			(xy 171.283941 -358.06368) (xy 171.242727 -358.027967) (xy 171.207016 -357.986753) (xy 171.177533 -357.940876)
			(xy 171.154879 -357.89127) (xy 171.139515 -357.838946) (xy 171.131754 -357.784967) (xy 169.648906 -357.784967)
			(xy 169.648906 -357.78497) (xy 169.641144 -357.838955) (xy 169.625779 -357.891286) (xy 169.603124 -357.940898)
			(xy 169.573638 -357.986781) (xy 169.537924 -358.028001) (xy 169.496707 -358.063719) (xy 169.450826 -358.093208)
			(xy 169.401216 -358.115868) (xy 169.348886 -358.131237) (xy 169.294902 -358.139003) (xy 169.267632 -358.139492)
			(xy 168.404032 -358.139492) (xy 168.376762 -358.138971) (xy 168.322776 -358.131213) (xy 168.270443 -358.115851)
			(xy 168.22083 -358.093197) (xy 168.174946 -358.063712) (xy 168.133725 -358.027998) (xy 168.098007 -357.98678)
			(xy 168.068519 -357.940898) (xy 168.045861 -357.891287) (xy 168.030494 -357.838956) (xy 168.022732 -357.78497)
			(xy 166.540028 -357.78497) (xy 166.540028 -357.784974) (xy 166.532265 -357.838968) (xy 166.516896 -357.891307)
			(xy 166.494235 -357.940926) (xy 166.464742 -357.986815) (xy 166.429019 -358.028039) (xy 166.387792 -358.063759)
			(xy 166.341901 -358.093248) (xy 166.292281 -358.115906) (xy 166.239941 -358.131271) (xy 166.185946 -358.13903)
			(xy 166.158672 -358.139492) (xy 165.295072 -358.139492) (xy 165.267806 -358.138944) (xy 165.21383 -358.131179)
			(xy 165.161508 -358.115813) (xy 165.111905 -358.093157) (xy 165.066031 -358.063673) (xy 165.02482 -358.02796)
			(xy 164.989111 -357.986746) (xy 164.95963 -357.94087) (xy 164.936977 -357.891266) (xy 164.921615 -357.838943)
			(xy 164.913854 -357.784966) (xy 163.431006 -357.784966) (xy 163.431006 -357.784971) (xy 163.423244 -357.838958)
			(xy 163.407878 -357.89129) (xy 163.385221 -357.940904) (xy 163.355733 -357.986788) (xy 163.320017 -358.028008)
			(xy 163.278797 -358.063726) (xy 163.232914 -358.093215) (xy 163.183302 -358.115873) (xy 163.130969 -358.131241)
			(xy 163.076983 -358.139005) (xy 163.049712 -358.139492) (xy 162.186112 -358.139492) (xy 162.158843 -358.138969)
			(xy 162.104859 -358.131209) (xy 162.052529 -358.115845) (xy 162.002918 -358.09319) (xy 161.957036 -358.063705)
			(xy 161.915818 -358.027991) (xy 161.880102 -357.986773) (xy 161.850616 -357.940893) (xy 161.827959 -357.891283)
			(xy 161.812593 -357.838953) (xy 161.804831 -357.784969) (xy 160.322128 -357.784969) (xy 160.322128 -357.784975)
			(xy 160.314364 -357.838971) (xy 160.298994 -357.891311) (xy 160.276332 -357.940932) (xy 160.246837 -357.986821)
			(xy 160.211112 -358.028046) (xy 160.169883 -358.063766) (xy 160.123989 -358.093255) (xy 160.074366 -358.115911)
			(xy 160.022024 -358.131275) (xy 159.968027 -358.139032) (xy 159.940752 -358.139492) (xy 159.077152 -358.139492)
			(xy 159.049887 -358.138942) (xy 158.995913 -358.131176) (xy 158.943593 -358.115807) (xy 158.893993 -358.09315)
			(xy 158.848122 -358.063665) (xy 158.806913 -358.027953) (xy 158.771206 -357.98674) (xy 158.741727 -357.940865)
			(xy 158.719076 -357.891262) (xy 158.703714 -357.83894) (xy 158.695954 -357.784965) (xy 144.196606 -357.784965)
			(xy 144.196606 -357.784971) (xy 144.188843 -357.838958) (xy 144.173477 -357.891291) (xy 144.15082 -357.940905)
			(xy 144.121332 -357.986789) (xy 144.085615 -358.02801) (xy 144.044395 -358.063728) (xy 143.998512 -358.093216)
			(xy 143.948899 -358.115875) (xy 143.896566 -358.131242) (xy 143.842579 -358.139005) (xy 143.815308 -358.139492)
			(xy 142.951708 -358.139492) (xy 142.924439 -358.138969) (xy 142.870455 -358.131209) (xy 142.818126 -358.115844)
			(xy 142.768515 -358.093189) (xy 142.722634 -358.063704) (xy 142.681417 -358.027989) (xy 142.645701 -357.986772)
			(xy 142.616215 -357.940892) (xy 142.593559 -357.891282) (xy 142.578193 -357.838953) (xy 142.570431 -357.784969)
			(xy 141.087606 -357.784969) (xy 141.079845 -357.838953) (xy 141.06448 -357.891283) (xy 141.041826 -357.940894)
			(xy 141.012342 -357.986776) (xy 140.976629 -358.027995) (xy 140.935414 -358.063713) (xy 140.889536 -358.093203)
			(xy 140.839928 -358.115864) (xy 140.7876 -358.131234) (xy 140.733617 -358.139002) (xy 140.706348 -358.139492)
			(xy 139.842748 -358.139492) (xy 139.815477 -358.138972) (xy 139.761489 -358.131216) (xy 139.709155 -358.115855)
			(xy 139.659539 -358.093202) (xy 139.613653 -358.063718) (xy 139.572431 -358.028003) (xy 139.536711 -357.986785)
			(xy 139.507221 -357.940903) (xy 139.484562 -357.89129) (xy 139.469194 -357.838958) (xy 139.461432 -357.784971)
			(xy 137.978728 -357.784971) (xy 137.978728 -357.784974) (xy 137.970965 -357.838966) (xy 137.955597 -357.891304)
			(xy 137.932937 -357.940921) (xy 137.903446 -357.986809) (xy 137.867724 -358.028033) (xy 137.8265 -358.063753)
			(xy 137.780611 -358.093243) (xy 137.730992 -358.115901) (xy 137.678654 -358.131268) (xy 137.624662 -358.139029)
			(xy 137.597388 -358.139492) (xy 136.733788 -358.139492) (xy 136.706521 -358.138945) (xy 136.652543 -358.131182)
			(xy 136.600219 -358.115817) (xy 136.550615 -358.093162) (xy 136.504739 -358.063678) (xy 136.463526 -358.027966)
			(xy 136.427815 -357.986752) (xy 136.398332 -357.940875) (xy 136.375679 -357.891269) (xy 136.360315 -357.838945)
			(xy 136.352554 -357.784967) (xy 134.869706 -357.784967) (xy 134.869706 -357.78497) (xy 134.861944 -357.838956)
			(xy 134.846579 -357.891287) (xy 134.823923 -357.940899) (xy 134.794437 -357.986782) (xy 134.758722 -358.028003)
			(xy 134.717505 -358.063721) (xy 134.671624 -358.09321) (xy 134.622013 -358.115869) (xy 134.569683 -358.131238)
			(xy 134.515698 -358.139004) (xy 134.488428 -358.139492) (xy 133.624828 -358.139492) (xy 133.597558 -358.13897)
			(xy 133.543572 -358.131212) (xy 133.49124 -358.11585) (xy 133.441627 -358.093195) (xy 133.395744 -358.063711)
			(xy 133.354524 -358.027996) (xy 133.318806 -357.986779) (xy 133.289318 -357.940897) (xy 133.26666 -357.891286)
			(xy 133.251294 -357.838955) (xy 133.243531 -357.78497) (xy 131.760828 -357.78497) (xy 131.760828 -357.784975)
			(xy 131.753065 -357.838969) (xy 131.737696 -357.891308) (xy 131.715034 -357.940927) (xy 131.685541 -357.986816)
			(xy 131.649817 -358.02804) (xy 131.60859 -358.06376) (xy 131.562699 -358.093249) (xy 131.513078 -358.115907)
			(xy 131.460737 -358.131272) (xy 131.406743 -358.139031) (xy 131.379468 -358.139492) (xy 130.515868 -358.139492)
			(xy 130.488602 -358.138943) (xy 130.434626 -358.131179) (xy 130.382305 -358.115812) (xy 130.332703 -358.093156)
			(xy 130.286829 -358.063671) (xy 130.245619 -358.027959) (xy 130.20991 -357.986745) (xy 130.180429 -357.940869)
			(xy 130.157777 -357.891265) (xy 130.142414 -357.838942) (xy 130.134654 -357.784966) (xy 128.651806 -357.784966)
			(xy 128.651806 -357.784971) (xy 128.644043 -357.838958) (xy 128.628677 -357.891291) (xy 128.60602 -357.940905)
			(xy 128.576532 -357.986789) (xy 128.540815 -358.02801) (xy 128.499595 -358.063728) (xy 128.453712 -358.093216)
			(xy 128.404099 -358.115875) (xy 128.351766 -358.131242) (xy 128.297779 -358.139005) (xy 128.270508 -358.139492)
			(xy 127.406908 -358.139492) (xy 127.379639 -358.138969) (xy 127.325655 -358.131209) (xy 127.273326 -358.115844)
			(xy 127.223715 -358.093189) (xy 127.177834 -358.063704) (xy 127.136617 -358.027989) (xy 127.100901 -357.986772)
			(xy 127.071415 -357.940892) (xy 127.048759 -357.891282) (xy 127.033393 -357.838953) (xy 127.025631 -357.784969)
			(xy 125.542806 -357.784969) (xy 125.535045 -357.838953) (xy 125.51968 -357.891283) (xy 125.497026 -357.940894)
			(xy 125.467542 -357.986776) (xy 125.431829 -358.027995) (xy 125.390614 -358.063713) (xy 125.344736 -358.093203)
			(xy 125.295128 -358.115864) (xy 125.2428 -358.131234) (xy 125.188817 -358.139002) (xy 125.161548 -358.139492)
			(xy 124.297948 -358.139492) (xy 124.270677 -358.138972) (xy 124.216689 -358.131216) (xy 124.164355 -358.115855)
			(xy 124.114739 -358.093202) (xy 124.068853 -358.063718) (xy 124.027631 -358.028003) (xy 123.991911 -357.986785)
			(xy 123.962421 -357.940903) (xy 123.939762 -357.89129) (xy 123.924394 -357.838958) (xy 123.916632 -357.784971)
			(xy 122.433928 -357.784971) (xy 122.433928 -357.784974) (xy 122.426165 -357.838966) (xy 122.410797 -357.891304)
			(xy 122.388137 -357.940921) (xy 122.358646 -357.986809) (xy 122.322924 -358.028033) (xy 122.2817 -358.063753)
			(xy 122.235811 -358.093243) (xy 122.186192 -358.115901) (xy 122.133854 -358.131268) (xy 122.079862 -358.139029)
			(xy 122.052588 -358.139492) (xy 121.188988 -358.139492) (xy 121.161721 -358.138945) (xy 121.107743 -358.131182)
			(xy 121.055419 -358.115817) (xy 121.005815 -358.093162) (xy 120.959939 -358.063678) (xy 120.918726 -358.027966)
			(xy 120.883015 -357.986752) (xy 120.853532 -357.940875) (xy 120.830879 -357.891269) (xy 120.815515 -357.838945)
			(xy 120.807754 -357.784967) (xy 119.324906 -357.784967) (xy 119.324906 -357.78497) (xy 119.317144 -357.838956)
			(xy 119.301779 -357.891287) (xy 119.279123 -357.940899) (xy 119.249637 -357.986782) (xy 119.213922 -358.028003)
			(xy 119.172705 -358.063721) (xy 119.126824 -358.09321) (xy 119.077213 -358.115869) (xy 119.024883 -358.131238)
			(xy 118.970898 -358.139004) (xy 118.943628 -358.139492) (xy 118.080028 -358.139492) (xy 118.052758 -358.13897)
			(xy 117.998772 -358.131212) (xy 117.94644 -358.11585) (xy 117.896827 -358.093195) (xy 117.850944 -358.063711)
			(xy 117.809724 -358.027996) (xy 117.774006 -357.986779) (xy 117.744518 -357.940897) (xy 117.72186 -357.891286)
			(xy 117.706494 -357.838955) (xy 117.698731 -357.78497) (xy 116.216028 -357.78497) (xy 116.216028 -357.784975)
			(xy 116.208265 -357.838969) (xy 116.192896 -357.891308) (xy 116.170234 -357.940927) (xy 116.140741 -357.986816)
			(xy 116.105017 -358.02804) (xy 116.06379 -358.06376) (xy 116.017899 -358.093249) (xy 115.968278 -358.115907)
			(xy 115.915937 -358.131272) (xy 115.861943 -358.139031) (xy 115.834668 -358.139492) (xy 114.971068 -358.139492)
			(xy 114.943802 -358.138943) (xy 114.889826 -358.131179) (xy 114.837505 -358.115812) (xy 114.787903 -358.093156)
			(xy 114.742029 -358.063671) (xy 114.700819 -358.027959) (xy 114.66511 -357.986745) (xy 114.635629 -357.940869)
			(xy 114.612977 -357.891265) (xy 114.597614 -357.838942) (xy 114.589854 -357.784966) (xy 93.706706 -357.784966)
			(xy 93.706706 -357.78497) (xy 93.698944 -357.838954) (xy 93.68358 -357.891284) (xy 93.660925 -357.940895)
			(xy 93.631441 -357.986778) (xy 93.595727 -358.027998) (xy 93.554511 -358.063716) (xy 93.508632 -358.093205)
			(xy 93.459023 -358.115865) (xy 93.406695 -358.131235) (xy 93.352712 -358.139003) (xy 93.325442 -358.139492)
			(xy 92.461842 -358.139492) (xy 92.434571 -358.138971) (xy 92.380584 -358.131215) (xy 92.32825 -358.115853)
			(xy 92.278636 -358.0932) (xy 92.23275 -358.063716) (xy 92.191529 -358.028001) (xy 92.155809 -357.986783)
			(xy 92.12632 -357.940901) (xy 92.103661 -357.891289) (xy 92.088294 -357.838957) (xy 92.080532 -357.784971)
			(xy 90.597828 -357.784971) (xy 90.597828 -357.784974) (xy 90.590065 -357.838967) (xy 90.574697 -357.891305)
			(xy 90.552036 -357.940923) (xy 90.522544 -357.986811) (xy 90.486822 -358.028035) (xy 90.445597 -358.063755)
			(xy 90.399707 -358.093245) (xy 90.350088 -358.115903) (xy 90.297749 -358.131269) (xy 90.243756 -358.13903)
			(xy 90.216482 -358.139492) (xy 89.352882 -358.139492) (xy 89.325616 -358.138944) (xy 89.271638 -358.131181)
			(xy 89.219315 -358.115816) (xy 89.169711 -358.09316) (xy 89.123836 -358.063676) (xy 89.082624 -358.027964)
			(xy 89.046913 -357.98675) (xy 89.017431 -357.940873) (xy 88.994778 -357.891268) (xy 88.979415 -357.838944)
			(xy 88.971654 -357.784966) (xy 87.488806 -357.784966) (xy 87.488806 -357.784971) (xy 87.481044 -357.838956)
			(xy 87.465678 -357.891288) (xy 87.443022 -357.940901) (xy 87.413536 -357.986784) (xy 87.37782 -358.028005)
			(xy 87.336602 -358.063723) (xy 87.29072 -358.093211) (xy 87.241109 -358.115871) (xy 87.188778 -358.131239)
			(xy 87.134792 -358.139004) (xy 87.107522 -358.139492) (xy 86.243922 -358.139492) (xy 86.216652 -358.13897)
			(xy 86.162667 -358.131211) (xy 86.110336 -358.115848) (xy 86.060724 -358.093193) (xy 86.014841 -358.063709)
			(xy 85.973622 -358.027994) (xy 85.937905 -357.986777) (xy 85.908417 -357.940895) (xy 85.88576 -357.891285)
			(xy 85.870394 -357.838954) (xy 85.862631 -357.78497) (xy 84.379928 -357.78497) (xy 84.379928 -357.784975)
			(xy 84.372165 -357.838969) (xy 84.356795 -357.891309) (xy 84.334133 -357.940929) (xy 84.30464 -357.986818)
			(xy 84.268915 -358.028042) (xy 84.227687 -358.063762) (xy 84.181795 -358.093251) (xy 84.132173 -358.115908)
			(xy 84.079832 -358.131273) (xy 84.025837 -358.139031) (xy 83.998562 -358.139492) (xy 83.134962 -358.139492)
			(xy 83.107697 -358.138943) (xy 83.053721 -358.131178) (xy 83.0014 -358.11581) (xy 82.951799 -358.093154)
			(xy 82.905926 -358.063669) (xy 82.864717 -358.027957) (xy 82.829008 -357.986743) (xy 82.799528 -357.940868)
			(xy 82.776877 -357.891264) (xy 82.761514 -357.838942) (xy 82.753754 -357.784966) (xy 81.270906 -357.784966)
			(xy 81.270906 -357.784971) (xy 81.263143 -357.838959) (xy 81.247777 -357.891293) (xy 81.225119 -357.940907)
			(xy 81.195631 -357.986791) (xy 81.159913 -358.028012) (xy 81.118693 -358.06373) (xy 81.072808 -358.093218)
			(xy 81.023194 -358.115876) (xy 80.970861 -358.131243) (xy 80.916873 -358.139005) (xy 80.889602 -358.139492)
			(xy 80.026002 -358.139492) (xy 79.998733 -358.138969) (xy 79.94475 -358.131207) (xy 79.892421 -358.115843)
			(xy 79.842812 -358.093187) (xy 79.796932 -358.063702) (xy 79.755714 -358.027987) (xy 79.72 -357.98677)
			(xy 79.690514 -357.94089) (xy 79.667858 -357.89128) (xy 79.652493 -357.838952) (xy 79.644731 -357.784969)
			(xy 78.161906 -357.784969) (xy 78.161906 -357.78497) (xy 78.154144 -357.838954) (xy 78.13878 -357.891284)
			(xy 78.116125 -357.940895) (xy 78.086641 -357.986778) (xy 78.050927 -358.027998) (xy 78.009711 -358.063716)
			(xy 77.963832 -358.093205) (xy 77.914223 -358.115865) (xy 77.861895 -358.131235) (xy 77.807912 -358.139003)
			(xy 77.780642 -358.139492) (xy 76.917042 -358.139492) (xy 76.889771 -358.138971) (xy 76.835784 -358.131215)
			(xy 76.78345 -358.115853) (xy 76.733836 -358.0932) (xy 76.68795 -358.063716) (xy 76.646729 -358.028001)
			(xy 76.611009 -357.986783) (xy 76.58152 -357.940901) (xy 76.558861 -357.891289) (xy 76.543494 -357.838957)
			(xy 76.535732 -357.784971) (xy 75.053028 -357.784971) (xy 75.053028 -357.784974) (xy 75.045265 -357.838967)
			(xy 75.029897 -357.891305) (xy 75.007236 -357.940923) (xy 74.977744 -357.986811) (xy 74.942022 -358.028035)
			(xy 74.900797 -358.063755) (xy 74.854907 -358.093245) (xy 74.805288 -358.115903) (xy 74.752949 -358.131269)
			(xy 74.698956 -358.13903) (xy 74.671682 -358.139492) (xy 73.808082 -358.139492) (xy 73.780816 -358.138944)
			(xy 73.726838 -358.131181) (xy 73.674515 -358.115816) (xy 73.624911 -358.09316) (xy 73.579036 -358.063676)
			(xy 73.537824 -358.027964) (xy 73.502113 -357.98675) (xy 73.472631 -357.940873) (xy 73.449978 -357.891268)
			(xy 73.434615 -357.838944) (xy 73.426854 -357.784966) (xy 71.944006 -357.784966) (xy 71.944006 -357.784971)
			(xy 71.936244 -357.838956) (xy 71.920878 -357.891288) (xy 71.898222 -357.940901) (xy 71.868736 -357.986784)
			(xy 71.83302 -358.028005) (xy 71.791802 -358.063723) (xy 71.74592 -358.093211) (xy 71.696309 -358.115871)
			(xy 71.643978 -358.131239) (xy 71.589992 -358.139004) (xy 71.562722 -358.139492) (xy 70.699122 -358.139492)
			(xy 70.671852 -358.13897) (xy 70.617867 -358.131211) (xy 70.565536 -358.115848) (xy 70.515924 -358.093193)
			(xy 70.470041 -358.063709) (xy 70.428822 -358.027994) (xy 70.393105 -357.986777) (xy 70.363617 -357.940895)
			(xy 70.34096 -357.891285) (xy 70.325594 -357.838954) (xy 70.317831 -357.78497) (xy 68.835128 -357.78497)
			(xy 68.835128 -357.784975) (xy 68.827365 -357.838969) (xy 68.811995 -357.891309) (xy 68.789333 -357.940929)
			(xy 68.75984 -357.986818) (xy 68.724115 -358.028042) (xy 68.682887 -358.063762) (xy 68.636995 -358.093251)
			(xy 68.587373 -358.115908) (xy 68.535032 -358.131273) (xy 68.481037 -358.139031) (xy 68.453762 -358.139492)
			(xy 67.590162 -358.139492) (xy 67.562897 -358.138943) (xy 67.508921 -358.131178) (xy 67.4566 -358.11581)
			(xy 67.406999 -358.093154) (xy 67.361126 -358.063669) (xy 67.319917 -358.027957) (xy 67.284208 -357.986743)
			(xy 67.254728 -357.940868) (xy 67.232077 -357.891264) (xy 67.216714 -357.838942) (xy 67.208954 -357.784966)
			(xy 65.726106 -357.784966) (xy 65.726106 -357.784971) (xy 65.718343 -357.838959) (xy 65.702977 -357.891293)
			(xy 65.680319 -357.940907) (xy 65.650831 -357.986791) (xy 65.615113 -358.028012) (xy 65.573893 -358.06373)
			(xy 65.528008 -358.093218) (xy 65.478394 -358.115876) (xy 65.426061 -358.131243) (xy 65.372073 -358.139005)
			(xy 65.344802 -358.139492) (xy 64.481202 -358.139492) (xy 64.453933 -358.138969) (xy 64.39995 -358.131207)
			(xy 64.347621 -358.115843) (xy 64.298012 -358.093187) (xy 64.252132 -358.063702) (xy 64.210914 -358.027987)
			(xy 64.1752 -357.98677) (xy 64.145714 -357.94089) (xy 64.123058 -357.89128) (xy 64.107693 -357.838952)
			(xy 64.099931 -357.784969) (xy 51.666906 -357.784969) (xy 51.659145 -357.838953) (xy 51.64378 -357.891283)
			(xy 51.621126 -357.940894) (xy 51.591642 -357.986776) (xy 51.555929 -358.027995) (xy 51.514714 -358.063713)
			(xy 51.468836 -358.093203) (xy 51.419228 -358.115864) (xy 51.3669 -358.131234) (xy 51.312917 -358.139002)
			(xy 51.285648 -358.139492) (xy 50.422048 -358.139492) (xy 50.394777 -358.138972) (xy 50.340789 -358.131216)
			(xy 50.288455 -358.115855) (xy 50.238839 -358.093202) (xy 50.192953 -358.063718) (xy 50.151731 -358.028003)
			(xy 50.116011 -357.986785) (xy 50.086521 -357.940903) (xy 50.063862 -357.89129) (xy 50.048494 -357.838958)
			(xy 50.040732 -357.784971) (xy 48.558028 -357.784971) (xy 48.558028 -357.784974) (xy 48.550265 -357.838966)
			(xy 48.534897 -357.891304) (xy 48.512237 -357.940921) (xy 48.482746 -357.986809) (xy 48.447024 -358.028033)
			(xy 48.4058 -358.063753) (xy 48.359911 -358.093243) (xy 48.310292 -358.115901) (xy 48.257954 -358.131268)
			(xy 48.203962 -358.139029) (xy 48.176688 -358.139492) (xy 47.313088 -358.139492) (xy 47.285821 -358.138945)
			(xy 47.231843 -358.131182) (xy 47.179519 -358.115817) (xy 47.129915 -358.093162) (xy 47.084039 -358.063678)
			(xy 47.042826 -358.027966) (xy 47.007115 -357.986752) (xy 46.977632 -357.940875) (xy 46.954979 -357.891269)
			(xy 46.939615 -357.838945) (xy 46.931854 -357.784967) (xy 45.449006 -357.784967) (xy 45.449006 -357.78497)
			(xy 45.441244 -357.838956) (xy 45.425879 -357.891287) (xy 45.403223 -357.940899) (xy 45.373737 -357.986782)
			(xy 45.338022 -358.028003) (xy 45.296805 -358.063721) (xy 45.250924 -358.09321) (xy 45.201313 -358.115869)
			(xy 45.148983 -358.131238) (xy 45.094998 -358.139004) (xy 45.067728 -358.139492) (xy 44.204128 -358.139492)
			(xy 44.176858 -358.13897) (xy 44.122872 -358.131212) (xy 44.07054 -358.11585) (xy 44.020927 -358.093195)
			(xy 43.975044 -358.063711) (xy 43.933824 -358.027996) (xy 43.898106 -357.986779) (xy 43.868618 -357.940897)
			(xy 43.84596 -357.891286) (xy 43.830594 -357.838955) (xy 43.822831 -357.78497) (xy 42.340128 -357.78497)
			(xy 42.340128 -357.784975) (xy 42.332365 -357.838969) (xy 42.316996 -357.891308) (xy 42.294334 -357.940927)
			(xy 42.264841 -357.986816) (xy 42.229117 -358.02804) (xy 42.18789 -358.06376) (xy 42.141999 -358.093249)
			(xy 42.092378 -358.115907) (xy 42.040037 -358.131272) (xy 41.986043 -358.139031) (xy 41.958768 -358.139492)
			(xy 41.095168 -358.139492) (xy 41.067902 -358.138943) (xy 41.013926 -358.131179) (xy 40.961605 -358.115812)
			(xy 40.912003 -358.093156) (xy 40.866129 -358.063671) (xy 40.824919 -358.027959) (xy 40.78921 -357.986745)
			(xy 40.759729 -357.940869) (xy 40.737077 -357.891265) (xy 40.721714 -357.838942) (xy 40.713954 -357.784966)
			(xy 39.231106 -357.784966) (xy 39.231106 -357.784971) (xy 39.223343 -357.838958) (xy 39.207977 -357.891291)
			(xy 39.18532 -357.940905) (xy 39.155832 -357.986789) (xy 39.120115 -358.02801) (xy 39.078895 -358.063728)
			(xy 39.033012 -358.093216) (xy 38.983399 -358.115875) (xy 38.931066 -358.131242) (xy 38.877079 -358.139005)
			(xy 38.849808 -358.139492) (xy 37.986208 -358.139492) (xy 37.958939 -358.138969) (xy 37.904955 -358.131209)
			(xy 37.852626 -358.115844) (xy 37.803015 -358.093189) (xy 37.757134 -358.063704) (xy 37.715917 -358.027989)
			(xy 37.680201 -357.986772) (xy 37.650715 -357.940892) (xy 37.628059 -357.891282) (xy 37.612693 -357.838953)
			(xy 37.604931 -357.784969) (xy 36.122106 -357.784969) (xy 36.114345 -357.838953) (xy 36.09898 -357.891283)
			(xy 36.076326 -357.940894) (xy 36.046842 -357.986776) (xy 36.011129 -358.027995) (xy 35.969914 -358.063713)
			(xy 35.924036 -358.093203) (xy 35.874428 -358.115864) (xy 35.8221 -358.131234) (xy 35.768117 -358.139002)
			(xy 35.740848 -358.139492) (xy 34.877248 -358.139492) (xy 34.849977 -358.138972) (xy 34.795989 -358.131216)
			(xy 34.743655 -358.115855) (xy 34.694039 -358.093202) (xy 34.648153 -358.063718) (xy 34.606931 -358.028003)
			(xy 34.571211 -357.986785) (xy 34.541721 -357.940903) (xy 34.519062 -357.89129) (xy 34.503694 -357.838958)
			(xy 34.495932 -357.784971) (xy 33.013228 -357.784971) (xy 33.013228 -357.784974) (xy 33.005465 -357.838966)
			(xy 32.990097 -357.891304) (xy 32.967437 -357.940921) (xy 32.937946 -357.986809) (xy 32.902224 -358.028033)
			(xy 32.861 -358.063753) (xy 32.815111 -358.093243) (xy 32.765492 -358.115901) (xy 32.713154 -358.131268)
			(xy 32.659162 -358.139029) (xy 32.631888 -358.139492) (xy 31.768288 -358.139492) (xy 31.741021 -358.138945)
			(xy 31.687043 -358.131182) (xy 31.634719 -358.115817) (xy 31.585115 -358.093162) (xy 31.539239 -358.063678)
			(xy 31.498026 -358.027966) (xy 31.462315 -357.986752) (xy 31.432832 -357.940875) (xy 31.410179 -357.891269)
			(xy 31.394815 -357.838945) (xy 31.387054 -357.784967) (xy 29.904206 -357.784967) (xy 29.904206 -357.78497)
			(xy 29.896444 -357.838956) (xy 29.881079 -357.891287) (xy 29.858423 -357.940899) (xy 29.828937 -357.986782)
			(xy 29.793222 -358.028003) (xy 29.752005 -358.063721) (xy 29.706124 -358.09321) (xy 29.656513 -358.115869)
			(xy 29.604183 -358.131238) (xy 29.550198 -358.139004) (xy 29.522928 -358.139492) (xy 28.659328 -358.139492)
			(xy 28.632058 -358.13897) (xy 28.578072 -358.131212) (xy 28.52574 -358.11585) (xy 28.476127 -358.093195)
			(xy 28.430244 -358.063711) (xy 28.389024 -358.027996) (xy 28.353306 -357.986779) (xy 28.323818 -357.940897)
			(xy 28.30116 -357.891286) (xy 28.285794 -357.838955) (xy 28.278031 -357.78497) (xy 26.795328 -357.78497)
			(xy 26.795328 -357.784975) (xy 26.787565 -357.838969) (xy 26.772196 -357.891308) (xy 26.749534 -357.940927)
			(xy 26.720041 -357.986816) (xy 26.684317 -358.02804) (xy 26.64309 -358.06376) (xy 26.597199 -358.093249)
			(xy 26.547578 -358.115907) (xy 26.495237 -358.131272) (xy 26.441243 -358.139031) (xy 26.413968 -358.139492)
			(xy 25.550368 -358.139492) (xy 25.523102 -358.138943) (xy 25.469126 -358.131179) (xy 25.416805 -358.115812)
			(xy 25.367203 -358.093156) (xy 25.321329 -358.063671) (xy 25.280119 -358.027959) (xy 25.24441 -357.986745)
			(xy 25.214929 -357.940869) (xy 25.192277 -357.891265) (xy 25.176914 -357.838942) (xy 25.169154 -357.784966)
			(xy 23.686306 -357.784966) (xy 23.686306 -357.784971) (xy 23.678543 -357.838958) (xy 23.663177 -357.891291)
			(xy 23.64052 -357.940905) (xy 23.611032 -357.986789) (xy 23.575315 -358.02801) (xy 23.534095 -358.063728)
			(xy 23.488212 -358.093216) (xy 23.438599 -358.115875) (xy 23.386266 -358.131242) (xy 23.332279 -358.139005)
			(xy 23.305008 -358.139492) (xy 22.441408 -358.139492) (xy 22.414139 -358.138969) (xy 22.360155 -358.131209)
			(xy 22.307826 -358.115844) (xy 22.258215 -358.093189) (xy 22.212334 -358.063704) (xy 22.171117 -358.027989)
			(xy 22.135401 -357.986772) (xy 22.105915 -357.940892) (xy 22.083259 -357.891282) (xy 22.067893 -357.838953)
			(xy 22.060131 -357.784969) (xy 0.508 -357.784969) (xy 0.508 -360.017783) (xy 101.774757 -360.017783)
			(xy 101.774757 -359.957817) (xy 101.782584 -359.898365) (xy 101.798104 -359.840443) (xy 101.821052 -359.785042)
			(xy 101.851035 -359.733111) (xy 101.88754 -359.685538) (xy 101.929942 -359.643136) (xy 101.977516 -359.606632)
			(xy 102.029448 -359.57665) (xy 102.084849 -359.553703) (xy 102.142771 -359.538183) (xy 102.202223 -359.530357)
			(xy 102.232206 -359.529888) (xy 103.095806 -359.529888) (xy 103.125793 -359.530279) (xy 103.185255 -359.538108)
			(xy 103.243186 -359.553631) (xy 103.298595 -359.576583) (xy 103.350534 -359.60657) (xy 103.398115 -359.643081)
			(xy 103.440523 -359.68549) (xy 103.477033 -359.733071) (xy 103.50702 -359.785011) (xy 103.529971 -359.84042)
			(xy 103.545494 -359.898351) (xy 103.553322 -359.957813) (xy 103.553322 -360.017787) (xy 103.545494 -360.077249)
			(xy 103.529971 -360.13518) (xy 103.50702 -360.190589) (xy 103.477033 -360.242529) (xy 103.440523 -360.29011)
			(xy 103.398115 -360.332519) (xy 103.350534 -360.36903) (xy 103.298595 -360.399017) (xy 103.243186 -360.421969)
			(xy 103.185255 -360.437492) (xy 103.125793 -360.445321) (xy 103.095806 -360.445812) (xy 102.232206 -360.445812)
			(xy 102.202223 -360.445243) (xy 102.142771 -360.437417) (xy 102.084849 -360.421897) (xy 102.029448 -360.39895)
			(xy 101.977516 -360.368968) (xy 101.929942 -360.332464) (xy 101.88754 -360.290062) (xy 101.851035 -360.242489)
			(xy 101.821052 -360.190558) (xy 101.798104 -360.135157) (xy 101.782584 -360.077235) (xy 101.774757 -360.017783)
			(xy 0.508 -360.017783) (xy 0.508 -363.334808) (xy 54.890416 -363.334808) (xy 54.890416 -362.471208)
			(xy 54.890906 -362.441224) (xy 54.898734 -362.381768) (xy 54.914255 -362.323843) (xy 54.937204 -362.268439)
			(xy 54.967188 -362.216505) (xy 55.003694 -362.168929) (xy 55.046099 -362.126524) (xy 55.093675 -362.090018)
			(xy 55.145609 -362.060034) (xy 55.201013 -362.037085) (xy 55.258938 -362.021564) (xy 55.318394 -362.013736)
			(xy 55.378362 -362.013736) (xy 55.437818 -362.021564) (xy 55.495743 -362.037085) (xy 55.551147 -362.060034)
			(xy 55.603081 -362.090018) (xy 55.650657 -362.126524) (xy 55.693062 -362.168929) (xy 55.729568 -362.216505)
			(xy 55.759552 -362.268439) (xy 55.782501 -362.323843) (xy 55.798022 -362.381768) (xy 55.80585 -362.441224)
			(xy 55.80634 -362.471208) (xy 55.80634 -363.334808) (xy 55.80585 -363.364792) (xy 55.798022 -363.424248)
			(xy 55.782501 -363.482173) (xy 55.759552 -363.537577) (xy 55.729568 -363.589511) (xy 55.693062 -363.637087)
			(xy 55.650657 -363.679492) (xy 55.603081 -363.715998) (xy 55.551147 -363.745982) (xy 55.495743 -363.768931)
			(xy 55.437818 -363.784452) (xy 55.378362 -363.79228) (xy 55.318394 -363.79228) (xy 55.258938 -363.784452)
			(xy 55.201013 -363.768931) (xy 55.145609 -363.745982) (xy 55.093675 -363.715998) (xy 55.046099 -363.679492)
			(xy 55.003694 -363.637087) (xy 54.967188 -363.589511) (xy 54.937204 -363.537577) (xy 54.914255 -363.482173)
			(xy 54.898734 -363.424248) (xy 54.890906 -363.364792) (xy 54.890416 -363.334808) (xy 0.508 -363.334808)
			(xy 0.508 -365.797384) (xy 54.438294 -365.797384) (xy 54.438294 -365.737416) (xy 54.446121 -365.67796)
			(xy 54.461641 -365.620034) (xy 54.484589 -365.564629) (xy 54.514571 -365.512694) (xy 54.551076 -365.465115)
			(xy 54.593478 -365.422709) (xy 54.641052 -365.386199) (xy 54.692984 -365.356211) (xy 54.748387 -365.333257)
			(xy 54.806311 -365.317731) (xy 54.865766 -365.309897) (xy 54.89575 -365.309404) (xy 55.75935 -365.309404)
			(xy 55.789336 -365.309938) (xy 55.848794 -365.31776) (xy 55.906723 -365.333276) (xy 55.962131 -365.356222)
			(xy 56.01407 -365.386203) (xy 56.06165 -365.422708) (xy 56.104059 -365.465112) (xy 56.140569 -365.512689)
			(xy 56.170556 -365.564624) (xy 56.193508 -365.620029) (xy 56.20903 -365.677957) (xy 56.216859 -365.737414)
			(xy 56.216859 -365.797386) (xy 56.20903 -365.856843) (xy 56.193508 -365.914771) (xy 56.170556 -365.970176)
			(xy 56.140569 -366.022112) (xy 56.104059 -366.069688) (xy 56.06165 -366.112092) (xy 56.01407 -366.148597)
			(xy 55.962131 -366.178578) (xy 55.906723 -366.201524) (xy 55.848794 -366.21704) (xy 55.789336 -366.224862)
			(xy 55.75935 -366.225328) (xy 54.89575 -366.225328) (xy 54.865766 -366.224903) (xy 54.806311 -366.217069)
			(xy 54.748386 -366.201543) (xy 54.692984 -366.178589) (xy 54.641052 -366.148601) (xy 54.593478 -366.112091)
			(xy 54.551076 -366.069685) (xy 54.514571 -366.022106) (xy 54.484589 -365.970171) (xy 54.461641 -365.914766)
			(xy 54.446121 -365.85684) (xy 54.438294 -365.797384) (xy 0.508 -365.797384) (xy 0.508 -368.516662)
			(xy 53.966364 -368.516662) (xy 53.966364 -367.653062) (xy 53.96685 -367.625793) (xy 53.974612 -367.571809)
			(xy 53.989977 -367.519479) (xy 54.012634 -367.469869) (xy 54.04212 -367.423988) (xy 54.077835 -367.382771)
			(xy 54.119052 -367.347056) (xy 54.164933 -367.31757) (xy 54.214543 -367.294913) (xy 54.266873 -367.279548)
			(xy 54.320857 -367.271786) (xy 54.375395 -367.271786) (xy 54.429379 -367.279548) (xy 54.481709 -367.294913)
			(xy 54.531319 -367.31757) (xy 54.5772 -367.347056) (xy 54.618417 -367.382771) (xy 54.654132 -367.423988)
			(xy 54.683618 -367.469869) (xy 54.706275 -367.519479) (xy 54.72164 -367.571809) (xy 54.729402 -367.625793)
			(xy 54.729888 -367.653062) (xy 54.729888 -368.516662) (xy 57.339484 -368.516662) (xy 57.339484 -367.653062)
			(xy 57.33997 -367.625793) (xy 57.347732 -367.571809) (xy 57.363097 -367.519479) (xy 57.385754 -367.469869)
			(xy 57.41524 -367.423988) (xy 57.450955 -367.382771) (xy 57.492172 -367.347056) (xy 57.538053 -367.31757)
			(xy 57.587663 -367.294913) (xy 57.639993 -367.279548) (xy 57.693977 -367.271786) (xy 57.748515 -367.271786)
			(xy 57.802499 -367.279548) (xy 57.854829 -367.294913) (xy 57.904439 -367.31757) (xy 57.95032 -367.347056)
			(xy 57.991537 -367.382771) (xy 58.027252 -367.423988) (xy 58.056738 -367.469869) (xy 58.079395 -367.519479)
			(xy 58.09476 -367.571809) (xy 58.102522 -367.625793) (xy 58.103008 -367.653062) (xy 58.103008 -368.516662)
			(xy 58.102522 -368.543931) (xy 58.09476 -368.597915) (xy 58.079395 -368.650245) (xy 58.056738 -368.699855)
			(xy 58.027252 -368.745736) (xy 57.991537 -368.786953) (xy 57.95032 -368.822668) (xy 57.904439 -368.852154)
			(xy 57.854829 -368.874811) (xy 57.802499 -368.890176) (xy 57.748515 -368.897938) (xy 57.693977 -368.897938)
			(xy 57.639993 -368.890176) (xy 57.587663 -368.874811) (xy 57.538053 -368.852154) (xy 57.492172 -368.822668)
			(xy 57.450955 -368.786953) (xy 57.41524 -368.745736) (xy 57.385754 -368.699855) (xy 57.363097 -368.650245)
			(xy 57.347732 -368.597915) (xy 57.33997 -368.543931) (xy 57.339484 -368.516662) (xy 54.729888 -368.516662)
			(xy 54.729402 -368.543931) (xy 54.72164 -368.597915) (xy 54.706275 -368.650245) (xy 54.683618 -368.699855)
			(xy 54.654132 -368.745736) (xy 54.618417 -368.786953) (xy 54.5772 -368.822668) (xy 54.531319 -368.852154)
			(xy 54.481709 -368.874811) (xy 54.429379 -368.890176) (xy 54.375395 -368.897938) (xy 54.320857 -368.897938)
			(xy 54.266873 -368.890176) (xy 54.214543 -368.874811) (xy 54.164933 -368.852154) (xy 54.119052 -368.822668)
			(xy 54.077835 -368.786953) (xy 54.04212 -368.745736) (xy 54.012634 -368.699855) (xy 53.989977 -368.650245)
			(xy 53.974612 -368.597915) (xy 53.96685 -368.543931) (xy 53.966364 -368.516662) (xy 0.508 -368.516662)
			(xy 0.508 -370.523703) (xy 27.348898 -370.523703) (xy 27.348899 -370.456279) (xy 27.356975 -370.38934)
			(xy 27.373012 -370.323851) (xy 27.396776 -370.260753) (xy 27.427927 -370.200957) (xy 27.466016 -370.145322)
			(xy 27.48788 -370.119656) (xy 27.493675 -370.11251) (xy 27.500191 -370.09532) (xy 27.50058 -370.086128)
			(xy 27.50058 -369.928902) (xy 27.501029 -369.918771) (xy 27.508764 -369.900042) (xy 27.523062 -369.885684)
			(xy 27.541759 -369.877872) (xy 27.551888 -369.87734) (xy 28.268168 -369.87734) (xy 28.278293 -369.877743)
			(xy 28.297004 -369.885488) (xy 28.311321 -369.899809) (xy 28.31906 -369.918522) (xy 28.319476 -369.928648)
			(xy 28.319476 -370.086128) (xy 28.319878 -370.095316) (xy 28.326398 -370.1125) (xy 28.332176 -370.119656)
			(xy 28.354029 -370.145331) (xy 28.39212 -370.200963) (xy 28.423272 -370.260758) (xy 28.447038 -370.323854)
			(xy 28.463075 -370.389342) (xy 28.471152 -370.456279) (xy 28.471153 -370.523644) (xy 31.749193 -370.523644)
			(xy 31.749194 -370.456338) (xy 31.75724 -370.389514) (xy 31.773215 -370.324131) (xy 31.79689 -370.261126)
			(xy 31.827927 -370.201402) (xy 31.865879 -370.145816) (xy 31.887668 -370.120164) (xy 31.893471 -370.113023)
			(xy 31.89998 -370.095829) (xy 31.900368 -370.086636) (xy 31.900368 -369.928902) (xy 31.900766 -369.918727)
			(xy 31.908556 -369.899926) (xy 31.92295 -369.88554) (xy 31.941755 -369.877761) (xy 31.95193 -369.87734)
			(xy 32.66821 -369.87734) (xy 32.678369 -369.877825) (xy 32.697138 -369.885603) (xy 32.711503 -369.899972)
			(xy 32.719277 -369.918743) (xy 32.719772 -369.928902) (xy 32.719772 -370.086636) (xy 32.720171 -370.095824)
			(xy 32.726693 -370.113008) (xy 32.732472 -370.120164) (xy 32.754248 -370.145826) (xy 32.792196 -370.201411)
			(xy 32.823229 -370.261134) (xy 32.846902 -370.324137) (xy 32.862876 -370.389518) (xy 32.870921 -370.456339)
			(xy 32.870922 -370.523643) (xy 32.870915 -370.523703) (xy 36.148986 -370.523703) (xy 36.148987 -370.456279)
			(xy 36.157063 -370.389341) (xy 36.173099 -370.323851) (xy 36.196863 -370.260754) (xy 36.228013 -370.200957)
			(xy 36.266101 -370.145322) (xy 36.287964 -370.119656) (xy 36.29377 -370.112518) (xy 36.300277 -370.095322)
			(xy 36.300664 -370.086128) (xy 36.300664 -369.928902) (xy 36.301129 -369.918772) (xy 36.308861 -369.900047)
			(xy 36.323154 -369.88569) (xy 36.341845 -369.877875) (xy 36.351972 -369.87734) (xy 37.068252 -369.87734)
			(xy 37.078408 -369.877762) (xy 37.097167 -369.885549) (xy 37.111494 -369.899947) (xy 37.119188 -369.918744)
			(xy 37.11956 -369.928902) (xy 37.11956 -370.086128) (xy 37.119966 -370.095315) (xy 37.126483 -370.112499)
			(xy 37.13226 -370.119656) (xy 37.154114 -370.14533) (xy 37.192205 -370.200963) (xy 37.223359 -370.260757)
			(xy 37.247125 -370.323853) (xy 37.263163 -370.389341) (xy 37.27124 -370.456279) (xy 37.271241 -370.523703)
			(xy 37.271241 -370.523704) (xy 40.548752 -370.523704) (xy 40.548753 -370.456278) (xy 40.556831 -370.389338)
			(xy 40.572869 -370.323848) (xy 40.596637 -370.26075) (xy 40.627792 -370.200954) (xy 40.665885 -370.14532)
			(xy 40.687752 -370.119656) (xy 40.693556 -370.112516) (xy 40.700065 -370.095321) (xy 40.700452 -370.086128)
			(xy 40.700452 -369.928902) (xy 40.700929 -369.918774) (xy 40.708658 -369.900051) (xy 40.722947 -369.885694)
			(xy 40.741634 -369.877877) (xy 40.75176 -369.87734) (xy 41.46804 -369.87734) (xy 41.478202 -369.87769)
			(xy 41.496963 -369.885506) (xy 41.511286 -369.899925) (xy 41.518977 -369.918738) (xy 41.519348 -369.928902)
			(xy 41.519348 -370.086128) (xy 41.519756 -370.095315) (xy 41.526273 -370.112499) (xy 41.532048 -370.119656)
			(xy 41.553902 -370.14533) (xy 41.591994 -370.200962) (xy 41.623149 -370.260757) (xy 41.646916 -370.323852)
			(xy 41.662954 -370.389341) (xy 41.671031 -370.456279) (xy 41.671032 -370.523644) (xy 44.949071 -370.523644)
			(xy 44.949073 -370.456338) (xy 44.957118 -370.389515) (xy 44.973092 -370.324132) (xy 44.996766 -370.261127)
			(xy 45.027801 -370.201403) (xy 45.065751 -370.145816) (xy 45.08754 -370.120164) (xy 45.093339 -370.113021)
			(xy 45.099851 -370.095829) (xy 45.10024 -370.086636) (xy 45.10024 -369.928902) (xy 45.100665 -369.91873)
			(xy 45.10845 -369.899935) (xy 45.122835 -369.88555) (xy 45.14163 -369.877765) (xy 45.151802 -369.87734)
			(xy 45.868082 -369.87734) (xy 45.878253 -369.877778) (xy 45.897047 -369.885558) (xy 45.911433 -369.899939)
			(xy 45.919218 -369.918731) (xy 45.919644 -369.928902) (xy 45.919644 -370.086636) (xy 45.92005 -370.095823)
			(xy 45.926568 -370.113007) (xy 45.932344 -370.120164) (xy 45.95412 -370.145826) (xy 45.992071 -370.20141)
			(xy 46.023105 -370.261132) (xy 46.046779 -370.324136) (xy 46.062754 -370.389517) (xy 46.070799 -370.456339)
			(xy 46.0708 -370.523643) (xy 46.062757 -370.590465) (xy 46.046785 -370.655847) (xy 46.023113 -370.718851)
			(xy 45.99208 -370.778574) (xy 45.954131 -370.83416) (xy 45.932344 -370.859812) (xy 45.926553 -370.866961)
			(xy 45.920036 -370.884149) (xy 45.919644 -370.89334) (xy 45.919644 -371.386862) (xy 45.920085 -371.396046)
			(xy 45.926578 -371.41323) (xy 45.932344 -371.42039) (xy 45.954146 -371.44603) (xy 45.992096 -371.501618)
			(xy 46.023129 -371.561343) (xy 46.046568 -371.623726) (xy 47.14919 -371.623726) (xy 47.149193 -371.556417)
			(xy 47.157242 -371.489591) (xy 47.17322 -371.424206) (xy 47.1969 -371.3612) (xy 47.22794 -371.301475)
			(xy 47.265897 -371.24589) (xy 47.287688 -371.220238) (xy 47.293492 -371.213098) (xy 47.300003 -371.195904)
			(xy 47.300388 -371.18671) (xy 47.300388 -371.028722) (xy 47.300783 -371.018546) (xy 47.30857 -370.999742)
			(xy 47.322966 -370.985355) (xy 47.341773 -370.977578) (xy 47.35195 -370.97716) (xy 48.06823 -370.97716)
			(xy 48.078392 -370.977609) (xy 48.097167 -370.985398) (xy 48.111532 -370.999777) (xy 48.119301 -371.018559)
			(xy 48.119792 -371.028722) (xy 48.119792 -371.18671) (xy 48.120199 -371.195898) (xy 48.126715 -371.213082)
			(xy 48.132492 -371.220238) (xy 48.154241 -371.245921) (xy 48.192189 -371.301504) (xy 48.196948 -371.310662)
			(xy 53.966364 -371.310662) (xy 53.966364 -370.447062) (xy 53.96685 -370.419793) (xy 53.974612 -370.365809)
			(xy 53.989977 -370.313479) (xy 54.012634 -370.263869) (xy 54.04212 -370.217988) (xy 54.077835 -370.176771)
			(xy 54.119052 -370.141056) (xy 54.164933 -370.11157) (xy 54.214543 -370.088913) (xy 54.266873 -370.073548)
			(xy 54.320857 -370.065786) (xy 54.375395 -370.065786) (xy 54.429379 -370.073548) (xy 54.481709 -370.088913)
			(xy 54.531319 -370.11157) (xy 54.5772 -370.141056) (xy 54.618417 -370.176771) (xy 54.654132 -370.217988)
			(xy 54.683618 -370.263869) (xy 54.706275 -370.313479) (xy 54.72164 -370.365809) (xy 54.729402 -370.419793)
			(xy 54.729888 -370.447062) (xy 54.729888 -371.310662) (xy 57.339484 -371.310662) (xy 57.339484 -370.447062)
			(xy 57.33997 -370.419793) (xy 57.347732 -370.365809) (xy 57.363097 -370.313479) (xy 57.385754 -370.263869)
			(xy 57.41524 -370.217988) (xy 57.450955 -370.176771) (xy 57.492172 -370.141056) (xy 57.538053 -370.11157)
			(xy 57.587663 -370.088913) (xy 57.639993 -370.073548) (xy 57.693977 -370.065786) (xy 57.748515 -370.065786)
			(xy 57.802499 -370.073548) (xy 57.854829 -370.088913) (xy 57.904439 -370.11157) (xy 57.95032 -370.141056)
			(xy 57.991537 -370.176771) (xy 58.027252 -370.217988) (xy 58.056738 -370.263869) (xy 58.079395 -370.313479)
			(xy 58.09476 -370.365809) (xy 58.102522 -370.419793) (xy 58.103008 -370.447062) (xy 58.103008 -370.523703)
			(xy 71.348807 -370.523703) (xy 71.348808 -370.456279) (xy 71.356885 -370.38934) (xy 71.372921 -370.32385)
			(xy 71.396686 -370.260753) (xy 71.427838 -370.200956) (xy 71.465928 -370.145321) (xy 71.487792 -370.119656)
			(xy 71.493589 -370.112511) (xy 71.500104 -370.09532) (xy 71.500492 -370.086128) (xy 71.500492 -369.928902)
			(xy 71.501027 -369.918781) (xy 71.508745 -369.900069) (xy 71.523016 -369.885715) (xy 71.541682 -369.877887)
			(xy 71.5518 -369.87734) (xy 72.26808 -369.87734) (xy 72.278238 -369.877739) (xy 72.296998 -369.885535)
			(xy 72.311323 -369.89994) (xy 72.319016 -369.918742) (xy 72.319388 -369.928902) (xy 72.319388 -370.086128)
			(xy 72.319787 -370.095316) (xy 72.326309 -370.1125) (xy 72.332088 -370.119656) (xy 72.353941 -370.145331)
			(xy 72.39203 -370.200964) (xy 72.423182 -370.260758) (xy 72.446948 -370.323854) (xy 72.462984 -370.389342)
			(xy 72.471061 -370.45628) (xy 72.471063 -370.523644) (xy 75.749102 -370.523644) (xy 75.749103 -370.456338)
			(xy 75.757149 -370.389513) (xy 75.773125 -370.32413) (xy 75.796801 -370.261125) (xy 75.827837 -370.201401)
			(xy 75.86579 -370.145816) (xy 75.88758 -370.120164) (xy 75.893372 -370.113015) (xy 75.89989 -370.095828)
			(xy 75.90028 -370.086636) (xy 75.90028 -369.928902) (xy 75.900666 -369.918725) (xy 75.908459 -369.899923)
			(xy 75.922856 -369.885536) (xy 75.941665 -369.877759) (xy 75.951842 -369.87734) (xy 76.668122 -369.87734)
			(xy 76.678281 -369.877815) (xy 76.697052 -369.885597) (xy 76.711416 -369.899969) (xy 76.71919 -369.918742)
			(xy 76.719684 -369.928902) (xy 76.719684 -370.086636) (xy 76.72008 -370.095825) (xy 76.726604 -370.113009)
			(xy 76.732384 -370.120164) (xy 76.754159 -370.145826) (xy 76.792107 -370.201412) (xy 76.82314 -370.261134)
			(xy 76.846812 -370.324137) (xy 76.862785 -370.389518) (xy 76.87083 -370.456339) (xy 76.870831 -370.523643)
			(xy 76.870824 -370.523703) (xy 80.148895 -370.523703) (xy 80.148896 -370.456279) (xy 80.156972 -370.38934)
			(xy 80.173008 -370.323851) (xy 80.196773 -370.260754) (xy 80.227924 -370.200957) (xy 80.266012 -370.145322)
			(xy 80.287876 -370.119656) (xy 80.293671 -370.112509) (xy 80.300187 -370.09532) (xy 80.300576 -370.086128)
			(xy 80.300576 -369.928902) (xy 80.301029 -369.918771) (xy 80.308763 -369.900043) (xy 80.32306 -369.885685)
			(xy 80.341755 -369.877873) (xy 80.351884 -369.87734) (xy 81.068164 -369.87734) (xy 81.078289 -369.877747)
			(xy 81.096999 -369.88549) (xy 81.111316 -369.899811) (xy 81.119056 -369.918523) (xy 81.119472 -369.928648)
			(xy 81.119472 -370.086128) (xy 81.119875 -370.095316) (xy 81.126394 -370.1125) (xy 81.132172 -370.119656)
			(xy 81.154025 -370.14533) (xy 81.192116 -370.200963) (xy 81.223269 -370.260758) (xy 81.247035 -370.323853)
			(xy 81.263072 -370.389342) (xy 81.271149 -370.456279) (xy 81.27115 -370.523703) (xy 84.548686 -370.523703)
			(xy 84.548687 -370.456279) (xy 84.556763 -370.389341) (xy 84.572799 -370.323851) (xy 84.596563 -370.260754)
			(xy 84.627713 -370.200957) (xy 84.665801 -370.145322) (xy 84.687664 -370.119656) (xy 84.69347 -370.112518)
			(xy 84.699977 -370.095322) (xy 84.700364 -370.086128) (xy 84.700364 -369.928902) (xy 84.700829 -369.918772)
			(xy 84.708561 -369.900047) (xy 84.722854 -369.88569) (xy 84.741545 -369.877875) (xy 84.751672 -369.87734)
			(xy 85.467952 -369.87734) (xy 85.478076 -369.877756) (xy 85.496787 -369.885496) (xy 85.511104 -369.899813)
			(xy 85.518844 -369.918524) (xy 85.51926 -369.928648) (xy 85.51926 -370.086128) (xy 85.519666 -370.095315)
			(xy 85.526183 -370.112499) (xy 85.53196 -370.119656) (xy 85.553814 -370.14533) (xy 85.591905 -370.200963)
			(xy 85.623059 -370.260757) (xy 85.646825 -370.323853) (xy 85.662863 -370.389341) (xy 85.67094 -370.456279)
			(xy 85.670941 -370.523644) (xy 115.349244 -370.523644) (xy 115.349245 -370.456338) (xy 115.35729 -370.389516)
			(xy 115.373263 -370.324133) (xy 115.396936 -370.261128) (xy 115.427969 -370.201404) (xy 115.465917 -370.145817)
			(xy 115.487704 -370.120164) (xy 115.493499 -370.113018) (xy 115.500014 -370.095828) (xy 115.500404 -370.086636)
			(xy 115.500404 -369.928902) (xy 115.500934 -369.918749) (xy 115.508702 -369.899986) (xy 115.523056 -369.885622)
			(xy 115.541813 -369.877841) (xy 115.551966 -369.87734) (xy 116.268246 -369.87734) (xy 116.278407 -369.877796)
			(xy 116.297177 -369.885586) (xy 116.311541 -369.899963) (xy 116.319314 -369.918741) (xy 116.319808 -369.928902)
			(xy 116.319808 -370.086636) (xy 116.320199 -370.095825) (xy 116.326726 -370.11301) (xy 116.332508 -370.120164)
			(xy 116.354286 -370.145825) (xy 116.392238 -370.201409) (xy 116.423275 -370.261131) (xy 116.446951 -370.324134)
			(xy 116.462926 -370.389516) (xy 116.470972 -370.456338) (xy 116.470973 -370.523644) (xy 116.470966 -370.523703)
			(xy 119.749013 -370.523703) (xy 119.749014 -370.456279) (xy 119.757091 -370.38934) (xy 119.773128 -370.32385)
			(xy 119.796893 -370.260752) (xy 119.828045 -370.200956) (xy 119.866135 -370.145321) (xy 119.888 -370.119656)
			(xy 119.893798 -370.112512) (xy 119.900312 -370.09532) (xy 119.9007 -370.086128) (xy 119.9007 -369.928902)
			(xy 119.901227 -369.91878) (xy 119.908947 -369.900067) (xy 119.92322 -369.885712) (xy 119.941889 -369.877886)
			(xy 119.952008 -369.87734) (xy 120.668288 -369.87734) (xy 120.678446 -369.877732) (xy 120.697206 -369.885531)
			(xy 120.711531 -369.899938) (xy 120.719224 -369.918741) (xy 120.719596 -369.928902) (xy 120.719596 -370.086128)
			(xy 120.719993 -370.095317) (xy 120.726516 -370.112501) (xy 120.732296 -370.119656) (xy 120.754148 -370.145331)
			(xy 120.792238 -370.200964) (xy 120.823389 -370.260759) (xy 120.847154 -370.323854) (xy 120.863191 -370.389342)
			(xy 120.871267 -370.45628) (xy 120.871269 -370.523644) (xy 124.149308 -370.523644) (xy 124.149309 -370.456338)
			(xy 124.157355 -370.389513) (xy 124.173331 -370.32413) (xy 124.197007 -370.261125) (xy 124.228045 -370.201401)
			(xy 124.265998 -370.145816) (xy 124.287788 -370.120164) (xy 124.293581 -370.113016) (xy 124.300098 -370.095828)
			(xy 124.300488 -370.086636) (xy 124.300488 -369.928902) (xy 124.300867 -369.918724) (xy 124.30866 -369.89992)
			(xy 124.32306 -369.885533) (xy 124.341872 -369.877757) (xy 124.35205 -369.87734) (xy 125.06833 -369.87734)
			(xy 125.07849 -369.877809) (xy 125.09726 -369.885593) (xy 125.111625 -369.899967) (xy 125.119398 -369.918742)
			(xy 125.119892 -369.928902) (xy 125.119892 -370.086636) (xy 125.120286 -370.095825) (xy 125.126811 -370.113009)
			(xy 125.132592 -370.120164) (xy 125.154367 -370.145826) (xy 125.192314 -370.201412) (xy 125.223346 -370.261134)
			(xy 125.247018 -370.324138) (xy 125.262991 -370.389518) (xy 125.271036 -370.456339) (xy 125.271037 -370.523643)
			(xy 125.271037 -370.523644) (xy 128.549099 -370.523644) (xy 128.5491 -370.456338) (xy 128.557146 -370.389514)
			(xy 128.573121 -370.32413) (xy 128.596797 -370.261125) (xy 128.627834 -370.201402) (xy 128.665787 -370.145816)
			(xy 128.687576 -370.120164) (xy 128.693368 -370.113015) (xy 128.699886 -370.095828) (xy 128.700276 -370.086636)
			(xy 128.700276 -369.928902) (xy 128.700666 -369.918726) (xy 128.708458 -369.899924) (xy 128.722854 -369.885538)
			(xy 128.741661 -369.877759) (xy 128.751838 -369.87734) (xy 129.468118 -369.87734) (xy 129.478277 -369.877818)
			(xy 129.497047 -369.885599) (xy 129.511412 -369.89997) (xy 129.519185 -369.918743) (xy 129.51968 -369.928902)
			(xy 129.51968 -370.086636) (xy 129.520077 -370.095824) (xy 129.5266 -370.113008) (xy 129.53238 -370.120164)
			(xy 129.554155 -370.145826) (xy 129.592103 -370.201412) (xy 129.623136 -370.261134) (xy 129.646809 -370.324137)
			(xy 129.662782 -370.389518) (xy 129.670827 -370.456339) (xy 129.670828 -370.523643) (xy 129.670828 -370.523644)
			(xy 159.349153 -370.523644) (xy 159.349154 -370.456338) (xy 159.357199 -370.389515) (xy 159.373173 -370.324133)
			(xy 159.396846 -370.261128) (xy 159.427879 -370.201404) (xy 159.465828 -370.145816) (xy 159.487616 -370.120164)
			(xy 159.493412 -370.113019) (xy 159.499927 -370.095828) (xy 159.500316 -370.086636) (xy 159.500316 -369.928902)
			(xy 159.500835 -369.918747) (xy 159.508604 -369.899982) (xy 159.522962 -369.885618) (xy 159.541723 -369.877839)
			(xy 159.551878 -369.87734) (xy 160.268158 -369.87734) (xy 160.278327 -369.877798) (xy 160.297121 -369.88557)
			(xy 160.311508 -369.899945) (xy 160.319294 -369.918733) (xy 160.31972 -369.928902) (xy 160.31972 -370.086636)
			(xy 160.320109 -370.095826) (xy 160.326637 -370.11301) (xy 160.33242 -370.120164) (xy 160.354197 -370.145825)
			(xy 160.392149 -370.20141) (xy 160.423185 -370.261131) (xy 160.44686 -370.324135) (xy 160.462835 -370.389516)
			(xy 160.470881 -370.456339) (xy 160.470882 -370.523643) (xy 160.470875 -370.523703) (xy 163.748922 -370.523703)
			(xy 163.748923 -370.456279) (xy 163.757 -370.389339) (xy 163.773037 -370.323849) (xy 163.796803 -370.260752)
			(xy 163.827956 -370.200955) (xy 163.866047 -370.145321) (xy 163.887912 -370.119656) (xy 163.893711 -370.112513)
			(xy 163.900224 -370.095321) (xy 163.900612 -370.086128) (xy 163.900612 -369.928902) (xy 163.901127 -369.918779)
			(xy 163.908849 -369.900063) (xy 163.923126 -369.885708) (xy 163.9418 -369.877884) (xy 163.95192 -369.87734)
			(xy 164.6682 -369.87734) (xy 164.678359 -369.877722) (xy 164.697119 -369.885526) (xy 164.711444 -369.899935)
			(xy 164.719136 -369.918741) (xy 164.719508 -369.928902) (xy 164.719508 -370.086128) (xy 164.719903 -370.095317)
			(xy 164.726427 -370.112501) (xy 164.732208 -370.119656) (xy 164.75406 -370.145331) (xy 164.792148 -370.200964)
			(xy 164.823299 -370.260759) (xy 164.847064 -370.323855) (xy 164.8631 -370.389343) (xy 164.871176 -370.45628)
			(xy 164.871178 -370.523644) (xy 168.149241 -370.523644) (xy 168.149242 -370.456338) (xy 168.157287 -370.389516)
			(xy 168.17326 -370.324133) (xy 168.196933 -370.261128) (xy 168.227965 -370.201404) (xy 168.265913 -370.145817)
			(xy 168.2877 -370.120164) (xy 168.293494 -370.113017) (xy 168.30001 -370.095828) (xy 168.3004 -370.086636)
			(xy 168.3004 -369.928902) (xy 168.300934 -369.918749) (xy 168.308701 -369.899987) (xy 168.323054 -369.885623)
			(xy 168.341809 -369.877842) (xy 168.351962 -369.87734) (xy 169.068242 -369.87734) (xy 169.078403 -369.877799)
			(xy 169.097173 -369.885588) (xy 169.111537 -369.899964) (xy 169.11931 -369.918741) (xy 169.119804 -369.928902)
			(xy 169.119804 -370.086636) (xy 169.120196 -370.095825) (xy 169.126722 -370.113009) (xy 169.132504 -370.120164)
			(xy 169.154279 -370.145826) (xy 169.192225 -370.201412) (xy 169.223256 -370.261135) (xy 169.246928 -370.324138)
			(xy 169.2629 -370.389519) (xy 169.270945 -370.456339) (xy 169.270946 -370.523643) (xy 169.270946 -370.523644)
			(xy 172.549008 -370.523644) (xy 172.549009 -370.456338) (xy 172.557055 -370.389513) (xy 172.573031 -370.32413)
			(xy 172.596707 -370.261125) (xy 172.627745 -370.201401) (xy 172.665698 -370.145816) (xy 172.687488 -370.120164)
			(xy 172.693281 -370.113016) (xy 172.699798 -370.095828) (xy 172.700188 -370.086636) (xy 172.700188 -369.928902)
			(xy 172.700567 -369.918724) (xy 172.70836 -369.89992) (xy 172.72276 -369.885533) (xy 172.741572 -369.877757)
			(xy 172.75175 -369.87734) (xy 173.46803 -369.87734) (xy 173.47819 -369.877809) (xy 173.49696 -369.885593)
			(xy 173.511325 -369.899967) (xy 173.519098 -369.918742) (xy 173.519592 -369.928902) (xy 173.519592 -370.086636)
			(xy 173.519986 -370.095825) (xy 173.526511 -370.113009) (xy 173.532292 -370.120164) (xy 173.554067 -370.145826)
			(xy 173.592014 -370.201412) (xy 173.623046 -370.261134) (xy 173.646718 -370.324138) (xy 173.662691 -370.389518)
			(xy 173.670736 -370.456339) (xy 173.670737 -370.523643) (xy 173.662694 -370.590464) (xy 173.646724 -370.655845)
			(xy 173.623054 -370.718849) (xy 173.592023 -370.778573) (xy 173.554078 -370.834159) (xy 173.532292 -370.859812)
			(xy 173.526507 -370.866965) (xy 173.519986 -370.88415) (xy 173.519592 -370.89334) (xy 173.519592 -370.901722)
			(xy 204.470508 -370.901722) (xy 204.470508 -367.316004) (xy 204.470934 -367.305935) (xy 204.478654 -367.287337)
			(xy 204.485494 -367.279936) (xy 204.682344 -367.083086) (xy 204.689733 -367.076232) (xy 204.708341 -367.068521)
			(xy 204.718412 -367.0681) (xy 208.051146 -367.0681) (xy 208.061216 -367.068527) (xy 208.079815 -367.076244)
			(xy 208.087214 -367.083086) (xy 208.263998 -367.25987) (xy 208.270817 -367.267287) (xy 208.278549 -367.285873)
			(xy 208.278984 -367.295938) (xy 208.278984 -370.103908) (xy 208.279552 -370.116248) (xy 208.288818 -370.13912)
			(xy 208.297018 -370.148358) (xy 208.297526 -370.148866) (xy 208.34985 -370.20119) (xy 208.35903 -370.209654)
			(xy 208.382078 -370.219214) (xy 208.394554 -370.219732) (xy 208.738724 -370.219732) (xy 208.748796 -370.220137)
			(xy 208.767394 -370.227871) (xy 208.774792 -370.234718) (xy 209.51444 -370.974366) (xy 209.523615 -370.982837)
			(xy 209.546667 -370.99239) (xy 209.559144 -370.992908) (xy 210.018376 -370.992908) (xy 210.028444 -370.993344)
			(xy 210.047042 -371.001057) (xy 210.054444 -371.007894) (xy 210.21421 -371.16766) (xy 210.221026 -371.175079)
			(xy 210.228759 -371.193664) (xy 210.229196 -371.203728) (xy 210.229196 -371.61724) (xy 210.229798 -371.629697)
			(xy 210.239356 -371.652707) (xy 210.247738 -371.661944) (xy 210.379056 -371.793262) (xy 210.379564 -371.79377)
			(xy 210.388781 -371.802003) (xy 210.411665 -371.811276) (xy 210.424014 -371.811804) (xy 216.605104 -371.811804)
			(xy 216.617445 -371.811237) (xy 216.640316 -371.801971) (xy 216.649554 -371.79377) (xy 216.650062 -371.793262)
			(xy 217.67927 -370.764054) (xy 217.679778 -370.763546) (xy 217.688008 -370.754327) (xy 217.697282 -370.731444)
			(xy 217.697812 -370.719096) (xy 217.697812 -367.36528) (xy 217.698224 -367.355209) (xy 217.705954 -367.336611)
			(xy 217.712798 -367.329212) (xy 217.96883 -367.073434) (xy 217.97623 -367.066593) (xy 217.994829 -367.058873)
			(xy 218.004898 -367.058448) (xy 221.295214 -367.058448) (xy 221.305259 -367.058823) (xy 221.323856 -367.066407)
			(xy 221.331282 -367.07318) (xy 221.508066 -367.249964) (xy 221.514878 -367.257386) (xy 221.522615 -367.275968)
			(xy 221.523052 -367.286032) (xy 221.523052 -370.745258) (xy 221.523577 -370.757603) (xy 221.532871 -370.780476)
			(xy 221.541086 -370.789708) (xy 221.541594 -370.790216) (xy 221.701614 -370.950236) (xy 221.708464 -370.957628)
			(xy 221.716177 -370.976233) (xy 221.7166 -370.986304) (xy 221.7166 -373.574564) (xy 221.71724 -373.587017)
			(xy 221.726771 -373.610028) (xy 221.735142 -373.619268) (xy 223.603312 -375.487438) (xy 223.6125 -375.495892)
			(xy 223.635542 -375.505456) (xy 223.648016 -375.50598) (xy 225.569526 -375.50598) (xy 225.581983 -375.505377)
			(xy 225.604994 -375.49582) (xy 225.61423 -375.487438) (xy 226.890326 -374.211342) (xy 226.890834 -374.210834)
			(xy 226.899064 -374.201614) (xy 226.90834 -374.178732) (xy 226.908868 -374.166384) (xy 226.908868 -372.704106)
			(xy 226.909279 -372.694035) (xy 226.917008 -372.675436) (xy 226.923854 -372.668038) (xy 228.193346 -371.3988)
			(xy 228.201796 -371.389609) (xy 228.211362 -371.366569) (xy 228.211888 -371.354096) (xy 228.211888 -370.983256)
			(xy 228.212267 -370.973181) (xy 228.220018 -370.954582) (xy 228.226874 -370.947188) (xy 228.380798 -370.793264)
			(xy 228.389257 -370.78408) (xy 228.398819 -370.761035) (xy 228.39934 -370.74856) (xy 228.39934 -367.292382)
			(xy 228.399715 -367.282337) (xy 228.4073 -367.263741) (xy 228.414072 -367.256314) (xy 228.600508 -367.069878)
			(xy 228.607909 -367.063039) (xy 228.626508 -367.055319) (xy 228.636576 -367.054892) (xy 231.959912 -367.054892)
			(xy 231.969985 -367.055287) (xy 231.988584 -367.063026) (xy 231.99598 -367.069878) (xy 232.182416 -367.256314)
			(xy 232.1891 -367.263803) (xy 232.196697 -367.282356) (xy 232.197148 -367.292382) (xy 232.197148 -370.755164)
			(xy 232.197775 -370.767618) (xy 232.207314 -370.79063) (xy 232.21569 -370.799868) (xy 232.35031 -370.934234)
			(xy 232.357159 -370.941627) (xy 232.364873 -370.960232) (xy 232.365296 -370.970302) (xy 232.365296 -371.212364)
			(xy 232.365833 -371.224708) (xy 232.37512 -371.247579) (xy 232.38333 -371.256814) (xy 232.383838 -371.257322)
			(xy 233.100118 -371.973602) (xy 233.106954 -371.981005) (xy 233.114675 -371.999602) (xy 233.115104 -372.00967)
			(xy 233.115104 -375.498868) (xy 233.115741 -375.511321) (xy 233.125274 -375.534332) (xy 233.133646 -375.543572)
			(xy 233.841798 -376.251724) (xy 235.85424 -376.251724) (xy 235.85424 -368.653314) (xy 235.854662 -368.643244)
			(xy 235.862384 -368.624646) (xy 235.869226 -368.617246) (xy 236.22889 -368.257582) (xy 236.236297 -368.250752)
			(xy 236.254891 -368.243027) (xy 236.264958 -368.242596) (xy 242.047014 -368.242596) (xy 242.057087 -368.242989)
			(xy 242.075686 -368.25073) (xy 242.083082 -368.257582) (xy 242.35029 -368.52479) (xy 242.357117 -368.532201)
			(xy 242.364845 -368.550792) (xy 242.365276 -368.560858) (xy 242.365276 -376.144028) (xy 242.364736 -376.155236)
			(xy 242.355238 -376.175537) (xy 242.346988 -376.183144) (xy 242.273836 -376.244104) (xy 242.269772 -376.247914)
			(xy 241.986816 -376.53087) (xy 241.986562 -376.531124) (xy 241.978942 -376.540522) (xy 241.91849 -376.631454)
			(xy 241.910997 -376.641545) (xy 241.888878 -376.653411) (xy 241.876326 -376.65406) (xy 236.25683 -376.65406)
			(xy 236.246761 -376.653629) (xy 236.228163 -376.645913) (xy 236.220762 -376.639074) (xy 235.869226 -376.287792)
			(xy 235.862394 -376.280386) (xy 235.854669 -376.261791) (xy 235.85424 -376.251724) (xy 233.841798 -376.251724)
			(xy 234.964478 -377.374404) (xy 242.49126 -377.374404) (xy 242.49126 -368.547142) (xy 242.491691 -368.537073)
			(xy 242.499406 -368.518474) (xy 242.506246 -368.511074) (xy 242.759738 -368.257582) (xy 242.767129 -368.25073)
			(xy 242.785735 -368.243018) (xy 242.795806 -368.242596) (xy 265.583924 -368.242596) (xy 265.593998 -368.242984)
			(xy 265.612597 -368.250728) (xy 265.619992 -368.257582) (xy 266.105894 -368.743484) (xy 266.112719 -368.750896)
			(xy 266.120448 -368.769486) (xy 266.12088 -368.779552) (xy 266.12088 -370.523704) (xy 286.928752 -370.523704)
			(xy 286.928753 -370.456278) (xy 286.936831 -370.389338) (xy 286.952869 -370.323848) (xy 286.976637 -370.26075)
			(xy 287.007792 -370.200954) (xy 287.045885 -370.14532) (xy 287.067752 -370.119656) (xy 287.073556 -370.112516)
			(xy 287.080065 -370.095321) (xy 287.080452 -370.086128) (xy 287.080452 -369.928902) (xy 287.080929 -369.918774)
			(xy 287.088658 -369.900051) (xy 287.102947 -369.885694) (xy 287.121634 -369.877877) (xy 287.13176 -369.87734)
			(xy 287.84804 -369.87734) (xy 287.85817 -369.877684) (xy 287.876882 -369.885453) (xy 287.891196 -369.899792)
			(xy 287.898933 -369.918517) (xy 287.899348 -369.928648) (xy 287.899348 -370.086128) (xy 287.899756 -370.095315)
			(xy 287.906273 -370.112499) (xy 287.912048 -370.119656) (xy 287.933902 -370.14533) (xy 287.971994 -370.200962)
			(xy 288.003149 -370.260757) (xy 288.026916 -370.323852) (xy 288.042954 -370.389341) (xy 288.051031 -370.456279)
			(xy 288.051032 -370.523644) (xy 291.329071 -370.523644) (xy 291.329073 -370.456338) (xy 291.337118 -370.389515)
			(xy 291.353092 -370.324132) (xy 291.376766 -370.261127) (xy 291.407801 -370.201403) (xy 291.445751 -370.145816)
			(xy 291.46754 -370.120164) (xy 291.473339 -370.113021) (xy 291.479851 -370.095829) (xy 291.48024 -370.086636)
			(xy 291.48024 -369.928902) (xy 291.480665 -369.91873) (xy 291.48845 -369.899935) (xy 291.502835 -369.88555)
			(xy 291.52163 -369.877765) (xy 291.531802 -369.87734) (xy 292.248082 -369.87734) (xy 292.258253 -369.877778)
			(xy 292.277047 -369.885558) (xy 292.291433 -369.899939) (xy 292.299218 -369.918731) (xy 292.299644 -369.928902)
			(xy 292.299644 -370.086636) (xy 292.30005 -370.095823) (xy 292.306568 -370.113007) (xy 292.312344 -370.120164)
			(xy 292.33412 -370.145826) (xy 292.372071 -370.20141) (xy 292.403105 -370.261132) (xy 292.426779 -370.324136)
			(xy 292.442754 -370.389517) (xy 292.450799 -370.456339) (xy 292.4508 -370.523643) (xy 292.450793 -370.523704)
			(xy 295.72884 -370.523704) (xy 295.728841 -370.456278) (xy 295.736918 -370.389339) (xy 295.752956 -370.323848)
			(xy 295.776723 -370.260751) (xy 295.807878 -370.200955) (xy 295.84597 -370.145321) (xy 295.867836 -370.119656)
			(xy 295.873638 -370.112515) (xy 295.880149 -370.095321) (xy 295.880536 -370.086128) (xy 295.880536 -369.928902)
			(xy 295.881028 -369.918776) (xy 295.888755 -369.900056) (xy 295.903039 -369.885699) (xy 295.92172 -369.877879)
			(xy 295.931844 -369.87734) (xy 296.648124 -369.87734) (xy 296.658285 -369.877703) (xy 296.677045 -369.885514)
			(xy 296.691369 -369.899929) (xy 296.699061 -369.918739) (xy 296.699432 -369.928902) (xy 296.699432 -370.086128)
			(xy 296.699844 -370.095315) (xy 296.706358 -370.112498) (xy 296.712132 -370.119656) (xy 296.733983 -370.145332)
			(xy 296.77207 -370.200965) (xy 296.803219 -370.26076) (xy 296.826983 -370.323856) (xy 296.843018 -370.389343)
			(xy 296.851095 -370.45628) (xy 296.851096 -370.523702) (xy 296.851096 -370.523704) (xy 300.128631 -370.523704)
			(xy 300.128632 -370.456278) (xy 300.136709 -370.389339) (xy 300.152747 -370.323849) (xy 300.176513 -370.260751)
			(xy 300.207667 -370.200955) (xy 300.245758 -370.145321) (xy 300.267624 -370.119656) (xy 300.273425 -370.112514)
			(xy 300.279936 -370.095321) (xy 300.280324 -370.086128) (xy 300.280324 -369.928902) (xy 300.280828 -369.918777)
			(xy 300.288552 -369.900059) (xy 300.302833 -369.885704) (xy 300.32151 -369.877882) (xy 300.331632 -369.87734)
			(xy 301.047912 -369.87734) (xy 301.058072 -369.877712) (xy 301.076832 -369.885519) (xy 301.091157 -369.899932)
			(xy 301.098849 -369.91874) (xy 301.09922 -369.928902) (xy 301.09922 -370.086128) (xy 301.099612 -370.095317)
			(xy 301.106138 -370.112502) (xy 301.11192 -370.119656) (xy 301.133771 -370.145331) (xy 301.171859 -370.200965)
			(xy 301.203009 -370.26076) (xy 301.226773 -370.323855) (xy 301.242809 -370.389343) (xy 301.250886 -370.45628)
			(xy 301.250887 -370.523644) (xy 330.92919 -370.523644) (xy 330.929191 -370.456338) (xy 330.937237 -370.389514)
			(xy 330.953212 -370.324131) (xy 330.976887 -370.261126) (xy 331.007923 -370.201402) (xy 331.045875 -370.145816)
			(xy 331.067664 -370.120164) (xy 331.073466 -370.113023) (xy 331.079976 -370.095829) (xy 331.080364 -370.086636)
			(xy 331.080364 -369.928902) (xy 331.080766 -369.918727) (xy 331.088555 -369.899928) (xy 331.102948 -369.885542)
			(xy 331.121751 -369.877761) (xy 331.131926 -369.87734) (xy 331.848206 -369.87734) (xy 331.858364 -369.877829)
			(xy 331.877134 -369.885605) (xy 331.891499 -369.899973) (xy 331.899273 -369.918744) (xy 331.899768 -369.928902)
			(xy 331.899768 -370.086636) (xy 331.900168 -370.095824) (xy 331.90669 -370.113008) (xy 331.912468 -370.120164)
			(xy 331.934244 -370.145826) (xy 331.972193 -370.201411) (xy 332.003226 -370.261133) (xy 332.026899 -370.324137)
			(xy 332.042873 -370.389518) (xy 332.050918 -370.456339) (xy 332.050919 -370.523643) (xy 332.050912 -370.523703)
			(xy 335.328983 -370.523703) (xy 335.328984 -370.456279) (xy 335.33706 -370.389341) (xy 335.353096 -370.323852)
			(xy 335.376859 -370.260754) (xy 335.408009 -370.200957) (xy 335.446097 -370.145322) (xy 335.46796 -370.119656)
			(xy 335.473765 -370.112517) (xy 335.480273 -370.095322) (xy 335.48066 -370.086128) (xy 335.48066 -369.928902)
			(xy 335.481129 -369.918773) (xy 335.48886 -369.900048) (xy 335.503152 -369.885691) (xy 335.521841 -369.877875)
			(xy 335.531968 -369.87734) (xy 336.248248 -369.87734) (xy 336.25841 -369.877683) (xy 336.277171 -369.885502)
			(xy 336.291494 -369.899923) (xy 336.299185 -369.918737) (xy 336.299556 -369.928902) (xy 336.299556 -370.086128)
			(xy 336.299963 -370.095315) (xy 336.30648 -370.112499) (xy 336.312256 -370.119656) (xy 336.33411 -370.14533)
			(xy 336.372202 -370.200962) (xy 336.403355 -370.260757) (xy 336.427122 -370.323853) (xy 336.44316 -370.389341)
			(xy 336.451237 -370.456279) (xy 336.451238 -370.523644) (xy 339.729277 -370.523644) (xy 339.729279 -370.456338)
			(xy 339.737324 -370.389514) (xy 339.753299 -370.324131) (xy 339.776973 -370.261126) (xy 339.808008 -370.201402)
			(xy 339.845959 -370.145816) (xy 339.867748 -370.120164) (xy 339.873548 -370.113022) (xy 339.880059 -370.095829)
			(xy 339.880448 -370.086636) (xy 339.880448 -369.928902) (xy 339.880866 -369.918729) (xy 339.888652 -369.899933)
			(xy 339.903039 -369.885547) (xy 339.921837 -369.877764) (xy 339.93201 -369.87734) (xy 340.64829 -369.87734)
			(xy 340.658461 -369.877772) (xy 340.677256 -369.885554) (xy 340.691641 -369.899937) (xy 340.699426 -369.918731)
			(xy 340.699852 -369.928902) (xy 340.699852 -370.086636) (xy 340.700256 -370.095824) (xy 340.706775 -370.113007)
			(xy 340.712552 -370.120164) (xy 340.734328 -370.145826) (xy 340.772278 -370.201411) (xy 340.803312 -370.261133)
			(xy 340.826986 -370.324136) (xy 340.84296 -370.389517) (xy 340.851005 -370.456339) (xy 340.851006 -370.523643)
			(xy 340.851006 -370.523644) (xy 344.129068 -370.523644) (xy 344.129069 -370.456338) (xy 344.137115 -370.389515)
			(xy 344.153089 -370.324132) (xy 344.176763 -370.261127) (xy 344.207797 -370.201403) (xy 344.245748 -370.145816)
			(xy 344.267536 -370.120164) (xy 344.273335 -370.113021) (xy 344.279847 -370.095829) (xy 344.280236 -370.086636)
			(xy 344.280236 -369.928902) (xy 344.280735 -369.918745) (xy 344.288508 -369.899976) (xy 344.302873 -369.885611)
			(xy 344.321641 -369.877836) (xy 344.331798 -369.87734) (xy 345.048078 -369.87734) (xy 345.058248 -369.877782)
			(xy 345.077043 -369.88556) (xy 345.091429 -369.89994) (xy 345.099214 -369.918732) (xy 345.09964 -369.928902)
			(xy 345.09964 -370.086636) (xy 345.100046 -370.095823) (xy 345.106564 -370.113007) (xy 345.11234 -370.120164)
			(xy 345.134116 -370.145826) (xy 345.172067 -370.20141) (xy 345.203102 -370.261132) (xy 345.226776 -370.324136)
			(xy 345.242751 -370.389517) (xy 345.250796 -370.456339) (xy 345.250797 -370.523643) (xy 345.250797 -370.523644)
			(xy 374.929099 -370.523644) (xy 374.9291 -370.456338) (xy 374.937146 -370.389514) (xy 374.953121 -370.32413)
			(xy 374.976797 -370.261125) (xy 375.007834 -370.201402) (xy 375.045787 -370.145816) (xy 375.067576 -370.120164)
			(xy 375.073368 -370.113015) (xy 375.079886 -370.095828) (xy 375.080276 -370.086636) (xy 375.080276 -369.928902)
			(xy 375.080666 -369.918726) (xy 375.088458 -369.899924) (xy 375.102854 -369.885538) (xy 375.121661 -369.877759)
			(xy 375.131838 -369.87734) (xy 375.848118 -369.87734) (xy 375.858277 -369.877818) (xy 375.877047 -369.885599)
			(xy 375.891412 -369.89997) (xy 375.899185 -369.918743) (xy 375.89968 -369.928902) (xy 375.89968 -370.086636)
			(xy 375.900077 -370.095824) (xy 375.9066 -370.113008) (xy 375.91238 -370.120164) (xy 375.934155 -370.145826)
			(xy 375.972103 -370.201412) (xy 376.003136 -370.261134) (xy 376.026809 -370.324137) (xy 376.042782 -370.389518)
			(xy 376.050827 -370.456339) (xy 376.050828 -370.523643) (xy 376.050821 -370.523703) (xy 379.328892 -370.523703)
			(xy 379.328893 -370.456279) (xy 379.336969 -370.38934) (xy 379.353005 -370.323851) (xy 379.376769 -370.260754)
			(xy 379.40792 -370.200957) (xy 379.446008 -370.145322) (xy 379.467872 -370.119656) (xy 379.473678 -370.112518)
			(xy 379.480185 -370.095322) (xy 379.480572 -370.086128) (xy 379.480572 -369.928902) (xy 379.481029 -369.918772)
			(xy 379.488762 -369.900044) (xy 379.503058 -369.885687) (xy 379.521752 -369.877873) (xy 379.53188 -369.87734)
			(xy 380.24816 -369.87734) (xy 380.258316 -369.877755) (xy 380.277076 -369.885545) (xy 380.291402 -369.899945)
			(xy 380.299096 -369.918743) (xy 380.299468 -369.928902) (xy 380.299468 -370.086128) (xy 380.299872 -370.095316)
			(xy 380.306391 -370.1125) (xy 380.312168 -370.119656) (xy 380.334021 -370.14533) (xy 380.372112 -370.200963)
			(xy 380.403265 -370.260758) (xy 380.427032 -370.323853) (xy 380.443069 -370.389342) (xy 380.451146 -370.456279)
			(xy 380.451147 -370.523644) (xy 383.729187 -370.523644) (xy 383.729188 -370.456338) (xy 383.737234 -370.389514)
			(xy 383.753209 -370.324131) (xy 383.776884 -370.261126) (xy 383.807919 -370.201402) (xy 383.845871 -370.145816)
			(xy 383.86766 -370.120164) (xy 383.873462 -370.113023) (xy 383.879972 -370.095829) (xy 383.88036 -370.086636)
			(xy 383.88036 -369.928902) (xy 383.880766 -369.918728) (xy 383.888554 -369.899929) (xy 383.902946 -369.885543)
			(xy 383.921748 -369.877762) (xy 383.931922 -369.87734) (xy 384.648202 -369.87734) (xy 384.65836 -369.877832)
			(xy 384.67713 -369.885607) (xy 384.691495 -369.899974) (xy 384.699269 -369.918744) (xy 384.699764 -369.928902)
			(xy 384.699764 -370.086636) (xy 384.700165 -370.095824) (xy 384.706686 -370.113008) (xy 384.712464 -370.120164)
			(xy 384.73424 -370.145826) (xy 384.772189 -370.201411) (xy 384.803222 -370.261133) (xy 384.826895 -370.324137)
			(xy 384.842869 -370.389518) (xy 384.850914 -370.456339) (xy 384.850915 -370.523643) (xy 384.850915 -370.523644)
			(xy 388.128977 -370.523644) (xy 388.128979 -370.456338) (xy 388.137024 -370.389514) (xy 388.152999 -370.324131)
			(xy 388.176673 -370.261126) (xy 388.207708 -370.201402) (xy 388.245659 -370.145816) (xy 388.267448 -370.120164)
			(xy 388.273248 -370.113022) (xy 388.279759 -370.095829) (xy 388.280148 -370.086636) (xy 388.280148 -369.928902)
			(xy 388.280566 -369.918729) (xy 388.288352 -369.899933) (xy 388.302739 -369.885547) (xy 388.321537 -369.877764)
			(xy 388.33171 -369.87734) (xy 389.04799 -369.87734) (xy 389.058161 -369.877772) (xy 389.076956 -369.885554)
			(xy 389.091341 -369.899937) (xy 389.099126 -369.918731) (xy 389.099552 -369.928902) (xy 389.099552 -370.086636)
			(xy 389.099956 -370.095824) (xy 389.106475 -370.113007) (xy 389.112252 -370.120164) (xy 389.134028 -370.145826)
			(xy 389.171978 -370.201411) (xy 389.203012 -370.261133) (xy 389.226686 -370.324136) (xy 389.24266 -370.389517)
			(xy 389.250705 -370.456339) (xy 389.250706 -370.523643) (xy 389.250706 -370.523644) (xy 418.929008 -370.523644)
			(xy 418.929009 -370.456338) (xy 418.937055 -370.389513) (xy 418.953031 -370.32413) (xy 418.976707 -370.261125)
			(xy 419.007745 -370.201401) (xy 419.045698 -370.145816) (xy 419.067488 -370.120164) (xy 419.073281 -370.113016)
			(xy 419.079798 -370.095828) (xy 419.080188 -370.086636) (xy 419.080188 -369.928902) (xy 419.080567 -369.918724)
			(xy 419.08836 -369.89992) (xy 419.10276 -369.885533) (xy 419.121572 -369.877757) (xy 419.13175 -369.87734)
			(xy 419.84803 -369.87734) (xy 419.85819 -369.877809) (xy 419.87696 -369.885593) (xy 419.891325 -369.899967)
			(xy 419.899098 -369.918742) (xy 419.899592 -369.928902) (xy 419.899592 -370.086636) (xy 419.899986 -370.095825)
			(xy 419.906511 -370.113009) (xy 419.912292 -370.120164) (xy 419.934067 -370.145826) (xy 419.972014 -370.201412)
			(xy 420.003046 -370.261134) (xy 420.026718 -370.324138) (xy 420.042691 -370.389518) (xy 420.050736 -370.456339)
			(xy 420.050737 -370.523643) (xy 420.05073 -370.523703) (xy 423.328801 -370.523703) (xy 423.328802 -370.456279)
			(xy 423.336878 -370.38934) (xy 423.352915 -370.323851) (xy 423.37668 -370.260753) (xy 423.407831 -370.200957)
			(xy 423.44592 -370.145322) (xy 423.467784 -370.119656) (xy 423.47358 -370.11251) (xy 423.480095 -370.09532)
			(xy 423.480484 -370.086128) (xy 423.480484 -369.928902) (xy 423.48093 -369.91877) (xy 423.488665 -369.900041)
			(xy 423.502964 -369.885683) (xy 423.521662 -369.877871) (xy 423.531792 -369.87734) (xy 424.248072 -369.87734)
			(xy 424.258198 -369.87774) (xy 424.276908 -369.885486) (xy 424.291225 -369.899808) (xy 424.298964 -369.918522)
			(xy 424.29938 -369.928648) (xy 424.29938 -370.086128) (xy 424.299781 -370.095316) (xy 424.306302 -370.1125)
			(xy 424.31208 -370.119656) (xy 424.333933 -370.145331) (xy 424.372023 -370.200963) (xy 424.403176 -370.260758)
			(xy 424.426941 -370.323854) (xy 424.442978 -370.389342) (xy 424.451055 -370.456279) (xy 424.451056 -370.523644)
			(xy 427.729096 -370.523644) (xy 427.729097 -370.456338) (xy 427.737143 -370.389514) (xy 427.753118 -370.32413)
			(xy 427.776794 -370.261125) (xy 427.80783 -370.201402) (xy 427.845783 -370.145816) (xy 427.867572 -370.120164)
			(xy 427.873375 -370.113024) (xy 427.879884 -370.095829) (xy 427.880272 -370.086636) (xy 427.880272 -369.928902)
			(xy 427.880666 -369.918726) (xy 427.888457 -369.899925) (xy 427.902852 -369.885539) (xy 427.921658 -369.87776)
			(xy 427.931834 -369.87734) (xy 428.648114 -369.87734) (xy 428.658273 -369.877822) (xy 428.677043 -369.885602)
			(xy 428.691407 -369.899971) (xy 428.699181 -369.918743) (xy 428.699676 -369.928902) (xy 428.699676 -370.086636)
			(xy 428.700074 -370.095824) (xy 428.706597 -370.113008) (xy 428.712376 -370.120164) (xy 428.734152 -370.145826)
			(xy 428.7721 -370.201411) (xy 428.803133 -370.261134) (xy 428.826806 -370.324137) (xy 428.842779 -370.389518)
			(xy 428.850824 -370.456339) (xy 428.850825 -370.523643) (xy 428.850825 -370.523644) (xy 432.128887 -370.523644)
			(xy 432.128888 -370.456338) (xy 432.136934 -370.389514) (xy 432.152909 -370.324131) (xy 432.176584 -370.261126)
			(xy 432.207619 -370.201402) (xy 432.245571 -370.145816) (xy 432.26736 -370.120164) (xy 432.273162 -370.113023)
			(xy 432.279672 -370.095829) (xy 432.28006 -370.086636) (xy 432.28006 -369.928902) (xy 432.280466 -369.918728)
			(xy 432.288254 -369.899929) (xy 432.302646 -369.885543) (xy 432.321448 -369.877762) (xy 432.331622 -369.87734)
			(xy 433.047902 -369.87734) (xy 433.05806 -369.877832) (xy 433.07683 -369.885607) (xy 433.091195 -369.899974)
			(xy 433.098969 -369.918744) (xy 433.099464 -369.928902) (xy 433.099464 -370.086636) (xy 433.099865 -370.095824)
			(xy 433.106386 -370.113008) (xy 433.112164 -370.120164) (xy 433.13394 -370.145826) (xy 433.171889 -370.201411)
			(xy 433.202922 -370.261133) (xy 433.226595 -370.324137) (xy 433.242569 -370.389518) (xy 433.250614 -370.456339)
			(xy 433.250615 -370.523643) (xy 433.242572 -370.590465) (xy 433.226601 -370.655846) (xy 433.20293 -370.71885)
			(xy 433.171898 -370.778573) (xy 433.133951 -370.83416) (xy 433.112164 -370.859812) (xy 433.106375 -370.866963)
			(xy 433.099857 -370.884149) (xy 433.099464 -370.89334) (xy 433.099464 -371.386862) (xy 433.099901 -371.396046)
			(xy 433.106397 -371.41323) (xy 433.112164 -371.42039) (xy 433.133966 -371.446031) (xy 433.171914 -371.501619)
			(xy 433.202946 -371.561344) (xy 433.226383 -371.623725) (xy 434.329029 -371.623725) (xy 434.329032 -371.556418)
			(xy 434.33708 -371.489593) (xy 434.353056 -371.424209) (xy 434.376732 -371.361203) (xy 434.407768 -371.301478)
			(xy 434.445719 -371.245891) (xy 434.467508 -371.220238) (xy 434.473314 -371.2131) (xy 434.479823 -371.195904)
			(xy 434.480208 -371.18671) (xy 434.480208 -371.028722) (xy 434.48075 -371.018569) (xy 434.488512 -370.999806)
			(xy 434.502863 -370.985441) (xy 434.521618 -370.977661) (xy 434.53177 -370.97716) (xy 435.24805 -370.97716)
			(xy 435.258221 -370.977605) (xy 435.277019 -370.985378) (xy 435.291406 -370.999758) (xy 435.299189 -371.018551)
			(xy 435.299612 -371.028722) (xy 435.299612 -371.18671) (xy 435.300015 -371.195898) (xy 435.306533 -371.213082)
			(xy 435.312312 -371.220238) (xy 435.334064 -371.24592) (xy 435.372017 -371.301501) (xy 435.403055 -371.36122)
			(xy 435.426732 -371.424221) (xy 435.442709 -371.4896) (xy 435.450757 -371.55642) (xy 435.45076 -371.623723)
			(xy 435.442719 -371.690544) (xy 435.426749 -371.755924) (xy 435.403078 -371.818928) (xy 435.372046 -371.87865)
			(xy 435.334099 -371.934235) (xy 435.312312 -371.959886) (xy 435.306498 -371.967019) (xy 435.299993 -371.984219)
			(xy 435.299612 -371.993414) (xy 435.299612 -372.486682) (xy 435.300028 -372.495869) (xy 435.306537 -372.513053)
			(xy 435.312312 -372.52021) (xy 435.334135 -372.545834) (xy 435.372086 -372.601423) (xy 435.40312 -372.66115)
			(xy 435.426793 -372.724159) (xy 435.442765 -372.789545) (xy 435.450807 -372.856371) (xy 435.450804 -372.92368)
			(xy 435.442756 -372.990506) (xy 435.426778 -373.05589) (xy 435.403099 -373.118896) (xy 435.372059 -373.178621)
			(xy 435.334103 -373.234206) (xy 435.312312 -373.259858) (xy 435.30651 -373.266999) (xy 435.299998 -373.284193)
			(xy 435.299612 -373.293386) (xy 435.299612 -373.451374) (xy 435.299213 -373.46155) (xy 435.291428 -373.480354)
			(xy 435.277034 -373.494741) (xy 435.258226 -373.502518) (xy 435.24805 -373.502936) (xy 434.53177 -373.502936)
			(xy 434.521607 -373.502491) (xy 434.502832 -373.494701) (xy 434.488467 -373.480321) (xy 434.480698 -373.461537)
			(xy 434.480208 -373.451374) (xy 434.480208 -373.293386) (xy 434.479803 -373.284198) (xy 434.473286 -373.267014)
			(xy 434.467508 -373.259858) (xy 434.445755 -373.234178) (xy 434.407807 -373.178595) (xy 434.376774 -373.118875)
			(xy 434.3531 -373.055874) (xy 434.337126 -372.990495) (xy 434.32908 -372.923676) (xy 434.329077 -372.856375)
			(xy 434.337117 -372.789555) (xy 434.353085 -372.724175) (xy 434.376753 -372.661172) (xy 434.40778 -372.601449)
			(xy 434.445723 -372.545863) (xy 434.467508 -372.52021) (xy 434.473326 -372.51308) (xy 434.479828 -372.495878)
			(xy 434.480208 -372.486682) (xy 434.480208 -371.993414) (xy 434.479789 -371.984228) (xy 434.473281 -371.967043)
			(xy 434.467508 -371.959886) (xy 434.445684 -371.934264) (xy 434.407738 -371.878673) (xy 434.376708 -371.818945)
			(xy 434.353039 -371.755936) (xy 434.33707 -371.690551) (xy 434.329029 -371.623725) (xy 433.226383 -371.623725)
			(xy 433.226618 -371.62435) (xy 433.24259 -371.689734) (xy 433.250633 -371.756557) (xy 433.250632 -371.823864)
			(xy 433.242586 -371.890687) (xy 433.226612 -371.95607) (xy 433.202938 -372.019075) (xy 433.171903 -372.078799)
			(xy 433.133953 -372.134386) (xy 433.112164 -372.160038) (xy 433.106364 -372.167181) (xy 433.099852 -372.184373)
			(xy 433.099464 -372.193566) (xy 433.099464 -372.351554) (xy 433.098999 -372.361722) (xy 433.091229 -372.380516)
			(xy 433.076856 -372.394902) (xy 433.05807 -372.402689) (xy 433.047902 -372.403116) (xy 432.331622 -372.403116)
			(xy 432.321446 -372.402717) (xy 432.302643 -372.394931) (xy 432.288256 -372.380537) (xy 432.280478 -372.36173)
			(xy 432.28006 -372.351554) (xy 432.28006 -372.193566) (xy 432.279653 -372.184379) (xy 432.273135 -372.167195)
			(xy 432.26736 -372.160038) (xy 432.245586 -372.134375) (xy 432.207635 -372.07879) (xy 432.1766 -372.019069)
			(xy 432.152925 -371.956065) (xy 432.136951 -371.890684) (xy 432.128905 -371.823863) (xy 432.128904 -371.756558)
			(xy 432.136947 -371.689736) (xy 432.152919 -371.624355) (xy 432.176591 -371.561351) (xy 432.207624 -371.501628)
			(xy 432.245573 -371.446042) (xy 432.26736 -371.42039) (xy 432.273151 -371.413241) (xy 432.279667 -371.396053)
			(xy 432.28006 -371.386862) (xy 432.28006 -370.89334) (xy 432.279617 -370.884157) (xy 432.273125 -370.866972)
			(xy 432.26736 -370.859812) (xy 432.24556 -370.83417) (xy 432.20761 -370.778582) (xy 432.176576 -370.718858)
			(xy 432.152903 -370.655852) (xy 432.136931 -370.590468) (xy 432.128887 -370.523644) (xy 428.850825 -370.523644)
			(xy 428.842782 -370.590464) (xy 428.826811 -370.655846) (xy 428.80314 -370.71885) (xy 428.772109 -370.778573)
			(xy 428.734163 -370.83416) (xy 428.712376 -370.859812) (xy 428.706589 -370.866964) (xy 428.700069 -370.884149)
			(xy 428.699676 -370.89334) (xy 428.699676 -371.386862) (xy 428.70011 -371.396047) (xy 428.706608 -371.413231)
			(xy 428.712376 -371.42039) (xy 428.734177 -371.446031) (xy 428.772125 -371.501619) (xy 428.803156 -371.561345)
			(xy 428.826615 -371.623785) (xy 429.928709 -371.623785) (xy 429.928713 -371.556358) (xy 429.936793 -371.489417)
			(xy 429.952833 -371.423925) (xy 429.976602 -371.360827) (xy 430.007759 -371.30103) (xy 430.045853 -371.245395)
			(xy 430.06772 -371.21973) (xy 430.073531 -371.212595) (xy 430.080036 -371.195397) (xy 430.08042 -371.186202)
			(xy 430.08042 -371.028722) (xy 430.080944 -371.018599) (xy 430.088661 -370.999882) (xy 430.102935 -370.985526)
			(xy 430.121608 -370.977702) (xy 430.131728 -370.97716) (xy 430.848008 -370.97716) (xy 430.858158 -370.977614)
			(xy 430.876902 -370.985405) (xy 430.891224 -370.999791) (xy 430.898931 -371.018571) (xy 430.899316 -371.028722)
			(xy 430.899316 -371.186202) (xy 430.899722 -371.19539) (xy 430.906238 -371.212574) (xy 430.912016 -371.21973)
			(xy 430.933842 -371.245426) (xy 430.971931 -371.301057) (xy 431.003082 -371.360849) (xy 431.026848 -371.423942)
			(xy 431.042886 -371.489427) (xy 431.050964 -371.556361) (xy 431.050968 -371.623782) (xy 431.042896 -371.690717)
			(xy 431.026865 -371.756204) (xy 431.003106 -371.819299) (xy 430.97196 -371.879094) (xy 430.933877 -371.934729)
			(xy 430.912016 -371.960394) (xy 430.906241 -371.967555) (xy 430.899713 -371.984733) (xy 430.899316 -371.993922)
			(xy 430.899316 -372.486174) (xy 430.899735 -372.49536) (xy 430.906242 -372.512545) (xy 430.912016 -372.519702)
			(xy 430.933913 -372.54534) (xy 430.971999 -372.600979) (xy 431.003148 -372.660779) (xy 431.026909 -372.723879)
			(xy 431.042942 -372.789371) (xy 431.051015 -372.856313) (xy 431.051012 -372.923739) (xy 431.042933 -372.990679)
			(xy 431.026894 -373.05617) (xy 431.003127 -373.119268) (xy 430.971973 -373.179065) (xy 430.933881 -373.2347)
			(xy 430.912016 -373.260366) (xy 430.906211 -373.267505) (xy 430.899701 -373.2847) (xy 430.899316 -373.293894)
			(xy 430.899316 -373.451374) (xy 430.898851 -373.461504) (xy 430.891124 -373.480233) (xy 430.87683 -373.494592)
			(xy 430.858136 -373.502405) (xy 430.848008 -373.502936) (xy 430.131728 -373.502936) (xy 430.12158 -373.502456)
			(xy 430.102835 -373.494677) (xy 430.088512 -373.480298) (xy 430.080805 -373.461523) (xy 430.08042 -373.451374)
			(xy 430.08042 -373.293894) (xy 430.080008 -373.284707) (xy 430.073495 -373.267523) (xy 430.06772 -373.260366)
			(xy 430.045889 -373.234674) (xy 430.007798 -373.179043) (xy 429.976644 -373.119251) (xy 429.952877 -373.056158)
			(xy 429.936839 -372.990672) (xy 429.92876 -372.923736) (xy 429.928757 -372.856315) (xy 429.93683 -372.789379)
			(xy 429.952862 -372.723891) (xy 429.976624 -372.660796) (xy 430.007771 -372.601) (xy 430.045857 -372.545367)
			(xy 430.06772 -372.519702) (xy 430.073501 -372.512546) (xy 430.080024 -372.495364) (xy 430.08042 -372.486174)
			(xy 430.08042 -371.993922) (xy 430.079995 -371.984737) (xy 430.073491 -371.967552) (xy 430.06772 -371.960394)
			(xy 430.045818 -371.93476) (xy 430.007729 -371.879121) (xy 429.976579 -371.819321) (xy 429.952816 -371.75622)
			(xy 429.936783 -371.690727) (xy 429.928709 -371.623785) (xy 428.826615 -371.623785) (xy 428.826828 -371.624351)
			(xy 428.842799 -371.689734) (xy 428.850842 -371.756558) (xy 428.850841 -371.823863) (xy 428.842795 -371.890687)
			(xy 428.826821 -371.95607) (xy 428.803148 -372.019075) (xy 428.772114 -372.078799) (xy 428.734164 -372.134386)
			(xy 428.712376 -372.160038) (xy 428.706578 -372.167182) (xy 428.700065 -372.184374) (xy 428.699676 -372.193566)
			(xy 428.699676 -372.351554) (xy 428.699199 -372.361721) (xy 428.691432 -372.380512) (xy 428.677062 -372.394898)
			(xy 428.65828 -372.402687) (xy 428.648114 -372.403116) (xy 427.931834 -372.403116) (xy 427.921659 -372.402707)
			(xy 427.902856 -372.394925) (xy 427.888469 -372.380534) (xy 427.880691 -372.361729) (xy 427.880272 -372.351554)
			(xy 427.880272 -372.193566) (xy 427.879884 -372.184376) (xy 427.873356 -372.167192) (xy 427.867572 -372.160038)
			(xy 427.845797 -372.134375) (xy 427.807846 -372.078791) (xy 427.77681 -372.019069) (xy 427.753135 -371.956066)
			(xy 427.73716 -371.890685) (xy 427.729114 -371.823863) (xy 427.729113 -371.756558) (xy 427.737156 -371.689736)
			(xy 427.753129 -371.624354) (xy 427.776801 -371.56135) (xy 427.807835 -371.501627) (xy 427.845784 -371.446042)
			(xy 427.867572 -371.42039) (xy 427.873364 -371.413242) (xy 427.879879 -371.396053) (xy 427.880272 -371.386862)
			(xy 427.880272 -370.89334) (xy 427.879849 -370.884154) (xy 427.873345 -370.866969) (xy 427.867572 -370.859812)
			(xy 427.845772 -370.83417) (xy 427.807821 -370.778583) (xy 427.776786 -370.718858) (xy 427.753113 -370.655852)
			(xy 427.73714 -370.590468) (xy 427.729096 -370.523644) (xy 424.451056 -370.523644) (xy 424.451056 -370.523703)
			(xy 424.442981 -370.59064) (xy 424.426947 -370.656129) (xy 424.403183 -370.719225) (xy 424.372033 -370.779021)
			(xy 424.333944 -370.834655) (xy 424.31208 -370.86032) (xy 424.30629 -370.86747) (xy 424.299772 -370.884657)
			(xy 424.29938 -370.893848) (xy 424.29938 -371.386354) (xy 424.299817 -371.395538) (xy 424.306312 -371.412723)
			(xy 424.31208 -371.419882) (xy 424.333958 -371.445536) (xy 424.372048 -371.501171) (xy 424.403199 -371.560969)
			(xy 424.426835 -371.623725) (xy 425.528941 -371.623725) (xy 425.528945 -371.556418) (xy 425.536992 -371.489593)
			(xy 425.552969 -371.424208) (xy 425.576645 -371.361202) (xy 425.607682 -371.301478) (xy 425.645634 -371.24589)
			(xy 425.667424 -371.220238) (xy 425.673232 -371.213101) (xy 425.679739 -371.195904) (xy 425.680124 -371.18671)
			(xy 425.680124 -371.028722) (xy 425.680582 -371.018554) (xy 425.688357 -370.999762) (xy 425.702732 -370.985377)
			(xy 425.721518 -370.977589) (xy 425.731686 -370.97716) (xy 426.447966 -370.97716) (xy 426.458138 -370.977592)
			(xy 426.476936 -370.98537) (xy 426.491323 -370.999754) (xy 426.499105 -371.01855) (xy 426.499528 -371.028722)
			(xy 426.499528 -371.18671) (xy 426.499927 -371.195898) (xy 426.506448 -371.213083) (xy 426.512228 -371.220238)
			(xy 426.533979 -371.24592) (xy 426.571931 -371.301502) (xy 426.602968 -371.361221) (xy 426.626645 -371.424221)
			(xy 426.642621 -371.4896) (xy 426.650669 -371.55642) (xy 426.650672 -371.623723) (xy 426.642631 -371.690543)
			(xy 426.626661 -371.755924) (xy 426.602991 -371.818927) (xy 426.571961 -371.878649) (xy 426.534014 -371.934234)
			(xy 426.512228 -371.959886) (xy 426.506404 -371.967011) (xy 426.499908 -371.984217) (xy 426.499528 -371.993414)
			(xy 426.499528 -372.486682) (xy 426.49994 -372.495869) (xy 426.506452 -372.513054) (xy 426.512228 -372.52021)
			(xy 426.53405 -372.545834) (xy 426.572 -372.601424) (xy 426.603034 -372.661151) (xy 426.626706 -372.724159)
			(xy 426.642678 -372.789545) (xy 426.65072 -372.856371) (xy 426.650717 -372.92368) (xy 426.642669 -372.990505)
			(xy 426.626691 -373.05589) (xy 426.603013 -373.118896) (xy 426.571974 -373.17862) (xy 426.534019 -373.234206)
			(xy 426.512228 -373.259858) (xy 426.506416 -373.266992) (xy 426.499912 -373.284191) (xy 426.499528 -373.293386)
			(xy 426.499528 -373.451374) (xy 426.499114 -373.461548) (xy 426.491331 -373.480349) (xy 426.476942 -373.494736)
			(xy 426.45814 -373.502515) (xy 426.447966 -373.502936) (xy 425.731686 -373.502936) (xy 425.72151 -373.502547)
			(xy 425.70271 -373.494752) (xy 425.688325 -373.480356) (xy 425.680545 -373.46155) (xy 425.680124 -373.451374)
			(xy 425.680124 -373.293386) (xy 425.679715 -373.284199) (xy 425.6732 -373.267015) (xy 425.667424 -373.259858)
			(xy 425.64567 -373.234178) (xy 425.607722 -373.178595) (xy 425.576688 -373.118875) (xy 425.553014 -373.055874)
			(xy 425.537039 -372.990496) (xy 425.528992 -372.923677) (xy 425.528989 -372.856375) (xy 425.53703 -372.789555)
			(xy 425.552999 -372.724174) (xy 425.576667 -372.661171) (xy 425.607695 -372.601449) (xy 425.645639 -372.545863)
			(xy 425.667424 -372.52021) (xy 425.673244 -372.513082) (xy 425.679744 -372.495878) (xy 425.680124 -372.486682)
			(xy 425.680124 -371.993414) (xy 425.679702 -371.984228) (xy 425.673196 -371.967044) (xy 425.667424 -371.959886)
			(xy 425.645599 -371.934264) (xy 425.607653 -371.878673) (xy 425.576622 -371.818945) (xy 425.552952 -371.755937)
			(xy 425.536982 -371.690551) (xy 425.528941 -371.623725) (xy 424.426835 -371.623725) (xy 424.426964 -371.624067)
			(xy 424.442999 -371.689558) (xy 424.451074 -371.756498) (xy 424.451072 -371.823923) (xy 424.442995 -371.890863)
			(xy 424.426957 -371.956353) (xy 424.403191 -372.01945) (xy 424.372037 -372.079247) (xy 424.333946 -372.134881)
			(xy 424.31208 -372.160546) (xy 424.306279 -372.167688) (xy 424.299768 -372.184881) (xy 424.29938 -372.194074)
			(xy 424.29938 -372.351554) (xy 424.298836 -372.361675) (xy 424.291127 -372.380392) (xy 424.276858 -372.394749)
			(xy 424.25819 -372.402573) (xy 424.248072 -372.403116) (xy 423.531792 -372.403116) (xy 423.521685 -372.402622)
			(xy 423.50301 -372.394884) (xy 423.488716 -372.38059) (xy 423.480978 -372.361915) (xy 423.480484 -372.351808)
			(xy 423.480484 -372.194074) (xy 423.48009 -372.184885) (xy 423.473565 -372.167701) (xy 423.467784 -372.160546)
			(xy 423.445934 -372.134869) (xy 423.407846 -372.079236) (xy 423.376696 -372.019441) (xy 423.352932 -371.956346)
			(xy 423.336896 -371.890858) (xy 423.328819 -371.823922) (xy 423.328818 -371.756499) (xy 423.336892 -371.689562)
			(xy 423.352925 -371.624074) (xy 423.376687 -371.560978) (xy 423.407835 -371.501182) (xy 423.445921 -371.445547)
			(xy 423.467784 -371.419882) (xy 423.473569 -371.412728) (xy 423.480091 -371.395544) (xy 423.480484 -371.386354)
			(xy 423.480484 -370.893848) (xy 423.480055 -370.884663) (xy 423.473555 -370.867478) (xy 423.467784 -370.86032)
			(xy 423.445909 -370.834664) (xy 423.407821 -370.779028) (xy 423.376672 -370.71923) (xy 423.352909 -370.656132)
			(xy 423.336875 -370.590642) (xy 423.328801 -370.523703) (xy 420.05073 -370.523703) (xy 420.042694 -370.590464)
			(xy 420.026724 -370.655845) (xy 420.003054 -370.718849) (xy 419.972023 -370.778573) (xy 419.934078 -370.834159)
			(xy 419.912292 -370.859812) (xy 419.906507 -370.866965) (xy 419.899986 -370.88415) (xy 419.899592 -370.89334)
			(xy 419.899592 -371.386862) (xy 419.900022 -371.396047) (xy 419.906522 -371.413231) (xy 419.912292 -371.42039)
			(xy 419.934093 -371.446031) (xy 419.972039 -371.50162) (xy 420.00307 -371.561345) (xy 420.026528 -371.623785)
			(xy 421.128621 -371.623785) (xy 421.128625 -371.556358) (xy 421.136705 -371.489416) (xy 421.152746 -371.423925)
			(xy 421.176516 -371.360826) (xy 421.207673 -371.301029) (xy 421.245769 -371.245395) (xy 421.267636 -371.21973)
			(xy 421.273449 -371.212597) (xy 421.279953 -371.195397) (xy 421.280336 -371.186202) (xy 421.280336 -371.028722)
			(xy 421.280844 -371.018597) (xy 421.288564 -370.999877) (xy 421.302844 -370.98552) (xy 421.321522 -370.9777)
			(xy 421.331644 -370.97716) (xy 422.047924 -370.97716) (xy 422.058029 -370.977664) (xy 422.076701 -370.985402)
			(xy 422.090993 -370.999693) (xy 422.098734 -371.018363) (xy 422.099232 -371.028468) (xy 422.099232 -371.186202)
			(xy 422.099656 -371.195387) (xy 422.106162 -371.212571) (xy 422.111932 -371.21973) (xy 422.133758 -371.245427)
			(xy 422.171845 -371.301057) (xy 422.202996 -371.36085) (xy 422.226761 -371.423942) (xy 422.242798 -371.489427)
			(xy 422.250876 -371.556361) (xy 422.25088 -371.623781) (xy 422.242808 -371.690717) (xy 422.226778 -371.756203)
			(xy 422.203019 -371.819298) (xy 422.171875 -371.879094) (xy 422.133793 -371.934728) (xy 422.111932 -371.960394)
			(xy 422.106147 -371.967547) (xy 422.099627 -371.984732) (xy 422.099232 -371.993922) (xy 422.099232 -372.486174)
			(xy 422.09967 -372.495358) (xy 422.106166 -372.512542) (xy 422.111932 -372.519702) (xy 422.133828 -372.54534)
			(xy 422.171914 -372.600979) (xy 422.203061 -372.66078) (xy 422.226822 -372.72388) (xy 422.242854 -372.789372)
			(xy 422.250927 -372.856313) (xy 422.250924 -372.923738) (xy 422.242845 -372.990678) (xy 422.226807 -373.056169)
			(xy 422.20304 -373.119267) (xy 422.171888 -373.179064) (xy 422.133797 -373.2347) (xy 422.111932 -373.260366)
			(xy 422.106117 -373.267498) (xy 422.099615 -373.284699) (xy 422.099232 -373.293894) (xy 422.099232 -373.451374)
			(xy 422.098751 -373.461503) (xy 422.091027 -373.480228) (xy 422.076738 -373.494587) (xy 422.05805 -373.502402)
			(xy 422.047924 -373.502936) (xy 421.331644 -373.502936) (xy 421.321529 -373.502449) (xy 421.302833 -373.494722)
			(xy 421.288519 -373.480427) (xy 421.280765 -373.461743) (xy 421.280336 -373.451628) (xy 421.280336 -373.293894)
			(xy 421.279921 -373.284708) (xy 421.27341 -373.267524) (xy 421.267636 -373.260366) (xy 421.245804 -373.234674)
			(xy 421.207712 -373.179044) (xy 421.176558 -373.119252) (xy 421.15279 -373.056158) (xy 421.136751 -372.990672)
			(xy 421.128672 -372.923736) (xy 421.128669 -372.856315) (xy 421.136742 -372.789378) (xy 421.152775 -372.72389)
			(xy 421.176537 -372.660795) (xy 421.207686 -372.601) (xy 421.245773 -372.545367) (xy 421.267636 -372.519702)
			(xy 421.273419 -372.512547) (xy 421.279941 -372.495364) (xy 421.280336 -372.486174) (xy 421.280336 -371.993922)
			(xy 421.279907 -371.984737) (xy 421.273406 -371.967553) (xy 421.267636 -371.960394) (xy 421.245733 -371.93476)
			(xy 421.207643 -371.879122) (xy 421.176492 -371.819322) (xy 421.152729 -371.756221) (xy 421.136695 -371.690727)
			(xy 421.128621 -371.623785) (xy 420.026528 -371.623785) (xy 420.026741 -371.624351) (xy 420.042712 -371.689734)
			(xy 420.050754 -371.756558) (xy 420.050753 -371.823863) (xy 420.042708 -371.890686) (xy 420.026734 -371.956069)
			(xy 420.003061 -372.019074) (xy 419.972028 -372.078798) (xy 419.93408 -372.134385) (xy 419.912292 -372.160038)
			(xy 419.906496 -372.167183) (xy 419.899981 -372.184374) (xy 419.899592 -372.193566) (xy 419.899592 -372.351554)
			(xy 419.899099 -372.361719) (xy 419.891335 -372.380507) (xy 419.876971 -372.394892) (xy 419.858194 -372.402684)
			(xy 419.84803 -372.403116) (xy 419.13175 -372.403116) (xy 419.121576 -372.402694) (xy 419.102773 -372.394917)
			(xy 419.088385 -372.38053) (xy 419.080607 -372.361728) (xy 419.080188 -372.351554) (xy 419.080188 -372.193566)
			(xy 419.079797 -372.184377) (xy 419.07327 -372.167192) (xy 419.067488 -372.160038) (xy 419.045713 -372.134375)
			(xy 419.00776 -372.078791) (xy 418.976724 -372.01907) (xy 418.953048 -371.956067) (xy 418.937072 -371.890685)
			(xy 418.929026 -371.823863) (xy 418.929025 -371.756558) (xy 418.937069 -371.689736) (xy 418.953042 -371.624354)
			(xy 418.976715 -371.561349) (xy 419.007749 -371.501627) (xy 419.0457 -371.446041) (xy 419.067488 -371.42039)
			(xy 419.07327 -371.413234) (xy 419.079794 -371.396052) (xy 419.080188 -371.386862) (xy 419.080188 -370.89334)
			(xy 419.079761 -370.884154) (xy 419.07326 -370.86697) (xy 419.067488 -370.859812) (xy 419.045687 -370.83417)
			(xy 419.007735 -370.778583) (xy 418.9767 -370.718859) (xy 418.953026 -370.655853) (xy 418.937052 -370.590469)
			(xy 418.929008 -370.523644) (xy 389.250706 -370.523644) (xy 389.242663 -370.590465) (xy 389.226691 -370.655847)
			(xy 389.203019 -370.718851) (xy 389.171987 -370.778574) (xy 389.134039 -370.83416) (xy 389.112252 -370.859812)
			(xy 389.106462 -370.866962) (xy 389.099945 -370.884149) (xy 389.099552 -370.89334) (xy 389.099552 -371.386862)
			(xy 389.099991 -371.396046) (xy 389.106486 -371.41323) (xy 389.112252 -371.42039) (xy 389.134054 -371.446031)
			(xy 389.172003 -371.501618) (xy 389.203036 -371.561344) (xy 389.226474 -371.623725) (xy 390.32912 -371.623725)
			(xy 390.329123 -371.556418) (xy 390.337171 -371.489593) (xy 390.353146 -371.42421) (xy 390.376822 -371.361204)
			(xy 390.407857 -371.301479) (xy 390.445807 -371.245891) (xy 390.467596 -371.220238) (xy 390.473401 -371.213099)
			(xy 390.479911 -371.195904) (xy 390.480296 -371.18671) (xy 390.480296 -371.028722) (xy 390.48085 -371.018571)
			(xy 390.48861 -370.99981) (xy 390.502956 -370.985446) (xy 390.521707 -370.977663) (xy 390.531858 -370.97716)
			(xy 391.248138 -370.97716) (xy 391.258301 -370.977603) (xy 391.277075 -370.985394) (xy 391.29144 -370.999775)
			(xy 391.299209 -371.018558) (xy 391.2997 -371.028722) (xy 391.2997 -371.18671) (xy 391.300106 -371.195898)
			(xy 391.306623 -371.213082) (xy 391.3124 -371.220238) (xy 391.334149 -371.245921) (xy 391.372097 -371.301504)
			(xy 391.403129 -371.361224) (xy 391.426803 -371.424224) (xy 391.442777 -371.489602) (xy 391.450824 -371.556421)
			(xy 391.450827 -371.623722) (xy 391.442787 -371.690541) (xy 391.42682 -371.755921) (xy 391.403153 -371.818924)
			(xy 391.372126 -371.878647) (xy 391.334184 -371.934233) (xy 391.3124 -371.959886) (xy 391.306584 -371.967018)
			(xy 391.300081 -371.984219) (xy 391.2997 -371.993414) (xy 391.2997 -372.486682) (xy 391.300119 -372.495868)
			(xy 391.306627 -372.513053) (xy 391.3124 -372.52021) (xy 391.33422 -372.545835) (xy 391.372165 -372.601426)
			(xy 391.403195 -372.661154) (xy 391.426864 -372.724162) (xy 391.442833 -372.789547) (xy 391.450874 -372.856372)
			(xy 391.450871 -372.923679) (xy 391.442824 -372.990503) (xy 391.426849 -373.055887) (xy 391.403174 -373.118893)
			(xy 391.372139 -373.178617) (xy 391.334189 -373.234205) (xy 391.3124 -373.259858) (xy 391.306596 -373.266998)
			(xy 391.300086 -373.284193) (xy 391.2997 -373.293386) (xy 391.2997 -373.451374) (xy 391.299146 -373.461525)
			(xy 391.291388 -373.480287) (xy 391.277041 -373.494652) (xy 391.258289 -373.502434) (xy 391.248138 -373.502936)
			(xy 390.531858 -373.502936) (xy 390.521694 -373.5025) (xy 390.502919 -373.494707) (xy 390.488555 -373.480324)
			(xy 390.480786 -373.461538) (xy 390.480296 -373.451374) (xy 390.480296 -373.293386) (xy 390.479893 -373.284198)
			(xy 390.473374 -373.267014) (xy 390.467596 -373.259858) (xy 390.445843 -373.234178) (xy 390.407896 -373.178594)
			(xy 390.376864 -373.118874) (xy 390.353191 -373.055874) (xy 390.337217 -372.990495) (xy 390.329171 -372.923676)
			(xy 390.329167 -372.856375) (xy 390.337208 -372.789555) (xy 390.353176 -372.724175) (xy 390.376843 -372.661173)
			(xy 390.40787 -372.60145) (xy 390.445812 -372.545863) (xy 390.467596 -372.52021) (xy 390.473413 -372.513079)
			(xy 390.479916 -372.495878) (xy 390.480296 -372.486682) (xy 390.480296 -371.993414) (xy 390.47988 -371.984227)
			(xy 390.47337 -371.967043) (xy 390.467596 -371.959886) (xy 390.445772 -371.934264) (xy 390.407827 -371.878672)
			(xy 390.376798 -371.818944) (xy 390.353129 -371.755936) (xy 390.33716 -371.69055) (xy 390.32912 -371.623725)
			(xy 389.226474 -371.623725) (xy 389.226709 -371.62435) (xy 389.242681 -371.689733) (xy 389.250724 -371.756557)
			(xy 389.250723 -371.823864) (xy 389.242677 -371.890687) (xy 389.226702 -371.956071) (xy 389.203028 -372.019076)
			(xy 389.171992 -372.0788) (xy 389.134041 -372.134386) (xy 389.112252 -372.160038) (xy 389.106451 -372.16718)
			(xy 389.09994 -372.184373) (xy 389.099552 -372.193566) (xy 389.099552 -372.351554) (xy 389.099098 -372.361724)
			(xy 389.091327 -372.380519) (xy 389.07695 -372.394906) (xy 389.05816 -372.402691) (xy 389.04799 -372.403116)
			(xy 388.33171 -372.403116) (xy 388.321533 -372.402727) (xy 388.30273 -372.394937) (xy 388.288343 -372.38054)
			(xy 388.280566 -372.361731) (xy 388.280148 -372.351554) (xy 388.280148 -372.193566) (xy 388.279743 -372.184378)
			(xy 388.273225 -372.167195) (xy 388.267448 -372.160038) (xy 388.245674 -372.134375) (xy 388.207724 -372.07879)
			(xy 388.17669 -372.019068) (xy 388.153016 -371.956065) (xy 388.137042 -371.890684) (xy 388.128996 -371.823863)
			(xy 388.128995 -371.756558) (xy 388.137038 -371.689737) (xy 388.15301 -371.624355) (xy 388.176681 -371.561351)
			(xy 388.207713 -371.501628) (xy 388.245661 -371.446042) (xy 388.267448 -371.42039) (xy 388.273237 -371.41324)
			(xy 388.279755 -371.396053) (xy 388.280148 -371.386862) (xy 388.280148 -370.89334) (xy 388.279708 -370.884156)
			(xy 388.273214 -370.866972) (xy 388.267448 -370.859812) (xy 388.245648 -370.83417) (xy 388.207699 -370.778582)
			(xy 388.176666 -370.718857) (xy 388.152993 -370.655851) (xy 388.137021 -370.590468) (xy 388.128977 -370.523644)
			(xy 384.850915 -370.523644) (xy 384.842872 -370.590465) (xy 384.826901 -370.655846) (xy 384.80323 -370.71885)
			(xy 384.772198 -370.778573) (xy 384.734251 -370.83416) (xy 384.712464 -370.859812) (xy 384.706675 -370.866963)
			(xy 384.700157 -370.884149) (xy 384.699764 -370.89334) (xy 384.699764 -371.386862) (xy 384.700201 -371.396046)
			(xy 384.706697 -371.41323) (xy 384.712464 -371.42039) (xy 384.734266 -371.446031) (xy 384.772214 -371.501619)
			(xy 384.803246 -371.561344) (xy 384.826706 -371.623785) (xy 385.9288 -371.623785) (xy 385.928804 -371.556358)
			(xy 385.936884 -371.489417) (xy 385.952923 -371.423926) (xy 385.976692 -371.360827) (xy 386.007848 -371.30103)
			(xy 386.045941 -371.245395) (xy 386.067808 -371.21973) (xy 386.073618 -371.212594) (xy 386.080124 -371.195396)
			(xy 386.080508 -371.186202) (xy 386.080508 -371.028722) (xy 386.081044 -371.018601) (xy 386.088758 -370.999886)
			(xy 386.103029 -370.98553) (xy 386.121698 -370.977704) (xy 386.131816 -370.97716) (xy 386.848096 -370.97716)
			(xy 386.858245 -370.977624) (xy 386.876989 -370.985411) (xy 386.891311 -370.999794) (xy 386.899019 -371.018571)
			(xy 386.899404 -371.028722) (xy 386.899404 -371.186202) (xy 386.899812 -371.195389) (xy 386.906327 -371.212574)
			(xy 386.912104 -371.21973) (xy 386.93393 -371.245426) (xy 386.97202 -371.301056) (xy 387.003172 -371.360848)
			(xy 387.026938 -371.423941) (xy 387.042976 -371.489426) (xy 387.051055 -371.556361) (xy 387.051059 -371.623782)
			(xy 387.042987 -371.690717) (xy 387.026955 -371.756204) (xy 387.003196 -371.8193) (xy 386.972049 -371.879095)
			(xy 386.933966 -371.934729) (xy 386.912104 -371.960394) (xy 386.906328 -371.967554) (xy 386.899801 -371.984733)
			(xy 386.899404 -371.993922) (xy 386.899404 -372.486174) (xy 386.899826 -372.49536) (xy 386.906331 -372.512545)
			(xy 386.912104 -372.519702) (xy 386.934001 -372.54534) (xy 386.972089 -372.600978) (xy 387.003238 -372.660778)
			(xy 387.027 -372.723879) (xy 387.043033 -372.789371) (xy 387.051106 -372.856312) (xy 387.051103 -372.923739)
			(xy 387.043024 -372.990679) (xy 387.026985 -373.05617) (xy 387.003217 -373.119268) (xy 386.972062 -373.179066)
			(xy 386.93397 -373.234701) (xy 386.912104 -373.260366) (xy 386.906297 -373.267504) (xy 386.899789 -373.2847)
			(xy 386.899404 -373.293894) (xy 386.899404 -373.451374) (xy 386.898854 -373.461494) (xy 386.891142 -373.480206)
			(xy 386.876876 -373.494562) (xy 386.858212 -373.50239) (xy 386.848096 -373.502936) (xy 386.131816 -373.502936)
			(xy 386.121667 -373.502466) (xy 386.102922 -373.494683) (xy 386.0886 -373.480301) (xy 386.080893 -373.461524)
			(xy 386.080508 -373.451374) (xy 386.080508 -373.293894) (xy 386.080099 -373.284707) (xy 386.073584 -373.267523)
			(xy 386.067808 -373.260366) (xy 386.045977 -373.234673) (xy 386.007887 -373.179043) (xy 385.976734 -373.119251)
			(xy 385.952968 -373.056157) (xy 385.93693 -372.990671) (xy 385.928851 -372.923736) (xy 385.928848 -372.856315)
			(xy 385.936921 -372.789379) (xy 385.952953 -372.723892) (xy 385.976713 -372.660796) (xy 386.007861 -372.601001)
			(xy 386.045946 -372.545367) (xy 386.067808 -372.519702) (xy 386.073587 -372.512544) (xy 386.080112 -372.495363)
			(xy 386.080508 -372.486174) (xy 386.080508 -371.993922) (xy 386.080085 -371.984736) (xy 386.07358 -371.967552)
			(xy 386.067808 -371.960394) (xy 386.045906 -371.93476) (xy 386.007818 -371.879121) (xy 385.976669 -371.819321)
			(xy 385.952906 -371.75622) (xy 385.936873 -371.690727) (xy 385.9288 -371.623785) (xy 384.826706 -371.623785)
			(xy 384.826918 -371.62435) (xy 384.84289 -371.689734) (xy 384.850933 -371.756557) (xy 384.850932 -371.823864)
			(xy 384.842886 -371.890687) (xy 384.826912 -371.95607) (xy 384.803238 -372.019075) (xy 384.772203 -372.078799)
			(xy 384.734253 -372.134386) (xy 384.712464 -372.160038) (xy 384.706664 -372.167181) (xy 384.700152 -372.184373)
			(xy 384.699764 -372.193566) (xy 384.699764 -372.351554) (xy 384.699299 -372.361722) (xy 384.691529 -372.380516)
			(xy 384.677156 -372.394902) (xy 384.65837 -372.402689) (xy 384.648202 -372.403116) (xy 383.931922 -372.403116)
			(xy 383.921746 -372.402717) (xy 383.902943 -372.394931) (xy 383.888556 -372.380537) (xy 383.880778 -372.36173)
			(xy 383.88036 -372.351554) (xy 383.88036 -372.193566) (xy 383.879953 -372.184379) (xy 383.873435 -372.167195)
			(xy 383.86766 -372.160038) (xy 383.845886 -372.134375) (xy 383.807935 -372.07879) (xy 383.7769 -372.019069)
			(xy 383.753225 -371.956065) (xy 383.737251 -371.890684) (xy 383.729205 -371.823863) (xy 383.729204 -371.756558)
			(xy 383.737247 -371.689736) (xy 383.753219 -371.624355) (xy 383.776891 -371.561351) (xy 383.807924 -371.501628)
			(xy 383.845873 -371.446042) (xy 383.86766 -371.42039) (xy 383.873451 -371.413241) (xy 383.879967 -371.396053)
			(xy 383.88036 -371.386862) (xy 383.88036 -370.89334) (xy 383.879917 -370.884157) (xy 383.873425 -370.866972)
			(xy 383.86766 -370.859812) (xy 383.84586 -370.83417) (xy 383.80791 -370.778582) (xy 383.776876 -370.718858)
			(xy 383.753203 -370.655852) (xy 383.737231 -370.590468) (xy 383.729187 -370.523644) (xy 380.451147 -370.523644)
			(xy 380.451147 -370.523703) (xy 380.443072 -370.590641) (xy 380.427037 -370.656129) (xy 380.403273 -370.719226)
			(xy 380.372122 -370.779022) (xy 380.334032 -370.834655) (xy 380.312168 -370.86032) (xy 380.306376 -370.867469)
			(xy 380.299859 -370.884657) (xy 380.299468 -370.893848) (xy 380.299468 -371.386354) (xy 380.299908 -371.395538)
			(xy 380.306402 -371.412722) (xy 380.312168 -371.419882) (xy 380.334047 -371.445535) (xy 380.372137 -371.501171)
			(xy 380.403289 -371.560968) (xy 380.426925 -371.623725) (xy 381.529032 -371.623725) (xy 381.529035 -371.556418)
			(xy 381.537083 -371.489593) (xy 381.553059 -371.424209) (xy 381.576735 -371.361203) (xy 381.607771 -371.301478)
			(xy 381.645723 -371.245891) (xy 381.667512 -371.220238) (xy 381.673319 -371.2131) (xy 381.679827 -371.195904)
			(xy 381.680212 -371.18671) (xy 381.680212 -371.028722) (xy 381.680751 -371.018569) (xy 381.688513 -370.999805)
			(xy 381.702865 -370.98544) (xy 381.721621 -370.97766) (xy 381.731774 -370.97716) (xy 382.448054 -370.97716)
			(xy 382.458225 -370.977602) (xy 382.477023 -370.985376) (xy 382.491411 -370.999757) (xy 382.499193 -371.018551)
			(xy 382.499616 -371.028722) (xy 382.499616 -371.18671) (xy 382.500018 -371.195898) (xy 382.506537 -371.213083)
			(xy 382.512316 -371.220238) (xy 382.534068 -371.24592) (xy 382.572021 -371.301501) (xy 382.603058 -371.36122)
			(xy 382.626735 -371.424221) (xy 382.642712 -371.4896) (xy 382.65076 -371.55642) (xy 382.650763 -371.623723)
			(xy 382.642722 -371.690544) (xy 382.626752 -371.755924) (xy 382.603081 -371.818927) (xy 382.57205 -371.87865)
			(xy 382.534103 -371.934234) (xy 382.512316 -371.959886) (xy 382.506502 -371.967019) (xy 382.499997 -371.984219)
			(xy 382.499616 -371.993414) (xy 382.499616 -372.486682) (xy 382.500031 -372.495869) (xy 382.506541 -372.513053)
			(xy 382.512316 -372.52021) (xy 382.534138 -372.545834) (xy 382.572089 -372.601424) (xy 382.603123 -372.661151)
			(xy 382.626796 -372.724159) (xy 382.642768 -372.789545) (xy 382.65081 -372.856371) (xy 382.650807 -372.92368)
			(xy 382.642759 -372.990506) (xy 382.626781 -373.05589) (xy 382.603103 -373.118896) (xy 382.572063 -373.17862)
			(xy 382.534107 -373.234206) (xy 382.512316 -373.259858) (xy 382.506514 -373.267) (xy 382.500002 -373.284193)
			(xy 382.499616 -373.293386) (xy 382.499616 -373.451374) (xy 382.499214 -373.46155) (xy 382.491429 -373.480352)
			(xy 382.477036 -373.49474) (xy 382.45823 -373.502517) (xy 382.448054 -373.502936) (xy 381.731774 -373.502936)
			(xy 381.721611 -373.502487) (xy 381.702837 -373.4947) (xy 381.688471 -373.48032) (xy 381.680702 -373.461537)
			(xy 381.680212 -373.451374) (xy 381.680212 -373.293386) (xy 381.679806 -373.284198) (xy 381.673289 -373.267014)
			(xy 381.667512 -373.259858) (xy 381.645758 -373.234178) (xy 381.60781 -373.178595) (xy 381.576777 -373.118875)
			(xy 381.553104 -373.055874) (xy 381.537129 -372.990496) (xy 381.529083 -372.923676) (xy 381.52908 -372.856375)
			(xy 381.53712 -372.789555) (xy 381.553088 -372.724175) (xy 381.576756 -372.661172) (xy 381.607784 -372.601449)
			(xy 381.645727 -372.545862) (xy 381.667512 -372.52021) (xy 381.673331 -372.51308) (xy 381.679832 -372.495878)
			(xy 381.680212 -372.486682) (xy 381.680212 -371.993414) (xy 381.679792 -371.984228) (xy 381.673285 -371.967044)
			(xy 381.667512 -371.959886) (xy 381.645688 -371.934264) (xy 381.607742 -371.878673) (xy 381.576712 -371.818945)
			(xy 381.553042 -371.755936) (xy 381.537073 -371.690551) (xy 381.529032 -371.623725) (xy 380.426925 -371.623725)
			(xy 380.427054 -371.624067) (xy 380.443089 -371.689558) (xy 380.451165 -371.756498) (xy 380.451163 -371.823923)
			(xy 380.443086 -371.890863) (xy 380.427048 -371.956353) (xy 380.403281 -372.019451) (xy 380.372126 -372.079247)
			(xy 380.334034 -372.134881) (xy 380.312168 -372.160546) (xy 380.306365 -372.167687) (xy 380.299855 -372.184881)
			(xy 380.299468 -372.194074) (xy 380.299468 -372.351554) (xy 380.298936 -372.361677) (xy 380.291225 -372.380395)
			(xy 380.276952 -372.394753) (xy 380.25828 -372.402575) (xy 380.24816 -372.403116) (xy 379.53188 -372.403116)
			(xy 379.521727 -372.402695) (xy 379.502977 -372.394896) (xy 379.488655 -372.3805) (xy 379.480953 -372.36171)
			(xy 379.480572 -372.351554) (xy 379.480572 -372.194074) (xy 379.480181 -372.184885) (xy 379.473655 -372.1677)
			(xy 379.467872 -372.160546) (xy 379.446023 -372.134869) (xy 379.407935 -372.079235) (xy 379.376786 -372.019441)
			(xy 379.353022 -371.956345) (xy 379.336986 -371.890858) (xy 379.32891 -371.823922) (xy 379.328909 -371.7565)
			(xy 379.336983 -371.689563) (xy 379.353016 -371.624075) (xy 379.376777 -371.560979) (xy 379.407925 -371.501183)
			(xy 379.44601 -371.445548) (xy 379.467872 -371.419882) (xy 379.473667 -371.412736) (xy 379.480181 -371.395546)
			(xy 379.480572 -371.386354) (xy 379.480572 -370.893848) (xy 379.480145 -370.884663) (xy 379.473644 -370.867478)
			(xy 379.467872 -370.86032) (xy 379.445997 -370.834664) (xy 379.407911 -370.779027) (xy 379.376762 -370.71923)
			(xy 379.353 -370.656132) (xy 379.336966 -370.590642) (xy 379.328892 -370.523703) (xy 376.050821 -370.523703)
			(xy 376.042785 -370.590464) (xy 376.026814 -370.655846) (xy 376.003143 -370.71885) (xy 375.972113 -370.778573)
			(xy 375.934166 -370.83416) (xy 375.91238 -370.859812) (xy 375.906594 -370.866964) (xy 375.900073 -370.884149)
			(xy 375.89968 -370.89334) (xy 375.89968 -371.386862) (xy 375.900113 -371.396047) (xy 375.906611 -371.413231)
			(xy 375.91238 -371.42039) (xy 375.934181 -371.446031) (xy 375.972128 -371.50162) (xy 376.00316 -371.561345)
			(xy 376.026618 -371.623785) (xy 377.128712 -371.623785) (xy 377.128716 -371.556358) (xy 377.136796 -371.489417)
			(xy 377.152836 -371.423925) (xy 377.176606 -371.360827) (xy 377.207762 -371.301029) (xy 377.245857 -371.245395)
			(xy 377.267724 -371.21973) (xy 377.273536 -371.212596) (xy 377.28004 -371.195397) (xy 377.280424 -371.186202)
			(xy 377.280424 -371.028722) (xy 377.280944 -371.018599) (xy 377.288662 -370.999881) (xy 377.302938 -370.985524)
			(xy 377.321612 -370.977702) (xy 377.331732 -370.97716) (xy 378.048012 -370.97716) (xy 378.058162 -370.977611)
			(xy 378.076907 -370.985403) (xy 378.091229 -370.99979) (xy 378.098935 -371.01857) (xy 378.09932 -371.028722)
			(xy 378.09932 -371.186202) (xy 378.099725 -371.19539) (xy 378.106242 -371.212574) (xy 378.11202 -371.21973)
			(xy 378.133846 -371.245426) (xy 378.171934 -371.301057) (xy 378.203086 -371.360849) (xy 378.226851 -371.423942)
			(xy 378.242889 -371.489427) (xy 378.250967 -371.556361) (xy 378.250971 -371.623782) (xy 378.242899 -371.690717)
			(xy 378.226868 -371.756204) (xy 378.203109 -371.819299) (xy 378.171964 -371.879094) (xy 378.133881 -371.934728)
			(xy 378.11202 -371.960394) (xy 378.106246 -371.967555) (xy 378.099717 -371.984733) (xy 378.09932 -371.993922)
			(xy 378.09932 -372.486174) (xy 378.099738 -372.49536) (xy 378.106246 -372.512545) (xy 378.11202 -372.519702)
			(xy 378.133917 -372.54534) (xy 378.172003 -372.600979) (xy 378.203151 -372.660779) (xy 378.226913 -372.723879)
			(xy 378.242945 -372.789372) (xy 378.251018 -372.856313) (xy 378.251015 -372.923739) (xy 378.242936 -372.990679)
			(xy 378.226897 -373.056169) (xy 378.20313 -373.119268) (xy 378.171977 -373.179065) (xy 378.133885 -373.2347)
			(xy 378.11202 -373.260366) (xy 378.106215 -373.267506) (xy 378.099705 -373.2847) (xy 378.09932 -373.293894)
			(xy 378.09932 -373.451374) (xy 378.098851 -373.461504) (xy 378.091125 -373.480232) (xy 378.076832 -373.494591)
			(xy 378.05814 -373.502404) (xy 378.048012 -373.502936) (xy 377.331732 -373.502936) (xy 377.321584 -373.502453)
			(xy 377.30284 -373.494675) (xy 377.288516 -373.480297) (xy 377.280809 -373.461523) (xy 377.280424 -373.451374)
			(xy 377.280424 -373.293894) (xy 377.280012 -373.284707) (xy 377.273499 -373.267523) (xy 377.267724 -373.260366)
			(xy 377.245893 -373.234674) (xy 377.207801 -373.179044) (xy 377.176648 -373.119251) (xy 377.152881 -373.056158)
			(xy 377.136842 -372.990672) (xy 377.128763 -372.923736) (xy 377.12876 -372.856315) (xy 377.136833 -372.789378)
			(xy 377.152865 -372.723891) (xy 377.176627 -372.660795) (xy 377.207775 -372.601) (xy 377.245861 -372.545367)
			(xy 377.267724 -372.519702) (xy 377.273505 -372.512546) (xy 377.280028 -372.495364) (xy 377.280424 -372.486174)
			(xy 377.280424 -371.993922) (xy 377.279998 -371.984737) (xy 377.273495 -371.967552) (xy 377.267724 -371.960394)
			(xy 377.245822 -371.93476) (xy 377.207733 -371.879122) (xy 377.176582 -371.819321) (xy 377.152819 -371.75622)
			(xy 377.136786 -371.690727) (xy 377.128712 -371.623785) (xy 376.026618 -371.623785) (xy 376.026831 -371.624351)
			(xy 376.042802 -371.689734) (xy 376.050845 -371.756558) (xy 376.050844 -371.823863) (xy 376.042799 -371.890687)
			(xy 376.026825 -371.956069) (xy 376.003151 -372.019074) (xy 375.972117 -372.078799) (xy 375.934168 -372.134386)
			(xy 375.91238 -372.160038) (xy 375.906582 -372.167182) (xy 375.900069 -372.184374) (xy 375.89968 -372.193566)
			(xy 375.89968 -372.351554) (xy 375.899199 -372.36172) (xy 375.891432 -372.380511) (xy 375.877064 -372.394896)
			(xy 375.858284 -372.402686) (xy 375.848118 -372.403116) (xy 375.131838 -372.403116) (xy 375.121663 -372.402704)
			(xy 375.102861 -372.394923) (xy 375.088473 -372.380533) (xy 375.080695 -372.361729) (xy 375.080276 -372.351554)
			(xy 375.080276 -372.193566) (xy 375.079887 -372.184376) (xy 375.073359 -372.167192) (xy 375.067576 -372.160038)
			(xy 375.045801 -372.134375) (xy 375.007849 -372.078791) (xy 374.976813 -372.019069) (xy 374.953138 -371.956066)
			(xy 374.937163 -371.890685) (xy 374.929117 -371.823863) (xy 374.929116 -371.756558) (xy 374.937159 -371.689736)
			(xy 374.953132 -371.624354) (xy 374.976805 -371.56135) (xy 375.007838 -371.501627) (xy 375.045788 -371.446042)
			(xy 375.067576 -371.42039) (xy 375.073357 -371.413233) (xy 375.079882 -371.396052) (xy 375.080276 -371.386862)
			(xy 375.080276 -370.89334) (xy 375.079852 -370.884154) (xy 375.073349 -370.866969) (xy 375.067576 -370.859812)
			(xy 375.045775 -370.83417) (xy 375.007825 -370.778583) (xy 374.97679 -370.718858) (xy 374.953116 -370.655852)
			(xy 374.937143 -370.590469) (xy 374.929099 -370.523644) (xy 345.250797 -370.523644) (xy 345.242754 -370.590465)
			(xy 345.226782 -370.655847) (xy 345.203109 -370.718851) (xy 345.172076 -370.778574) (xy 345.134128 -370.83416)
			(xy 345.11234 -370.859812) (xy 345.106548 -370.86696) (xy 345.100032 -370.884149) (xy 345.09964 -370.89334)
			(xy 345.09964 -371.386862) (xy 345.100082 -371.396046) (xy 345.106575 -371.41323) (xy 345.11234 -371.42039)
			(xy 345.134142 -371.446031) (xy 345.172092 -371.501618) (xy 345.203126 -371.561343) (xy 345.226564 -371.623726)
			(xy 346.329187 -371.623726) (xy 346.32919 -371.556417) (xy 346.337239 -371.489591) (xy 346.353217 -371.424206)
			(xy 346.376896 -371.3612) (xy 346.407936 -371.301476) (xy 346.445893 -371.24589) (xy 346.467684 -371.220238)
			(xy 346.473488 -371.213098) (xy 346.479999 -371.195904) (xy 346.480384 -371.18671) (xy 346.480384 -371.028722)
			(xy 346.480783 -371.018546) (xy 346.488569 -370.999743) (xy 346.502963 -370.985356) (xy 346.52177 -370.977578)
			(xy 346.531946 -370.97716) (xy 347.248226 -370.97716) (xy 347.258388 -370.977612) (xy 347.277162 -370.9854)
			(xy 347.291527 -370.999778) (xy 347.299297 -371.018559) (xy 347.299788 -371.028722) (xy 347.299788 -371.18671)
			(xy 347.300196 -371.195897) (xy 347.306711 -371.213082) (xy 347.312488 -371.220238) (xy 347.334237 -371.245921)
			(xy 347.372185 -371.301504) (xy 347.403219 -371.361224) (xy 347.426893 -371.424224) (xy 347.442867 -371.489602)
			(xy 347.450914 -371.556421) (xy 347.450918 -371.623722) (xy 347.442878 -371.690542) (xy 347.426909 -371.755921)
			(xy 347.403242 -371.818924) (xy 347.372215 -371.878647) (xy 347.334272 -371.934233) (xy 347.312488 -371.959886)
			(xy 347.306671 -371.967017) (xy 347.300169 -371.984218) (xy 347.299788 -371.993414) (xy 347.299788 -372.486682)
			(xy 347.30021 -372.495868) (xy 347.306716 -372.513052) (xy 347.312488 -372.52021) (xy 347.334308 -372.545835)
			(xy 347.372254 -372.601426) (xy 347.403285 -372.661154) (xy 347.426954 -372.724162) (xy 347.442924 -372.789547)
			(xy 347.450965 -372.856372) (xy 347.450962 -372.923679) (xy 347.442915 -372.990504) (xy 347.426939 -373.055887)
			(xy 347.403264 -373.118893) (xy 347.372228 -373.178618) (xy 347.334277 -373.234205) (xy 347.312488 -373.259858)
			(xy 347.306683 -373.266997) (xy 347.300174 -373.284192) (xy 347.299788 -373.293386) (xy 347.299788 -373.451374)
			(xy 347.299246 -373.461527) (xy 347.291485 -373.480291) (xy 347.277134 -373.494656) (xy 347.258378 -373.502436)
			(xy 347.248226 -373.502936) (xy 346.531946 -373.502936) (xy 346.521774 -373.502498) (xy 346.502975 -373.494723)
			(xy 346.488588 -373.480341) (xy 346.480806 -373.461546) (xy 346.480384 -373.451374) (xy 346.480384 -373.293386)
			(xy 346.479984 -373.284198) (xy 346.473464 -373.267013) (xy 346.467684 -373.259858) (xy 346.445928 -373.234179)
			(xy 346.407976 -373.178597) (xy 346.376938 -373.118878) (xy 346.353262 -373.055877) (xy 346.337285 -372.990498)
			(xy 346.329237 -372.923677) (xy 346.329234 -372.856374) (xy 346.337276 -372.789553) (xy 346.353247 -372.724172)
			(xy 346.376917 -372.661169) (xy 346.407949 -372.601447) (xy 346.445897 -372.545862) (xy 346.467684 -372.52021)
			(xy 346.473499 -372.513078) (xy 346.480003 -372.495877) (xy 346.480384 -372.486682) (xy 346.480384 -371.993414)
			(xy 346.479971 -371.984227) (xy 346.47346 -371.967042) (xy 346.467684 -371.959886) (xy 346.445858 -371.934265)
			(xy 346.407907 -371.878675) (xy 346.376873 -371.818948) (xy 346.3532 -371.755939) (xy 346.337229 -371.690553)
			(xy 346.329187 -371.623726) (xy 345.226564 -371.623726) (xy 345.226798 -371.624349) (xy 345.242771 -371.689733)
			(xy 345.250814 -371.756557) (xy 345.250813 -371.823864) (xy 345.242767 -371.890688) (xy 345.226792 -371.956071)
			(xy 345.203117 -372.019076) (xy 345.172081 -372.0788) (xy 345.134129 -372.134386) (xy 345.11234 -372.160038)
			(xy 345.106537 -372.167179) (xy 345.100028 -372.184373) (xy 345.09964 -372.193566) (xy 345.09964 -372.351554)
			(xy 345.099198 -372.361725) (xy 345.091424 -372.380523) (xy 345.077043 -372.394911) (xy 345.058249 -372.402693)
			(xy 345.048078 -372.403116) (xy 344.331798 -372.403116) (xy 344.321621 -372.402737) (xy 344.302817 -372.394942)
			(xy 344.288431 -372.380543) (xy 344.280654 -372.361732) (xy 344.280236 -372.351554) (xy 344.280236 -372.193566)
			(xy 344.279834 -372.184378) (xy 344.273314 -372.167194) (xy 344.267536 -372.160038) (xy 344.245762 -372.134374)
			(xy 344.207813 -372.078789) (xy 344.17678 -372.019067) (xy 344.153106 -371.956064) (xy 344.137132 -371.890684)
			(xy 344.129087 -371.823862) (xy 344.129086 -371.756559) (xy 344.137129 -371.689737) (xy 344.1531 -371.624356)
			(xy 344.176771 -371.561352) (xy 344.207803 -371.501629) (xy 344.245749 -371.446042) (xy 344.267536 -371.42039)
			(xy 344.273324 -371.413239) (xy 344.279843 -371.396053) (xy 344.280236 -371.386862) (xy 344.280236 -370.89334)
			(xy 344.279798 -370.884156) (xy 344.273303 -370.866972) (xy 344.267536 -370.859812) (xy 344.245736 -370.83417)
			(xy 344.207788 -370.778582) (xy 344.176756 -370.718857) (xy 344.153084 -370.655851) (xy 344.137112 -370.590468)
			(xy 344.129068 -370.523644) (xy 340.851006 -370.523644) (xy 340.842963 -370.590465) (xy 340.826991 -370.655847)
			(xy 340.803319 -370.718851) (xy 340.772287 -370.778574) (xy 340.734339 -370.83416) (xy 340.712552 -370.859812)
			(xy 340.706762 -370.866962) (xy 340.700245 -370.884149) (xy 340.699852 -370.89334) (xy 340.699852 -371.386862)
			(xy 340.700291 -371.396046) (xy 340.706786 -371.41323) (xy 340.712552 -371.42039) (xy 340.734354 -371.446031)
			(xy 340.772303 -371.501618) (xy 340.803336 -371.561344) (xy 340.826797 -371.623785) (xy 341.928891 -371.623785)
			(xy 341.928895 -371.556358) (xy 341.936974 -371.489417) (xy 341.953014 -371.423926) (xy 341.976782 -371.360828)
			(xy 342.007937 -371.301031) (xy 342.04603 -371.245395) (xy 342.067896 -371.21973) (xy 342.073704 -371.212593)
			(xy 342.080212 -371.195396) (xy 342.080596 -371.186202) (xy 342.080596 -371.028722) (xy 342.081143 -371.018602)
			(xy 342.088856 -370.99989) (xy 342.103123 -370.985534) (xy 342.121787 -370.977706) (xy 342.131904 -370.97716)
			(xy 342.848184 -370.97716) (xy 342.858332 -370.977634) (xy 342.877076 -370.985417) (xy 342.891399 -370.999797)
			(xy 342.899106 -371.018572) (xy 342.899492 -371.028722) (xy 342.899492 -371.186202) (xy 342.899903 -371.195389)
			(xy 342.906416 -371.212573) (xy 342.912192 -371.21973) (xy 342.934019 -371.245426) (xy 342.972109 -371.301056)
			(xy 343.003262 -371.360848) (xy 343.027029 -371.423941) (xy 343.043067 -371.489426) (xy 343.051146 -371.556361)
			(xy 343.05115 -371.623782) (xy 343.043077 -371.690718) (xy 343.027046 -371.756205) (xy 343.003285 -371.8193)
			(xy 342.972139 -371.879095) (xy 342.934054 -371.934729) (xy 342.912192 -371.960394) (xy 342.906415 -371.967553)
			(xy 342.899889 -371.984733) (xy 342.899492 -371.993922) (xy 342.899492 -372.486174) (xy 342.899917 -372.49536)
			(xy 342.90642 -372.512544) (xy 342.912192 -372.519702) (xy 342.93409 -372.54534) (xy 342.972178 -372.600978)
			(xy 343.003328 -372.660778) (xy 343.02709 -372.723878) (xy 343.043124 -372.789371) (xy 343.051197 -372.856312)
			(xy 343.051194 -372.923739) (xy 343.043114 -372.99068) (xy 343.027075 -373.056171) (xy 343.003307 -373.119269)
			(xy 342.972152 -373.179066) (xy 342.934058 -373.234701) (xy 342.912192 -373.260366) (xy 342.906384 -373.267503)
			(xy 342.899876 -373.2847) (xy 342.899492 -373.293894) (xy 342.899492 -373.451374) (xy 342.898953 -373.461495)
			(xy 342.89124 -373.48021) (xy 342.87697 -373.494566) (xy 342.858302 -373.502392) (xy 342.848184 -373.502936)
			(xy 342.131904 -373.502936) (xy 342.121755 -373.502476) (xy 342.103009 -373.494688) (xy 342.088687 -373.480304)
			(xy 342.080981 -373.461525) (xy 342.080596 -373.451374) (xy 342.080596 -373.293894) (xy 342.080189 -373.284706)
			(xy 342.073673 -373.267522) (xy 342.067896 -373.260366) (xy 342.046066 -373.234673) (xy 342.007976 -373.179042)
			(xy 341.976824 -373.11925) (xy 341.953058 -373.056157) (xy 341.937021 -372.990671) (xy 341.928942 -372.923736)
			(xy 341.928939 -372.856315) (xy 341.937011 -372.789379) (xy 341.953043 -372.723892) (xy 341.976803 -372.660797)
			(xy 342.00795 -372.601001) (xy 342.046034 -372.545367) (xy 342.067896 -372.519702) (xy 342.073674 -372.512543)
			(xy 342.0802 -372.495363) (xy 342.080596 -372.486174) (xy 342.080596 -371.993922) (xy 342.080176 -371.984736)
			(xy 342.073669 -371.967551) (xy 342.067896 -371.960394) (xy 342.045995 -371.934759) (xy 342.007908 -371.87912)
			(xy 341.976759 -371.81932) (xy 341.952997 -371.756219) (xy 341.936964 -371.690726) (xy 341.928891 -371.623785)
			(xy 340.826797 -371.623785) (xy 340.827009 -371.62435) (xy 340.842981 -371.689733) (xy 340.851024 -371.756557)
			(xy 340.851023 -371.823864) (xy 340.842977 -371.890687) (xy 340.827002 -371.956071) (xy 340.803328 -372.019076)
			(xy 340.772292 -372.0788) (xy 340.734341 -372.134386) (xy 340.712552 -372.160038) (xy 340.706751 -372.16718)
			(xy 340.70024 -372.184373) (xy 340.699852 -372.193566) (xy 340.699852 -372.351554) (xy 340.699398 -372.361724)
			(xy 340.691627 -372.380519) (xy 340.67725 -372.394906) (xy 340.65846 -372.402691) (xy 340.64829 -372.403116)
			(xy 339.93201 -372.403116) (xy 339.921833 -372.402727) (xy 339.90303 -372.394937) (xy 339.888643 -372.38054)
			(xy 339.880866 -372.361731) (xy 339.880448 -372.351554) (xy 339.880448 -372.193566) (xy 339.880043 -372.184378)
			(xy 339.873525 -372.167195) (xy 339.867748 -372.160038) (xy 339.845974 -372.134375) (xy 339.808024 -372.07879)
			(xy 339.77699 -372.019068) (xy 339.753316 -371.956065) (xy 339.737342 -371.890684) (xy 339.729296 -371.823863)
			(xy 339.729295 -371.756558) (xy 339.737338 -371.689737) (xy 339.75331 -371.624355) (xy 339.776981 -371.561351)
			(xy 339.808013 -371.501628) (xy 339.845961 -371.446042) (xy 339.867748 -371.42039) (xy 339.873537 -371.41324)
			(xy 339.880055 -371.396053) (xy 339.880448 -371.386862) (xy 339.880448 -370.89334) (xy 339.880008 -370.884156)
			(xy 339.873514 -370.866972) (xy 339.867748 -370.859812) (xy 339.845948 -370.83417) (xy 339.807999 -370.778582)
			(xy 339.776966 -370.718857) (xy 339.753293 -370.655851) (xy 339.737321 -370.590468) (xy 339.729277 -370.523644)
			(xy 336.451238 -370.523644) (xy 336.451238 -370.523703) (xy 336.443163 -370.590641) (xy 336.427128 -370.65613)
			(xy 336.403363 -370.719227) (xy 336.372211 -370.779022) (xy 336.334121 -370.834656) (xy 336.312256 -370.86032)
			(xy 336.306463 -370.867467) (xy 336.299947 -370.884656) (xy 336.299556 -370.893848) (xy 336.299556 -371.386354)
			(xy 336.299998 -371.395538) (xy 336.306491 -371.412722) (xy 336.312256 -371.419882) (xy 336.334135 -371.445535)
			(xy 336.372226 -371.50117) (xy 336.403379 -371.560968) (xy 336.427016 -371.623725) (xy 337.529123 -371.623725)
			(xy 337.529126 -371.556418) (xy 337.537174 -371.489593) (xy 337.55315 -371.424209) (xy 337.576825 -371.361204)
			(xy 337.60786 -371.301479) (xy 337.645811 -371.245891) (xy 337.6676 -371.220238) (xy 337.673405 -371.213099)
			(xy 337.679915 -371.195904) (xy 337.6803 -371.18671) (xy 337.6803 -371.028722) (xy 337.68085 -371.01857)
			(xy 337.68861 -370.999809) (xy 337.702958 -370.985444) (xy 337.721711 -370.977662) (xy 337.731862 -370.97716)
			(xy 338.448142 -370.97716) (xy 338.458305 -370.9776) (xy 338.477079 -370.985392) (xy 338.491444 -370.999774)
			(xy 338.499213 -371.018558) (xy 338.499704 -371.028722) (xy 338.499704 -371.18671) (xy 338.500109 -371.195898)
			(xy 338.506626 -371.213082) (xy 338.512404 -371.220238) (xy 338.534153 -371.245921) (xy 338.5721 -371.301504)
			(xy 338.603133 -371.361224) (xy 338.626806 -371.424224) (xy 338.64278 -371.489602) (xy 338.650827 -371.556421)
			(xy 338.65083 -371.623722) (xy 338.64279 -371.690541) (xy 338.626823 -371.755921) (xy 338.603156 -371.818924)
			(xy 338.57213 -371.878646) (xy 338.534188 -371.934233) (xy 338.512404 -371.959886) (xy 338.506589 -371.967018)
			(xy 338.500085 -371.984219) (xy 338.499704 -371.993414) (xy 338.499704 -372.486682) (xy 338.500122 -372.495868)
			(xy 338.50663 -372.513053) (xy 338.512404 -372.52021) (xy 338.534224 -372.545835) (xy 338.572169 -372.601427)
			(xy 338.603198 -372.661154) (xy 338.626867 -372.724162) (xy 338.642836 -372.789547) (xy 338.650877 -372.856372)
			(xy 338.650874 -372.923679) (xy 338.642827 -372.990503) (xy 338.626852 -373.055887) (xy 338.603177 -373.118892)
			(xy 338.572142 -373.178617) (xy 338.534192 -373.234205) (xy 338.512404 -373.259858) (xy 338.506601 -373.266999)
			(xy 338.50009 -373.284193) (xy 338.499704 -373.293386) (xy 338.499704 -373.451374) (xy 338.499147 -373.461525)
			(xy 338.491388 -373.480286) (xy 338.477043 -373.49465) (xy 338.458292 -373.502433) (xy 338.448142 -373.502936)
			(xy 337.731862 -373.502936) (xy 337.721699 -373.502497) (xy 337.702924 -373.494705) (xy 337.688559 -373.480323)
			(xy 337.68079 -373.461538) (xy 337.6803 -373.451374) (xy 337.6803 -373.293386) (xy 337.679896 -373.284198)
			(xy 337.673378 -373.267014) (xy 337.6676 -373.259858) (xy 337.645847 -373.234178) (xy 337.6079 -373.178595)
			(xy 337.576867 -373.118874) (xy 337.553194 -373.055874) (xy 337.53722 -372.990495) (xy 337.529174 -372.923676)
			(xy 337.52917 -372.856375) (xy 337.537211 -372.789555) (xy 337.553179 -372.724175) (xy 337.576846 -372.661172)
			(xy 337.607873 -372.601449) (xy 337.645816 -372.545863) (xy 337.6676 -372.52021) (xy 337.673417 -372.513079)
			(xy 337.67992 -372.495878) (xy 337.6803 -372.486682) (xy 337.6803 -371.993414) (xy 337.679883 -371.984228)
			(xy 337.673374 -371.967043) (xy 337.6676 -371.959886) (xy 337.645776 -371.934264) (xy 337.607831 -371.878672)
			(xy 337.576802 -371.818944) (xy 337.553133 -371.755936) (xy 337.537163 -371.69055) (xy 337.529123 -371.623725)
			(xy 336.427016 -371.623725) (xy 336.427144 -371.624066) (xy 336.44318 -371.689557) (xy 336.451256 -371.756498)
			(xy 336.451254 -371.823923) (xy 336.443176 -371.890863) (xy 336.427138 -371.956354) (xy 336.40337 -372.019451)
			(xy 336.372216 -372.079248) (xy 336.334122 -372.134881) (xy 336.312256 -372.160546) (xy 336.306452 -372.167686)
			(xy 336.299943 -372.184881) (xy 336.299556 -372.194074) (xy 336.299556 -372.351554) (xy 336.299036 -372.361678)
			(xy 336.291322 -372.380399) (xy 336.277046 -372.394757) (xy 336.258369 -372.402577) (xy 336.248248 -372.403116)
			(xy 335.531968 -372.403116) (xy 335.521814 -372.402705) (xy 335.503064 -372.394902) (xy 335.488742 -372.380502)
			(xy 335.481041 -372.36171) (xy 335.48066 -372.351554) (xy 335.48066 -372.194074) (xy 335.480249 -372.184887)
			(xy 335.473734 -372.167704) (xy 335.46796 -372.160546) (xy 335.446111 -372.134869) (xy 335.408025 -372.079235)
			(xy 335.376876 -372.01944) (xy 335.353112 -371.956345) (xy 335.337077 -371.890858) (xy 335.329001 -371.823921)
			(xy 335.329 -371.7565) (xy 335.337073 -371.689563) (xy 335.353106 -371.624075) (xy 335.376867 -371.560979)
			(xy 335.408014 -371.501183) (xy 335.446098 -371.445548) (xy 335.46796 -371.419882) (xy 335.473754 -371.412735)
			(xy 335.480269 -371.395546) (xy 335.48066 -371.386354) (xy 335.48066 -370.893848) (xy 335.480214 -370.884665)
			(xy 335.473724 -370.867481) (xy 335.46796 -370.86032) (xy 335.446086 -370.834664) (xy 335.408 -370.779027)
			(xy 335.376852 -370.719229) (xy 335.35309 -370.656131) (xy 335.337057 -370.590642) (xy 335.328983 -370.523703)
			(xy 332.050912 -370.523703) (xy 332.042876 -370.590465) (xy 332.026905 -370.655846) (xy 332.003233 -370.71885)
			(xy 331.972202 -370.778573) (xy 331.934255 -370.83416) (xy 331.912468 -370.859812) (xy 331.90668 -370.866963)
			(xy 331.900161 -370.884149) (xy 331.899768 -370.89334) (xy 331.899768 -371.386862) (xy 331.900204 -371.396046)
			(xy 331.906701 -371.41323) (xy 331.912468 -371.42039) (xy 331.934269 -371.446031) (xy 331.972217 -371.501619)
			(xy 332.00325 -371.561344) (xy 332.026709 -371.623785) (xy 333.128803 -371.623785) (xy 333.128807 -371.556358)
			(xy 333.136887 -371.489417) (xy 333.152927 -371.423926) (xy 333.176696 -371.360827) (xy 333.207851 -371.30103)
			(xy 333.245945 -371.245395) (xy 333.267812 -371.21973) (xy 333.273622 -371.212594) (xy 333.280128 -371.195397)
			(xy 333.280512 -371.186202) (xy 333.280512 -371.028722) (xy 333.281044 -371.0186) (xy 333.288759 -370.999885)
			(xy 333.303031 -370.985529) (xy 333.321701 -370.977704) (xy 333.33182 -370.97716) (xy 334.0481 -370.97716)
			(xy 334.058249 -370.977621) (xy 334.076994 -370.985409) (xy 334.091316 -370.999793) (xy 334.099023 -371.018571)
			(xy 334.099408 -371.028722) (xy 334.099408 -371.186202) (xy 334.099815 -371.195389) (xy 334.106331 -371.212574)
			(xy 334.112108 -371.21973) (xy 334.133934 -371.245426) (xy 334.172024 -371.301056) (xy 334.203176 -371.360848)
			(xy 334.226942 -371.423941) (xy 334.242979 -371.489426) (xy 334.251058 -371.556361) (xy 334.251062 -371.623782)
			(xy 334.24299 -371.690717) (xy 334.226958 -371.756204) (xy 334.203199 -371.819299) (xy 334.172053 -371.879095)
			(xy 334.133969 -371.934729) (xy 334.112108 -371.960394) (xy 334.106332 -371.967554) (xy 334.099805 -371.984733)
			(xy 334.099408 -371.993922) (xy 334.099408 -372.486174) (xy 334.099829 -372.49536) (xy 334.106335 -372.512545)
			(xy 334.112108 -372.519702) (xy 334.134005 -372.54534) (xy 334.172092 -372.600978) (xy 334.203241 -372.660779)
			(xy 334.227003 -372.723879) (xy 334.243036 -372.789371) (xy 334.251109 -372.856312) (xy 334.251106 -372.923739)
			(xy 334.243027 -372.990679) (xy 334.226988 -373.05617) (xy 334.20322 -373.119268) (xy 334.172066 -373.179065)
			(xy 334.133974 -373.234701) (xy 334.112108 -373.260366) (xy 334.106302 -373.267504) (xy 334.099793 -373.2847)
			(xy 334.099408 -373.293894) (xy 334.099408 -373.451374) (xy 334.098854 -373.461493) (xy 334.091143 -373.480205)
			(xy 334.076878 -373.49456) (xy 334.058216 -373.502389) (xy 334.0481 -373.502936) (xy 333.33182 -373.502936)
			(xy 333.321672 -373.502463) (xy 333.302927 -373.494681) (xy 333.288604 -373.4803) (xy 333.280897 -373.461524)
			(xy 333.280512 -373.451374) (xy 333.280512 -373.293894) (xy 333.280102 -373.284707) (xy 333.273588 -373.267523)
			(xy 333.267812 -373.260366) (xy 333.245981 -373.234673) (xy 333.20789 -373.179043) (xy 333.176738 -373.119251)
			(xy 333.152971 -373.056157) (xy 333.136933 -372.990672) (xy 333.128854 -372.923736) (xy 333.128851 -372.856315)
			(xy 333.136924 -372.789379) (xy 333.152956 -372.723891) (xy 333.176717 -372.660796) (xy 333.207864 -372.601001)
			(xy 333.24595 -372.545367) (xy 333.267812 -372.519702) (xy 333.273592 -372.512545) (xy 333.280116 -372.495363)
			(xy 333.280512 -372.486174) (xy 333.280512 -371.993922) (xy 333.280088 -371.984736) (xy 333.273584 -371.967552)
			(xy 333.267812 -371.960394) (xy 333.24591 -371.93476) (xy 333.207822 -371.879121) (xy 333.176672 -371.819321)
			(xy 333.15291 -371.75622) (xy 333.136876 -371.690727) (xy 333.128803 -371.623785) (xy 332.026709 -371.623785)
			(xy 332.026921 -371.62435) (xy 332.042893 -371.689734) (xy 332.050936 -371.756558) (xy 332.050935 -371.823864)
			(xy 332.042889 -371.890687) (xy 332.026915 -371.95607) (xy 332.003241 -372.019075) (xy 331.972207 -372.078799)
			(xy 331.934256 -372.134386) (xy 331.912468 -372.160038) (xy 331.906669 -372.167181) (xy 331.900156 -372.184373)
			(xy 331.899768 -372.193566) (xy 331.899768 -372.351554) (xy 331.899299 -372.361722) (xy 331.89153 -372.380514)
			(xy 331.877158 -372.394901) (xy 331.858373 -372.402688) (xy 331.848206 -372.403116) (xy 331.131926 -372.403116)
			(xy 331.12175 -372.402714) (xy 331.102948 -372.394929) (xy 331.08856 -372.380536) (xy 331.080783 -372.36173)
			(xy 331.080364 -372.351554) (xy 331.080364 -372.193566) (xy 331.079956 -372.184379) (xy 331.073439 -372.167195)
			(xy 331.067664 -372.160038) (xy 331.045889 -372.134375) (xy 331.007939 -372.078791) (xy 330.976903 -372.019069)
			(xy 330.953229 -371.956066) (xy 330.937254 -371.890684) (xy 330.929208 -371.823863) (xy 330.929207 -371.756558)
			(xy 330.93725 -371.689736) (xy 330.953222 -371.624355) (xy 330.976895 -371.561351) (xy 331.007928 -371.501628)
			(xy 331.045876 -371.446042) (xy 331.067664 -371.42039) (xy 331.073455 -371.413241) (xy 331.079971 -371.396053)
			(xy 331.080364 -371.386862) (xy 331.080364 -370.89334) (xy 331.07992 -370.884157) (xy 331.073428 -370.866973)
			(xy 331.067664 -370.859812) (xy 331.045864 -370.83417) (xy 331.007914 -370.778582) (xy 330.97688 -370.718858)
			(xy 330.953206 -370.655852) (xy 330.937234 -370.590468) (xy 330.92919 -370.523644) (xy 301.250887 -370.523644)
			(xy 301.250887 -370.523702) (xy 301.242812 -370.590639) (xy 301.226779 -370.656127) (xy 301.203017 -370.719224)
			(xy 301.171869 -370.77902) (xy 301.133783 -370.834654) (xy 301.11192 -370.86032) (xy 301.106135 -370.867473)
			(xy 301.099613 -370.884658) (xy 301.09922 -370.893848) (xy 301.09922 -371.386354) (xy 301.099648 -371.395539)
			(xy 301.106149 -371.412724) (xy 301.11192 -371.419882) (xy 301.133797 -371.445536) (xy 301.171884 -371.501173)
			(xy 301.203033 -371.560971) (xy 301.226688 -371.623785) (xy 302.328773 -371.623785) (xy 302.328777 -371.556358)
			(xy 302.336856 -371.489418) (xy 302.352895 -371.423927) (xy 302.376662 -371.360829) (xy 302.407815 -371.301031)
			(xy 302.445907 -371.245396) (xy 302.467772 -371.21973) (xy 302.47359 -371.2126) (xy 302.48009 -371.195398)
			(xy 302.480472 -371.186202) (xy 302.480472 -371.028722) (xy 302.480945 -371.018593) (xy 302.488672 -370.999866)
			(xy 302.502963 -370.985508) (xy 302.521653 -370.977693) (xy 302.53178 -370.97716) (xy 303.24806 -370.97716)
			(xy 303.258207 -370.977654) (xy 303.27695 -370.985429) (xy 303.291274 -370.999803) (xy 303.298982 -371.018574)
			(xy 303.299368 -371.028722) (xy 303.299368 -371.186202) (xy 303.299784 -371.195388) (xy 303.306294 -371.212572)
			(xy 303.312068 -371.21973) (xy 303.333896 -371.245425) (xy 303.371988 -371.301055) (xy 303.403142 -371.360847)
			(xy 303.42691 -371.42394) (xy 303.442949 -371.489425) (xy 303.451028 -371.556361) (xy 303.451031 -371.623782)
			(xy 303.442959 -371.690718) (xy 303.426926 -371.756206) (xy 303.403165 -371.819301) (xy 303.372017 -371.879096)
			(xy 303.333931 -371.934729) (xy 303.312068 -371.960394) (xy 303.306287 -371.96755) (xy 303.299764 -371.984732)
			(xy 303.299368 -371.993922) (xy 303.299368 -372.486174) (xy 303.299798 -372.495359) (xy 303.306299 -372.512543)
			(xy 303.312068 -372.519702) (xy 303.333966 -372.545339) (xy 303.372056 -372.600977) (xy 303.403207 -372.660777)
			(xy 303.426971 -372.723877) (xy 303.443005 -372.78937) (xy 303.451079 -372.856312) (xy 303.451076 -372.923739)
			(xy 303.442996 -372.99068) (xy 303.426956 -373.056172) (xy 303.403186 -373.11927) (xy 303.37203 -373.179067)
			(xy 303.333935 -373.234701) (xy 303.312068 -373.260366) (xy 303.306257 -373.267501) (xy 303.299752 -373.284699)
			(xy 303.299368 -373.293894) (xy 303.299368 -373.451374) (xy 303.298853 -373.461498) (xy 303.291135 -373.480217)
			(xy 303.276857 -373.494574) (xy 303.258181 -373.502396) (xy 303.24806 -373.502936) (xy 302.53178 -373.502936)
			(xy 302.521629 -373.502496) (xy 302.502883 -373.4947) (xy 302.488562 -373.48031) (xy 302.480856 -373.461527)
			(xy 302.480472 -373.451374) (xy 302.480472 -373.293894) (xy 302.480071 -373.284706) (xy 302.473552 -373.267521)
			(xy 302.467772 -373.260366) (xy 302.445942 -373.234673) (xy 302.407855 -373.179042) (xy 302.376704 -373.119249)
			(xy 302.352939 -373.056156) (xy 302.336902 -372.99067) (xy 302.328824 -372.923736) (xy 302.328821 -372.856315)
			(xy 302.336893 -372.78938) (xy 302.352924 -372.723893) (xy 302.376683 -372.660798) (xy 302.407828 -372.601002)
			(xy 302.445911 -372.545368) (xy 302.467772 -372.519702) (xy 302.473559 -372.51255) (xy 302.480077 -372.495364)
			(xy 302.480472 -372.486174) (xy 302.480472 -371.993922) (xy 302.480058 -371.984735) (xy 302.473548 -371.96755)
			(xy 302.467772 -371.960394) (xy 302.445872 -371.934759) (xy 302.407786 -371.87912) (xy 302.376638 -371.819319)
			(xy 302.352878 -371.756218) (xy 302.336846 -371.690726) (xy 302.328773 -371.623785) (xy 301.226688 -371.623785)
			(xy 301.226795 -371.624069) (xy 301.242829 -371.689559) (xy 301.250904 -371.756498) (xy 301.250903 -371.823923)
			(xy 301.242826 -371.890862) (xy 301.226789 -371.956351) (xy 301.203024 -372.019449) (xy 301.171873 -372.079245)
			(xy 301.133784 -372.13488) (xy 301.11192 -372.160546) (xy 301.106124 -372.167692) (xy 301.099608 -372.184882)
			(xy 301.09922 -372.194074) (xy 301.09922 -372.351554) (xy 301.098734 -372.361683) (xy 301.091014 -372.38041)
			(xy 301.076727 -372.39477) (xy 301.058038 -372.402583) (xy 301.047912 -372.403116) (xy 300.331632 -372.403116)
			(xy 300.321482 -372.402653) (xy 300.302733 -372.394871) (xy 300.288409 -372.380487) (xy 300.280705 -372.361706)
			(xy 300.280324 -372.351554) (xy 300.280324 -372.194074) (xy 300.279921 -372.184886) (xy 300.273402 -372.167702)
			(xy 300.267624 -372.160546) (xy 300.245773 -372.13487) (xy 300.207682 -372.079237) (xy 300.17653 -372.019443)
			(xy 300.152764 -371.956347) (xy 300.136726 -371.890859) (xy 300.128649 -371.823922) (xy 300.128648 -371.756499)
			(xy 300.136723 -371.689561) (xy 300.152757 -371.624073) (xy 300.176521 -371.560976) (xy 300.207671 -371.501181)
			(xy 300.24576 -371.445547) (xy 300.267624 -371.419882) (xy 300.273413 -371.412732) (xy 300.279932 -371.395545)
			(xy 300.280324 -371.386354) (xy 300.280324 -370.893848) (xy 300.279885 -370.884664) (xy 300.273391 -370.86748)
			(xy 300.267624 -370.86032) (xy 300.245747 -370.834665) (xy 300.207657 -370.779029) (xy 300.176506 -370.719232)
			(xy 300.152741 -370.656134) (xy 300.136706 -370.590643) (xy 300.128631 -370.523704) (xy 296.851096 -370.523704)
			(xy 296.843021 -370.590639) (xy 296.826988 -370.656127) (xy 296.803227 -370.719223) (xy 296.772079 -370.779019)
			(xy 296.733994 -370.834654) (xy 296.712132 -370.86032) (xy 296.706336 -370.867465) (xy 296.699823 -370.884656)
			(xy 296.699432 -370.893848) (xy 296.699432 -371.386354) (xy 296.699879 -371.395537) (xy 296.706369 -371.412721)
			(xy 296.712132 -371.419882) (xy 296.734009 -371.445536) (xy 296.772095 -371.501173) (xy 296.803243 -371.560971)
			(xy 296.826876 -371.623726) (xy 297.92898 -371.623726) (xy 297.928984 -371.556417) (xy 297.937032 -371.489591)
			(xy 297.95301 -371.424206) (xy 297.976689 -371.3612) (xy 298.007729 -371.301476) (xy 298.045685 -371.245889)
			(xy 298.067476 -371.220238) (xy 298.073279 -371.213097) (xy 298.07979 -371.195903) (xy 298.080176 -371.18671)
			(xy 298.080176 -371.028722) (xy 298.080583 -371.018547) (xy 298.088368 -370.999746) (xy 298.102759 -370.985359)
			(xy 298.121563 -370.97758) (xy 298.131738 -370.97716) (xy 298.848018 -370.97716) (xy 298.858193 -370.97755)
			(xy 298.876993 -370.985345) (xy 298.891378 -370.999741) (xy 298.899158 -371.018546) (xy 298.89958 -371.028722)
			(xy 298.89958 -371.18671) (xy 298.89999 -371.195897) (xy 298.906504 -371.213081) (xy 298.91228 -371.220238)
			(xy 298.93403 -371.245921) (xy 298.971978 -371.301504) (xy 299.003012 -371.361223) (xy 299.026686 -371.424224)
			(xy 299.042661 -371.489602) (xy 299.050708 -371.556421) (xy 299.050711 -371.623722) (xy 299.042671 -371.690542)
			(xy 299.026703 -371.755922) (xy 299.003035 -371.818925) (xy 298.972008 -371.878647) (xy 298.934065 -371.934233)
			(xy 298.91228 -371.959886) (xy 298.906462 -371.967016) (xy 298.899961 -371.984218) (xy 298.89958 -371.993414)
			(xy 298.89958 -372.486682) (xy 298.900003 -372.495868) (xy 298.906508 -372.513052) (xy 298.91228 -372.52021)
			(xy 298.934101 -372.545835) (xy 298.972047 -372.601426) (xy 299.003078 -372.661153) (xy 299.026748 -372.724161)
			(xy 299.042718 -372.789547) (xy 299.050759 -372.856372) (xy 299.050756 -372.923679) (xy 299.042709 -372.990504)
			(xy 299.026733 -373.055888) (xy 299.003057 -373.118894) (xy 298.972021 -373.178618) (xy 298.934069 -373.234206)
			(xy 298.91228 -373.259858) (xy 298.906474 -373.266996) (xy 298.899966 -373.284192) (xy 298.89958 -373.293386)
			(xy 298.89958 -373.451374) (xy 298.899115 -373.461542) (xy 298.891342 -373.480332) (xy 298.876969 -373.494717)
			(xy 298.858185 -373.502506) (xy 298.848018 -373.502936) (xy 298.131738 -373.502936) (xy 298.121566 -373.502504)
			(xy 298.102767 -373.494727) (xy 298.08838 -373.480343) (xy 298.080598 -373.461546) (xy 298.080176 -373.451374)
			(xy 298.080176 -373.293386) (xy 298.079778 -373.284197) (xy 298.073256 -373.267013) (xy 298.067476 -373.259858)
			(xy 298.045721 -373.234179) (xy 298.007768 -373.178597) (xy 297.976732 -373.118878) (xy 297.953055 -373.055877)
			(xy 297.937079 -372.990497) (xy 297.929031 -372.923677) (xy 297.929028 -372.856374) (xy 297.93707 -372.789553)
			(xy 297.95304 -372.724172) (xy 297.976711 -372.661169) (xy 298.007742 -372.601447) (xy 298.045689 -372.545862)
			(xy 298.067476 -372.52021) (xy 298.073291 -372.513077) (xy 298.079795 -372.495877) (xy 298.080176 -372.486682)
			(xy 298.080176 -371.993414) (xy 298.079765 -371.984227) (xy 298.073252 -371.967042) (xy 298.067476 -371.959886)
			(xy 298.04565 -371.934265) (xy 298.007699 -371.878675) (xy 297.976666 -371.818948) (xy 297.952993 -371.755939)
			(xy 297.937022 -371.690552) (xy 297.92898 -371.623726) (xy 296.826876 -371.623726) (xy 296.827005 -371.624069)
			(xy 296.843039 -371.689559) (xy 296.851113 -371.756498) (xy 296.851112 -371.823923) (xy 296.843035 -371.890861)
			(xy 296.826999 -371.956351) (xy 296.803235 -372.019448) (xy 296.772084 -372.079245) (xy 296.733996 -372.13488)
			(xy 296.712132 -372.160546) (xy 296.706325 -372.167684) (xy 296.699819 -372.18488) (xy 296.699432 -372.194074)
			(xy 296.699432 -372.351554) (xy 296.698935 -372.361681) (xy 296.691217 -372.380407) (xy 296.676933 -372.394765)
			(xy 296.658249 -372.402581) (xy 296.648124 -372.403116) (xy 295.931844 -372.403116) (xy 295.921695 -372.402643)
			(xy 295.902946 -372.394865) (xy 295.888622 -372.380484) (xy 295.880918 -372.361705) (xy 295.880536 -372.351554)
			(xy 295.880536 -372.194074) (xy 295.88013 -372.184887) (xy 295.873613 -372.167703) (xy 295.867836 -372.160546)
			(xy 295.845985 -372.13487) (xy 295.807893 -372.079238) (xy 295.77674 -372.019444) (xy 295.752973 -371.956348)
			(xy 295.736936 -371.89086) (xy 295.728858 -371.823922) (xy 295.728857 -371.756499) (xy 295.736932 -371.689561)
			(xy 295.752967 -371.624072) (xy 295.776731 -371.560976) (xy 295.807882 -371.50118) (xy 295.845972 -371.445547)
			(xy 295.867836 -371.419882) (xy 295.873627 -371.412733) (xy 295.880144 -371.395545) (xy 295.880536 -371.386354)
			(xy 295.880536 -370.893848) (xy 295.880095 -370.884664) (xy 295.873602 -370.86748) (xy 295.867836 -370.86032)
			(xy 295.845959 -370.834665) (xy 295.807868 -370.77903) (xy 295.776716 -370.719233) (xy 295.752951 -370.656134)
			(xy 295.736915 -370.590644) (xy 295.72884 -370.523704) (xy 292.450793 -370.523704) (xy 292.442757 -370.590465)
			(xy 292.426785 -370.655847) (xy 292.403113 -370.718851) (xy 292.37208 -370.778574) (xy 292.334131 -370.83416)
			(xy 292.312344 -370.859812) (xy 292.306553 -370.866961) (xy 292.300036 -370.884149) (xy 292.299644 -370.89334)
			(xy 292.299644 -371.386862) (xy 292.300085 -371.396046) (xy 292.306578 -371.41323) (xy 292.312344 -371.42039)
			(xy 292.334146 -371.44603) (xy 292.372096 -371.501618) (xy 292.403129 -371.561343) (xy 292.42659 -371.623785)
			(xy 293.528685 -371.623785) (xy 293.528689 -371.556358) (xy 293.536768 -371.489418) (xy 293.552807 -371.423927)
			(xy 293.576575 -371.360828) (xy 293.60773 -371.301031) (xy 293.645822 -371.245395) (xy 293.667688 -371.21973)
			(xy 293.673495 -371.212592) (xy 293.680004 -371.195396) (xy 293.680388 -371.186202) (xy 293.680388 -371.028722)
			(xy 293.680943 -371.018603) (xy 293.688654 -370.999892) (xy 293.702919 -370.985537) (xy 293.72158 -370.977708)
			(xy 293.731696 -370.97716) (xy 294.447976 -370.97716) (xy 294.458078 -370.977704) (xy 294.476748 -370.985426)
			(xy 294.491043 -370.999705) (xy 294.498785 -371.018366) (xy 294.499284 -371.028468) (xy 294.499284 -371.186202)
			(xy 294.499697 -371.195389) (xy 294.506209 -371.212573) (xy 294.511984 -371.21973) (xy 294.533811 -371.245426)
			(xy 294.571902 -371.301056) (xy 294.603055 -371.360847) (xy 294.626822 -371.42394) (xy 294.642861 -371.489426)
			(xy 294.65094 -371.556361) (xy 294.650944 -371.623782) (xy 294.642871 -371.690718) (xy 294.626839 -371.756205)
			(xy 294.603079 -371.8193) (xy 294.571932 -371.879095) (xy 294.533846 -371.934729) (xy 294.511984 -371.960394)
			(xy 294.506206 -371.967552) (xy 294.499681 -371.984733) (xy 294.499284 -371.993922) (xy 294.499284 -372.486174)
			(xy 294.49971 -372.495359) (xy 294.506213 -372.512544) (xy 294.511984 -372.519702) (xy 294.533882 -372.545339)
			(xy 294.571971 -372.600978) (xy 294.603121 -372.660777) (xy 294.626884 -372.723878) (xy 294.642917 -372.789371)
			(xy 294.650991 -372.856312) (xy 294.650988 -372.923739) (xy 294.642908 -372.99068) (xy 294.626869 -373.056171)
			(xy 294.6031 -373.119269) (xy 294.571944 -373.179066) (xy 294.533851 -373.234701) (xy 294.511984 -373.260366)
			(xy 294.506175 -373.267502) (xy 294.499668 -373.2847) (xy 294.499284 -373.293894) (xy 294.499284 -373.451374)
			(xy 294.498753 -373.461496) (xy 294.491038 -373.480212) (xy 294.476766 -373.494569) (xy 294.458095 -373.502393)
			(xy 294.447976 -373.502936) (xy 293.731696 -373.502936) (xy 293.721591 -373.502419) (xy 293.70292 -373.494687)
			(xy 293.688627 -373.4804) (xy 293.680886 -373.461732) (xy 293.680388 -373.451628) (xy 293.680388 -373.293894)
			(xy 293.679983 -373.284706) (xy 293.673466 -373.267522) (xy 293.667688 -373.260366) (xy 293.645858 -373.234673)
			(xy 293.607769 -373.179042) (xy 293.576617 -373.11925) (xy 293.552852 -373.056156) (xy 293.536814 -372.990671)
			(xy 293.528736 -372.923736) (xy 293.528733 -372.856315) (xy 293.536805 -372.789379) (xy 293.552837 -372.723892)
			(xy 293.576597 -372.660797) (xy 293.607743 -372.601002) (xy 293.645826 -372.545367) (xy 293.667688 -372.519702)
			(xy 293.673465 -372.512543) (xy 293.679992 -372.495363) (xy 293.680388 -372.486174) (xy 293.680388 -371.993922)
			(xy 293.67997 -371.984736) (xy 293.673462 -371.967551) (xy 293.667688 -371.960394) (xy 293.645787 -371.934759)
			(xy 293.6077 -371.87912) (xy 293.576552 -371.81932) (xy 293.55279 -371.756219) (xy 293.536758 -371.690726)
			(xy 293.528685 -371.623785) (xy 292.42659 -371.623785) (xy 292.426802 -371.624349) (xy 292.442775 -371.689733)
			(xy 292.450818 -371.756557) (xy 292.450817 -371.823864) (xy 292.442771 -371.890688) (xy 292.426796 -371.956071)
			(xy 292.403121 -372.019076) (xy 292.372085 -372.0788) (xy 292.334133 -372.134386) (xy 292.312344 -372.160038)
			(xy 292.306542 -372.167179) (xy 292.300032 -372.184373) (xy 292.299644 -372.193566) (xy 292.299644 -372.351554)
			(xy 292.299198 -372.361725) (xy 292.291425 -372.380522) (xy 292.277046 -372.394909) (xy 292.258253 -372.402693)
			(xy 292.248082 -372.403116) (xy 291.531802 -372.403116) (xy 291.521625 -372.402733) (xy 291.502821 -372.394941)
			(xy 291.488435 -372.380542) (xy 291.480658 -372.361732) (xy 291.48024 -372.351554) (xy 291.48024 -372.193566)
			(xy 291.479837 -372.184378) (xy 291.473317 -372.167194) (xy 291.46754 -372.160038) (xy 291.445766 -372.134374)
			(xy 291.407817 -372.07879) (xy 291.376783 -372.019068) (xy 291.353109 -371.956065) (xy 291.337135 -371.890684)
			(xy 291.32909 -371.823862) (xy 291.329089 -371.756559) (xy 291.337132 -371.689737) (xy 291.353103 -371.624356)
			(xy 291.376774 -371.561352) (xy 291.407806 -371.501628) (xy 291.445753 -371.446042) (xy 291.46754 -371.42039)
			(xy 291.473328 -371.413239) (xy 291.479847 -371.396053) (xy 291.48024 -371.386862) (xy 291.48024 -370.89334)
			(xy 291.479801 -370.884156) (xy 291.473306 -370.866972) (xy 291.46754 -370.859812) (xy 291.44574 -370.83417)
			(xy 291.407792 -370.778582) (xy 291.376759 -370.718857) (xy 291.353087 -370.655851) (xy 291.337115 -370.590468)
			(xy 291.329071 -370.523644) (xy 288.051032 -370.523644) (xy 288.051032 -370.523703) (xy 288.042957 -370.590641)
			(xy 288.026921 -370.65613) (xy 288.003156 -370.719227) (xy 287.972004 -370.779022) (xy 287.933913 -370.834656)
			(xy 287.912048 -370.86032) (xy 287.906254 -370.867467) (xy 287.899739 -370.884656) (xy 287.899348 -370.893848)
			(xy 287.899348 -371.386354) (xy 287.899792 -371.395537) (xy 287.906284 -371.412721) (xy 287.912048 -371.419882)
			(xy 287.933928 -371.445535) (xy 287.972019 -371.50117) (xy 288.003172 -371.560967) (xy 288.02681 -371.623726)
			(xy 289.128893 -371.623726) (xy 289.128896 -371.556417) (xy 289.136945 -371.489591) (xy 289.152924 -371.424206)
			(xy 289.176603 -371.3612) (xy 289.207644 -371.301475) (xy 289.2456 -371.245889) (xy 289.267392 -371.220238)
			(xy 289.273196 -371.213098) (xy 289.279707 -371.195904) (xy 289.280092 -371.18671) (xy 289.280092 -371.028722)
			(xy 289.28065 -371.018571) (xy 289.288409 -370.999811) (xy 289.302754 -370.985447) (xy 289.321504 -370.977663)
			(xy 289.331654 -370.97716) (xy 290.047934 -370.97716) (xy 290.058097 -370.977606) (xy 290.076871 -370.985396)
			(xy 290.091236 -370.999776) (xy 290.099005 -371.018559) (xy 290.099496 -371.028722) (xy 290.099496 -371.18671)
			(xy 290.099902 -371.195898) (xy 290.106419 -371.213082) (xy 290.112196 -371.220238) (xy 290.133945 -371.245921)
			(xy 290.171893 -371.301504) (xy 290.202926 -371.361224) (xy 290.226599 -371.424224) (xy 290.242574 -371.489602)
			(xy 290.250621 -371.556421) (xy 290.250624 -371.623722) (xy 290.242584 -371.690542) (xy 290.226616 -371.755921)
			(xy 290.202949 -371.818924) (xy 290.171922 -371.878647) (xy 290.13398 -371.934233) (xy 290.112196 -371.959886)
			(xy 290.10638 -371.967017) (xy 290.099877 -371.984218) (xy 290.099496 -371.993414) (xy 290.099496 -372.486682)
			(xy 290.099916 -372.495868) (xy 290.106423 -372.513053) (xy 290.112196 -372.52021) (xy 290.134016 -372.545835)
			(xy 290.171962 -372.601426) (xy 290.202991 -372.661154) (xy 290.226661 -372.724162) (xy 290.24263 -372.789547)
			(xy 290.250671 -372.856372) (xy 290.250668 -372.923679) (xy 290.242621 -372.990503) (xy 290.226646 -373.055887)
			(xy 290.202971 -373.118893) (xy 290.171935 -373.178618) (xy 290.133985 -373.234205) (xy 290.112196 -373.259858)
			(xy 290.106392 -373.266998) (xy 290.099882 -373.284192) (xy 290.099496 -373.293386) (xy 290.099496 -373.451374)
			(xy 290.098946 -373.461526) (xy 290.091187 -373.480288) (xy 290.076838 -373.494653) (xy 290.058085 -373.502435)
			(xy 290.047934 -373.502936) (xy 289.331654 -373.502936) (xy 289.32149 -373.502504) (xy 289.302715 -373.494709)
			(xy 289.28835 -373.480325) (xy 289.280582 -373.461539) (xy 289.280092 -373.451374) (xy 289.280092 -373.293386)
			(xy 289.27969 -373.284198) (xy 289.273171 -373.267014) (xy 289.267392 -373.259858) (xy 289.245636 -373.234179)
			(xy 289.207683 -373.178598) (xy 289.176645 -373.118878) (xy 289.152968 -373.055877) (xy 289.136991 -372.990498)
			(xy 289.128943 -372.923677) (xy 289.12894 -372.856374) (xy 289.136982 -372.789553) (xy 289.152953 -372.724172)
			(xy 289.176624 -372.661168) (xy 289.207656 -372.601446) (xy 289.245605 -372.545861) (xy 289.267392 -372.52021)
			(xy 289.273208 -372.513079) (xy 289.279711 -372.495878) (xy 289.280092 -372.486682) (xy 289.280092 -371.993414)
			(xy 289.279677 -371.984227) (xy 289.273167 -371.967043) (xy 289.267392 -371.959886) (xy 289.245565 -371.934265)
			(xy 289.207614 -371.878676) (xy 289.17658 -371.818948) (xy 289.152907 -371.755939) (xy 289.136935 -371.690553)
			(xy 289.128893 -371.623726) (xy 288.02681 -371.623726) (xy 288.026938 -371.624066) (xy 288.042974 -371.689557)
			(xy 288.05105 -371.756498) (xy 288.051048 -371.823923) (xy 288.04297 -371.890864) (xy 288.026932 -371.956354)
			(xy 288.003164 -372.019452) (xy 287.972008 -372.079248) (xy 287.933915 -372.134882) (xy 287.912048 -372.160546)
			(xy 287.906243 -372.167685) (xy 287.899735 -372.18488) (xy 287.899348 -372.194074) (xy 287.899348 -372.351554)
			(xy 287.898835 -372.361679) (xy 287.89112 -372.380402) (xy 287.876842 -372.39476) (xy 287.858162 -372.402579)
			(xy 287.84804 -372.403116) (xy 287.13176 -372.403116) (xy 287.121651 -372.402648) (xy 287.102975 -372.3949)
			(xy 287.088682 -372.380598) (xy 287.080946 -372.361918) (xy 287.080452 -372.351808) (xy 287.080452 -372.194074)
			(xy 287.080043 -372.184887) (xy 287.073527 -372.167703) (xy 287.067752 -372.160546) (xy 287.0459 -372.13487)
			(xy 287.007807 -372.079238) (xy 286.976653 -372.019444) (xy 286.952886 -371.956349) (xy 286.936848 -371.89086)
			(xy 286.92877 -371.823922) (xy 286.928769 -371.756499) (xy 286.936844 -371.68956) (xy 286.95288 -371.624072)
			(xy 286.976645 -371.560975) (xy 287.007797 -371.50118) (xy 287.045887 -371.445546) (xy 287.067752 -371.419882)
			(xy 287.073545 -371.412735) (xy 287.08006 -371.395546) (xy 287.080452 -371.386354) (xy 287.080452 -370.893848)
			(xy 287.080007 -370.884665) (xy 287.073516 -370.867481) (xy 287.067752 -370.86032) (xy 287.045874 -370.834665)
			(xy 287.007783 -370.779031) (xy 286.97663 -370.719233) (xy 286.952864 -370.656135) (xy 286.936828 -370.590644)
			(xy 286.928752 -370.523704) (xy 266.12088 -370.523704) (xy 266.12088 -374.423882) (xy 286.928731 -374.423882)
			(xy 286.928735 -374.356454) (xy 286.936815 -374.289512) (xy 286.952857 -374.22402) (xy 286.976628 -374.160921)
			(xy 287.007787 -374.101124) (xy 287.045884 -374.04549) (xy 287.067752 -374.019826) (xy 287.073569 -374.012695)
			(xy 287.08007 -373.995494) (xy 287.080452 -373.986298) (xy 287.080452 -373.828818) (xy 287.080942 -373.818691)
			(xy 287.088666 -373.799968) (xy 287.102951 -373.785611) (xy 287.121636 -373.777793) (xy 287.13176 -373.777256)
			(xy 287.84804 -373.777256) (xy 287.858146 -373.777751) (xy 287.876817 -373.785494) (xy 287.891108 -373.799787)
			(xy 287.898849 -373.818458) (xy 287.899348 -373.828564) (xy 287.899348 -373.986298) (xy 287.899771 -373.995484)
			(xy 287.906277 -374.012667) (xy 287.912048 -374.019826) (xy 287.933873 -374.045524) (xy 287.971966 -374.101153)
			(xy 288.003121 -374.160944) (xy 288.02689 -374.224037) (xy 288.04293 -374.289522) (xy 288.05101 -374.356458)
			(xy 288.051014 -374.423823) (xy 291.32905 -374.423823) (xy 291.329054 -374.356514) (xy 291.337102 -374.289689)
			(xy 291.35308 -374.224304) (xy 291.376757 -374.161298) (xy 291.407796 -374.101573) (xy 291.44575 -374.045986)
			(xy 291.46754 -374.020334) (xy 291.473352 -374.0132) (xy 291.479857 -373.996001) (xy 291.48024 -373.986806)
			(xy 291.48024 -373.828818) (xy 291.480678 -373.818647) (xy 291.488458 -373.799853) (xy 291.502839 -373.785467)
			(xy 291.521631 -373.777682) (xy 291.531802 -373.777256) (xy 292.248082 -373.777256) (xy 292.258255 -373.777679)
			(xy 292.277053 -373.785461) (xy 292.291439 -373.799847) (xy 292.299221 -373.818645) (xy 292.299644 -373.828818)
			(xy 292.299644 -373.986806) (xy 292.300064 -373.995992) (xy 292.306572 -374.013176) (xy 292.312344 -374.020334)
			(xy 292.334091 -374.04602) (xy 292.372042 -374.101601) (xy 292.403078 -374.16132) (xy 292.426754 -374.22432)
			(xy 292.44273 -374.289698) (xy 292.450778 -374.356517) (xy 292.450782 -374.423819) (xy 292.450774 -374.423882)
			(xy 295.728819 -374.423882) (xy 295.728822 -374.356455) (xy 295.736903 -374.289513) (xy 295.752944 -374.224021)
			(xy 295.776715 -374.160922) (xy 295.807872 -374.101125) (xy 295.845968 -374.045491) (xy 295.867836 -374.019826)
			(xy 295.873651 -374.012694) (xy 295.880154 -373.995493) (xy 295.880536 -373.986298) (xy 295.880536 -373.828818)
			(xy 295.881041 -373.818693) (xy 295.888762 -373.799973) (xy 295.903043 -373.785616) (xy 295.921722 -373.777796)
			(xy 295.931844 -373.777256) (xy 296.648124 -373.777256) (xy 296.658274 -373.777701) (xy 296.677019 -373.785496)
			(xy 296.69134 -373.799885) (xy 296.699046 -373.818666) (xy 296.699432 -373.828818) (xy 296.699432 -373.986298)
			(xy 296.699858 -373.995483) (xy 296.706362 -374.012667) (xy 296.712132 -374.019826) (xy 296.733954 -374.045526)
			(xy 296.772041 -374.101156) (xy 296.803192 -374.160948) (xy 296.826957 -374.22404) (xy 296.842995 -374.289525)
			(xy 296.851073 -374.356459) (xy 296.851077 -374.423878) (xy 296.851077 -374.423882) (xy 300.12861 -374.423882)
			(xy 300.128613 -374.356455) (xy 300.136694 -374.289513) (xy 300.152734 -374.224021) (xy 300.176504 -374.160923)
			(xy 300.207661 -374.101126) (xy 300.245757 -374.045491) (xy 300.267624 -374.019826) (xy 300.273437 -374.012693)
			(xy 300.279941 -373.995493) (xy 300.280324 -373.986298) (xy 300.280324 -373.828818) (xy 300.280841 -373.818694)
			(xy 300.28856 -373.799977) (xy 300.302837 -373.78562) (xy 300.321511 -373.777798) (xy 300.331632 -373.777256)
			(xy 301.047912 -373.777256) (xy 301.058061 -373.777711) (xy 301.076806 -373.785502) (xy 301.091127 -373.799888)
			(xy 301.098834 -373.818667) (xy 301.09922 -373.828818) (xy 301.09922 -373.986298) (xy 301.099627 -373.995486)
			(xy 301.106142 -374.01267) (xy 301.11192 -374.019826) (xy 301.133742 -374.045526) (xy 301.171831 -374.101156)
			(xy 301.202982 -374.160947) (xy 301.226748 -374.22404) (xy 301.242785 -374.289524) (xy 301.250864 -374.356458)
			(xy 301.250868 -374.423823) (xy 330.929168 -374.423823) (xy 330.929172 -374.356514) (xy 330.937221 -374.289688)
			(xy 330.953199 -374.224303) (xy 330.976878 -374.161297) (xy 331.007917 -374.101572) (xy 331.045873 -374.045986)
			(xy 331.067664 -374.020334) (xy 331.073479 -374.013202) (xy 331.079981 -373.996001) (xy 331.080364 -373.986806)
			(xy 331.080364 -373.828818) (xy 331.080779 -373.818644) (xy 331.088563 -373.799845) (xy 331.102952 -373.785458)
			(xy 331.121752 -373.777677) (xy 331.131926 -373.777256) (xy 331.848206 -373.777256) (xy 331.85838 -373.777659)
			(xy 331.877178 -373.78545) (xy 331.891564 -373.799842) (xy 331.899345 -373.818644) (xy 331.899768 -373.828818)
			(xy 331.899768 -373.986806) (xy 331.900182 -373.995993) (xy 331.906694 -374.013177) (xy 331.912468 -374.020334)
			(xy 331.934214 -374.04602) (xy 331.972164 -374.101602) (xy 332.003198 -374.161321) (xy 332.026873 -374.224321)
			(xy 332.042849 -374.289699) (xy 332.050896 -374.356518) (xy 332.0509 -374.423819) (xy 332.050892 -374.423882)
			(xy 335.328961 -374.423882) (xy 335.328965 -374.356455) (xy 335.337045 -374.289515) (xy 335.353083 -374.224024)
			(xy 335.37685 -374.160926) (xy 335.408004 -374.101128) (xy 335.446095 -374.045492) (xy 335.46796 -374.019826)
			(xy 335.473778 -374.012696) (xy 335.480278 -373.995494) (xy 335.48066 -373.986298) (xy 335.48066 -373.828818)
			(xy 335.481142 -373.81869) (xy 335.488867 -373.799965) (xy 335.503156 -373.785608) (xy 335.521842 -373.777791)
			(xy 335.531968 -373.777256) (xy 336.248248 -373.777256) (xy 336.2584 -373.777682) (xy 336.277145 -373.785485)
			(xy 336.291465 -373.799879) (xy 336.299171 -373.818664) (xy 336.299556 -373.828818) (xy 336.299556 -373.986298)
			(xy 336.299977 -373.995484) (xy 336.306484 -374.012668) (xy 336.312256 -374.019826) (xy 336.33408 -374.045525)
			(xy 336.372173 -374.101153) (xy 336.403328 -374.160944) (xy 336.427097 -374.224037) (xy 336.443136 -374.289523)
			(xy 336.451216 -374.356458) (xy 336.45122 -374.423823) (xy 339.729256 -374.423823) (xy 339.72926 -374.356514)
			(xy 339.737309 -374.289689) (xy 339.753286 -374.224304) (xy 339.776964 -374.161298) (xy 339.808003 -374.101573)
			(xy 339.845957 -374.045986) (xy 339.867748 -374.020334) (xy 339.873561 -374.013201) (xy 339.880065 -373.996001)
			(xy 339.880448 -373.986806) (xy 339.880448 -373.828818) (xy 339.880879 -373.818646) (xy 339.88866 -373.79985)
			(xy 339.903043 -373.785464) (xy 339.921838 -373.77768) (xy 339.93201 -373.777256) (xy 340.64829 -373.777256)
			(xy 340.658463 -373.777672) (xy 340.677261 -373.785457) (xy 340.691647 -373.799846) (xy 340.699429 -373.818645)
			(xy 340.699852 -373.828818) (xy 340.699852 -373.986806) (xy 340.70027 -373.995992) (xy 340.706779 -374.013176)
			(xy 340.712552 -374.020334) (xy 340.734299 -374.04602) (xy 340.772249 -374.101601) (xy 340.803285 -374.16132)
			(xy 340.82696 -374.22432) (xy 340.842936 -374.289699) (xy 340.850984 -374.356517) (xy 340.850988 -374.423819)
			(xy 340.850988 -374.423823) (xy 344.129047 -374.423823) (xy 344.129051 -374.356514) (xy 344.137099 -374.289689)
			(xy 344.153077 -374.224304) (xy 344.176754 -374.161298) (xy 344.207792 -374.101573) (xy 344.245746 -374.045986)
			(xy 344.267536 -374.020334) (xy 344.273348 -374.0132) (xy 344.279852 -373.996001) (xy 344.280236 -373.986806)
			(xy 344.280236 -373.828818) (xy 344.280678 -373.818648) (xy 344.288457 -373.799854) (xy 344.302837 -373.785468)
			(xy 344.321628 -373.777682) (xy 344.331798 -373.777256) (xy 345.048078 -373.777256) (xy 345.05825 -373.777683)
			(xy 345.077048 -373.785464) (xy 345.091434 -373.799849) (xy 345.099217 -373.818646) (xy 345.09964 -373.828818)
			(xy 345.09964 -373.986806) (xy 345.100061 -373.995992) (xy 345.106569 -374.013175) (xy 345.11234 -374.020334)
			(xy 345.134087 -374.04602) (xy 345.172038 -374.101601) (xy 345.203075 -374.16132) (xy 345.226751 -374.22432)
			(xy 345.242727 -374.289698) (xy 345.250775 -374.356517) (xy 345.250779 -374.423819) (xy 345.250779 -374.423823)
			(xy 374.929078 -374.423823) (xy 374.929081 -374.356514) (xy 374.93713 -374.289688) (xy 374.953109 -374.224303)
			(xy 374.976788 -374.161296) (xy 375.007828 -374.101572) (xy 375.045784 -374.045985) (xy 375.067576 -374.020334)
			(xy 375.07338 -374.013194) (xy 375.079891 -373.996) (xy 375.080276 -373.986806) (xy 375.080276 -373.828818)
			(xy 375.080679 -373.818643) (xy 375.088465 -373.799841) (xy 375.102858 -373.785454) (xy 375.121663 -373.777675)
			(xy 375.131838 -373.777256) (xy 375.848118 -373.777256) (xy 375.858279 -373.777719) (xy 375.877052 -373.785503)
			(xy 375.891418 -373.799878) (xy 375.899188 -373.818656) (xy 375.89968 -373.828818) (xy 375.89968 -373.986806)
			(xy 375.900092 -373.995993) (xy 375.906605 -374.013177) (xy 375.91238 -374.020334) (xy 375.934126 -374.046021)
			(xy 375.972074 -374.101603) (xy 376.003108 -374.161322) (xy 376.026783 -374.224321) (xy 376.042758 -374.289699)
			(xy 376.050805 -374.356518) (xy 376.050809 -374.423819) (xy 376.050801 -374.423882) (xy 379.32887 -374.423882)
			(xy 379.328874 -374.356455) (xy 379.336954 -374.289515) (xy 379.352993 -374.224024) (xy 379.376761 -374.160925)
			(xy 379.407915 -374.101127) (xy 379.446007 -374.045492) (xy 379.467872 -374.019826) (xy 379.473691 -374.012697)
			(xy 379.48019 -373.995494) (xy 379.480572 -373.986298) (xy 379.480572 -373.828818) (xy 379.481042 -373.818688)
			(xy 379.48877 -373.799962) (xy 379.503062 -373.785604) (xy 379.521753 -373.777789) (xy 379.53188 -373.777256)
			(xy 380.24816 -373.777256) (xy 380.258306 -373.777754) (xy 380.277049 -373.785528) (xy 380.291372 -373.799901)
			(xy 380.299081 -373.818671) (xy 380.299468 -373.828818) (xy 380.299468 -373.986298) (xy 380.299886 -373.995484)
			(xy 380.306395 -374.012668) (xy 380.312168 -374.019826) (xy 380.333992 -374.045525) (xy 380.372084 -374.101154)
			(xy 380.403238 -374.160945) (xy 380.427006 -374.224038) (xy 380.443046 -374.289523) (xy 380.451125 -374.356458)
			(xy 380.451129 -374.423823) (xy 383.729165 -374.423823) (xy 383.729169 -374.356514) (xy 383.737218 -374.289688)
			(xy 383.753196 -374.224303) (xy 383.776874 -374.161297) (xy 383.807914 -374.101572) (xy 383.845869 -374.045986)
			(xy 383.86766 -374.020334) (xy 383.873474 -374.013202) (xy 383.879977 -373.996001) (xy 383.88036 -373.986806)
			(xy 383.88036 -373.828818) (xy 383.880779 -373.818645) (xy 383.888562 -373.799846) (xy 383.90295 -373.78546)
			(xy 383.921749 -373.777678) (xy 383.931922 -373.777256) (xy 384.648202 -373.777256) (xy 384.658376 -373.777663)
			(xy 384.677174 -373.785452) (xy 384.69156 -373.799843) (xy 384.699341 -373.818644) (xy 384.699764 -373.828818)
			(xy 384.699764 -373.986806) (xy 384.700179 -373.995992) (xy 384.70669 -374.013176) (xy 384.712464 -374.020334)
			(xy 384.73421 -374.04602) (xy 384.77216 -374.101602) (xy 384.803195 -374.161321) (xy 384.82687 -374.224321)
			(xy 384.842846 -374.289699) (xy 384.850893 -374.356518) (xy 384.850897 -374.423819) (xy 384.850897 -374.423823)
			(xy 388.128956 -374.423823) (xy 388.12896 -374.356514) (xy 388.137009 -374.289689) (xy 388.152986 -374.224304)
			(xy 388.176664 -374.161298) (xy 388.207703 -374.101573) (xy 388.245657 -374.045986) (xy 388.267448 -374.020334)
			(xy 388.273261 -374.013201) (xy 388.279765 -373.996001) (xy 388.280148 -373.986806) (xy 388.280148 -373.828818)
			(xy 388.280579 -373.818646) (xy 388.28836 -373.79985) (xy 388.302743 -373.785464) (xy 388.321538 -373.77768)
			(xy 388.33171 -373.777256) (xy 389.04799 -373.777256) (xy 389.058163 -373.777672) (xy 389.076961 -373.785457)
			(xy 389.091347 -373.799846) (xy 389.099129 -373.818645) (xy 389.099552 -373.828818) (xy 389.099552 -373.986806)
			(xy 389.09997 -373.995992) (xy 389.106479 -374.013176) (xy 389.112252 -374.020334) (xy 389.133999 -374.04602)
			(xy 389.171949 -374.101601) (xy 389.202985 -374.16132) (xy 389.22666 -374.22432) (xy 389.242636 -374.289699)
			(xy 389.250684 -374.356517) (xy 389.250688 -374.423819) (xy 389.250688 -374.423823) (xy 418.928987 -374.423823)
			(xy 418.928991 -374.356514) (xy 418.93704 -374.289688) (xy 418.953019 -374.224302) (xy 418.976698 -374.161296)
			(xy 419.007739 -374.101572) (xy 419.045696 -374.045986) (xy 419.067488 -374.020334) (xy 419.073294 -374.013195)
			(xy 419.079803 -373.996) (xy 419.080188 -373.986806) (xy 419.080188 -373.828818) (xy 419.08058 -373.818641)
			(xy 419.088368 -373.799837) (xy 419.102764 -373.78545) (xy 419.121573 -373.777673) (xy 419.13175 -373.777256)
			(xy 419.84803 -373.777256) (xy 419.858192 -373.777709) (xy 419.876965 -373.785497) (xy 419.89133 -373.799875)
			(xy 419.8991 -373.818656) (xy 419.899592 -373.828818) (xy 419.899592 -373.986806) (xy 419.900001 -373.995993)
			(xy 419.906516 -374.013177) (xy 419.912292 -374.020334) (xy 419.934038 -374.04602) (xy 419.971986 -374.101603)
			(xy 420.003019 -374.161322) (xy 420.026693 -374.224322) (xy 420.042668 -374.2897) (xy 420.050715 -374.356518)
			(xy 420.050719 -374.423819) (xy 420.050711 -374.423882) (xy 423.328779 -374.423882) (xy 423.328783 -374.356455)
			(xy 423.336863 -374.289514) (xy 423.352903 -374.224023) (xy 423.376671 -374.160925) (xy 423.407825 -374.101127)
			(xy 423.445918 -374.045492) (xy 423.467784 -374.019826) (xy 423.473593 -374.012689) (xy 423.480101 -373.995492)
			(xy 423.480484 -373.986298) (xy 423.480484 -373.828818) (xy 423.480942 -373.818687) (xy 423.488672 -373.799958)
			(xy 423.502968 -373.785599) (xy 423.521663 -373.777787) (xy 423.531792 -373.777256) (xy 424.248072 -373.777256)
			(xy 424.258174 -373.777807) (xy 424.276843 -373.785527) (xy 424.291137 -373.799803) (xy 424.298881 -373.818463)
			(xy 424.29938 -373.828564) (xy 424.29938 -373.986298) (xy 424.299795 -373.995485) (xy 424.306306 -374.012669)
			(xy 424.31208 -374.019826) (xy 424.333903 -374.045525) (xy 424.371995 -374.101154) (xy 424.403148 -374.160946)
			(xy 424.426916 -374.224038) (xy 424.442955 -374.289523) (xy 424.451034 -374.356458) (xy 424.451038 -374.423823)
			(xy 427.729074 -374.423823) (xy 427.729078 -374.356514) (xy 427.737127 -374.289688) (xy 427.753106 -374.224303)
			(xy 427.776784 -374.161296) (xy 427.807824 -374.101572) (xy 427.84578 -374.045986) (xy 427.867572 -374.020334)
			(xy 427.873388 -374.013203) (xy 427.879889 -373.996001) (xy 427.880272 -373.986806) (xy 427.880272 -373.828818)
			(xy 427.880679 -373.818643) (xy 427.888465 -373.799842) (xy 427.902856 -373.785456) (xy 427.921659 -373.777676)
			(xy 427.931834 -373.777256) (xy 428.648114 -373.777256) (xy 428.658289 -373.777653) (xy 428.677087 -373.785446)
			(xy 428.691472 -373.79984) (xy 428.699253 -373.818643) (xy 428.699676 -373.828818) (xy 428.699676 -373.986806)
			(xy 428.700088 -373.995993) (xy 428.706601 -374.013177) (xy 428.712376 -374.020334) (xy 428.734122 -374.04602)
			(xy 428.772071 -374.101602) (xy 428.803105 -374.161321) (xy 428.82678 -374.224321) (xy 428.842755 -374.289699)
			(xy 428.850802 -374.356518) (xy 428.850806 -374.423819) (xy 428.850806 -374.423823) (xy 432.128865 -374.423823)
			(xy 432.128869 -374.356514) (xy 432.136918 -374.289688) (xy 432.152896 -374.224303) (xy 432.176574 -374.161297)
			(xy 432.207614 -374.101572) (xy 432.245569 -374.045986) (xy 432.26736 -374.020334) (xy 432.273174 -374.013202)
			(xy 432.279677 -373.996001) (xy 432.28006 -373.986806) (xy 432.28006 -373.828818) (xy 432.280479 -373.818645)
			(xy 432.288262 -373.799846) (xy 432.30265 -373.78546) (xy 432.321449 -373.777678) (xy 432.331622 -373.777256)
			(xy 433.047902 -373.777256) (xy 433.058076 -373.777663) (xy 433.076874 -373.785452) (xy 433.09126 -373.799843)
			(xy 433.099041 -373.818644) (xy 433.099464 -373.828818) (xy 433.099464 -373.986806) (xy 433.099879 -373.995992)
			(xy 433.10639 -374.013176) (xy 433.112164 -374.020334) (xy 433.13391 -374.04602) (xy 433.17186 -374.101602)
			(xy 433.202895 -374.161321) (xy 433.22657 -374.224321) (xy 433.242546 -374.289699) (xy 433.250593 -374.356518)
			(xy 433.250597 -374.423819) (xy 433.242557 -374.490639) (xy 433.226589 -374.556019) (xy 433.202921 -374.619021)
			(xy 433.171892 -374.678744) (xy 433.133949 -374.73433) (xy 433.112164 -374.759982) (xy 433.106346 -374.767112)
			(xy 433.099845 -374.784314) (xy 433.099464 -374.79351) (xy 433.099464 -375.286778) (xy 433.099893 -375.295963)
			(xy 433.106394 -375.313147) (xy 433.112164 -375.320306) (xy 433.133981 -375.345934) (xy 433.171929 -375.401524)
			(xy 433.202961 -375.461251) (xy 433.226632 -375.524259) (xy 433.242603 -375.589644) (xy 433.250644 -375.656469)
			(xy 433.250642 -375.723776) (xy 433.242594 -375.790601) (xy 433.226618 -375.855985) (xy 433.202942 -375.91899)
			(xy 433.171906 -375.978715) (xy 433.133954 -376.034302) (xy 433.112164 -376.059954) (xy 433.106357 -376.067092)
			(xy 433.09985 -376.084288) (xy 433.099464 -376.093482) (xy 433.099464 -376.25147) (xy 433.099011 -376.261639)
			(xy 433.091237 -376.280433) (xy 433.07686 -376.294819) (xy 433.058071 -376.302605) (xy 433.047902 -376.303032)
			(xy 432.331622 -376.303032) (xy 432.321448 -376.302617) (xy 432.302648 -376.294834) (xy 432.288262 -376.280445)
			(xy 432.280481 -376.261644) (xy 432.28006 -376.25147) (xy 432.28006 -376.093482) (xy 432.279645 -376.084296)
			(xy 432.273133 -376.067112) (xy 432.26736 -376.059954) (xy 432.245601 -376.034278) (xy 432.20765 -375.978695)
			(xy 432.176614 -375.918975) (xy 432.152939 -375.855974) (xy 432.136963 -375.790594) (xy 432.128917 -375.723774)
			(xy 432.128914 -375.656471) (xy 432.136955 -375.58965) (xy 432.152926 -375.524269) (xy 432.176596 -375.461266)
			(xy 432.207627 -375.401543) (xy 432.245574 -375.345958) (xy 432.26736 -375.320306) (xy 432.273144 -375.313152)
			(xy 432.279664 -375.295968) (xy 432.28006 -375.286778) (xy 432.28006 -374.79351) (xy 432.279632 -374.784325)
			(xy 432.273129 -374.767141) (xy 432.26736 -374.759982) (xy 432.24553 -374.734364) (xy 432.207581 -374.678773)
			(xy 432.176549 -374.619045) (xy 432.152877 -374.556036) (xy 432.136907 -374.49065) (xy 432.128865 -374.423823)
			(xy 428.850806 -374.423823) (xy 428.842766 -374.490639) (xy 428.826798 -374.556018) (xy 428.803131 -374.619021)
			(xy 428.772103 -374.678743) (xy 428.73416 -374.734329) (xy 428.712376 -374.759982) (xy 428.706559 -374.767113)
			(xy 428.700057 -374.784314) (xy 428.699676 -374.79351) (xy 428.699676 -375.286778) (xy 428.700102 -375.295963)
			(xy 428.706605 -375.313148) (xy 428.712376 -375.320306) (xy 428.734193 -375.345934) (xy 428.77214 -375.401524)
			(xy 428.803171 -375.461251) (xy 428.826841 -375.524259) (xy 428.842812 -375.589644) (xy 428.850853 -375.656469)
			(xy 428.850851 -375.723776) (xy 428.842804 -375.790601) (xy 428.826828 -375.855984) (xy 428.803152 -375.91899)
			(xy 428.772117 -375.978714) (xy 428.734165 -376.034302) (xy 428.712376 -376.059954) (xy 428.706571 -376.067093)
			(xy 428.700062 -376.084288) (xy 428.699676 -376.093482) (xy 428.699676 -376.25147) (xy 428.699212 -376.261638)
			(xy 428.691439 -376.280429) (xy 428.677066 -376.294815) (xy 428.658282 -376.302603) (xy 428.648114 -376.303032)
			(xy 427.931834 -376.303032) (xy 427.921661 -376.302607) (xy 427.902861 -376.294828) (xy 427.888474 -376.280442)
			(xy 427.880693 -376.261643) (xy 427.880272 -376.25147) (xy 427.880272 -376.093482) (xy 427.879877 -376.084293)
			(xy 427.873353 -376.067109) (xy 427.867572 -376.059954) (xy 427.845813 -376.034278) (xy 427.807861 -375.978696)
			(xy 427.776825 -375.918976) (xy 427.753149 -375.855974) (xy 427.737173 -375.790595) (xy 427.729126 -375.723774)
			(xy 427.729123 -375.656471) (xy 427.737165 -375.58965) (xy 427.753135 -375.524269) (xy 427.776806 -375.461266)
			(xy 427.807838 -375.401543) (xy 427.845785 -375.345958) (xy 427.867572 -375.320306) (xy 427.873357 -375.313153)
			(xy 427.879877 -375.295968) (xy 427.880272 -375.286778) (xy 427.880272 -374.79351) (xy 427.879863 -374.784323)
			(xy 427.873349 -374.767138) (xy 427.867572 -374.759982) (xy 427.845742 -374.734364) (xy 427.807792 -374.678774)
			(xy 427.776759 -374.619046) (xy 427.753087 -374.556037) (xy 427.737116 -374.49065) (xy 427.729074 -374.423823)
			(xy 424.451038 -374.423823) (xy 424.451038 -374.423879) (xy 424.442966 -374.490815) (xy 424.426934 -374.556302)
			(xy 424.403174 -374.619397) (xy 424.372027 -374.679192) (xy 424.333942 -374.734825) (xy 424.31208 -374.76049)
			(xy 424.30626 -374.767619) (xy 424.29976 -374.784822) (xy 424.29938 -374.794018) (xy 424.29938 -375.28627)
			(xy 424.299809 -375.295455) (xy 424.30631 -375.312639) (xy 424.31208 -375.319798) (xy 424.333974 -375.345439)
			(xy 424.372063 -375.401076) (xy 424.403214 -375.460876) (xy 424.426977 -375.523976) (xy 424.443011 -375.589468)
			(xy 424.451085 -375.656409) (xy 424.451082 -375.723836) (xy 424.443003 -375.790776) (xy 424.426964 -375.856267)
			(xy 424.403195 -375.919366) (xy 424.37204 -375.979163) (xy 424.333946 -376.034797) (xy 424.31208 -376.060462)
			(xy 424.306272 -376.067599) (xy 424.299765 -376.084796) (xy 424.29938 -376.09399) (xy 424.29938 -376.25147)
			(xy 424.29885 -376.261592) (xy 424.291135 -376.280309) (xy 424.276863 -376.294666) (xy 424.258191 -376.30249)
			(xy 424.248072 -376.303032) (xy 423.531792 -376.303032) (xy 423.521687 -376.302522) (xy 423.503015 -376.294788)
			(xy 423.488721 -376.280499) (xy 423.480981 -376.261829) (xy 423.480484 -376.251724) (xy 423.480484 -376.09399)
			(xy 423.480082 -376.084802) (xy 423.473563 -376.067617) (xy 423.467784 -376.060462) (xy 423.44595 -376.034772)
			(xy 423.407862 -375.979141) (xy 423.37671 -375.919348) (xy 423.352945 -375.856254) (xy 423.336908 -375.790768)
			(xy 423.32883 -375.723833) (xy 423.328827 -375.656412) (xy 423.3369 -375.589476) (xy 423.352932 -375.523989)
			(xy 423.376692 -375.460893) (xy 423.407838 -375.401098) (xy 423.445922 -375.345463) (xy 423.467784 -375.319798)
			(xy 423.473562 -375.31264) (xy 423.480088 -375.295459) (xy 423.480484 -375.28627) (xy 423.480484 -374.794018)
			(xy 423.480069 -374.784831) (xy 423.473559 -374.767647) (xy 423.467784 -374.76049) (xy 423.445879 -374.734859)
			(xy 423.407793 -374.679219) (xy 423.376645 -374.619418) (xy 423.352884 -374.556317) (xy 423.336852 -374.490824)
			(xy 423.328779 -374.423882) (xy 420.050711 -374.423882) (xy 420.042679 -374.490638) (xy 420.026712 -374.556018)
			(xy 420.003045 -374.61902) (xy 419.972018 -374.678743) (xy 419.934076 -374.73433) (xy 419.912292 -374.759982)
			(xy 419.906477 -374.767114) (xy 419.899974 -374.784315) (xy 419.899592 -374.79351) (xy 419.899592 -375.286778)
			(xy 419.900015 -375.295964) (xy 419.90652 -375.313148) (xy 419.912292 -375.320306) (xy 419.934108 -375.345934)
			(xy 419.972054 -375.401525) (xy 420.003084 -375.461252) (xy 420.026754 -375.52426) (xy 420.042724 -375.589644)
			(xy 420.050765 -375.656469) (xy 420.050763 -375.723776) (xy 420.042716 -375.7906) (xy 420.026741 -375.855984)
			(xy 420.003066 -375.918989) (xy 419.972031 -375.978714) (xy 419.934081 -376.034301) (xy 419.912292 -376.059954)
			(xy 419.906489 -376.067095) (xy 419.899978 -376.084289) (xy 419.899592 -376.093482) (xy 419.899592 -376.25147)
			(xy 419.899043 -376.261622) (xy 419.891284 -376.280385) (xy 419.876935 -376.29475) (xy 419.858182 -376.302531)
			(xy 419.84803 -376.303032) (xy 419.13175 -376.303032) (xy 419.121578 -376.302595) (xy 419.102779 -376.29482)
			(xy 419.088391 -376.280438) (xy 419.080609 -376.261642) (xy 419.080188 -376.25147) (xy 419.080188 -376.093482)
			(xy 419.079789 -376.084294) (xy 419.073268 -376.067109) (xy 419.067488 -376.059954) (xy 419.045728 -376.034278)
			(xy 419.007775 -375.978696) (xy 418.976738 -375.918976) (xy 418.953061 -375.855975) (xy 418.937085 -375.790595)
			(xy 418.929038 -375.723774) (xy 418.929035 -375.656471) (xy 418.937077 -375.589649) (xy 418.953048 -375.524268)
			(xy 418.97672 -375.461265) (xy 419.007752 -375.401542) (xy 419.045701 -375.345957) (xy 419.067488 -375.320306)
			(xy 419.073263 -375.313145) (xy 419.079791 -375.295967) (xy 419.080188 -375.286778) (xy 419.080188 -374.79351)
			(xy 419.079776 -374.784323) (xy 419.073264 -374.767138) (xy 419.067488 -374.759982) (xy 419.045658 -374.734364)
			(xy 419.007707 -374.678774) (xy 418.976673 -374.619046) (xy 418.953 -374.556037) (xy 418.937029 -374.49065)
			(xy 418.928987 -374.423823) (xy 389.250688 -374.423823) (xy 389.242648 -374.490639) (xy 389.226679 -374.556019)
			(xy 389.203011 -374.619022) (xy 389.171982 -374.678744) (xy 389.134037 -374.73433) (xy 389.112252 -374.759982)
			(xy 389.106432 -374.76711) (xy 389.099933 -374.784314) (xy 389.099552 -374.79351) (xy 389.099552 -375.286778)
			(xy 389.099983 -375.295963) (xy 389.106483 -375.313147) (xy 389.112252 -375.320306) (xy 389.13407 -375.345934)
			(xy 389.172018 -375.401523) (xy 389.203051 -375.46125) (xy 389.226722 -375.524258) (xy 389.242693 -375.589643)
			(xy 389.250735 -375.656469) (xy 389.250732 -375.723776) (xy 389.242685 -375.790601) (xy 389.226709 -375.855985)
			(xy 389.203032 -375.918991) (xy 389.171995 -375.978715) (xy 389.134042 -376.034302) (xy 389.112252 -376.059954)
			(xy 389.106444 -376.067091) (xy 389.099937 -376.084288) (xy 389.099552 -376.093482) (xy 389.099552 -376.25147)
			(xy 389.099111 -376.261641) (xy 389.091334 -376.280437) (xy 389.076954 -376.294823) (xy 389.058161 -376.302607)
			(xy 389.04799 -376.303032) (xy 388.33171 -376.303032) (xy 388.321535 -376.302627) (xy 388.302735 -376.29484)
			(xy 388.288349 -376.280448) (xy 388.280569 -376.261645) (xy 388.280148 -376.25147) (xy 388.280148 -376.093482)
			(xy 388.279736 -376.084295) (xy 388.273222 -376.067111) (xy 388.267448 -376.059954) (xy 388.24569 -376.034278)
			(xy 388.207739 -375.978695) (xy 388.176704 -375.918975) (xy 388.153029 -375.855973) (xy 388.137054 -375.790594)
			(xy 388.129007 -375.723774) (xy 388.129005 -375.656471) (xy 388.137046 -375.58965) (xy 388.153016 -375.52427)
			(xy 388.176686 -375.461267) (xy 388.207716 -375.401544) (xy 388.245662 -375.345958) (xy 388.267448 -375.320306)
			(xy 388.273231 -375.313151) (xy 388.279752 -375.295968) (xy 388.280148 -375.286778) (xy 388.280148 -374.79351)
			(xy 388.279722 -374.784325) (xy 388.273218 -374.767141) (xy 388.267448 -374.759982) (xy 388.245619 -374.734364)
			(xy 388.20767 -374.678773) (xy 388.176638 -374.619045) (xy 388.152968 -374.556036) (xy 388.136997 -374.490649)
			(xy 388.128956 -374.423823) (xy 384.850897 -374.423823) (xy 384.842857 -374.490639) (xy 384.826889 -374.556019)
			(xy 384.803221 -374.619021) (xy 384.772192 -374.678744) (xy 384.734249 -374.73433) (xy 384.712464 -374.759982)
			(xy 384.706646 -374.767112) (xy 384.700145 -374.784314) (xy 384.699764 -374.79351) (xy 384.699764 -375.286778)
			(xy 384.700193 -375.295963) (xy 384.706694 -375.313147) (xy 384.712464 -375.320306) (xy 384.734281 -375.345934)
			(xy 384.772229 -375.401524) (xy 384.803261 -375.461251) (xy 384.826932 -375.524259) (xy 384.842903 -375.589644)
			(xy 384.850944 -375.656469) (xy 384.850942 -375.723776) (xy 384.842894 -375.790601) (xy 384.826918 -375.855985)
			(xy 384.803242 -375.91899) (xy 384.772206 -375.978715) (xy 384.734254 -376.034302) (xy 384.712464 -376.059954)
			(xy 384.706657 -376.067092) (xy 384.70015 -376.084288) (xy 384.699764 -376.093482) (xy 384.699764 -376.25147)
			(xy 384.699311 -376.261639) (xy 384.691537 -376.280433) (xy 384.67716 -376.294819) (xy 384.658371 -376.302605)
			(xy 384.648202 -376.303032) (xy 383.931922 -376.303032) (xy 383.921748 -376.302617) (xy 383.902948 -376.294834)
			(xy 383.888562 -376.280445) (xy 383.880781 -376.261644) (xy 383.88036 -376.25147) (xy 383.88036 -376.093482)
			(xy 383.879945 -376.084296) (xy 383.873433 -376.067112) (xy 383.86766 -376.059954) (xy 383.845901 -376.034278)
			(xy 383.80795 -375.978695) (xy 383.776914 -375.918975) (xy 383.753239 -375.855974) (xy 383.737263 -375.790594)
			(xy 383.729217 -375.723774) (xy 383.729214 -375.656471) (xy 383.737255 -375.58965) (xy 383.753226 -375.524269)
			(xy 383.776896 -375.461266) (xy 383.807927 -375.401543) (xy 383.845874 -375.345958) (xy 383.86766 -375.320306)
			(xy 383.873444 -375.313152) (xy 383.879964 -375.295968) (xy 383.88036 -375.286778) (xy 383.88036 -374.79351)
			(xy 383.879932 -374.784325) (xy 383.873429 -374.767141) (xy 383.86766 -374.759982) (xy 383.84583 -374.734364)
			(xy 383.807881 -374.678773) (xy 383.776849 -374.619045) (xy 383.753177 -374.556036) (xy 383.737207 -374.49065)
			(xy 383.729165 -374.423823) (xy 380.451129 -374.423823) (xy 380.451129 -374.423879) (xy 380.443057 -374.490815)
			(xy 380.427025 -374.556302) (xy 380.403264 -374.619397) (xy 380.372116 -374.679192) (xy 380.334031 -374.734825)
			(xy 380.312168 -374.76049) (xy 380.306347 -374.767617) (xy 380.299847 -374.784822) (xy 380.299468 -374.794018)
			(xy 380.299468 -375.28627) (xy 380.2999 -375.295455) (xy 380.306399 -375.312639) (xy 380.312168 -375.319798)
			(xy 380.334063 -375.345438) (xy 380.372152 -375.401076) (xy 380.403304 -375.460875) (xy 380.427068 -375.523975)
			(xy 380.443102 -375.589468) (xy 380.451176 -375.656409) (xy 380.451173 -375.723836) (xy 380.443094 -375.790777)
			(xy 380.427054 -375.856268) (xy 380.403285 -375.919366) (xy 380.372129 -375.979163) (xy 380.334035 -376.034797)
			(xy 380.312168 -376.060462) (xy 380.306358 -376.067598) (xy 380.299852 -376.084796) (xy 380.299468 -376.09399)
			(xy 380.299468 -376.25147) (xy 380.298949 -376.261594) (xy 380.291233 -376.280313) (xy 380.276956 -376.29467)
			(xy 380.258281 -376.302492) (xy 380.24816 -376.303032) (xy 379.53188 -376.303032) (xy 379.521729 -376.302596)
			(xy 379.502982 -376.294799) (xy 379.48866 -376.280408) (xy 379.480955 -376.261623) (xy 379.480572 -376.25147)
			(xy 379.480572 -376.09399) (xy 379.480173 -376.084802) (xy 379.473652 -376.067617) (xy 379.467872 -376.060462)
			(xy 379.446038 -376.034772) (xy 379.407951 -375.97914) (xy 379.3768 -375.919347) (xy 379.353036 -375.856254)
			(xy 379.336999 -375.790768) (xy 379.328921 -375.723833) (xy 379.328918 -375.656412) (xy 379.336991 -375.589476)
			(xy 379.353022 -375.523989) (xy 379.376782 -375.460894) (xy 379.407928 -375.401098) (xy 379.446011 -375.345464)
			(xy 379.467872 -375.319798) (xy 379.473661 -375.312648) (xy 379.480178 -375.295461) (xy 379.480572 -375.28627)
			(xy 379.480572 -374.794018) (xy 379.48016 -374.784831) (xy 379.473648 -374.767646) (xy 379.467872 -374.76049)
			(xy 379.445968 -374.734858) (xy 379.407882 -374.679218) (xy 379.376735 -374.619417) (xy 379.352974 -374.556316)
			(xy 379.336943 -374.490823) (xy 379.32887 -374.423882) (xy 376.050801 -374.423882) (xy 376.042769 -374.490638)
			(xy 376.026801 -374.556018) (xy 376.003134 -374.619021) (xy 375.972107 -374.678743) (xy 375.934164 -374.734329)
			(xy 375.91238 -374.759982) (xy 375.906564 -374.767113) (xy 375.900062 -374.784315) (xy 375.89968 -374.79351)
			(xy 375.89968 -375.286778) (xy 375.900105 -375.295963) (xy 375.906609 -375.313148) (xy 375.91238 -375.320306)
			(xy 375.934197 -375.345934) (xy 375.972143 -375.401524) (xy 376.003174 -375.461252) (xy 376.026845 -375.524259)
			(xy 376.042815 -375.589644) (xy 376.050856 -375.656469) (xy 376.050854 -375.723776) (xy 376.042807 -375.7906)
			(xy 376.026831 -375.855984) (xy 376.003156 -375.91899) (xy 375.97212 -375.978714) (xy 375.934169 -376.034302)
			(xy 375.91238 -376.059954) (xy 375.906576 -376.067094) (xy 375.900066 -376.084288) (xy 375.89968 -376.093482)
			(xy 375.89968 -376.25147) (xy 375.899212 -376.261637) (xy 375.89144 -376.280428) (xy 375.877068 -376.294813)
			(xy 375.858285 -376.302602) (xy 375.848118 -376.303032) (xy 375.131838 -376.303032) (xy 375.121665 -376.302604)
			(xy 375.102866 -376.294826) (xy 375.088478 -376.280441) (xy 375.080697 -376.261643) (xy 375.080276 -376.25147)
			(xy 375.080276 -376.093482) (xy 375.07988 -376.084293) (xy 375.073357 -376.067109) (xy 375.067576 -376.059954)
			(xy 375.045817 -376.034278) (xy 375.007865 -375.978696) (xy 374.976828 -375.918976) (xy 374.953152 -375.855974)
			(xy 374.937176 -375.790595) (xy 374.929129 -375.723774) (xy 374.929126 -375.656471) (xy 374.937168 -375.58965)
			(xy 374.953138 -375.524269) (xy 374.97681 -375.461265) (xy 375.007841 -375.401543) (xy 375.045789 -375.345958)
			(xy 375.067576 -375.320306) (xy 375.07335 -375.313144) (xy 375.079879 -375.295967) (xy 375.080276 -375.286778)
			(xy 375.080276 -374.79351) (xy 375.079866 -374.784323) (xy 375.073353 -374.767138) (xy 375.067576 -374.759982)
			(xy 375.045746 -374.734365) (xy 375.007796 -374.678774) (xy 374.976762 -374.619046) (xy 374.95309 -374.556037)
			(xy 374.937119 -374.49065) (xy 374.929078 -374.423823) (xy 345.250779 -374.423823) (xy 345.242739 -374.49064)
			(xy 345.226769 -374.55602) (xy 345.2031 -374.619022) (xy 345.172071 -374.678745) (xy 345.134126 -374.73433)
			(xy 345.11234 -374.759982) (xy 345.106519 -374.767109) (xy 345.10002 -374.784314) (xy 345.09964 -374.79351)
			(xy 345.09964 -375.286778) (xy 345.100074 -375.295962) (xy 345.106573 -375.313146) (xy 345.11234 -375.320306)
			(xy 345.134158 -375.345933) (xy 345.172107 -375.401523) (xy 345.203141 -375.46125) (xy 345.226813 -375.524258)
			(xy 345.242784 -375.589643) (xy 345.250826 -375.656469) (xy 345.250823 -375.723776) (xy 345.242776 -375.790602)
			(xy 345.226799 -375.855986) (xy 345.203122 -375.918992) (xy 345.172084 -375.978716) (xy 345.13413 -376.034302)
			(xy 345.11234 -376.059954) (xy 345.106531 -376.06709) (xy 345.100025 -376.084288) (xy 345.09964 -376.093482)
			(xy 345.09964 -376.25147) (xy 345.099211 -376.261642) (xy 345.091432 -376.280441) (xy 345.077047 -376.294827)
			(xy 345.05825 -376.302609) (xy 345.048078 -376.303032) (xy 344.331798 -376.303032) (xy 344.321623 -376.302637)
			(xy 344.302822 -376.294846) (xy 344.288436 -376.280451) (xy 344.280657 -376.261646) (xy 344.280236 -376.25147)
			(xy 344.280236 -376.093482) (xy 344.279826 -376.084295) (xy 344.273311 -376.067111) (xy 344.267536 -376.059954)
			(xy 344.245778 -376.034277) (xy 344.207829 -375.978694) (xy 344.176794 -375.918974) (xy 344.15312 -375.855973)
			(xy 344.137145 -375.790594) (xy 344.129098 -375.723774) (xy 344.129096 -375.656471) (xy 344.137137 -375.589651)
			(xy 344.153106 -375.52427) (xy 344.176776 -375.461267) (xy 344.207805 -375.401544) (xy 344.24575 -375.345958)
			(xy 344.267536 -375.320306) (xy 344.273317 -375.31315) (xy 344.27984 -375.295968) (xy 344.280236 -375.286778)
			(xy 344.280236 -374.79351) (xy 344.279813 -374.784324) (xy 344.273308 -374.76714) (xy 344.267536 -374.759982)
			(xy 344.245707 -374.734364) (xy 344.20776 -374.678772) (xy 344.176728 -374.619044) (xy 344.153058 -374.556035)
			(xy 344.137088 -374.490649) (xy 344.129047 -374.423823) (xy 340.850988 -374.423823) (xy 340.842948 -374.490639)
			(xy 340.826979 -374.556019) (xy 340.803311 -374.619022) (xy 340.772282 -374.678744) (xy 340.734337 -374.73433)
			(xy 340.712552 -374.759982) (xy 340.706732 -374.76711) (xy 340.700233 -374.784314) (xy 340.699852 -374.79351)
			(xy 340.699852 -375.286778) (xy 340.700283 -375.295963) (xy 340.706783 -375.313147) (xy 340.712552 -375.320306)
			(xy 340.73437 -375.345934) (xy 340.772318 -375.401523) (xy 340.803351 -375.46125) (xy 340.827022 -375.524258)
			(xy 340.842993 -375.589643) (xy 340.851035 -375.656469) (xy 340.851032 -375.723776) (xy 340.842985 -375.790601)
			(xy 340.827009 -375.855985) (xy 340.803332 -375.918991) (xy 340.772295 -375.978715) (xy 340.734342 -376.034302)
			(xy 340.712552 -376.059954) (xy 340.706744 -376.067091) (xy 340.700237 -376.084288) (xy 340.699852 -376.093482)
			(xy 340.699852 -376.25147) (xy 340.699411 -376.261641) (xy 340.691634 -376.280437) (xy 340.677254 -376.294823)
			(xy 340.658461 -376.302607) (xy 340.64829 -376.303032) (xy 339.93201 -376.303032) (xy 339.921835 -376.302627)
			(xy 339.903035 -376.29484) (xy 339.888649 -376.280448) (xy 339.880869 -376.261645) (xy 339.880448 -376.25147)
			(xy 339.880448 -376.093482) (xy 339.880036 -376.084295) (xy 339.873522 -376.067111) (xy 339.867748 -376.059954)
			(xy 339.84599 -376.034278) (xy 339.808039 -375.978695) (xy 339.777004 -375.918975) (xy 339.753329 -375.855973)
			(xy 339.737354 -375.790594) (xy 339.729307 -375.723774) (xy 339.729305 -375.656471) (xy 339.737346 -375.58965)
			(xy 339.753316 -375.52427) (xy 339.776986 -375.461267) (xy 339.808016 -375.401544) (xy 339.845962 -375.345958)
			(xy 339.867748 -375.320306) (xy 339.873531 -375.313151) (xy 339.880052 -375.295968) (xy 339.880448 -375.286778)
			(xy 339.880448 -374.79351) (xy 339.880022 -374.784325) (xy 339.873518 -374.767141) (xy 339.867748 -374.759982)
			(xy 339.845919 -374.734364) (xy 339.80797 -374.678773) (xy 339.776938 -374.619045) (xy 339.753268 -374.556036)
			(xy 339.737297 -374.490649) (xy 339.729256 -374.423823) (xy 336.45122 -374.423823) (xy 336.45122 -374.423879)
			(xy 336.443148 -374.490815) (xy 336.427115 -374.556303) (xy 336.403354 -374.619398) (xy 336.372206 -374.679193)
			(xy 336.334119 -374.734826) (xy 336.312256 -374.76049) (xy 336.306433 -374.767616) (xy 336.299935 -374.784821)
			(xy 336.299556 -374.794018) (xy 336.299556 -375.28627) (xy 336.29999 -375.295454) (xy 336.306488 -375.312639)
			(xy 336.312256 -375.319798) (xy 336.334151 -375.345438) (xy 336.372242 -375.401075) (xy 336.403394 -375.460875)
			(xy 336.427158 -375.523975) (xy 336.443193 -375.589467) (xy 336.451267 -375.656409) (xy 336.451264 -375.723836)
			(xy 336.443185 -375.790777) (xy 336.427145 -375.856268) (xy 336.403375 -375.919367) (xy 336.372218 -375.979163)
			(xy 336.334123 -376.034797) (xy 336.312256 -376.060462) (xy 336.306445 -376.067597) (xy 336.29994 -376.084795)
			(xy 336.299556 -376.09399) (xy 336.299556 -376.25147) (xy 336.299049 -376.261595) (xy 336.29133 -376.280317)
			(xy 336.27705 -376.294674) (xy 336.258371 -376.302494) (xy 336.248248 -376.303032) (xy 335.531968 -376.303032)
			(xy 335.521816 -376.302605) (xy 335.503069 -376.294805) (xy 335.488748 -376.280411) (xy 335.481043 -376.261624)
			(xy 335.48066 -376.25147) (xy 335.48066 -376.09399) (xy 335.480241 -376.084804) (xy 335.473732 -376.06762)
			(xy 335.46796 -376.060462) (xy 335.446127 -376.034772) (xy 335.40804 -375.97914) (xy 335.37689 -375.919347)
			(xy 335.353126 -375.856253) (xy 335.33709 -375.790768) (xy 335.329012 -375.723833) (xy 335.329009 -375.656412)
			(xy 335.337082 -375.589477) (xy 335.353113 -375.52399) (xy 335.376872 -375.460894) (xy 335.408017 -375.401099)
			(xy 335.446099 -375.345464) (xy 335.46796 -375.319798) (xy 335.473747 -375.312647) (xy 335.480266 -375.295461)
			(xy 335.48066 -375.28627) (xy 335.48066 -374.794018) (xy 335.480228 -374.784833) (xy 335.473728 -374.76765)
			(xy 335.46796 -374.76049) (xy 335.446056 -374.734858) (xy 335.407971 -374.679218) (xy 335.376825 -374.619417)
			(xy 335.353065 -374.556316) (xy 335.337033 -374.490823) (xy 335.328961 -374.423882) (xy 332.050892 -374.423882)
			(xy 332.04286 -374.490639) (xy 332.026892 -374.556019) (xy 332.003224 -374.619021) (xy 331.972196 -374.678744)
			(xy 331.934253 -374.73433) (xy 331.912468 -374.759982) (xy 331.90665 -374.767112) (xy 331.900149 -374.784314)
			(xy 331.899768 -374.79351) (xy 331.899768 -375.286778) (xy 331.900196 -375.295963) (xy 331.906698 -375.313147)
			(xy 331.912468 -375.320306) (xy 331.934285 -375.345934) (xy 331.972233 -375.401524) (xy 332.003264 -375.461251)
			(xy 332.026935 -375.524259) (xy 332.042906 -375.589644) (xy 332.050947 -375.656469) (xy 332.050945 -375.723776)
			(xy 332.042898 -375.790601) (xy 332.026922 -375.855985) (xy 332.003246 -375.91899) (xy 331.972209 -375.978715)
			(xy 331.934257 -376.034302) (xy 331.912468 -376.059954) (xy 331.906662 -376.067092) (xy 331.900154 -376.084288)
			(xy 331.899768 -376.093482) (xy 331.899768 -376.25147) (xy 331.899312 -376.261639) (xy 331.891538 -376.280432)
			(xy 331.877162 -376.294817) (xy 331.858375 -376.302604) (xy 331.848206 -376.303032) (xy 331.131926 -376.303032)
			(xy 331.121752 -376.302614) (xy 331.102953 -376.294832) (xy 331.088566 -376.280444) (xy 331.080785 -376.261644)
			(xy 331.080364 -376.25147) (xy 331.080364 -376.093482) (xy 331.079948 -376.084296) (xy 331.073437 -376.067112)
			(xy 331.067664 -376.059954) (xy 331.045905 -376.034278) (xy 331.007954 -375.978695) (xy 330.976918 -375.918975)
			(xy 330.953242 -375.855974) (xy 330.937266 -375.790594) (xy 330.92922 -375.723774) (xy 330.929217 -375.656471)
			(xy 330.937258 -375.58965) (xy 330.953229 -375.524269) (xy 330.976899 -375.461266) (xy 331.007931 -375.401543)
			(xy 331.045877 -375.345958) (xy 331.067664 -375.320306) (xy 331.073448 -375.313152) (xy 331.079969 -375.295968)
			(xy 331.080364 -375.286778) (xy 331.080364 -374.79351) (xy 331.079935 -374.784325) (xy 331.073433 -374.767141)
			(xy 331.067664 -374.759982) (xy 331.045834 -374.734364) (xy 331.007885 -374.678773) (xy 330.976852 -374.619045)
			(xy 330.95318 -374.556036) (xy 330.93721 -374.49065) (xy 330.929168 -374.423823) (xy 301.250868 -374.423823)
			(xy 301.250868 -374.423878) (xy 301.242797 -374.490814) (xy 301.226766 -374.5563) (xy 301.203008 -374.619395)
			(xy 301.171863 -374.67919) (xy 301.133781 -374.734824) (xy 301.11192 -374.76049) (xy 301.106105 -374.767622)
			(xy 301.099601 -374.784823) (xy 301.09922 -374.794018) (xy 301.09922 -375.28627) (xy 301.09964 -375.295456)
			(xy 301.106146 -375.312641) (xy 301.11192 -375.319798) (xy 301.133813 -375.345439) (xy 301.171899 -375.401078)
			(xy 301.203048 -375.460877) (xy 301.226809 -375.523977) (xy 301.242842 -375.589469) (xy 301.250915 -375.65641)
			(xy 301.250912 -375.723835) (xy 301.242834 -375.790775) (xy 301.226796 -375.856266) (xy 301.203029 -375.919364)
			(xy 301.171876 -375.979161) (xy 301.133785 -376.034796) (xy 301.11192 -376.060462) (xy 301.106117 -376.067603)
			(xy 301.099605 -376.084797) (xy 301.09922 -376.09399) (xy 301.09922 -376.25147) (xy 301.098748 -376.2616)
			(xy 301.091023 -376.280328) (xy 301.076731 -376.294687) (xy 301.058039 -376.3025) (xy 301.047912 -376.303032)
			(xy 300.331632 -376.303032) (xy 300.321484 -376.302553) (xy 300.302738 -376.294774) (xy 300.288415 -376.280395)
			(xy 300.280708 -376.26162) (xy 300.280324 -376.25147) (xy 300.280324 -376.09399) (xy 300.279913 -376.084803)
			(xy 300.2734 -376.067619) (xy 300.267624 -376.060462) (xy 300.245789 -376.034773) (xy 300.207697 -375.979142)
			(xy 300.176544 -375.91935) (xy 300.152777 -375.856256) (xy 300.136739 -375.790769) (xy 300.12866 -375.723833)
			(xy 300.128658 -375.656412) (xy 300.136731 -375.589475) (xy 300.152764 -375.523987) (xy 300.176526 -375.460892)
			(xy 300.207674 -375.401096) (xy 300.245761 -375.345463) (xy 300.267624 -375.319798) (xy 300.273407 -375.312643)
			(xy 300.279929 -375.29546) (xy 300.280324 -375.28627) (xy 300.280324 -374.794018) (xy 300.2799 -374.784832)
			(xy 300.273395 -374.767648) (xy 300.267624 -374.76049) (xy 300.245718 -374.734859) (xy 300.207629 -374.67922)
			(xy 300.176479 -374.61942) (xy 300.152716 -374.556318) (xy 300.136683 -374.490825) (xy 300.12861 -374.423882)
			(xy 296.851077 -374.423882) (xy 296.843006 -374.490813) (xy 296.826976 -374.556299) (xy 296.803218 -374.619394)
			(xy 296.772074 -374.67919) (xy 296.733992 -374.734824) (xy 296.712132 -374.76049) (xy 296.706306 -374.767614)
			(xy 296.699811 -374.784821) (xy 296.699432 -374.794018) (xy 296.699432 -375.28627) (xy 296.699872 -375.295454)
			(xy 296.706366 -375.312638) (xy 296.712132 -375.319798) (xy 296.734024 -375.345439) (xy 296.77211 -375.401078)
			(xy 296.803258 -375.460878) (xy 296.827019 -375.523978) (xy 296.843051 -375.589469) (xy 296.851124 -375.65641)
			(xy 296.851121 -375.723835) (xy 296.843043 -375.790775) (xy 296.827005 -375.856265) (xy 296.803239 -375.919363)
			(xy 296.772087 -375.979161) (xy 296.733997 -376.034796) (xy 296.712132 -376.060462) (xy 296.706318 -376.067595)
			(xy 296.699816 -376.084795) (xy 296.699432 -376.09399) (xy 296.699432 -376.25147) (xy 296.698948 -376.261598)
			(xy 296.691225 -376.280324) (xy 296.676937 -376.294683) (xy 296.65825 -376.302498) (xy 296.648124 -376.303032)
			(xy 295.931844 -376.303032) (xy 295.921697 -376.302543) (xy 295.902951 -376.294768) (xy 295.888628 -376.280392)
			(xy 295.880921 -376.261619) (xy 295.880536 -376.25147) (xy 295.880536 -376.09399) (xy 295.880123 -376.084803)
			(xy 295.87361 -376.067619) (xy 295.867836 -376.060462) (xy 295.846 -376.034773) (xy 295.807908 -375.979143)
			(xy 295.776754 -375.91935) (xy 295.752987 -375.856256) (xy 295.736948 -375.79077) (xy 295.728869 -375.723834)
			(xy 295.728867 -375.656412) (xy 295.73694 -375.589475) (xy 295.752973 -375.523987) (xy 295.776736 -375.460891)
			(xy 295.807885 -375.401096) (xy 295.845973 -375.345463) (xy 295.867836 -375.319798) (xy 295.873621 -375.312644)
			(xy 295.880142 -375.29546) (xy 295.880536 -375.28627) (xy 295.880536 -374.794018) (xy 295.880109 -374.784833)
			(xy 295.873606 -374.767649) (xy 295.867836 -374.76049) (xy 295.84593 -374.734859) (xy 295.80784 -374.679221)
			(xy 295.776689 -374.61942) (xy 295.752925 -374.556319) (xy 295.736892 -374.490825) (xy 295.728819 -374.423882)
			(xy 292.450774 -374.423882) (xy 292.442742 -374.490639) (xy 292.426773 -374.55602) (xy 292.403104 -374.619022)
			(xy 292.372075 -374.678745) (xy 292.33413 -374.73433) (xy 292.312344 -374.759982) (xy 292.306523 -374.76711)
			(xy 292.300025 -374.784314) (xy 292.299644 -374.79351) (xy 292.299644 -375.286778) (xy 292.300077 -375.295962)
			(xy 292.306576 -375.313146) (xy 292.312344 -375.320306) (xy 292.334162 -375.345934) (xy 292.372111 -375.401523)
			(xy 292.403144 -375.46125) (xy 292.426816 -375.524258) (xy 292.442787 -375.589643) (xy 292.450829 -375.656469)
			(xy 292.450826 -375.723776) (xy 292.442779 -375.790601) (xy 292.426802 -375.855985) (xy 292.403125 -375.918991)
			(xy 292.372088 -375.978716) (xy 292.334134 -376.034302) (xy 292.312344 -376.059954) (xy 292.306535 -376.06709)
			(xy 292.300029 -376.084288) (xy 292.299644 -376.093482) (xy 292.299644 -376.25147) (xy 292.299211 -376.261642)
			(xy 292.291433 -376.280439) (xy 292.277049 -376.294826) (xy 292.258254 -376.302609) (xy 292.248082 -376.303032)
			(xy 291.531802 -376.303032) (xy 291.521627 -376.302634) (xy 291.502826 -376.294844) (xy 291.48844 -376.28045)
			(xy 291.480661 -376.261645) (xy 291.48024 -376.25147) (xy 291.48024 -376.093482) (xy 291.47983 -376.084295)
			(xy 291.473315 -376.067111) (xy 291.46754 -376.059954) (xy 291.445782 -376.034277) (xy 291.407832 -375.978695)
			(xy 291.376798 -375.918974) (xy 291.353123 -375.855973) (xy 291.337148 -375.790594) (xy 291.329101 -375.723774)
			(xy 291.329099 -375.656471) (xy 291.33714 -375.589651) (xy 291.35311 -375.52427) (xy 291.376779 -375.461267)
			(xy 291.407809 -375.401544) (xy 291.445754 -375.345958) (xy 291.46754 -375.320306) (xy 291.473322 -375.31315)
			(xy 291.479844 -375.295968) (xy 291.48024 -375.286778) (xy 291.48024 -374.79351) (xy 291.479816 -374.784324)
			(xy 291.473311 -374.76714) (xy 291.46754 -374.759982) (xy 291.445711 -374.734364) (xy 291.407763 -374.678773)
			(xy 291.376732 -374.619044) (xy 291.353061 -374.556035) (xy 291.337091 -374.490649) (xy 291.32905 -374.423823)
			(xy 288.051014 -374.423823) (xy 288.051014 -374.423879) (xy 288.042941 -374.490816) (xy 288.026909 -374.556303)
			(xy 288.003147 -374.619398) (xy 287.971998 -374.679193) (xy 287.933911 -374.734826) (xy 287.912048 -374.76049)
			(xy 287.906224 -374.767616) (xy 287.899727 -374.784821) (xy 287.899348 -374.794018) (xy 287.899348 -375.28627)
			(xy 287.899784 -375.295454) (xy 287.906281 -375.312638) (xy 287.912048 -375.319798) (xy 287.933943 -375.345438)
			(xy 287.972035 -375.401075) (xy 288.003187 -375.460874) (xy 288.026952 -375.523974) (xy 288.042987 -375.589467)
			(xy 288.051061 -375.656409) (xy 288.051058 -375.723836) (xy 288.042978 -375.790777) (xy 288.026938 -375.856269)
			(xy 288.003168 -375.919367) (xy 287.972011 -375.979164) (xy 287.933916 -376.034798) (xy 287.912048 -376.060462)
			(xy 287.906236 -376.067596) (xy 287.899732 -376.084795) (xy 287.899348 -376.09399) (xy 287.899348 -376.25147)
			(xy 287.898849 -376.261596) (xy 287.891129 -376.280319) (xy 287.876846 -376.294677) (xy 287.858164 -376.302495)
			(xy 287.84804 -376.303032) (xy 287.13176 -376.303032) (xy 287.121653 -376.302548) (xy 287.10298 -376.294804)
			(xy 287.088687 -376.280507) (xy 287.080948 -376.261831) (xy 287.080452 -376.251724) (xy 287.080452 -376.09399)
			(xy 287.080035 -376.084804) (xy 287.073525 -376.06762) (xy 287.067752 -376.060462) (xy 287.045916 -376.034773)
			(xy 287.007823 -375.979143) (xy 286.976668 -375.919351) (xy 286.9529 -375.856257) (xy 286.93686 -375.79077)
			(xy 286.928781 -375.723834) (xy 286.928779 -375.656411) (xy 286.936852 -375.589474) (xy 286.952886 -375.523986)
			(xy 286.976649 -375.46089) (xy 287.007799 -375.401095) (xy 287.045888 -375.345462) (xy 287.067752 -375.319798)
			(xy 287.073538 -375.312646) (xy 287.080058 -375.29546) (xy 287.080452 -375.28627) (xy 287.080452 -374.794018)
			(xy 287.080022 -374.784833) (xy 287.073521 -374.767649) (xy 287.067752 -374.76049) (xy 287.045845 -374.73486)
			(xy 287.007754 -374.679221) (xy 286.976602 -374.619421) (xy 286.952838 -374.556319) (xy 286.936804 -374.490825)
			(xy 286.928731 -374.423882) (xy 266.12088 -374.423882) (xy 266.12088 -377.534932) (xy 266.120477 -377.545004)
			(xy 266.112741 -377.563602) (xy 266.105894 -377.571) (xy 265.757406 -377.919234) (xy 265.750002 -377.926069)
			(xy 265.731406 -377.933791) (xy 265.721338 -377.93422) (xy 243.05133 -377.93422) (xy 243.04126 -377.9338)
			(xy 243.022661 -377.926078) (xy 243.015262 -377.919234) (xy 242.506246 -377.410472) (xy 242.499408 -377.40307)
			(xy 242.491685 -377.384473) (xy 242.49126 -377.374404) (xy 234.964478 -377.374404) (xy 236.356885 -378.766811)
			(xy 269.68983 -378.766811) (xy 269.68983 -378.633249) (xy 269.697894 -378.499931) (xy 269.713994 -378.367343)
			(xy 269.738069 -378.235969) (xy 269.770032 -378.106288) (xy 269.809767 -377.978774) (xy 269.857129 -377.853891)
			(xy 269.911944 -377.732096) (xy 269.974014 -377.613833) (xy 270.04311 -377.499534) (xy 270.118982 -377.389614)
			(xy 270.201352 -377.284477) (xy 270.28992 -377.184504) (xy 270.384362 -377.090062) (xy 270.484335 -377.001494)
			(xy 270.589472 -376.919124) (xy 270.699392 -376.843252) (xy 270.813691 -376.774156) (xy 270.931954 -376.712086)
			(xy 271.053749 -376.657271) (xy 271.178632 -376.609909) (xy 271.306146 -376.570174) (xy 271.435827 -376.538211)
			(xy 271.567201 -376.514136) (xy 271.699789 -376.498036) (xy 271.833107 -376.489972) (xy 271.966669 -376.489972)
			(xy 272.099987 -376.498036) (xy 272.232575 -376.514136) (xy 272.363949 -376.538211) (xy 272.49363 -376.570174)
			(xy 272.621144 -376.609909) (xy 272.746027 -376.657271) (xy 272.867822 -376.712086) (xy 272.986085 -376.774156)
			(xy 273.068299 -376.823856) (xy 289.128922 -376.823856) (xy 289.128922 -376.75655) (xy 289.136967 -376.689727)
			(xy 289.152941 -376.624344) (xy 289.176615 -376.56134) (xy 289.207651 -376.501617) (xy 289.245603 -376.446031)
			(xy 289.267392 -376.42038) (xy 289.273179 -376.413228) (xy 289.2797 -376.396043) (xy 289.280092 -376.386852)
			(xy 289.280092 -375.893584) (xy 289.279691 -375.884396) (xy 289.273171 -375.867212) (xy 289.267392 -375.860056)
			(xy 289.245634 -375.834379) (xy 289.207681 -375.778797) (xy 289.176643 -375.719078) (xy 289.152966 -375.656076)
			(xy 289.13699 -375.590696) (xy 289.128942 -375.523876) (xy 289.128939 -375.456572) (xy 289.136981 -375.389751)
			(xy 289.152952 -375.32437) (xy 289.176624 -375.261367) (xy 289.207656 -375.201644) (xy 289.245605 -375.146059)
			(xy 289.267392 -375.120408) (xy 289.273167 -375.113247) (xy 289.279695 -375.096069) (xy 289.280092 -375.08688)
			(xy 289.280092 -374.928638) (xy 289.280664 -374.918488) (xy 289.288417 -374.899729) (xy 289.302758 -374.885364)
			(xy 289.321505 -374.87758) (xy 289.331654 -374.877076) (xy 290.047934 -374.877076) (xy 290.058113 -374.877437)
			(xy 290.076915 -374.88524) (xy 290.0913 -374.899645) (xy 290.099077 -374.918459) (xy 290.099496 -374.928638)
			(xy 290.099496 -375.08688) (xy 290.099917 -375.096066) (xy 290.106423 -375.11325) (xy 290.112196 -375.120408)
			(xy 290.134014 -375.146035) (xy 290.17196 -375.201626) (xy 290.20299 -375.261353) (xy 290.226659 -375.324361)
			(xy 290.242629 -375.389746) (xy 290.25067 -375.456571) (xy 290.250667 -375.523878) (xy 290.24262 -375.590702)
			(xy 290.226645 -375.656085) (xy 290.20297 -375.719091) (xy 290.171935 -375.778816) (xy 290.133985 -375.834403)
			(xy 290.112196 -375.860056) (xy 290.106393 -375.867196) (xy 290.099882 -375.884391) (xy 290.099496 -375.893584)
			(xy 290.099496 -376.386852) (xy 290.09993 -376.396037) (xy 290.106427 -376.413221) (xy 290.112196 -376.42038)
			(xy 290.133987 -376.446029) (xy 290.171933 -376.501617) (xy 290.202964 -376.561341) (xy 290.226635 -376.624346)
			(xy 290.242607 -376.689728) (xy 290.25065 -376.756551) (xy 290.25065 -376.823855) (xy 290.250643 -376.823915)
			(xy 293.528715 -376.823915) (xy 293.528715 -376.756491) (xy 293.53679 -376.689554) (xy 293.552824 -376.624065)
			(xy 293.576588 -376.560968) (xy 293.607737 -376.501172) (xy 293.645825 -376.445537) (xy 293.667688 -376.419872)
			(xy 293.673478 -376.412722) (xy 293.679997 -376.395535) (xy 293.680388 -376.386344) (xy 293.680388 -375.894092)
			(xy 293.679984 -375.884904) (xy 293.673466 -375.86772) (xy 293.667688 -375.860564) (xy 293.645856 -375.834873)
			(xy 293.607767 -375.779242) (xy 293.576616 -375.719449) (xy 293.55285 -375.656355) (xy 293.536813 -375.59087)
			(xy 293.528735 -375.523934) (xy 293.528732 -375.456514) (xy 293.536804 -375.389578) (xy 293.552836 -375.324091)
			(xy 293.576596 -375.260995) (xy 293.607742 -375.2012) (xy 293.645826 -375.145565) (xy 293.667688 -375.1199)
			(xy 293.673466 -375.112741) (xy 293.679992 -375.095561) (xy 293.680388 -375.086372) (xy 293.680388 -374.928638)
			(xy 293.680956 -374.91852) (xy 293.688662 -374.89981) (xy 293.702923 -374.885454) (xy 293.721582 -374.877624)
			(xy 293.731696 -374.877076) (xy 294.447976 -374.877076) (xy 294.458094 -374.877535) (xy 294.476793 -374.885271)
			(xy 294.491107 -374.899574) (xy 294.498857 -374.918266) (xy 294.499284 -374.928384) (xy 294.499284 -375.086372)
			(xy 294.499711 -375.095557) (xy 294.506214 -375.112742) (xy 294.511984 -375.1199) (xy 294.53388 -375.145539)
			(xy 294.571969 -375.201177) (xy 294.603119 -375.260977) (xy 294.626882 -375.324077) (xy 294.642916 -375.389569)
			(xy 294.650989 -375.456511) (xy 294.650986 -375.523937) (xy 294.642907 -375.590878) (xy 294.626868 -375.656369)
			(xy 294.603099 -375.719467) (xy 294.571944 -375.779264) (xy 294.53385 -375.834899) (xy 294.511984 -375.860564)
			(xy 294.506176 -375.867701) (xy 294.499669 -375.884898) (xy 294.499284 -375.894092) (xy 294.499284 -376.386344)
			(xy 294.499677 -376.395533) (xy 294.506203 -376.412717) (xy 294.511984 -376.419872) (xy 294.533852 -376.445534)
			(xy 294.571942 -376.501168) (xy 294.603094 -376.560965) (xy 294.626858 -376.624062) (xy 294.642894 -376.689552)
			(xy 294.65097 -376.756491) (xy 294.650969 -376.823856) (xy 297.92901 -376.823856) (xy 297.92901 -376.75655)
			(xy 297.937054 -376.689727) (xy 297.953028 -376.624345) (xy 297.976702 -376.56134) (xy 298.007737 -376.501617)
			(xy 298.045687 -376.446032) (xy 298.067476 -376.42038) (xy 298.073261 -376.413226) (xy 298.079783 -376.396042)
			(xy 298.080176 -376.386852) (xy 298.080176 -375.893584) (xy 298.079779 -375.884395) (xy 298.073257 -375.867211)
			(xy 298.067476 -375.860056) (xy 298.045719 -375.834378) (xy 298.007766 -375.778797) (xy 297.97673 -375.719077)
			(xy 297.953054 -375.656076) (xy 297.937077 -375.590696) (xy 297.92903 -375.523876) (xy 297.929027 -375.456572)
			(xy 297.937069 -375.389751) (xy 297.953039 -375.324371) (xy 297.97671 -375.261367) (xy 298.007742 -375.201645)
			(xy 298.045689 -375.14606) (xy 298.067476 -375.120408) (xy 298.073249 -375.113246) (xy 298.079778 -375.096068)
			(xy 298.080176 -375.08688) (xy 298.080176 -374.928638) (xy 298.080596 -374.918464) (xy 298.088376 -374.899663)
			(xy 298.102763 -374.885276) (xy 298.121564 -374.877496) (xy 298.131738 -374.877076) (xy 298.848018 -374.877076)
			(xy 298.858195 -374.87745) (xy 298.876998 -374.885248) (xy 298.891383 -374.899649) (xy 298.899161 -374.91846)
			(xy 298.89958 -374.928638) (xy 298.89958 -375.08688) (xy 298.900004 -375.096066) (xy 298.906509 -375.11325)
			(xy 298.91228 -375.120408) (xy 298.934099 -375.146035) (xy 298.972045 -375.201625) (xy 299.003076 -375.261352)
			(xy 299.026746 -375.32436) (xy 299.042716 -375.389745) (xy 299.050758 -375.45657) (xy 299.050755 -375.523878)
			(xy 299.042708 -375.590702) (xy 299.026732 -375.656086) (xy 299.003056 -375.719092) (xy 298.972021 -375.778816)
			(xy 298.934069 -375.834404) (xy 298.91228 -375.860056) (xy 298.906475 -375.867195) (xy 298.899966 -375.88439)
			(xy 298.89958 -375.893584) (xy 298.89958 -376.386852) (xy 298.900018 -376.396036) (xy 298.906513 -376.413221)
			(xy 298.91228 -376.42038) (xy 298.934071 -376.446029) (xy 298.972019 -376.501616) (xy 299.003051 -376.561341)
			(xy 299.026722 -376.624345) (xy 299.042695 -376.689728) (xy 299.050731 -376.756492) (xy 302.328802 -376.756492)
			(xy 302.336877 -376.689554) (xy 302.352912 -376.624066) (xy 302.376674 -376.560969) (xy 302.407823 -376.501173)
			(xy 302.445909 -376.445538) (xy 302.467772 -376.419872) (xy 302.473572 -376.412729) (xy 302.480082 -376.395537)
			(xy 302.480472 -376.386344) (xy 302.480472 -375.894092) (xy 302.480072 -375.884904) (xy 302.473552 -375.867719)
			(xy 302.467772 -375.860564) (xy 302.44594 -375.834872) (xy 302.407853 -375.779241) (xy 302.376702 -375.719448)
			(xy 302.352937 -375.656355) (xy 302.336901 -375.590869) (xy 302.328823 -375.523934) (xy 302.32882 -375.456514)
			(xy 302.336892 -375.389578) (xy 302.352923 -375.324091) (xy 302.376682 -375.260996) (xy 302.407828 -375.2012)
			(xy 302.445911 -375.145566) (xy 302.467772 -375.1199) (xy 302.47356 -375.112749) (xy 302.480078 -375.095563)
			(xy 302.480472 -375.086372) (xy 302.480472 -374.928638) (xy 302.480959 -374.91851) (xy 302.48868 -374.899784)
			(xy 302.502967 -374.885425) (xy 302.521654 -374.87761) (xy 302.53178 -374.877076) (xy 303.24806 -374.877076)
			(xy 303.258209 -374.877554) (xy 303.276955 -374.885332) (xy 303.291279 -374.899711) (xy 303.298985 -374.918488)
			(xy 303.299368 -374.928638) (xy 303.299368 -375.086372) (xy 303.299799 -375.095557) (xy 303.306299 -375.112741)
			(xy 303.312068 -375.1199) (xy 303.333965 -375.145539) (xy 303.372054 -375.201176) (xy 303.403205 -375.260976)
			(xy 303.426969 -375.324076) (xy 303.443004 -375.389569) (xy 303.451077 -375.456511) (xy 303.451074 -375.523937)
			(xy 303.442995 -375.590878) (xy 303.426955 -375.65637) (xy 303.403186 -375.719468) (xy 303.37203 -375.779265)
			(xy 303.333935 -375.834899) (xy 303.312068 -375.860564) (xy 303.306258 -375.867699) (xy 303.299752 -375.884898)
			(xy 303.299368 -375.894092) (xy 303.299368 -376.386344) (xy 303.299764 -376.395533) (xy 303.306288 -376.412716)
			(xy 303.312068 -376.419872) (xy 303.333937 -376.445533) (xy 303.372028 -376.501168) (xy 303.40318 -376.560964)
			(xy 303.426945 -376.624062) (xy 303.442982 -376.689551) (xy 303.451058 -376.756491) (xy 303.451057 -376.823915)
			(xy 333.128833 -376.823915) (xy 333.128833 -376.756491) (xy 333.136908 -376.689553) (xy 333.152944 -376.624064)
			(xy 333.176708 -376.560967) (xy 333.207859 -376.501171) (xy 333.245948 -376.445537) (xy 333.267812 -376.419872)
			(xy 333.273604 -376.412724) (xy 333.280121 -376.395536) (xy 333.280512 -376.386344) (xy 333.280512 -375.894092)
			(xy 333.280103 -375.884905) (xy 333.273588 -375.86772) (xy 333.267812 -375.860564) (xy 333.245979 -375.834873)
			(xy 333.207889 -375.779242) (xy 333.176736 -375.71945) (xy 333.152969 -375.656356) (xy 333.136931 -375.59087)
			(xy 333.128853 -375.523935) (xy 333.12885 -375.456513) (xy 333.136923 -375.389577) (xy 333.152955 -375.32409)
			(xy 333.176716 -375.260994) (xy 333.207864 -375.201199) (xy 333.24595 -375.145565) (xy 333.267812 -375.1199)
			(xy 333.273592 -375.112743) (xy 333.280116 -375.095562) (xy 333.280512 -375.086372) (xy 333.280512 -374.928638)
			(xy 333.281057 -374.918517) (xy 333.288767 -374.899802) (xy 333.303035 -374.885446) (xy 333.321702 -374.87762)
			(xy 333.33182 -374.877076) (xy 334.0481 -374.877076) (xy 334.058251 -374.877521) (xy 334.076999 -374.885312)
			(xy 334.091321 -374.899701) (xy 334.099025 -374.918485) (xy 334.099408 -374.928638) (xy 334.099408 -375.086372)
			(xy 334.09983 -375.095558) (xy 334.106335 -375.112743) (xy 334.112108 -375.1199) (xy 334.134003 -375.145539)
			(xy 334.17209 -375.201178) (xy 334.203239 -375.260978) (xy 334.227001 -375.324078) (xy 334.243034 -375.38957)
			(xy 334.251107 -375.456511) (xy 334.251105 -375.523937) (xy 334.243026 -375.590877) (xy 334.226987 -375.656368)
			(xy 334.20322 -375.719466) (xy 334.172066 -375.779263) (xy 334.133974 -375.834899) (xy 334.112108 -375.860564)
			(xy 334.106303 -375.867703) (xy 334.099793 -375.884898) (xy 334.099408 -375.894092) (xy 334.099408 -376.386344)
			(xy 334.099795 -376.395534) (xy 334.106324 -376.412718) (xy 334.112108 -376.419872) (xy 334.133976 -376.445534)
			(xy 334.172064 -376.501169) (xy 334.203214 -376.560966) (xy 334.226977 -376.624063) (xy 334.243012 -376.689553)
			(xy 334.251088 -376.756491) (xy 334.251087 -376.823855) (xy 337.529152 -376.823855) (xy 337.529152 -376.756551)
			(xy 337.537195 -376.689729) (xy 337.553167 -376.624348) (xy 337.576837 -376.561344) (xy 337.607868 -376.50162)
			(xy 337.645814 -376.446033) (xy 337.6676 -376.42038) (xy 337.673388 -376.413228) (xy 337.679908 -376.396043)
			(xy 337.6803 -376.386852) (xy 337.6803 -375.893584) (xy 337.679897 -375.884396) (xy 337.673378 -375.867212)
			(xy 337.6676 -375.860056) (xy 337.645845 -375.834377) (xy 337.607898 -375.778794) (xy 337.576865 -375.719074)
			(xy 337.553192 -375.656073) (xy 337.537218 -375.590694) (xy 337.529172 -375.523875) (xy 337.529169 -375.456573)
			(xy 337.53721 -375.389753) (xy 337.553178 -375.324373) (xy 337.576846 -375.26137) (xy 337.607873 -375.201647)
			(xy 337.645815 -375.146061) (xy 337.6676 -375.120408) (xy 337.673376 -375.113248) (xy 337.679903 -375.096069)
			(xy 337.6803 -375.08688) (xy 337.6803 -374.928638) (xy 337.680864 -374.918487) (xy 337.688619 -374.899726)
			(xy 337.702963 -374.885361) (xy 337.721712 -374.877579) (xy 337.731862 -374.877076) (xy 338.448142 -374.877076)
			(xy 338.458307 -374.8775) (xy 338.477085 -374.885295) (xy 338.49145 -374.899683) (xy 338.499216 -374.918472)
			(xy 338.499704 -374.928638) (xy 338.499704 -375.08688) (xy 338.500123 -375.096066) (xy 338.50663 -375.113251)
			(xy 338.512404 -375.120408) (xy 338.534222 -375.146035) (xy 338.572167 -375.201626) (xy 338.603196 -375.261353)
			(xy 338.626865 -375.324361) (xy 338.642835 -375.389746) (xy 338.650876 -375.456571) (xy 338.650873 -375.523877)
			(xy 338.642826 -375.590701) (xy 338.626851 -375.656085) (xy 338.603177 -375.719091) (xy 338.572142 -375.778815)
			(xy 338.534192 -375.834403) (xy 338.512404 -375.860056) (xy 338.506602 -375.867197) (xy 338.50009 -375.884391)
			(xy 338.499704 -375.893584) (xy 338.499704 -376.386852) (xy 338.500136 -376.396037) (xy 338.506634 -376.413222)
			(xy 338.512404 -376.42038) (xy 338.534194 -376.44603) (xy 338.57214 -376.501617) (xy 338.603171 -376.561342)
			(xy 338.626842 -376.624346) (xy 338.642813 -376.689729) (xy 338.650856 -376.756551) (xy 338.650856 -376.823855)
			(xy 338.650849 -376.823915) (xy 341.928921 -376.823915) (xy 341.928921 -376.756491) (xy 341.936996 -376.689553)
			(xy 341.953031 -376.624065) (xy 341.976794 -376.560968) (xy 342.007944 -376.501172) (xy 342.046032 -376.445537)
			(xy 342.067896 -376.419872) (xy 342.073686 -376.412722) (xy 342.080205 -376.395535) (xy 342.080596 -376.386344)
			(xy 342.080596 -375.894092) (xy 342.08019 -375.884904) (xy 342.073674 -375.86772) (xy 342.067896 -375.860564)
			(xy 342.046064 -375.834873) (xy 342.007974 -375.779242) (xy 341.976822 -375.719449) (xy 341.953057 -375.656356)
			(xy 341.937019 -375.59087) (xy 341.928941 -375.523935) (xy 341.928938 -375.456513) (xy 341.93701 -375.389577)
			(xy 341.953042 -375.32409) (xy 341.976803 -375.260995) (xy 342.007949 -375.201199) (xy 342.046034 -375.145565)
			(xy 342.067896 -375.1199) (xy 342.073675 -375.112742) (xy 342.0802 -375.095561) (xy 342.080596 -375.086372)
			(xy 342.080596 -374.928638) (xy 342.081157 -374.918519) (xy 342.088864 -374.899807) (xy 342.103127 -374.885451)
			(xy 342.121789 -374.877623) (xy 342.131904 -374.877076) (xy 342.848184 -374.877076) (xy 342.858334 -374.877534)
			(xy 342.877082 -374.88532) (xy 342.891405 -374.899705) (xy 342.899109 -374.918486) (xy 342.899492 -374.928638)
			(xy 342.899492 -375.086372) (xy 342.899917 -375.095558) (xy 342.906421 -375.112742) (xy 342.912192 -375.1199)
			(xy 342.934088 -375.145539) (xy 342.972176 -375.201177) (xy 343.003326 -375.260977) (xy 343.027088 -375.324077)
			(xy 343.043122 -375.38957) (xy 343.051195 -375.456511) (xy 343.051193 -375.523937) (xy 343.043113 -375.590878)
			(xy 343.027074 -375.656369) (xy 343.003306 -375.719467) (xy 342.972151 -375.779264) (xy 342.934058 -375.834899)
			(xy 342.912192 -375.860564) (xy 342.906385 -375.867702) (xy 342.899877 -375.884898) (xy 342.899492 -375.894092)
			(xy 342.899492 -376.386344) (xy 342.899883 -376.395533) (xy 342.90641 -376.412717) (xy 342.912192 -376.419872)
			(xy 342.93406 -376.445534) (xy 342.972149 -376.501169) (xy 343.0033 -376.560965) (xy 343.027065 -376.624063)
			(xy 343.0431 -376.689552) (xy 343.051176 -376.756491) (xy 343.051175 -376.823856) (xy 346.329216 -376.823856)
			(xy 346.329216 -376.75655) (xy 346.33726 -376.689727) (xy 346.353234 -376.624345) (xy 346.376909 -376.56134)
			(xy 346.407944 -376.501617) (xy 346.445895 -376.446032) (xy 346.467684 -376.42038) (xy 346.47347 -376.413227)
			(xy 346.479991 -376.396043) (xy 346.480384 -376.386852) (xy 346.480384 -375.893584) (xy 346.479985 -375.884396)
			(xy 346.473464 -375.867211) (xy 346.467684 -375.860056) (xy 346.445926 -375.834379) (xy 346.407974 -375.778797)
			(xy 346.376937 -375.719077) (xy 346.35326 -375.656076) (xy 346.337283 -375.590696) (xy 346.329236 -375.523876)
			(xy 346.329233 -375.456572) (xy 346.337275 -375.389751) (xy 346.353246 -375.32437) (xy 346.376917 -375.261367)
			(xy 346.407949 -375.201645) (xy 346.445897 -375.14606) (xy 346.467684 -375.120408) (xy 346.473458 -375.113247)
			(xy 346.479987 -375.096069) (xy 346.480384 -375.08688) (xy 346.480384 -374.928638) (xy 346.480796 -374.918463)
			(xy 346.488577 -374.899661) (xy 346.502967 -374.885273) (xy 346.521771 -374.877495) (xy 346.531946 -374.877076)
			(xy 347.248226 -374.877076) (xy 347.258404 -374.877443) (xy 347.277207 -374.885244) (xy 347.291592 -374.899647)
			(xy 347.299369 -374.918459) (xy 347.299788 -374.928638) (xy 347.299788 -375.08688) (xy 347.300211 -375.096066)
			(xy 347.306716 -375.11325) (xy 347.312488 -375.120408) (xy 347.334306 -375.146035) (xy 347.372252 -375.201625)
			(xy 347.403283 -375.261353) (xy 347.426953 -375.324361) (xy 347.442923 -375.389746) (xy 347.450964 -375.456571)
			(xy 347.450961 -375.523878) (xy 347.442914 -375.590702) (xy 347.426938 -375.656086) (xy 347.403263 -375.719091)
			(xy 347.372228 -375.778816) (xy 347.334277 -375.834403) (xy 347.312488 -375.860056) (xy 347.306684 -375.867196)
			(xy 347.300174 -375.88439) (xy 347.299788 -375.893584) (xy 347.299788 -376.386852) (xy 347.300224 -376.396036)
			(xy 347.30672 -376.413221) (xy 347.312488 -376.42038) (xy 347.334279 -376.446029) (xy 347.372226 -376.501617)
			(xy 347.403257 -376.561341) (xy 347.426929 -376.624346) (xy 347.442901 -376.689728) (xy 347.450944 -376.756551)
			(xy 347.450944 -376.823855) (xy 347.450937 -376.823915) (xy 377.128742 -376.823915) (xy 377.128742 -376.756491)
			(xy 377.136817 -376.689553) (xy 377.152853 -376.624064) (xy 377.176618 -376.560967) (xy 377.20777 -376.501171)
			(xy 377.245859 -376.445537) (xy 377.267724 -376.419872) (xy 377.273518 -376.412725) (xy 377.280033 -376.395536)
			(xy 377.280424 -376.386344) (xy 377.280424 -375.894092) (xy 377.280012 -375.884905) (xy 377.273499 -375.867721)
			(xy 377.267724 -375.860564) (xy 377.245891 -375.834873) (xy 377.207799 -375.779243) (xy 377.176646 -375.71945)
			(xy 377.152879 -375.656357) (xy 377.136841 -375.590871) (xy 377.128762 -375.523935) (xy 377.128759 -375.456513)
			(xy 377.136832 -375.389577) (xy 377.152865 -375.324089) (xy 377.176626 -375.260993) (xy 377.207775 -375.201198)
			(xy 377.245861 -375.145565) (xy 377.267724 -375.1199) (xy 377.273506 -375.112744) (xy 377.280029 -375.095562)
			(xy 377.280424 -375.086372) (xy 377.280424 -374.928638) (xy 377.280957 -374.918516) (xy 377.28867 -374.899799)
			(xy 377.302942 -374.885442) (xy 377.321613 -374.877618) (xy 377.331732 -374.877076) (xy 378.048012 -374.877076)
			(xy 378.058164 -374.877511) (xy 378.076912 -374.885306) (xy 378.091234 -374.899698) (xy 378.098938 -374.918484)
			(xy 378.09932 -374.928638) (xy 378.09932 -375.086372) (xy 378.099739 -375.095558) (xy 378.106246 -375.112743)
			(xy 378.11202 -375.1199) (xy 378.133915 -375.14554) (xy 378.172001 -375.201178) (xy 378.203149 -375.260978)
			(xy 378.226911 -375.324078) (xy 378.242943 -375.38957) (xy 378.251016 -375.456511) (xy 378.251014 -375.523937)
			(xy 378.242935 -375.590877) (xy 378.226897 -375.656368) (xy 378.20313 -375.719466) (xy 378.171976 -375.779263)
			(xy 378.133885 -375.834898) (xy 378.11202 -375.860564) (xy 378.106216 -375.867704) (xy 378.099705 -375.884898)
			(xy 378.09932 -375.894092) (xy 378.09932 -376.386344) (xy 378.099704 -376.395534) (xy 378.106235 -376.412718)
			(xy 378.11202 -376.419872) (xy 378.133887 -376.445534) (xy 378.171974 -376.50117) (xy 378.203124 -376.560967)
			(xy 378.226887 -376.624064) (xy 378.242922 -376.689553) (xy 378.250997 -376.756491) (xy 378.250997 -376.756551)
			(xy 381.529061 -376.756551) (xy 381.537105 -376.689729) (xy 381.553076 -376.624347) (xy 381.576747 -376.561343)
			(xy 381.607779 -376.501619) (xy 381.645725 -376.446032) (xy 381.667512 -376.42038) (xy 381.673301 -376.413229)
			(xy 381.67982 -376.396043) (xy 381.680212 -376.386852) (xy 381.680212 -375.893584) (xy 381.679807 -375.884396)
			(xy 381.67329 -375.867212) (xy 381.667512 -375.860056) (xy 381.645756 -375.834378) (xy 381.607808 -375.778794)
			(xy 381.576775 -375.719074) (xy 381.553102 -375.656073) (xy 381.537127 -375.590694) (xy 381.529081 -375.523875)
			(xy 381.529078 -375.456573) (xy 381.537119 -375.389753) (xy 381.553088 -375.324373) (xy 381.576756 -375.26137)
			(xy 381.607784 -375.201647) (xy 381.645727 -375.14606) (xy 381.667512 -375.120408) (xy 381.673289 -375.113249)
			(xy 381.679815 -375.096069) (xy 381.680212 -375.08688) (xy 381.680212 -374.928638) (xy 381.680694 -374.918472)
			(xy 381.688462 -374.899683) (xy 381.702829 -374.885298) (xy 381.721609 -374.877507) (xy 381.731774 -374.877076)
			(xy 382.448054 -374.877076) (xy 382.458227 -374.877502) (xy 382.477028 -374.885279) (xy 382.491416 -374.899665)
			(xy 382.499196 -374.918465) (xy 382.499616 -374.928638) (xy 382.499616 -375.08688) (xy 382.500032 -375.096067)
			(xy 382.506541 -375.113251) (xy 382.512316 -375.120408) (xy 382.534136 -375.146034) (xy 382.572087 -375.201623)
			(xy 382.603122 -375.26135) (xy 382.626795 -375.324358) (xy 382.642767 -375.389744) (xy 382.650809 -375.45657)
			(xy 382.650806 -375.523878) (xy 382.642758 -375.590704) (xy 382.62678 -375.656088) (xy 382.603102 -375.719094)
			(xy 382.572063 -375.778818) (xy 382.534107 -375.834404) (xy 382.512316 -375.860056) (xy 382.506515 -375.867198)
			(xy 382.500002 -375.884391) (xy 382.499616 -375.893584) (xy 382.499616 -376.386852) (xy 382.500045 -376.396037)
			(xy 382.506545 -376.413222) (xy 382.512316 -376.42038) (xy 382.534109 -376.446028) (xy 382.572061 -376.501614)
			(xy 382.603096 -376.561338) (xy 382.626771 -376.624343) (xy 382.642745 -376.689726) (xy 382.650789 -376.75655)
			(xy 382.650789 -376.823856) (xy 382.650782 -376.823915) (xy 385.92883 -376.823915) (xy 385.92883 -376.756491)
			(xy 385.936905 -376.689553) (xy 385.95294 -376.624064) (xy 385.976705 -376.560967) (xy 386.007855 -376.501171)
			(xy 386.045944 -376.445537) (xy 386.067808 -376.419872) (xy 386.0736 -376.412724) (xy 386.080117 -376.395535)
			(xy 386.080508 -376.386344) (xy 386.080508 -375.894092) (xy 386.0801 -375.884905) (xy 386.073584 -375.867721)
			(xy 386.067808 -375.860564) (xy 386.045975 -375.834873) (xy 386.007885 -375.779242) (xy 385.976732 -375.71945)
			(xy 385.952966 -375.656356) (xy 385.936928 -375.59087) (xy 385.92885 -375.523935) (xy 385.928847 -375.456513)
			(xy 385.93692 -375.389577) (xy 385.952952 -375.32409) (xy 385.976713 -375.260994) (xy 386.00786 -375.201199)
			(xy 386.045946 -375.145565) (xy 386.067808 -375.1199) (xy 386.073588 -375.112743) (xy 386.080112 -375.095562)
			(xy 386.080508 -375.086372) (xy 386.080508 -374.928638) (xy 386.081057 -374.918518) (xy 386.088766 -374.899804)
			(xy 386.103033 -374.885447) (xy 386.121699 -374.877621) (xy 386.131816 -374.877076) (xy 386.848096 -374.877076)
			(xy 386.858247 -374.877524) (xy 386.876995 -374.885314) (xy 386.891317 -374.899702) (xy 386.899021 -374.918485)
			(xy 386.899404 -374.928638) (xy 386.899404 -375.086372) (xy 386.899827 -375.095558) (xy 386.906332 -375.112742)
			(xy 386.912104 -375.1199) (xy 386.933999 -375.145539) (xy 386.972087 -375.201178) (xy 387.003236 -375.260978)
			(xy 387.026998 -375.324078) (xy 387.043031 -375.38957) (xy 387.051104 -375.456511) (xy 387.051102 -375.523937)
			(xy 387.043023 -375.590877) (xy 387.026984 -375.656368) (xy 387.003216 -375.719466) (xy 386.972062 -375.779264)
			(xy 386.93397 -375.834899) (xy 386.912104 -375.860564) (xy 386.906298 -375.867703) (xy 386.899789 -375.884898)
			(xy 386.899404 -375.894092) (xy 386.899404 -376.386344) (xy 386.899792 -376.395534) (xy 386.906321 -376.412718)
			(xy 386.912104 -376.419872) (xy 386.933972 -376.445534) (xy 386.97206 -376.501169) (xy 387.00321 -376.560966)
			(xy 387.026974 -376.624063) (xy 387.043009 -376.689552) (xy 387.051085 -376.756491) (xy 387.051084 -376.823855)
			(xy 390.329149 -376.823855) (xy 390.329149 -376.756551) (xy 390.337192 -376.689729) (xy 390.353163 -376.624348)
			(xy 390.376834 -376.561344) (xy 390.407864 -376.50162) (xy 390.44581 -376.446033) (xy 390.467596 -376.42038)
			(xy 390.473383 -376.413228) (xy 390.479904 -376.396043) (xy 390.480296 -376.386852) (xy 390.480296 -375.893584)
			(xy 390.479894 -375.884396) (xy 390.473375 -375.867212) (xy 390.467596 -375.860056) (xy 390.445841 -375.834377)
			(xy 390.407894 -375.778794) (xy 390.376862 -375.719073) (xy 390.353189 -375.656072) (xy 390.337215 -375.590694)
			(xy 390.329169 -375.523875) (xy 390.329166 -375.456573) (xy 390.337207 -375.389754) (xy 390.353175 -375.324374)
			(xy 390.376842 -375.261371) (xy 390.407869 -375.201648) (xy 390.445812 -375.146061) (xy 390.467596 -375.120408)
			(xy 390.473371 -375.113248) (xy 390.479899 -375.096069) (xy 390.480296 -375.08688) (xy 390.480296 -374.928638)
			(xy 390.480864 -374.918488) (xy 390.488618 -374.899728) (xy 390.502961 -374.885363) (xy 390.521709 -374.877579)
			(xy 390.531858 -374.877076) (xy 391.248138 -374.877076) (xy 391.258303 -374.877503) (xy 391.27708 -374.885297)
			(xy 391.291445 -374.899684) (xy 391.299212 -374.918472) (xy 391.2997 -374.928638) (xy 391.2997 -375.08688)
			(xy 391.30012 -375.096066) (xy 391.306627 -375.113251) (xy 391.3124 -375.120408) (xy 391.334218 -375.146035)
			(xy 391.372163 -375.201626) (xy 391.403193 -375.261353) (xy 391.426862 -375.324361) (xy 391.442832 -375.389746)
			(xy 391.450873 -375.456571) (xy 391.45087 -375.523877) (xy 391.442823 -375.590702) (xy 391.426848 -375.656085)
			(xy 391.403173 -375.719091) (xy 391.372139 -375.778816) (xy 391.334188 -375.834403) (xy 391.3124 -375.860056)
			(xy 391.306597 -375.867197) (xy 391.300086 -375.884391) (xy 391.2997 -375.893584) (xy 391.2997 -376.386852)
			(xy 391.300133 -376.396037) (xy 391.306631 -376.413221) (xy 391.3124 -376.42038) (xy 391.33419 -376.446029)
			(xy 391.372137 -376.501617) (xy 391.403168 -376.561342) (xy 391.426838 -376.624346) (xy 391.44281 -376.689728)
			(xy 391.450853 -376.756551) (xy 391.450853 -376.823855) (xy 391.450846 -376.823915) (xy 421.128651 -376.823915)
			(xy 421.128651 -376.756491) (xy 421.136727 -376.689552) (xy 421.152763 -376.624063) (xy 421.176528 -376.560966)
			(xy 421.20768 -376.50117) (xy 421.245771 -376.445537) (xy 421.267636 -376.419872) (xy 421.273432 -376.412726)
			(xy 421.279946 -376.395536) (xy 421.280336 -376.386344) (xy 421.280336 -375.894092) (xy 421.279922 -375.884905)
			(xy 421.27341 -375.867721) (xy 421.267636 -375.860564) (xy 421.245802 -375.834873) (xy 421.20771 -375.779243)
			(xy 421.176556 -375.719451) (xy 421.152788 -375.656357) (xy 421.13675 -375.590871) (xy 421.128671 -375.523935)
			(xy 421.128668 -375.456513) (xy 421.136741 -375.389576) (xy 421.152774 -375.324089) (xy 421.176536 -375.260993)
			(xy 421.207685 -375.201198) (xy 421.245773 -375.145565) (xy 421.267636 -375.1199) (xy 421.27342 -375.112746)
			(xy 421.279941 -375.095562) (xy 421.280336 -375.086372) (xy 421.280336 -374.928638) (xy 421.280858 -374.918514)
			(xy 421.288572 -374.899795) (xy 421.302848 -374.885437) (xy 421.321523 -374.877616) (xy 421.331644 -374.877076)
			(xy 422.047924 -374.877076) (xy 422.058031 -374.877565) (xy 422.076706 -374.885306) (xy 422.090999 -374.899601)
			(xy 422.098737 -374.918277) (xy 422.099232 -374.928384) (xy 422.099232 -375.086372) (xy 422.099671 -375.095556)
			(xy 422.106166 -375.11274) (xy 422.111932 -375.1199) (xy 422.133826 -375.14554) (xy 422.171912 -375.201179)
			(xy 422.203059 -375.260979) (xy 422.22682 -375.324079) (xy 422.242853 -375.389571) (xy 422.250926 -375.456511)
			(xy 422.250923 -375.523937) (xy 422.242844 -375.590877) (xy 422.226806 -375.656367) (xy 422.20304 -375.719465)
			(xy 422.171887 -375.779263) (xy 422.133797 -375.834898) (xy 422.111932 -375.860564) (xy 422.106117 -375.867696)
			(xy 422.099615 -375.884897) (xy 422.099232 -375.894092) (xy 422.099232 -376.386344) (xy 422.099636 -376.395532)
			(xy 422.106156 -376.412715) (xy 422.111932 -376.419872) (xy 422.133799 -376.445535) (xy 422.171885 -376.50117)
			(xy 422.203034 -376.560967) (xy 422.226797 -376.624064) (xy 422.242831 -376.689553) (xy 422.250906 -376.756491)
			(xy 422.250906 -376.756551) (xy 425.52897 -376.756551) (xy 425.537014 -376.689729) (xy 425.552986 -376.624347)
			(xy 425.576658 -376.561343) (xy 425.607689 -376.501619) (xy 425.645637 -376.446032) (xy 425.667424 -376.42038)
			(xy 425.673214 -376.413231) (xy 425.679732 -376.396043) (xy 425.680124 -376.386852) (xy 425.680124 -375.893584)
			(xy 425.679716 -375.884397) (xy 425.6732 -375.867213) (xy 425.667424 -375.860056) (xy 425.645668 -375.834378)
			(xy 425.60772 -375.778795) (xy 425.576686 -375.719074) (xy 425.553012 -375.656073) (xy 425.537037 -375.590695)
			(xy 425.528991 -375.523875) (xy 425.528988 -375.456573) (xy 425.537029 -375.389753) (xy 425.552998 -375.324373)
			(xy 425.576666 -375.26137) (xy 425.607695 -375.201647) (xy 425.645639 -375.146061) (xy 425.667424 -375.120408)
			(xy 425.673202 -375.11325) (xy 425.679727 -375.096069) (xy 425.680124 -375.08688) (xy 425.680124 -374.928638)
			(xy 425.680595 -374.918471) (xy 425.688365 -374.899679) (xy 425.702736 -374.885294) (xy 425.721519 -374.877505)
			(xy 425.731686 -374.877076) (xy 426.447966 -374.877076) (xy 426.45814 -374.877493) (xy 426.476941 -374.885274)
			(xy 426.491329 -374.899662) (xy 426.499108 -374.918464) (xy 426.499528 -374.928638) (xy 426.499528 -375.08688)
			(xy 426.499941 -375.096067) (xy 426.506452 -375.113252) (xy 426.512228 -375.120408) (xy 426.534048 -375.146034)
			(xy 426.571998 -375.201623) (xy 426.603032 -375.26135) (xy 426.626705 -375.324358) (xy 426.642676 -375.389744)
			(xy 426.650718 -375.45657) (xy 426.650716 -375.523878) (xy 426.642668 -375.590704) (xy 426.62669 -375.656088)
			(xy 426.603013 -375.719094) (xy 426.571974 -375.778818) (xy 426.534019 -375.834404) (xy 426.512228 -375.860056)
			(xy 426.506416 -375.86719) (xy 426.499913 -375.884389) (xy 426.499528 -375.893584) (xy 426.499528 -376.386852)
			(xy 426.499955 -376.396037) (xy 426.506456 -376.413222) (xy 426.512228 -376.42038) (xy 426.534021 -376.446029)
			(xy 426.571971 -376.501615) (xy 426.603006 -376.561338) (xy 426.62668 -376.624344) (xy 426.642654 -376.689727)
			(xy 426.650698 -376.75655) (xy 426.650698 -376.823856) (xy 426.650691 -376.823915) (xy 429.928739 -376.823915)
			(xy 429.928739 -376.756491) (xy 429.936814 -376.689553) (xy 429.95285 -376.624064) (xy 429.976615 -376.560967)
			(xy 430.007766 -376.501171) (xy 430.045856 -376.445537) (xy 430.06772 -376.419872) (xy 430.073513 -376.412725)
			(xy 430.080029 -376.395536) (xy 430.08042 -376.386344) (xy 430.08042 -375.894092) (xy 430.080009 -375.884905)
			(xy 430.073496 -375.867721) (xy 430.06772 -375.860564) (xy 430.045887 -375.834873) (xy 430.007796 -375.779243)
			(xy 429.976643 -375.71945) (xy 429.952876 -375.656357) (xy 429.936837 -375.590871) (xy 429.928759 -375.523935)
			(xy 429.928756 -375.456513) (xy 429.936829 -375.389577) (xy 429.952861 -375.324089) (xy 429.976623 -375.260994)
			(xy 430.007771 -375.201199) (xy 430.045857 -375.145565) (xy 430.06772 -375.1199) (xy 430.073501 -375.112744)
			(xy 430.080024 -375.095562) (xy 430.08042 -375.086372) (xy 430.08042 -374.928638) (xy 430.080957 -374.918516)
			(xy 430.088669 -374.8998) (xy 430.10294 -374.885443) (xy 430.121609 -374.877619) (xy 430.131728 -374.877076)
			(xy 430.848008 -374.877076) (xy 430.85816 -374.877515) (xy 430.876907 -374.885308) (xy 430.89123 -374.899699)
			(xy 430.898933 -374.918484) (xy 430.899316 -374.928638) (xy 430.899316 -375.086372) (xy 430.899736 -375.095558)
			(xy 430.906242 -375.112743) (xy 430.912016 -375.1199) (xy 430.933911 -375.14554) (xy 430.971998 -375.201178)
			(xy 431.003146 -375.260978) (xy 431.026908 -375.324078) (xy 431.04294 -375.38957) (xy 431.051013 -375.456511)
			(xy 431.051011 -375.523937) (xy 431.042932 -375.590877) (xy 431.026893 -375.656368) (xy 431.003126 -375.719466)
			(xy 430.971973 -375.779263) (xy 430.933881 -375.834898) (xy 430.912016 -375.860564) (xy 430.906212 -375.867704)
			(xy 430.899701 -375.884898) (xy 430.899316 -375.894092) (xy 430.899316 -376.386344) (xy 430.899701 -376.395534)
			(xy 430.906232 -376.412718) (xy 430.912016 -376.419872) (xy 430.933883 -376.445534) (xy 430.971971 -376.50117)
			(xy 431.003121 -376.560966) (xy 431.026884 -376.624064) (xy 431.042918 -376.689553) (xy 431.050994 -376.756491)
			(xy 431.050994 -376.756551) (xy 434.329058 -376.756551) (xy 434.337101 -376.689729) (xy 434.353073 -376.624348)
			(xy 434.376744 -376.561343) (xy 434.407775 -376.50162) (xy 434.445721 -376.446033) (xy 434.467508 -376.42038)
			(xy 434.473296 -376.413229) (xy 434.479816 -376.396043) (xy 434.480208 -376.386852) (xy 434.480208 -375.893584)
			(xy 434.479804 -375.884396) (xy 434.473286 -375.867212) (xy 434.467508 -375.860056) (xy 434.445753 -375.834378)
			(xy 434.407805 -375.778794) (xy 434.376772 -375.719074) (xy 434.353099 -375.656073) (xy 434.337124 -375.590694)
			(xy 434.329078 -375.523875) (xy 434.329075 -375.456573) (xy 434.337116 -375.389753) (xy 434.353084 -375.324373)
			(xy 434.376752 -375.26137) (xy 434.40778 -375.201647) (xy 434.445723 -375.146061) (xy 434.467508 -375.120408)
			(xy 434.473285 -375.113249) (xy 434.479811 -375.096069) (xy 434.480208 -375.08688) (xy 434.480208 -374.928638)
			(xy 434.480694 -374.918473) (xy 434.488461 -374.899684) (xy 434.502827 -374.885299) (xy 434.521605 -374.877508)
			(xy 434.53177 -374.877076) (xy 435.24805 -374.877076) (xy 435.258223 -374.877506) (xy 435.277024 -374.885281)
			(xy 435.291412 -374.899666) (xy 435.299192 -374.918465) (xy 435.299612 -374.928638) (xy 435.299612 -375.08688)
			(xy 435.300029 -375.096067) (xy 435.306538 -375.113251) (xy 435.312312 -375.120408) (xy 435.334133 -375.146034)
			(xy 435.372084 -375.201623) (xy 435.403118 -375.26135) (xy 435.426791 -375.324358) (xy 435.442764 -375.389744)
			(xy 435.450806 -375.45657) (xy 435.450803 -375.523878) (xy 435.442755 -375.590704) (xy 435.426777 -375.656088)
			(xy 435.403099 -375.719094) (xy 435.372059 -375.778819) (xy 435.334103 -375.834404) (xy 435.312312 -375.860056)
			(xy 435.306511 -375.867198) (xy 435.299998 -375.884391) (xy 435.299612 -375.893584) (xy 435.299612 -376.386852)
			(xy 435.300042 -376.396037) (xy 435.306542 -376.413222) (xy 435.312312 -376.42038) (xy 435.334105 -376.446028)
			(xy 435.372057 -376.501614) (xy 435.403093 -376.561338) (xy 435.426768 -376.624343) (xy 435.442742 -376.689726)
			(xy 435.450786 -376.75655) (xy 435.450786 -376.823856) (xy 435.442741 -376.89068) (xy 435.426766 -376.956063)
			(xy 435.40309 -377.019068) (xy 435.372054 -377.078791) (xy 435.334101 -377.134376) (xy 435.312312 -377.160028)
			(xy 435.306522 -377.167178) (xy 435.300003 -377.184365) (xy 435.299612 -377.193556) (xy 435.299612 -377.35129)
			(xy 435.299227 -377.361467) (xy 435.291436 -377.380271) (xy 435.277038 -377.394658) (xy 435.258228 -377.402435)
			(xy 435.24805 -377.402852) (xy 434.53177 -377.402852) (xy 434.521609 -377.402391) (xy 434.502837 -377.394605)
			(xy 434.488473 -377.380229) (xy 434.480701 -377.361451) (xy 434.480208 -377.35129) (xy 434.480208 -377.193556)
			(xy 434.479817 -377.184367) (xy 434.47329 -377.167183) (xy 434.467508 -377.160028) (xy 434.445725 -377.134372)
			(xy 434.407778 -377.078786) (xy 434.376746 -377.019062) (xy 434.353075 -376.956058) (xy 434.337103 -376.890677)
			(xy 434.329059 -376.823855) (xy 434.329058 -376.756551) (xy 431.050994 -376.756551) (xy 431.050993 -376.823915)
			(xy 431.042917 -376.890853) (xy 431.026882 -376.956342) (xy 431.003118 -377.019439) (xy 430.971968 -377.079236)
			(xy 430.93388 -377.13487) (xy 430.912016 -377.160536) (xy 430.906223 -377.167684) (xy 430.899706 -377.184872)
			(xy 430.899316 -377.194064) (xy 430.899316 -377.35129) (xy 430.898864 -377.361421) (xy 430.891131 -377.380151)
			(xy 430.876834 -377.394509) (xy 430.858137 -377.402321) (xy 430.848008 -377.402852) (xy 430.131728 -377.402852)
			(xy 430.121582 -377.402357) (xy 430.10284 -377.39458) (xy 430.088518 -377.380207) (xy 430.080808 -377.361437)
			(xy 430.08042 -377.35129) (xy 430.08042 -377.194064) (xy 430.080023 -377.184876) (xy 430.0735 -377.167692)
			(xy 430.06772 -377.160536) (xy 430.045859 -377.134868) (xy 430.007769 -377.079234) (xy 429.976617 -377.019439)
			(xy 429.952852 -376.956342) (xy 429.936815 -376.890853) (xy 429.928739 -376.823915) (xy 426.650691 -376.823915)
			(xy 426.642653 -376.890679) (xy 426.626679 -376.956062) (xy 426.603004 -377.019067) (xy 426.571968 -377.07879)
			(xy 426.534017 -377.134376) (xy 426.512228 -377.160028) (xy 426.506428 -377.167171) (xy 426.499918 -377.184363)
			(xy 426.499528 -377.193556) (xy 426.499528 -377.35129) (xy 426.499127 -377.361465) (xy 426.491339 -377.380266)
			(xy 426.476946 -377.394653) (xy 426.458141 -377.402432) (xy 426.447966 -377.402852) (xy 425.731686 -377.402852)
			(xy 425.721526 -377.402378) (xy 425.702755 -377.394597) (xy 425.68839 -377.380225) (xy 425.680618 -377.36145)
			(xy 425.680124 -377.35129) (xy 425.680124 -377.193556) (xy 425.67973 -377.184367) (xy 425.673204 -377.167183)
			(xy 425.667424 -377.160028) (xy 425.645641 -377.134372) (xy 425.607693 -377.078786) (xy 425.57666 -377.019063)
			(xy 425.552988 -376.956059) (xy 425.537015 -376.890677) (xy 425.528971 -376.823855) (xy 425.52897 -376.756551)
			(xy 422.250906 -376.756551) (xy 422.250905 -376.823915) (xy 422.24283 -376.890853) (xy 422.226795 -376.956342)
			(xy 422.203032 -377.019438) (xy 422.171882 -377.079235) (xy 422.133795 -377.13487) (xy 422.111932 -377.160536)
			(xy 422.106129 -377.167677) (xy 422.09962 -377.184871) (xy 422.099232 -377.194064) (xy 422.099232 -377.35129)
			(xy 422.098764 -377.36142) (xy 422.091035 -377.380146) (xy 422.076742 -377.394503) (xy 422.058051 -377.402318)
			(xy 422.047924 -377.402852) (xy 421.331644 -377.402852) (xy 421.321544 -377.40228) (xy 421.302877 -377.394567)
			(xy 421.288583 -377.380297) (xy 421.280837 -377.361643) (xy 421.280336 -377.351544) (xy 421.280336 -377.194064)
			(xy 421.279935 -377.184876) (xy 421.273414 -377.167692) (xy 421.267636 -377.160536) (xy 421.245775 -377.134868)
			(xy 421.207684 -377.079235) (xy 421.176531 -377.019439) (xy 421.152765 -376.956343) (xy 421.136728 -376.890854)
			(xy 421.128651 -376.823915) (xy 391.450846 -376.823915) (xy 391.442809 -376.890678) (xy 391.426837 -376.956059)
			(xy 391.403165 -377.019064) (xy 391.372134 -377.078788) (xy 391.334187 -377.134375) (xy 391.3124 -377.160028)
			(xy 391.306609 -377.167177) (xy 391.300091 -377.184365) (xy 391.2997 -377.193556) (xy 391.2997 -377.35129)
			(xy 391.299159 -377.361442) (xy 391.291395 -377.380204) (xy 391.277044 -377.394568) (xy 391.25829 -377.40235)
			(xy 391.248138 -377.402852) (xy 390.531858 -377.402852) (xy 390.521696 -377.402401) (xy 390.502924 -377.394611)
			(xy 390.48856 -377.380232) (xy 390.480789 -377.361452) (xy 390.480296 -377.35129) (xy 390.480296 -377.193556)
			(xy 390.479908 -377.184366) (xy 390.473379 -377.167182) (xy 390.467596 -377.160028) (xy 390.445814 -377.134372)
			(xy 390.407867 -377.078785) (xy 390.376836 -377.019062) (xy 390.353165 -376.956058) (xy 390.337193 -376.890676)
			(xy 390.329149 -376.823855) (xy 387.051084 -376.823855) (xy 387.051084 -376.823915) (xy 387.043008 -376.890853)
			(xy 387.026972 -376.956343) (xy 387.003208 -377.01944) (xy 386.972057 -377.079236) (xy 386.933968 -377.134871)
			(xy 386.912104 -377.160536) (xy 386.90631 -377.167683) (xy 386.899794 -377.184872) (xy 386.899404 -377.194064)
			(xy 386.899404 -377.35129) (xy 386.898867 -377.361411) (xy 386.89115 -377.380123) (xy 386.87688 -377.394478)
			(xy 386.858214 -377.402306) (xy 386.848096 -377.402852) (xy 386.131816 -377.402852) (xy 386.121669 -377.402366)
			(xy 386.102927 -377.394586) (xy 386.088605 -377.380209) (xy 386.080896 -377.361438) (xy 386.080508 -377.35129)
			(xy 386.080508 -377.194064) (xy 386.080114 -377.184875) (xy 386.073589 -377.167691) (xy 386.067808 -377.160536)
			(xy 386.045948 -377.134868) (xy 386.007858 -377.079234) (xy 385.976707 -377.019438) (xy 385.952942 -376.956342)
			(xy 385.936906 -376.890853) (xy 385.92883 -376.823915) (xy 382.650782 -376.823915) (xy 382.642744 -376.89068)
			(xy 382.626769 -376.956063) (xy 382.603094 -377.019068) (xy 382.572058 -377.078791) (xy 382.534105 -377.134376)
			(xy 382.512316 -377.160028) (xy 382.506527 -377.167179) (xy 382.500007 -377.184365) (xy 382.499616 -377.193556)
			(xy 382.499616 -377.35129) (xy 382.499227 -377.361467) (xy 382.491437 -377.38027) (xy 382.47704 -377.394657)
			(xy 382.458231 -377.402434) (xy 382.448054 -377.402852) (xy 381.731774 -377.402852) (xy 381.721613 -377.402388)
			(xy 381.702842 -377.394603) (xy 381.688477 -377.380228) (xy 381.680705 -377.361451) (xy 381.680212 -377.35129)
			(xy 381.680212 -377.193556) (xy 381.67982 -377.184367) (xy 381.673294 -377.167183) (xy 381.667512 -377.160028)
			(xy 381.645729 -377.134372) (xy 381.607782 -377.078786) (xy 381.57675 -377.019062) (xy 381.553078 -376.956058)
			(xy 381.537106 -376.890677) (xy 381.529062 -376.823855) (xy 381.529061 -376.756551) (xy 378.250997 -376.756551)
			(xy 378.250996 -376.823915) (xy 378.24292 -376.890853) (xy 378.226885 -376.956342) (xy 378.203121 -377.019439)
			(xy 378.171971 -377.079235) (xy 378.133884 -377.13487) (xy 378.11202 -377.160536) (xy 378.106228 -377.167685)
			(xy 378.09971 -377.184872) (xy 378.09932 -377.194064) (xy 378.09932 -377.35129) (xy 378.098864 -377.361421)
			(xy 378.091132 -377.38015) (xy 378.076836 -377.394508) (xy 378.058141 -377.40232) (xy 378.048012 -377.402852)
			(xy 377.331732 -377.402852) (xy 377.321586 -377.402353) (xy 377.302845 -377.394578) (xy 377.288522 -377.380206)
			(xy 377.280812 -377.361437) (xy 377.280424 -377.35129) (xy 377.280424 -377.194064) (xy 377.280026 -377.184876)
			(xy 377.273503 -377.167692) (xy 377.267724 -377.160536) (xy 377.245863 -377.134868) (xy 377.207773 -377.079234)
			(xy 377.17662 -377.019439) (xy 377.152855 -376.956342) (xy 377.136819 -376.890853) (xy 377.128742 -376.823915)
			(xy 347.450937 -376.823915) (xy 347.4429 -376.890678) (xy 347.426927 -376.95606) (xy 347.403255 -377.019065)
			(xy 347.372223 -377.078788) (xy 347.334275 -377.134376) (xy 347.312488 -377.160028) (xy 347.306696 -377.167176)
			(xy 347.300179 -377.184364) (xy 347.299788 -377.193556) (xy 347.299788 -377.35129) (xy 347.299259 -377.361444)
			(xy 347.291493 -377.380208) (xy 347.277138 -377.394573) (xy 347.25838 -377.402352) (xy 347.248226 -377.402852)
			(xy 346.531946 -377.402852) (xy 346.521776 -377.402398) (xy 346.502981 -377.394627) (xy 346.488594 -377.38025)
			(xy 346.480809 -377.36146) (xy 346.480384 -377.35129) (xy 346.480384 -377.193556) (xy 346.479999 -377.184366)
			(xy 346.473468 -377.167182) (xy 346.467684 -377.160028) (xy 346.445899 -377.134373) (xy 346.407947 -377.078788)
			(xy 346.376911 -377.019065) (xy 346.353236 -376.956061) (xy 346.337262 -376.890679) (xy 346.329216 -376.823856)
			(xy 343.051175 -376.823856) (xy 343.051175 -376.823915) (xy 343.043099 -376.890854) (xy 343.027063 -376.956343)
			(xy 343.003298 -377.01944) (xy 342.972146 -377.079236) (xy 342.934056 -377.134871) (xy 342.912192 -377.160536)
			(xy 342.906397 -377.167682) (xy 342.899882 -377.184872) (xy 342.899492 -377.194064) (xy 342.899492 -377.35129)
			(xy 342.898966 -377.361412) (xy 342.891248 -377.380127) (xy 342.876974 -377.394483) (xy 342.858303 -377.402308)
			(xy 342.848184 -377.402852) (xy 342.131904 -377.402852) (xy 342.121757 -377.402376) (xy 342.103014 -377.394592)
			(xy 342.088693 -377.380212) (xy 342.080984 -377.361439) (xy 342.080596 -377.35129) (xy 342.080596 -377.194064)
			(xy 342.080204 -377.184875) (xy 342.073678 -377.167691) (xy 342.067896 -377.160536) (xy 342.046036 -377.134867)
			(xy 342.007948 -377.079233) (xy 341.976797 -377.019438) (xy 341.953033 -376.956341) (xy 341.936997 -376.890852)
			(xy 341.928921 -376.823915) (xy 338.650849 -376.823915) (xy 338.642812 -376.890677) (xy 338.62684 -376.956059)
			(xy 338.603168 -377.019064) (xy 338.572137 -377.078788) (xy 338.534191 -377.134375) (xy 338.512404 -377.160028)
			(xy 338.506614 -377.167178) (xy 338.500095 -377.184365) (xy 338.499704 -377.193556) (xy 338.499704 -377.35129)
			(xy 338.49916 -377.361442) (xy 338.491396 -377.380203) (xy 338.477047 -377.394567) (xy 338.458293 -377.402349)
			(xy 338.448142 -377.402852) (xy 337.731862 -377.402852) (xy 337.721701 -377.402397) (xy 337.702929 -377.394609)
			(xy 337.688564 -377.380231) (xy 337.680793 -377.361452) (xy 337.6803 -377.35129) (xy 337.6803 -377.193556)
			(xy 337.679911 -377.184367) (xy 337.673383 -377.167182) (xy 337.6676 -377.160028) (xy 337.645817 -377.134372)
			(xy 337.607871 -377.078785) (xy 337.57684 -377.019062) (xy 337.553168 -376.956058) (xy 337.537196 -376.890677)
			(xy 337.529152 -376.823855) (xy 334.251087 -376.823855) (xy 334.251087 -376.823915) (xy 334.243011 -376.890853)
			(xy 334.226976 -376.956342) (xy 334.203211 -377.019439) (xy 334.172061 -377.079236) (xy 334.133972 -377.134871)
			(xy 334.112108 -377.160536) (xy 334.106315 -377.167684) (xy 334.099798 -377.184872) (xy 334.099408 -377.194064)
			(xy 334.099408 -377.35129) (xy 334.098867 -377.36141) (xy 334.091151 -377.380122) (xy 334.076882 -377.394477)
			(xy 334.058217 -377.402305) (xy 334.0481 -377.402852) (xy 333.33182 -377.402852) (xy 333.321674 -377.402363)
			(xy 333.302932 -377.394584) (xy 333.288609 -377.380209) (xy 333.2809 -377.361438) (xy 333.280512 -377.35129)
			(xy 333.280512 -377.194064) (xy 333.280117 -377.184875) (xy 333.273592 -377.167691) (xy 333.267812 -377.160536)
			(xy 333.245952 -377.134868) (xy 333.207862 -377.079234) (xy 333.17671 -377.019438) (xy 333.152945 -376.956342)
			(xy 333.136909 -376.890853) (xy 333.128833 -376.823915) (xy 303.451057 -376.823915) (xy 303.44298 -376.890854)
			(xy 303.426944 -376.956344) (xy 303.403178 -377.019441) (xy 303.372025 -377.079237) (xy 303.333933 -377.134871)
			(xy 303.312068 -377.160536) (xy 303.30627 -377.16768) (xy 303.299757 -377.184871) (xy 303.299368 -377.194064)
			(xy 303.299368 -377.35129) (xy 303.298865 -377.361415) (xy 303.291142 -377.380135) (xy 303.276861 -377.394491)
			(xy 303.258182 -377.402312) (xy 303.24806 -377.402852) (xy 302.53178 -377.402852) (xy 302.521631 -377.402396)
			(xy 302.502888 -377.394604) (xy 302.488567 -377.380218) (xy 302.480859 -377.361441) (xy 302.480472 -377.35129)
			(xy 302.480472 -377.194064) (xy 302.480085 -377.184874) (xy 302.473556 -377.16769) (xy 302.467772 -377.160536)
			(xy 302.445913 -377.134867) (xy 302.407826 -377.079232) (xy 302.376677 -377.019436) (xy 302.352913 -376.95634)
			(xy 302.336879 -376.890852) (xy 302.328803 -376.823914) (xy 302.328802 -376.756492) (xy 299.050731 -376.756492)
			(xy 299.050738 -376.756551) (xy 299.050738 -376.823856) (xy 299.042693 -376.890678) (xy 299.026721 -376.95606)
			(xy 299.003048 -377.019065) (xy 298.972016 -377.078789) (xy 298.934067 -377.134376) (xy 298.91228 -377.160028)
			(xy 298.906487 -377.167175) (xy 298.899971 -377.184364) (xy 298.89958 -377.193556) (xy 298.89958 -377.35129)
			(xy 298.899059 -377.361445) (xy 298.891291 -377.38021) (xy 298.876934 -377.394575) (xy 298.858173 -377.402353)
			(xy 298.848018 -377.402852) (xy 298.131738 -377.402852) (xy 298.121568 -377.402405) (xy 298.102772 -377.39463)
			(xy 298.088385 -377.380252) (xy 298.080601 -377.36146) (xy 298.080176 -377.35129) (xy 298.080176 -377.193556)
			(xy 298.079792 -377.184366) (xy 298.073261 -377.167182) (xy 298.067476 -377.160028) (xy 298.045691 -377.134373)
			(xy 298.00774 -377.078788) (xy 297.976704 -377.019065) (xy 297.95303 -376.956061) (xy 297.937055 -376.890679)
			(xy 297.92901 -376.823856) (xy 294.650969 -376.823856) (xy 294.650969 -376.823915) (xy 294.642893 -376.890854)
			(xy 294.626856 -376.956343) (xy 294.603091 -377.019441) (xy 294.571939 -377.079237) (xy 294.533849 -377.134871)
			(xy 294.511984 -377.160536) (xy 294.506188 -377.167681) (xy 294.499673 -377.184872) (xy 294.499284 -377.194064)
			(xy 294.499284 -377.35129) (xy 294.498766 -377.361413) (xy 294.491046 -377.38013) (xy 294.47677 -377.394485)
			(xy 294.458096 -377.402309) (xy 294.447976 -377.402852) (xy 293.731696 -377.402852) (xy 293.721593 -377.402319)
			(xy 293.702925 -377.39459) (xy 293.688632 -377.380308) (xy 293.680889 -377.361646) (xy 293.680388 -377.351544)
			(xy 293.680388 -377.194064) (xy 293.679998 -377.184875) (xy 293.673471 -377.16769) (xy 293.667688 -377.160536)
			(xy 293.645828 -377.134867) (xy 293.60774 -377.079233) (xy 293.57659 -377.019437) (xy 293.552826 -376.956341)
			(xy 293.536791 -376.890852) (xy 293.528715 -376.823915) (xy 290.250643 -376.823915) (xy 290.242606 -376.890678)
			(xy 290.226633 -376.95606) (xy 290.202962 -377.019064) (xy 290.17193 -377.078788) (xy 290.133983 -377.134375)
			(xy 290.112196 -377.160028) (xy 290.106405 -377.167177) (xy 290.099887 -377.184365) (xy 290.099496 -377.193556)
			(xy 290.099496 -377.35129) (xy 290.098959 -377.361443) (xy 290.091194 -377.380205) (xy 290.076842 -377.39457)
			(xy 290.058087 -377.402351) (xy 290.047934 -377.402852) (xy 289.331654 -377.402852) (xy 289.321492 -377.402404)
			(xy 289.30272 -377.394613) (xy 289.288356 -377.380233) (xy 289.280585 -377.361452) (xy 289.280092 -377.35129)
			(xy 289.280092 -377.193556) (xy 289.279705 -377.184366) (xy 289.273176 -377.167182) (xy 289.267392 -377.160028)
			(xy 289.245607 -377.134373) (xy 289.207654 -377.078788) (xy 289.176618 -377.019066) (xy 289.152942 -376.956061)
			(xy 289.136968 -376.890679) (xy 289.128922 -376.823856) (xy 273.068299 -376.823856) (xy 273.100384 -376.843252)
			(xy 273.210304 -376.919124) (xy 273.315441 -377.001494) (xy 273.415414 -377.090062) (xy 273.509856 -377.184504)
			(xy 273.598424 -377.284477) (xy 273.680794 -377.389614) (xy 273.756666 -377.499534) (xy 273.825762 -377.613833)
			(xy 273.887832 -377.732096) (xy 273.942647 -377.853891) (xy 273.990009 -377.978774) (xy 274.029744 -378.106288)
			(xy 274.061707 -378.235969) (xy 274.077801 -378.323794) (xy 286.928742 -378.323794) (xy 286.928744 -378.256367)
			(xy 286.936824 -378.189426) (xy 286.952863 -378.123935) (xy 286.976633 -378.060837) (xy 287.007789 -378.00104)
			(xy 287.045885 -377.945406) (xy 287.067752 -377.919742) (xy 287.073562 -377.912607) (xy 287.080067 -377.895408)
			(xy 287.080452 -377.886214) (xy 287.080452 -377.728734) (xy 287.080955 -377.718608) (xy 287.088674 -377.699885)
			(xy 287.102955 -377.685528) (xy 287.121637 -377.677709) (xy 287.13176 -377.677172) (xy 287.84804 -377.677172)
			(xy 287.858148 -377.677652) (xy 287.876822 -377.685397) (xy 287.891114 -377.699695) (xy 287.898852 -377.718372)
			(xy 287.899348 -377.72848) (xy 287.899348 -377.886214) (xy 287.899763 -377.8954) (xy 287.906275 -377.912584)
			(xy 287.912048 -377.919742) (xy 287.933888 -377.945427) (xy 287.971981 -378.001058) (xy 288.003136 -378.060851)
			(xy 288.026904 -378.123945) (xy 288.042943 -378.189432) (xy 288.051021 -378.256369) (xy 288.051024 -378.323734)
			(xy 291.329062 -378.323734) (xy 291.329064 -378.256427) (xy 291.337111 -378.189602) (xy 291.353086 -378.124219)
			(xy 291.376762 -378.061213) (xy 291.407799 -378.001489) (xy 291.445751 -377.945902) (xy 291.46754 -377.92025)
			(xy 291.473345 -377.913111) (xy 291.479854 -377.895916) (xy 291.48024 -377.886722) (xy 291.48024 -377.728734)
			(xy 291.480692 -377.718564) (xy 291.488466 -377.69977) (xy 291.502843 -377.685384) (xy 291.521633 -377.677598)
			(xy 291.531802 -377.677172) (xy 292.248082 -377.677172) (xy 292.258257 -377.677579) (xy 292.277058 -377.685365)
			(xy 292.291444 -377.699756) (xy 292.299224 -377.718559) (xy 292.299644 -377.728734) (xy 292.299644 -377.886722)
			(xy 292.300056 -377.895909) (xy 292.30657 -377.913092) (xy 292.312344 -377.92025) (xy 292.334107 -377.945923)
			(xy 292.372057 -378.001506) (xy 292.403093 -378.061227) (xy 292.426768 -378.124228) (xy 292.442743 -378.189608)
			(xy 292.450789 -378.256429) (xy 292.450792 -378.323732) (xy 292.450785 -378.323794) (xy 295.72883 -378.323794)
			(xy 295.728832 -378.256367) (xy 295.736911 -378.189427) (xy 295.752951 -378.123936) (xy 295.776719 -378.060837)
			(xy 295.807875 -378.001041) (xy 295.845969 -377.945407) (xy 295.867836 -377.919742) (xy 295.873644 -377.912605)
			(xy 295.880151 -377.895408) (xy 295.880536 -377.886214) (xy 295.880536 -377.728734) (xy 295.881055 -377.71861)
			(xy 295.88877 -377.69989) (xy 295.903047 -377.685533) (xy 295.921723 -377.677712) (xy 295.931844 -377.677172)
			(xy 296.648124 -377.677172) (xy 296.658276 -377.677601) (xy 296.677024 -377.6854) (xy 296.691345 -377.699793)
			(xy 296.699049 -377.71858) (xy 296.699432 -377.728734) (xy 296.699432 -377.886214) (xy 296.699851 -377.8954)
			(xy 296.70636 -377.912584) (xy 296.712132 -377.919742) (xy 296.733969 -377.945429) (xy 296.772057 -378.001061)
			(xy 296.803207 -378.060855) (xy 296.826971 -378.123949) (xy 296.843007 -378.189435) (xy 296.851085 -378.25637)
			(xy 296.851087 -378.323791) (xy 296.851087 -378.323794) (xy 300.128621 -378.323794) (xy 300.128623 -378.256367)
			(xy 300.136702 -378.189427) (xy 300.152741 -378.123936) (xy 300.176509 -378.060838) (xy 300.207664 -378.001041)
			(xy 300.245758 -377.945407) (xy 300.267624 -377.919742) (xy 300.27343 -377.912604) (xy 300.279938 -377.895408)
			(xy 300.280324 -377.886214) (xy 300.280324 -377.728734) (xy 300.280854 -377.718611) (xy 300.288568 -377.699894)
			(xy 300.302841 -377.685537) (xy 300.321512 -377.677714) (xy 300.331632 -377.677172) (xy 301.047912 -377.677172)
			(xy 301.058063 -377.677611) (xy 301.076811 -377.685405) (xy 301.091133 -377.699796) (xy 301.098837 -377.718581)
			(xy 301.09922 -377.728734) (xy 301.09922 -377.886214) (xy 301.099619 -377.895402) (xy 301.10614 -377.912587)
			(xy 301.11192 -377.919742) (xy 301.133758 -377.945429) (xy 301.171846 -378.001061) (xy 301.202997 -378.060854)
			(xy 301.226761 -378.123948) (xy 301.242798 -378.189434) (xy 301.250876 -378.25637) (xy 301.250878 -378.323734)
			(xy 330.92918 -378.323734) (xy 330.929182 -378.256427) (xy 330.937229 -378.189602) (xy 330.953206 -378.124218)
			(xy 330.976882 -378.061212) (xy 331.00792 -378.001488) (xy 331.045874 -377.945902) (xy 331.067664 -377.92025)
			(xy 331.073472 -377.913113) (xy 331.079978 -377.895916) (xy 331.080364 -377.886722) (xy 331.080364 -377.728734)
			(xy 331.080792 -377.718561) (xy 331.088571 -377.699763) (xy 331.102956 -377.685376) (xy 331.121753 -377.677594)
			(xy 331.131926 -377.677172) (xy 331.848206 -377.677172) (xy 331.858382 -377.67756) (xy 331.877184 -377.685353)
			(xy 331.891569 -377.69975) (xy 331.899348 -377.718557) (xy 331.899768 -377.728734) (xy 331.899768 -377.886722)
			(xy 331.900175 -377.895909) (xy 331.906692 -377.913093) (xy 331.912468 -377.92025) (xy 331.93423 -377.945923)
			(xy 331.972179 -378.001507) (xy 332.003213 -378.061228) (xy 332.026887 -378.124229) (xy 332.042861 -378.189609)
			(xy 332.050907 -378.256429) (xy 332.05091 -378.323732) (xy 332.050903 -378.323793) (xy 335.328973 -378.323793)
			(xy 335.328975 -378.256368) (xy 335.337053 -378.189429) (xy 335.35309 -378.123939) (xy 335.376855 -378.060841)
			(xy 335.408007 -378.001044) (xy 335.446096 -377.945408) (xy 335.46796 -377.919742) (xy 335.473771 -377.912607)
			(xy 335.480275 -377.895409) (xy 335.48066 -377.886214) (xy 335.48066 -377.728734) (xy 335.481155 -377.718607)
			(xy 335.488875 -377.699883) (xy 335.50316 -377.685525) (xy 335.521844 -377.677708) (xy 335.531968 -377.677172)
			(xy 336.248248 -377.677172) (xy 336.258402 -377.677582) (xy 336.27715 -377.685388) (xy 336.29147 -377.699787)
			(xy 336.299173 -377.718578) (xy 336.299556 -377.728734) (xy 336.299556 -377.886214) (xy 336.299969 -377.895401)
			(xy 336.306482 -377.912585) (xy 336.312256 -377.919742) (xy 336.334096 -377.945428) (xy 336.372188 -378.001058)
			(xy 336.403343 -378.060851) (xy 336.42711 -378.123945) (xy 336.443149 -378.189433) (xy 336.451227 -378.256369)
			(xy 336.45123 -378.323734) (xy 339.729268 -378.323734) (xy 339.72927 -378.256427) (xy 339.737317 -378.189602)
			(xy 339.753293 -378.124218) (xy 339.776969 -378.061213) (xy 339.808006 -378.001489) (xy 339.845958 -377.945902)
			(xy 339.867748 -377.92025) (xy 339.873554 -377.913112) (xy 339.880062 -377.895916) (xy 339.880448 -377.886722)
			(xy 339.880448 -377.728734) (xy 339.880892 -377.718563) (xy 339.888668 -377.699768) (xy 339.903047 -377.685381)
			(xy 339.92184 -377.677597) (xy 339.93201 -377.677172) (xy 340.64829 -377.677172) (xy 340.658465 -377.677573)
			(xy 340.677266 -377.685361) (xy 340.691653 -377.699754) (xy 340.699432 -377.718559) (xy 340.699852 -377.728734)
			(xy 340.699852 -377.886722) (xy 340.700262 -377.895909) (xy 340.706777 -377.913093) (xy 340.712552 -377.92025)
			(xy 340.734314 -377.945923) (xy 340.772264 -378.001506) (xy 340.803299 -378.061227) (xy 340.826974 -378.124229)
			(xy 340.842949 -378.189608) (xy 340.850995 -378.256429) (xy 340.850998 -378.323732) (xy 340.850998 -378.323734)
			(xy 344.129059 -378.323734) (xy 344.129061 -378.256427) (xy 344.137108 -378.189603) (xy 344.153083 -378.124219)
			(xy 344.176759 -378.061213) (xy 344.207795 -378.001489) (xy 344.245747 -377.945902) (xy 344.267536 -377.92025)
			(xy 344.273341 -377.913111) (xy 344.27985 -377.895916) (xy 344.280236 -377.886722) (xy 344.280236 -377.728734)
			(xy 344.280692 -377.718565) (xy 344.288465 -377.699771) (xy 344.302841 -377.685385) (xy 344.321629 -377.677599)
			(xy 344.331798 -377.677172) (xy 345.048078 -377.677172) (xy 345.058252 -377.677583) (xy 345.077053 -377.685367)
			(xy 345.09144 -377.699757) (xy 345.099219 -377.71856) (xy 345.09964 -377.728734) (xy 345.09964 -377.886722)
			(xy 345.100053 -377.895909) (xy 345.106566 -377.913092) (xy 345.11234 -377.92025) (xy 345.134103 -377.945923)
			(xy 345.172054 -378.001506) (xy 345.203089 -378.061226) (xy 345.226764 -378.124228) (xy 345.24274 -378.189608)
			(xy 345.250786 -378.256429) (xy 345.250789 -378.323732) (xy 345.250789 -378.323734) (xy 374.929089 -378.323734)
			(xy 374.929092 -378.256427) (xy 374.937139 -378.189602) (xy 374.953116 -378.124218) (xy 374.976793 -378.061212)
			(xy 375.007831 -378.001488) (xy 375.045786 -377.945902) (xy 375.067576 -377.92025) (xy 375.073374 -377.913105)
			(xy 375.079888 -377.895915) (xy 375.080276 -377.886722) (xy 375.080276 -377.728734) (xy 375.080693 -377.71856)
			(xy 375.088474 -377.699759) (xy 375.102862 -377.685371) (xy 375.121664 -377.677592) (xy 375.131838 -377.677172)
			(xy 375.848118 -377.677172) (xy 375.858295 -377.67755) (xy 375.877097 -377.685347) (xy 375.891482 -377.699747)
			(xy 375.89926 -377.718557) (xy 375.89968 -377.728734) (xy 375.89968 -377.886722) (xy 375.900084 -377.89591)
			(xy 375.906602 -377.913094) (xy 375.91238 -377.92025) (xy 375.934142 -377.945923) (xy 375.97209 -378.001507)
			(xy 376.003123 -378.061228) (xy 376.026797 -378.12423) (xy 376.042771 -378.189609) (xy 376.050817 -378.256429)
			(xy 376.050819 -378.323732) (xy 376.050812 -378.323793) (xy 379.328882 -378.323793) (xy 379.328884 -378.256368)
			(xy 379.336962 -378.189428) (xy 379.352999 -378.123938) (xy 379.376765 -378.06084) (xy 379.407917 -378.001043)
			(xy 379.446007 -377.945408) (xy 379.467872 -377.919742) (xy 379.473684 -377.912608) (xy 379.480188 -377.895409)
			(xy 379.480572 -377.886214) (xy 379.480572 -377.728734) (xy 379.481056 -377.718606) (xy 379.488778 -377.699879)
			(xy 379.503066 -377.685521) (xy 379.521754 -377.677706) (xy 379.53188 -377.677172) (xy 380.24816 -377.677172)
			(xy 380.258308 -377.677654) (xy 380.277054 -377.685431) (xy 380.291378 -377.699809) (xy 380.299084 -377.718584)
			(xy 380.299468 -377.728734) (xy 380.299468 -377.886214) (xy 380.299878 -377.895401) (xy 380.306393 -377.912585)
			(xy 380.312168 -377.919742) (xy 380.334008 -377.945428) (xy 380.372099 -378.001059) (xy 380.403253 -378.060852)
			(xy 380.42702 -378.123946) (xy 380.443058 -378.189433) (xy 380.451137 -378.256369) (xy 380.451139 -378.323734)
			(xy 383.729177 -378.323734) (xy 383.729179 -378.256427) (xy 383.737226 -378.189602) (xy 383.753202 -378.124218)
			(xy 383.776879 -378.061212) (xy 383.807917 -378.001488) (xy 383.84587 -377.945902) (xy 383.86766 -377.92025)
			(xy 383.873468 -377.913113) (xy 383.879974 -377.895916) (xy 383.88036 -377.886722) (xy 383.88036 -377.728734)
			(xy 383.880792 -377.718562) (xy 383.88857 -377.699764) (xy 383.902954 -377.685377) (xy 383.92175 -377.677595)
			(xy 383.931922 -377.677172) (xy 384.648202 -377.677172) (xy 384.658378 -377.677563) (xy 384.677179 -377.685355)
			(xy 384.691565 -377.699751) (xy 384.699344 -377.718558) (xy 384.699764 -377.728734) (xy 384.699764 -377.886722)
			(xy 384.700172 -377.895909) (xy 384.706688 -377.913093) (xy 384.712464 -377.92025) (xy 384.734226 -377.945923)
			(xy 384.772175 -378.001507) (xy 384.803209 -378.061228) (xy 384.826884 -378.124229) (xy 384.842858 -378.189609)
			(xy 384.850904 -378.256429) (xy 384.850907 -378.323732) (xy 384.850907 -378.323734) (xy 388.128968 -378.323734)
			(xy 388.12897 -378.256427) (xy 388.137017 -378.189602) (xy 388.152993 -378.124218) (xy 388.176669 -378.061213)
			(xy 388.207706 -378.001489) (xy 388.245658 -377.945902) (xy 388.267448 -377.92025) (xy 388.273254 -377.913112)
			(xy 388.279762 -377.895916) (xy 388.280148 -377.886722) (xy 388.280148 -377.728734) (xy 388.280592 -377.718563)
			(xy 388.288368 -377.699768) (xy 388.302747 -377.685381) (xy 388.32154 -377.677597) (xy 388.33171 -377.677172)
			(xy 389.04799 -377.677172) (xy 389.058165 -377.677573) (xy 389.076966 -377.685361) (xy 389.091353 -377.699754)
			(xy 389.099132 -377.718559) (xy 389.099552 -377.728734) (xy 389.099552 -377.886722) (xy 389.099962 -377.895909)
			(xy 389.106477 -377.913093) (xy 389.112252 -377.92025) (xy 389.134014 -377.945923) (xy 389.171964 -378.001506)
			(xy 389.202999 -378.061227) (xy 389.226674 -378.124229) (xy 389.242649 -378.189608) (xy 389.250695 -378.256429)
			(xy 389.250698 -378.323732) (xy 389.250698 -378.323734) (xy 418.928998 -378.323734) (xy 418.929001 -378.256426)
			(xy 418.937048 -378.189601) (xy 418.953025 -378.124217) (xy 418.976703 -378.061211) (xy 419.007742 -378.001487)
			(xy 419.045697 -377.945902) (xy 419.067488 -377.92025) (xy 419.073287 -377.913106) (xy 419.079801 -377.895915)
			(xy 419.080188 -377.886722) (xy 419.080188 -377.728734) (xy 419.080593 -377.718558) (xy 419.088376 -377.699755)
			(xy 419.102768 -377.685367) (xy 419.121574 -377.67759) (xy 419.13175 -377.677172) (xy 419.84803 -377.677172)
			(xy 419.858208 -377.67754) (xy 419.87701 -377.685341) (xy 419.891395 -377.699744) (xy 419.899173 -377.718556)
			(xy 419.899592 -377.728734) (xy 419.899592 -377.886722) (xy 419.899993 -377.89591) (xy 419.906513 -377.913094)
			(xy 419.912292 -377.92025) (xy 419.934053 -377.945924) (xy 419.972001 -378.001508) (xy 420.003034 -378.061229)
			(xy 420.026706 -378.12423) (xy 420.04268 -378.189609) (xy 420.050726 -378.256429) (xy 420.050728 -378.323732)
			(xy 420.050721 -378.323793) (xy 423.328791 -378.323793) (xy 423.328793 -378.256368) (xy 423.336871 -378.189428)
			(xy 423.352909 -378.123938) (xy 423.376675 -378.06084) (xy 423.407828 -378.001043) (xy 423.445919 -377.945408)
			(xy 423.467784 -377.919742) (xy 423.473586 -377.9126) (xy 423.480098 -377.895407) (xy 423.480484 -377.886214)
			(xy 423.480484 -377.728734) (xy 423.480956 -377.718604) (xy 423.488681 -377.699875) (xy 423.502972 -377.685516)
			(xy 423.521664 -377.677704) (xy 423.531792 -377.677172) (xy 424.248072 -377.677172) (xy 424.258189 -377.677638)
			(xy 424.276887 -377.685372) (xy 424.291201 -377.699673) (xy 424.298953 -377.718363) (xy 424.29938 -377.72848)
			(xy 424.29938 -377.886214) (xy 424.299788 -377.895401) (xy 424.306303 -377.912585) (xy 424.31208 -377.919742)
			(xy 424.333919 -377.945428) (xy 424.37201 -378.001059) (xy 424.403163 -378.060852) (xy 424.426929 -378.123946)
			(xy 424.442967 -378.189433) (xy 424.451046 -378.256369) (xy 424.451048 -378.323734) (xy 427.729086 -378.323734)
			(xy 427.729089 -378.256427) (xy 427.737136 -378.189602) (xy 427.753113 -378.124218) (xy 427.77679 -378.061212)
			(xy 427.807828 -378.001488) (xy 427.845782 -377.945902) (xy 427.867572 -377.92025) (xy 427.873381 -377.913114)
			(xy 427.879886 -377.895916) (xy 427.880272 -377.886722) (xy 427.880272 -377.728734) (xy 427.880693 -377.71856)
			(xy 427.888473 -377.69976) (xy 427.90286 -377.685373) (xy 427.92166 -377.677593) (xy 427.931834 -377.677172)
			(xy 428.648114 -377.677172) (xy 428.658291 -377.677553) (xy 428.677092 -377.685349) (xy 428.691478 -377.699748)
			(xy 428.699256 -377.718557) (xy 428.699676 -377.728734) (xy 428.699676 -377.886722) (xy 428.700081 -377.89591)
			(xy 428.706599 -377.913094) (xy 428.712376 -377.92025) (xy 428.734137 -377.945924) (xy 428.772086 -378.001507)
			(xy 428.80312 -378.061228) (xy 428.826793 -378.12423) (xy 428.842767 -378.189609) (xy 428.850813 -378.256429)
			(xy 428.850816 -378.323732) (xy 428.850816 -378.323734) (xy 432.128877 -378.323734) (xy 432.128879 -378.256427)
			(xy 432.136926 -378.189602) (xy 432.152902 -378.124218) (xy 432.176579 -378.061212) (xy 432.207617 -378.001488)
			(xy 432.24557 -377.945902) (xy 432.26736 -377.92025) (xy 432.273168 -377.913113) (xy 432.279674 -377.895916)
			(xy 432.28006 -377.886722) (xy 432.28006 -377.728734) (xy 432.280492 -377.718562) (xy 432.28827 -377.699764)
			(xy 432.302654 -377.685377) (xy 432.32145 -377.677595) (xy 432.331622 -377.677172) (xy 433.047902 -377.677172)
			(xy 433.058078 -377.677563) (xy 433.076879 -377.685355) (xy 433.091265 -377.699751) (xy 433.099044 -377.718558)
			(xy 433.099464 -377.728734) (xy 433.099464 -377.886722) (xy 433.099872 -377.895909) (xy 433.106388 -377.913093)
			(xy 433.112164 -377.92025) (xy 433.133926 -377.945923) (xy 433.171875 -378.001507) (xy 433.202909 -378.061228)
			(xy 433.226584 -378.124229) (xy 433.242558 -378.189609) (xy 433.250604 -378.256429) (xy 433.250607 -378.323732)
			(xy 433.242565 -378.390553) (xy 433.226595 -378.455933) (xy 433.202925 -378.518937) (xy 433.171895 -378.57866)
			(xy 433.13395 -378.634246) (xy 433.112164 -378.659898) (xy 433.106381 -378.667053) (xy 433.099859 -378.684236)
			(xy 433.099464 -378.693426) (xy 433.099464 -379.186694) (xy 433.099885 -379.19588) (xy 433.106392 -379.213064)
			(xy 433.112164 -379.220222) (xy 433.133997 -379.245837) (xy 433.171944 -379.301429) (xy 433.202975 -379.361158)
			(xy 433.226645 -379.424167) (xy 433.242615 -379.489554) (xy 433.250655 -379.55638) (xy 433.250651 -379.623689)
			(xy 433.242603 -379.690515) (xy 433.226625 -379.755899) (xy 433.202947 -379.818906) (xy 433.171909 -379.878631)
			(xy 433.133955 -379.934218) (xy 433.112164 -379.95987) (xy 433.106351 -379.967003) (xy 433.099847 -379.984203)
			(xy 433.099464 -379.993398) (xy 433.099464 -380.151386) (xy 433.099025 -380.161556) (xy 433.091245 -380.180351)
			(xy 433.076864 -380.194736) (xy 433.058072 -380.202522) (xy 433.047902 -380.202948) (xy 432.331622 -380.202948)
			(xy 432.32145 -380.202518) (xy 432.302653 -380.194737) (xy 432.288267 -380.180353) (xy 432.280484 -380.161558)
			(xy 432.28006 -380.151386) (xy 432.28006 -379.993398) (xy 432.279637 -379.984212) (xy 432.273131 -379.967029)
			(xy 432.26736 -379.95987) (xy 432.245617 -379.934181) (xy 432.207665 -379.8786) (xy 432.176629 -379.818882)
			(xy 432.152953 -379.755882) (xy 432.136976 -379.690504) (xy 432.128928 -379.623685) (xy 432.128924 -379.556384)
			(xy 432.136964 -379.489564) (xy 432.152932 -379.424184) (xy 432.176601 -379.361181) (xy 432.20763 -379.301459)
			(xy 432.245575 -379.245874) (xy 432.26736 -379.220222) (xy 432.27318 -379.213093) (xy 432.279679 -379.19589)
			(xy 432.28006 -379.186694) (xy 432.28006 -378.693426) (xy 432.279624 -378.684242) (xy 432.273127 -378.667058)
			(xy 432.26736 -378.659898) (xy 432.245546 -378.634267) (xy 432.207596 -378.578678) (xy 432.176563 -378.518952)
			(xy 432.152891 -378.455945) (xy 432.136919 -378.39056) (xy 432.128877 -378.323734) (xy 428.850816 -378.323734)
			(xy 428.842774 -378.390552) (xy 428.826805 -378.455933) (xy 428.803136 -378.518936) (xy 428.772106 -378.578659)
			(xy 428.734161 -378.634245) (xy 428.712376 -378.659898) (xy 428.706595 -378.667054) (xy 428.700072 -378.684236)
			(xy 428.699676 -378.693426) (xy 428.699676 -379.186694) (xy 428.700094 -379.19588) (xy 428.706603 -379.213064)
			(xy 428.712376 -379.220222) (xy 428.734209 -379.245837) (xy 428.772155 -379.301429) (xy 428.803185 -379.361158)
			(xy 428.826855 -379.424167) (xy 428.842824 -379.489554) (xy 428.850865 -379.55638) (xy 428.85086 -379.623689)
			(xy 428.842812 -379.690514) (xy 428.826835 -379.755899) (xy 428.803157 -379.818905) (xy 428.772119 -379.87863)
			(xy 428.734166 -379.934218) (xy 428.712376 -379.95987) (xy 428.706564 -379.967004) (xy 428.70006 -379.984203)
			(xy 428.699676 -379.993398) (xy 428.699676 -380.151386) (xy 428.699156 -380.161541) (xy 428.691388 -380.180307)
			(xy 428.677031 -380.194673) (xy 428.658269 -380.20245) (xy 428.648114 -380.202948) (xy 427.931834 -380.202948)
			(xy 427.921663 -380.202508) (xy 427.902866 -380.194731) (xy 427.88848 -380.180351) (xy 427.880696 -380.161557)
			(xy 427.880272 -380.151386) (xy 427.880272 -379.993398) (xy 427.879869 -379.98421) (xy 427.873351 -379.967025)
			(xy 427.867572 -379.95987) (xy 427.845829 -379.934181) (xy 427.807876 -379.878601) (xy 427.776839 -379.818882)
			(xy 427.753162 -379.755883) (xy 427.737185 -379.690505) (xy 427.729137 -379.623686) (xy 427.729133 -379.556384)
			(xy 427.737173 -379.489564) (xy 427.753142 -379.424183) (xy 427.776811 -379.361181) (xy 427.807841 -379.301459)
			(xy 427.845786 -379.245874) (xy 427.867572 -379.220222) (xy 427.873393 -379.213094) (xy 427.879891 -379.19589)
			(xy 427.880272 -379.186694) (xy 427.880272 -378.693426) (xy 427.879856 -378.684239) (xy 427.873347 -378.667055)
			(xy 427.867572 -378.659898) (xy 427.845758 -378.634267) (xy 427.807808 -378.578678) (xy 427.776774 -378.518952)
			(xy 427.753101 -378.455945) (xy 427.737129 -378.39056) (xy 427.729086 -378.323734) (xy 424.451048 -378.323734)
			(xy 424.451048 -378.323791) (xy 424.442974 -378.390728) (xy 424.426941 -378.456216) (xy 424.403179 -378.519312)
			(xy 424.37203 -378.579107) (xy 424.333943 -378.634741) (xy 424.31208 -378.660406) (xy 424.306296 -378.66756)
			(xy 424.299775 -378.684744) (xy 424.29938 -378.693934) (xy 424.29938 -379.186186) (xy 424.299802 -379.195372)
			(xy 424.306308 -379.212556) (xy 424.31208 -379.219714) (xy 424.33399 -379.245342) (xy 424.372079 -379.300981)
			(xy 424.403228 -379.360782) (xy 424.426991 -379.423884) (xy 424.443024 -379.489378) (xy 424.451096 -379.556321)
			(xy 424.451092 -379.623748) (xy 424.443011 -379.69069) (xy 424.42697 -379.756182) (xy 424.4032 -379.819281)
			(xy 424.372043 -379.879078) (xy 424.333947 -379.934713) (xy 424.31208 -379.960378) (xy 424.306266 -379.96751)
			(xy 424.299762 -379.984711) (xy 424.29938 -379.993906) (xy 424.29938 -380.151386) (xy 424.298863 -380.161509)
			(xy 424.291143 -380.180226) (xy 424.276866 -380.194583) (xy 424.258193 -380.202406) (xy 424.248072 -380.202948)
			(xy 423.531792 -380.202948) (xy 423.521689 -380.202422) (xy 423.50302 -380.194691) (xy 423.488727 -380.180407)
			(xy 423.480984 -380.161743) (xy 423.480484 -380.15164) (xy 423.480484 -379.993906) (xy 423.480075 -379.984719)
			(xy 423.473561 -379.967534) (xy 423.467784 -379.960378) (xy 423.445966 -379.934675) (xy 423.407877 -379.879046)
			(xy 423.376725 -379.819255) (xy 423.352959 -379.756163) (xy 423.336921 -379.690678) (xy 423.328841 -379.623744)
			(xy 423.328837 -379.556325) (xy 423.336908 -379.48939) (xy 423.352938 -379.423904) (xy 423.376697 -379.360809)
			(xy 423.407841 -379.301014) (xy 423.445923 -379.245379) (xy 423.467784 -379.219714) (xy 423.473598 -379.212581)
			(xy 423.480103 -379.195381) (xy 423.480484 -379.186186) (xy 423.480484 -378.693934) (xy 423.480061 -378.684748)
			(xy 423.473557 -378.667563) (xy 423.467784 -378.660406) (xy 423.445895 -378.634762) (xy 423.407808 -378.579124)
			(xy 423.376659 -378.519324) (xy 423.352897 -378.456225) (xy 423.336864 -378.390733) (xy 423.328791 -378.323793)
			(xy 420.050721 -378.323793) (xy 420.042687 -378.390552) (xy 420.026718 -378.455932) (xy 420.003049 -378.518936)
			(xy 419.972021 -378.578659) (xy 419.934077 -378.634245) (xy 419.912292 -378.659898) (xy 419.906513 -378.667056)
			(xy 419.899988 -378.684237) (xy 419.899592 -378.693426) (xy 419.899592 -379.186694) (xy 419.900007 -379.195881)
			(xy 419.906518 -379.213065) (xy 419.912292 -379.220222) (xy 419.934124 -379.245837) (xy 419.972069 -379.30143)
			(xy 420.003099 -379.361159) (xy 420.026768 -379.424168) (xy 420.042737 -379.489554) (xy 420.050777 -379.556381)
			(xy 420.050772 -379.623689) (xy 420.042724 -379.690514) (xy 420.026747 -379.755898) (xy 420.003071 -379.818905)
			(xy 419.972034 -379.87863) (xy 419.934082 -379.934217) (xy 419.912292 -379.95987) (xy 419.906482 -379.967006)
			(xy 419.899976 -379.984204) (xy 419.899592 -379.993398) (xy 419.899592 -380.151386) (xy 419.899056 -380.161539)
			(xy 419.891292 -380.180302) (xy 419.876939 -380.194667) (xy 419.858183 -380.202447) (xy 419.84803 -380.202948)
			(xy 419.13175 -380.202948) (xy 419.12158 -380.202495) (xy 419.102784 -380.194724) (xy 419.088396 -380.180347)
			(xy 419.080612 -380.161556) (xy 419.080188 -380.151386) (xy 419.080188 -379.993398) (xy 419.079781 -379.98421)
			(xy 419.073266 -379.967026) (xy 419.067488 -379.95987) (xy 419.045744 -379.934181) (xy 419.007791 -379.878601)
			(xy 418.976753 -379.818883) (xy 418.953075 -379.755883) (xy 418.937097 -379.690505) (xy 418.929049 -379.623686)
			(xy 418.929045 -379.556383) (xy 418.937085 -379.489563) (xy 418.953055 -379.424183) (xy 418.976724 -379.36118)
			(xy 419.007755 -379.301458) (xy 419.045702 -379.245873) (xy 419.067488 -379.220222) (xy 419.073299 -379.213087)
			(xy 419.079805 -379.195889) (xy 419.080188 -379.186694) (xy 419.080188 -378.693426) (xy 419.079768 -378.68424)
			(xy 419.073262 -378.667055) (xy 419.067488 -378.659898) (xy 419.045673 -378.634268) (xy 419.007722 -378.578679)
			(xy 418.976687 -378.518953) (xy 418.953014 -378.455946) (xy 418.937041 -378.39056) (xy 418.928998 -378.323734)
			(xy 389.250698 -378.323734) (xy 389.242656 -378.390553) (xy 389.226686 -378.455934) (xy 389.203015 -378.518937)
			(xy 389.171985 -378.57866) (xy 389.134038 -378.634246) (xy 389.112252 -378.659898) (xy 389.106468 -378.667052)
			(xy 389.099947 -378.684236) (xy 389.099552 -378.693426) (xy 389.099552 -379.186694) (xy 389.099976 -379.19588)
			(xy 389.106481 -379.213063) (xy 389.112252 -379.220222) (xy 389.134085 -379.245837) (xy 389.172033 -379.301428)
			(xy 389.203065 -379.361157) (xy 389.226736 -379.424166) (xy 389.242706 -379.489553) (xy 389.250746 -379.55638)
			(xy 389.250742 -379.623689) (xy 389.242693 -379.690515) (xy 389.226715 -379.7559) (xy 389.203037 -379.818906)
			(xy 389.171998 -379.878631) (xy 389.134043 -379.934218) (xy 389.112252 -379.95987) (xy 389.106437 -379.967002)
			(xy 389.099935 -379.984203) (xy 389.099552 -379.993398) (xy 389.099552 -380.151386) (xy 389.099125 -380.161558)
			(xy 389.091342 -380.180354) (xy 389.076958 -380.19474) (xy 389.058162 -380.202524) (xy 389.04799 -380.202948)
			(xy 388.33171 -380.202948) (xy 388.321537 -380.202528) (xy 388.30274 -380.194743) (xy 388.288354 -380.180357)
			(xy 388.280571 -380.161559) (xy 388.280148 -380.151386) (xy 388.280148 -379.993398) (xy 388.279728 -379.984212)
			(xy 388.27322 -379.967028) (xy 388.267448 -379.95987) (xy 388.245705 -379.934181) (xy 388.207755 -379.8786)
			(xy 388.176719 -379.818881) (xy 388.153043 -379.755882) (xy 388.137067 -379.690504) (xy 388.129019 -379.623685)
			(xy 388.129015 -379.556384) (xy 388.137054 -379.489564) (xy 388.153023 -379.424184) (xy 388.176691 -379.361182)
			(xy 388.207719 -379.30146) (xy 388.245663 -379.245874) (xy 388.267448 -379.220222) (xy 388.273266 -379.213092)
			(xy 388.279767 -379.19589) (xy 388.280148 -379.186694) (xy 388.280148 -378.693426) (xy 388.279715 -378.684241)
			(xy 388.273216 -378.667057) (xy 388.267448 -378.659898) (xy 388.245634 -378.634267) (xy 388.207686 -378.578678)
			(xy 388.176653 -378.518951) (xy 388.152981 -378.455944) (xy 388.13701 -378.390559) (xy 388.128968 -378.323734)
			(xy 384.850907 -378.323734) (xy 384.842865 -378.390553) (xy 384.826895 -378.455933) (xy 384.803225 -378.518937)
			(xy 384.772195 -378.57866) (xy 384.73425 -378.634246) (xy 384.712464 -378.659898) (xy 384.706681 -378.667053)
			(xy 384.700159 -378.684236) (xy 384.699764 -378.693426) (xy 384.699764 -379.186694) (xy 384.700185 -379.19588)
			(xy 384.706692 -379.213064) (xy 384.712464 -379.220222) (xy 384.734297 -379.245837) (xy 384.772244 -379.301429)
			(xy 384.803275 -379.361158) (xy 384.826945 -379.424167) (xy 384.842915 -379.489554) (xy 384.850955 -379.55638)
			(xy 384.850951 -379.623689) (xy 384.842903 -379.690515) (xy 384.826925 -379.755899) (xy 384.803247 -379.818906)
			(xy 384.772209 -379.878631) (xy 384.734255 -379.934218) (xy 384.712464 -379.95987) (xy 384.706651 -379.967003)
			(xy 384.700147 -379.984203) (xy 384.699764 -379.993398) (xy 384.699764 -380.151386) (xy 384.699325 -380.161556)
			(xy 384.691545 -380.180351) (xy 384.677164 -380.194736) (xy 384.658372 -380.202522) (xy 384.648202 -380.202948)
			(xy 383.931922 -380.202948) (xy 383.92175 -380.202518) (xy 383.902953 -380.194737) (xy 383.888567 -380.180353)
			(xy 383.880784 -380.161558) (xy 383.88036 -380.151386) (xy 383.88036 -379.993398) (xy 383.879937 -379.984212)
			(xy 383.873431 -379.967029) (xy 383.86766 -379.95987) (xy 383.845917 -379.934181) (xy 383.807965 -379.8786)
			(xy 383.776929 -379.818882) (xy 383.753253 -379.755882) (xy 383.737276 -379.690504) (xy 383.729228 -379.623685)
			(xy 383.729224 -379.556384) (xy 383.737264 -379.489564) (xy 383.753232 -379.424184) (xy 383.776901 -379.361181)
			(xy 383.80793 -379.301459) (xy 383.845875 -379.245874) (xy 383.86766 -379.220222) (xy 383.87348 -379.213093)
			(xy 383.879979 -379.19589) (xy 383.88036 -379.186694) (xy 383.88036 -378.693426) (xy 383.879924 -378.684242)
			(xy 383.873427 -378.667058) (xy 383.86766 -378.659898) (xy 383.845846 -378.634267) (xy 383.807896 -378.578678)
			(xy 383.776863 -378.518952) (xy 383.753191 -378.455945) (xy 383.737219 -378.39056) (xy 383.729177 -378.323734)
			(xy 380.451139 -378.323734) (xy 380.451139 -378.323792) (xy 380.443065 -378.390729) (xy 380.427031 -378.456217)
			(xy 380.403269 -378.519313) (xy 380.372119 -378.579108) (xy 380.334032 -378.634741) (xy 380.312168 -378.660406)
			(xy 380.306382 -378.667559) (xy 380.299862 -378.684744) (xy 380.299468 -378.693934) (xy 380.299468 -379.186186)
			(xy 380.299892 -379.195372) (xy 380.306397 -379.212556) (xy 380.312168 -379.219714) (xy 380.334078 -379.245341)
			(xy 380.372168 -379.300981) (xy 380.403318 -379.360782) (xy 380.427081 -379.423884) (xy 380.443114 -379.489378)
			(xy 380.451187 -379.556321) (xy 380.451183 -379.623749) (xy 380.443102 -379.69069) (xy 380.427061 -379.756182)
			(xy 380.40329 -379.819281) (xy 380.372132 -379.879079) (xy 380.334036 -379.934713) (xy 380.312168 -379.960378)
			(xy 380.306352 -379.967509) (xy 380.29985 -379.984711) (xy 380.299468 -379.993906) (xy 380.299468 -380.151386)
			(xy 380.298962 -380.161511) (xy 380.291241 -380.18023) (xy 380.27696 -380.194587) (xy 380.258282 -380.202408)
			(xy 380.24816 -380.202948) (xy 379.53188 -380.202948) (xy 379.521731 -380.202496) (xy 379.502987 -380.194703)
			(xy 379.488666 -380.180316) (xy 379.480958 -380.161537) (xy 379.480572 -380.151386) (xy 379.480572 -379.993906)
			(xy 379.480165 -379.984718) (xy 379.47365 -379.967534) (xy 379.467872 -379.960378) (xy 379.446054 -379.934675)
			(xy 379.407966 -379.879045) (xy 379.376815 -379.819254) (xy 379.353049 -379.756162) (xy 379.337011 -379.690678)
			(xy 379.328932 -379.623744) (xy 379.328928 -379.556325) (xy 379.336999 -379.48939) (xy 379.353029 -379.423904)
			(xy 379.376787 -379.360809) (xy 379.40793 -379.301014) (xy 379.446012 -379.24538) (xy 379.467872 -379.219714)
			(xy 379.473696 -379.212589) (xy 379.480192 -379.195383) (xy 379.480572 -379.186186) (xy 379.480572 -378.693934)
			(xy 379.480152 -378.684748) (xy 379.473646 -378.667563) (xy 379.467872 -378.660406) (xy 379.445983 -378.634761)
			(xy 379.407897 -378.579123) (xy 379.376749 -378.519324) (xy 379.352988 -378.456224) (xy 379.336955 -378.390733)
			(xy 379.328882 -378.323793) (xy 376.050812 -378.323793) (xy 376.042778 -378.390552) (xy 376.026808 -378.455933)
			(xy 376.003139 -378.518936) (xy 375.97211 -378.578659) (xy 375.934166 -378.634246) (xy 375.91238 -378.659898)
			(xy 375.906599 -378.667054) (xy 375.900076 -378.684236) (xy 375.89968 -378.693426) (xy 375.89968 -379.186694)
			(xy 375.900098 -379.19588) (xy 375.906607 -379.213064) (xy 375.91238 -379.220222) (xy 375.934212 -379.245837)
			(xy 375.972159 -379.301429) (xy 376.003189 -379.361158) (xy 376.026858 -379.424168) (xy 376.042827 -379.489554)
			(xy 376.050868 -379.55638) (xy 376.050863 -379.623689) (xy 376.042815 -379.690514) (xy 376.026838 -379.755899)
			(xy 376.003161 -379.818905) (xy 375.972123 -379.87863) (xy 375.93417 -379.934218) (xy 375.91238 -379.95987)
			(xy 375.906569 -379.967005) (xy 375.900064 -379.984203) (xy 375.89968 -379.993398) (xy 375.89968 -380.151386)
			(xy 375.899156 -380.161541) (xy 375.891389 -380.180306) (xy 375.877033 -380.194671) (xy 375.858272 -380.202449)
			(xy 375.848118 -380.202948) (xy 375.131838 -380.202948) (xy 375.121667 -380.202505) (xy 375.102871 -380.19473)
			(xy 375.088484 -380.18035) (xy 375.0807 -380.161557) (xy 375.080276 -380.151386) (xy 375.080276 -379.993398)
			(xy 375.079872 -379.98421) (xy 375.073355 -379.967025) (xy 375.067576 -379.95987) (xy 375.045832 -379.934181)
			(xy 375.00788 -379.878601) (xy 374.976842 -379.818883) (xy 374.953165 -379.755883) (xy 374.937188 -379.690505)
			(xy 374.92914 -379.623686) (xy 374.929136 -379.556384) (xy 374.937176 -379.489563) (xy 374.953145 -379.424183)
			(xy 374.976814 -379.361181) (xy 375.007844 -379.301459) (xy 375.04579 -379.245874) (xy 375.067576 -379.220222)
			(xy 375.073385 -379.213086) (xy 375.079893 -379.195889) (xy 375.080276 -379.186694) (xy 375.080276 -378.693426)
			(xy 375.079859 -378.684239) (xy 375.073351 -378.667055) (xy 375.067576 -378.659898) (xy 375.045762 -378.634267)
			(xy 375.007811 -378.578679) (xy 374.976777 -378.518952) (xy 374.953104 -378.455945) (xy 374.937132 -378.39056)
			(xy 374.929089 -378.323734) (xy 345.250789 -378.323734) (xy 345.242747 -378.390553) (xy 345.226776 -378.455934)
			(xy 345.203105 -378.518938) (xy 345.172074 -378.57866) (xy 345.134127 -378.634246) (xy 345.11234 -378.659898)
			(xy 345.106554 -378.667051) (xy 345.100035 -378.684236) (xy 345.09964 -378.693426) (xy 345.09964 -379.186694)
			(xy 345.100066 -379.195879) (xy 345.10657 -379.213063) (xy 345.11234 -379.220222) (xy 345.134174 -379.245837)
			(xy 345.172123 -379.301428) (xy 345.203155 -379.361156) (xy 345.226826 -379.424166) (xy 345.242797 -379.489553)
			(xy 345.250837 -379.55638) (xy 345.250833 -379.623689) (xy 345.242784 -379.690515) (xy 345.226806 -379.7559)
			(xy 345.203127 -379.818907) (xy 345.172087 -379.878632) (xy 345.134131 -379.934218) (xy 345.11234 -379.95987)
			(xy 345.106524 -379.967001) (xy 345.100023 -379.984203) (xy 345.09964 -379.993398) (xy 345.09964 -380.151386)
			(xy 345.099224 -380.161559) (xy 345.09144 -380.180358) (xy 345.077051 -380.194744) (xy 345.058252 -380.202526)
			(xy 345.048078 -380.202948) (xy 344.331798 -380.202948) (xy 344.321625 -380.202537) (xy 344.302827 -380.194749)
			(xy 344.288442 -380.180359) (xy 344.280659 -380.16156) (xy 344.280236 -380.151386) (xy 344.280236 -379.993398)
			(xy 344.279819 -379.984212) (xy 344.273309 -379.967028) (xy 344.267536 -379.95987) (xy 344.245794 -379.93418)
			(xy 344.207844 -379.878599) (xy 344.176809 -379.818881) (xy 344.153133 -379.755881) (xy 344.137157 -379.690504)
			(xy 344.12911 -379.623685) (xy 344.129106 -379.556384) (xy 344.137145 -379.489565) (xy 344.153113 -379.424185)
			(xy 344.17678 -379.361182) (xy 344.207808 -379.30146) (xy 344.245751 -379.245874) (xy 344.267536 -379.220222)
			(xy 344.273353 -379.213091) (xy 344.279855 -379.19589) (xy 344.280236 -379.186694) (xy 344.280236 -378.693426)
			(xy 344.279805 -378.684241) (xy 344.273305 -378.667057) (xy 344.267536 -378.659898) (xy 344.245723 -378.634267)
			(xy 344.207775 -378.578677) (xy 344.176743 -378.518951) (xy 344.153072 -378.455944) (xy 344.137101 -378.390559)
			(xy 344.129059 -378.323734) (xy 340.850998 -378.323734) (xy 340.842956 -378.390553) (xy 340.826986 -378.455934)
			(xy 340.803315 -378.518937) (xy 340.772285 -378.57866) (xy 340.734338 -378.634246) (xy 340.712552 -378.659898)
			(xy 340.706768 -378.667052) (xy 340.700247 -378.684236) (xy 340.699852 -378.693426) (xy 340.699852 -379.186694)
			(xy 340.700276 -379.19588) (xy 340.706781 -379.213063) (xy 340.712552 -379.220222) (xy 340.734385 -379.245837)
			(xy 340.772333 -379.301428) (xy 340.803365 -379.361157) (xy 340.827036 -379.424166) (xy 340.843006 -379.489553)
			(xy 340.851046 -379.55638) (xy 340.851042 -379.623689) (xy 340.842993 -379.690515) (xy 340.827015 -379.7559)
			(xy 340.803337 -379.818906) (xy 340.772298 -379.878631) (xy 340.734343 -379.934218) (xy 340.712552 -379.95987)
			(xy 340.706737 -379.967002) (xy 340.700235 -379.984203) (xy 340.699852 -379.993398) (xy 340.699852 -380.151386)
			(xy 340.699425 -380.161558) (xy 340.691642 -380.180354) (xy 340.677258 -380.19474) (xy 340.658462 -380.202524)
			(xy 340.64829 -380.202948) (xy 339.93201 -380.202948) (xy 339.921837 -380.202528) (xy 339.90304 -380.194743)
			(xy 339.888654 -380.180357) (xy 339.880871 -380.161559) (xy 339.880448 -380.151386) (xy 339.880448 -379.993398)
			(xy 339.880028 -379.984212) (xy 339.87352 -379.967028) (xy 339.867748 -379.95987) (xy 339.846005 -379.934181)
			(xy 339.808055 -379.8786) (xy 339.777019 -379.818881) (xy 339.753343 -379.755882) (xy 339.737367 -379.690504)
			(xy 339.729319 -379.623685) (xy 339.729315 -379.556384) (xy 339.737354 -379.489564) (xy 339.753323 -379.424184)
			(xy 339.776991 -379.361182) (xy 339.808019 -379.30146) (xy 339.845963 -379.245874) (xy 339.867748 -379.220222)
			(xy 339.873566 -379.213092) (xy 339.880067 -379.19589) (xy 339.880448 -379.186694) (xy 339.880448 -378.693426)
			(xy 339.880015 -378.684241) (xy 339.873516 -378.667057) (xy 339.867748 -378.659898) (xy 339.845934 -378.634267)
			(xy 339.807986 -378.578678) (xy 339.776953 -378.518951) (xy 339.753281 -378.455944) (xy 339.73731 -378.390559)
			(xy 339.729268 -378.323734) (xy 336.45123 -378.323734) (xy 336.45123 -378.323792) (xy 336.443156 -378.390729)
			(xy 336.427122 -378.456217) (xy 336.403359 -378.519313) (xy 336.372208 -378.579108) (xy 336.33412 -378.634742)
			(xy 336.312256 -378.660406) (xy 336.306469 -378.667558) (xy 336.29995 -378.684743) (xy 336.299556 -378.693934)
			(xy 336.299556 -379.186186) (xy 336.299983 -379.195371) (xy 336.306486 -379.212555) (xy 336.312256 -379.219714)
			(xy 336.334167 -379.245341) (xy 336.372257 -379.30098) (xy 336.403408 -379.360781) (xy 336.427172 -379.423883)
			(xy 336.443205 -379.489377) (xy 336.451278 -379.55632) (xy 336.451274 -379.623749) (xy 336.443193 -379.690691)
			(xy 336.427151 -379.756183) (xy 336.40338 -379.819282) (xy 336.372221 -379.879079) (xy 336.334124 -379.934713)
			(xy 336.312256 -379.960378) (xy 336.306438 -379.967508) (xy 336.299937 -379.98471) (xy 336.299556 -379.993906)
			(xy 336.299556 -380.151386) (xy 336.299062 -380.161512) (xy 336.291338 -380.180234) (xy 336.277054 -380.194591)
			(xy 336.258372 -380.20241) (xy 336.248248 -380.202948) (xy 335.531968 -380.202948) (xy 335.521818 -380.202506)
			(xy 335.503074 -380.194708) (xy 335.488753 -380.180319) (xy 335.481046 -380.161538) (xy 335.48066 -380.151386)
			(xy 335.48066 -379.993906) (xy 335.480234 -379.984721) (xy 335.47373 -379.967537) (xy 335.46796 -379.960378)
			(xy 335.446143 -379.934675) (xy 335.408055 -379.879045) (xy 335.376905 -379.819253) (xy 335.35314 -379.756162)
			(xy 335.337102 -379.690678) (xy 335.329023 -379.623744) (xy 335.329019 -379.556325) (xy 335.33709 -379.48939)
			(xy 335.353119 -379.423904) (xy 335.376876 -379.36081) (xy 335.40802 -379.301015) (xy 335.4461 -379.24538)
			(xy 335.46796 -379.219714) (xy 335.473783 -379.212588) (xy 335.48028 -379.195382) (xy 335.48066 -379.186186)
			(xy 335.48066 -378.693934) (xy 335.48022 -378.68475) (xy 335.473726 -378.667566) (xy 335.46796 -378.660406)
			(xy 335.446072 -378.634761) (xy 335.407987 -378.579123) (xy 335.376839 -378.519323) (xy 335.353078 -378.456224)
			(xy 335.337046 -378.390733) (xy 335.328973 -378.323793) (xy 332.050903 -378.323793) (xy 332.042868 -378.390553)
			(xy 332.026898 -378.455933) (xy 332.003229 -378.518937) (xy 331.972199 -378.578659) (xy 331.934254 -378.634246)
			(xy 331.912468 -378.659898) (xy 331.906686 -378.667053) (xy 331.900163 -378.684236) (xy 331.899768 -378.693426)
			(xy 331.899768 -379.186694) (xy 331.900188 -379.19588) (xy 331.906696 -379.213064) (xy 331.912468 -379.220222)
			(xy 331.934301 -379.245837) (xy 331.972248 -379.301429) (xy 332.003279 -379.361158) (xy 332.026949 -379.424167)
			(xy 332.042918 -379.489554) (xy 332.050958 -379.55638) (xy 332.050954 -379.623689) (xy 332.042906 -379.690514)
			(xy 332.026928 -379.755899) (xy 332.00325 -379.818906) (xy 331.972212 -379.878631) (xy 331.934258 -379.934218)
			(xy 331.912468 -379.95987) (xy 331.906655 -379.967003) (xy 331.900151 -379.984203) (xy 331.899768 -379.993398)
			(xy 331.899768 -380.151386) (xy 331.899325 -380.161556) (xy 331.891546 -380.180349) (xy 331.877166 -380.194734)
			(xy 331.858376 -380.202521) (xy 331.848206 -380.202948) (xy 331.131926 -380.202948) (xy 331.121754 -380.202514)
			(xy 331.102958 -380.194735) (xy 331.088571 -380.180352) (xy 331.080788 -380.161558) (xy 331.080364 -380.151386)
			(xy 331.080364 -379.993398) (xy 331.07994 -379.984213) (xy 331.073434 -379.967029) (xy 331.067664 -379.95987)
			(xy 331.045921 -379.934181) (xy 331.007969 -379.8786) (xy 330.976932 -379.818882) (xy 330.953256 -379.755882)
			(xy 330.937279 -379.690504) (xy 330.929231 -379.623686) (xy 330.929227 -379.556384) (xy 330.937267 -379.489564)
			(xy 330.953235 -379.424184) (xy 330.976904 -379.361181) (xy 331.007933 -379.301459) (xy 331.045878 -379.245874)
			(xy 331.067664 -379.220222) (xy 331.073484 -379.213094) (xy 331.079983 -379.19589) (xy 331.080364 -379.186694)
			(xy 331.080364 -378.693426) (xy 331.079927 -378.684242) (xy 331.07343 -378.667058) (xy 331.067664 -378.659898)
			(xy 331.04585 -378.634267) (xy 331.0079 -378.578678) (xy 330.976866 -378.518952) (xy 330.953194 -378.455945)
			(xy 330.937222 -378.39056) (xy 330.92918 -378.323734) (xy 301.250878 -378.323734) (xy 301.250878 -378.323791)
			(xy 301.242805 -378.390727) (xy 301.226773 -378.456215) (xy 301.203013 -378.51931) (xy 301.171866 -378.579106)
			(xy 301.133782 -378.63474) (xy 301.11192 -378.660406) (xy 301.106141 -378.667564) (xy 301.099615 -378.684745)
			(xy 301.09922 -378.693934) (xy 301.09922 -379.186186) (xy 301.099632 -379.195373) (xy 301.106144 -379.212558)
			(xy 301.11192 -379.219714) (xy 301.133828 -379.245342) (xy 301.171914 -379.300983) (xy 301.203062 -379.360784)
			(xy 301.226823 -379.423886) (xy 301.242854 -379.489379) (xy 301.250926 -379.556321) (xy 301.250922 -379.623748)
			(xy 301.242842 -379.690689) (xy 301.226802 -379.75618) (xy 301.203034 -379.819279) (xy 301.171879 -379.879077)
			(xy 301.133786 -379.934712) (xy 301.11192 -379.960378) (xy 301.10611 -379.967514) (xy 301.099603 -379.984711)
			(xy 301.09922 -379.993906) (xy 301.09922 -380.151386) (xy 301.098761 -380.161517) (xy 301.09103 -380.180245)
			(xy 301.076735 -380.194603) (xy 301.058041 -380.202416) (xy 301.047912 -380.202948) (xy 300.331632 -380.202948)
			(xy 300.321486 -380.202453) (xy 300.302743 -380.194677) (xy 300.28842 -380.180304) (xy 300.280711 -380.161534)
			(xy 300.280324 -380.151386) (xy 300.280324 -379.993906) (xy 300.279906 -379.98472) (xy 300.273397 -379.967536)
			(xy 300.267624 -379.960378) (xy 300.245804 -379.934676) (xy 300.207713 -379.879047) (xy 300.176559 -379.819256)
			(xy 300.152791 -379.756164) (xy 300.136751 -379.690679) (xy 300.128672 -379.623745) (xy 300.128667 -379.556324)
			(xy 300.136739 -379.489389) (xy 300.15277 -379.423902) (xy 300.17653 -379.360807) (xy 300.207677 -379.301012)
			(xy 300.245762 -379.245379) (xy 300.267624 -379.219714) (xy 300.273442 -379.212584) (xy 300.279943 -379.195382)
			(xy 300.280324 -379.186186) (xy 300.280324 -378.693934) (xy 300.279892 -378.684749) (xy 300.273393 -378.667565)
			(xy 300.267624 -378.660406) (xy 300.245734 -378.634762) (xy 300.207644 -378.579125) (xy 300.176493 -378.519326)
			(xy 300.152729 -378.456227) (xy 300.136695 -378.390735) (xy 300.128621 -378.323794) (xy 296.851087 -378.323794)
			(xy 296.843014 -378.390727) (xy 296.826983 -378.456214) (xy 296.803223 -378.51931) (xy 296.772077 -378.579105)
			(xy 296.733993 -378.63474) (xy 296.712132 -378.660406) (xy 296.706342 -378.667556) (xy 296.699825 -378.684743)
			(xy 296.699432 -378.693934) (xy 296.699432 -379.186186) (xy 296.699864 -379.195371) (xy 296.706364 -379.212554)
			(xy 296.712132 -379.219714) (xy 296.73404 -379.245342) (xy 296.772125 -379.300983) (xy 296.803272 -379.360785)
			(xy 296.827032 -379.423886) (xy 296.843064 -379.489379) (xy 296.851135 -379.556321) (xy 296.851131 -379.623748)
			(xy 296.843051 -379.690689) (xy 296.827012 -379.75618) (xy 296.803244 -379.819279) (xy 296.77209 -379.879076)
			(xy 296.733998 -379.934712) (xy 296.712132 -379.960378) (xy 296.706312 -379.967506) (xy 296.699813 -379.98471)
			(xy 296.699432 -379.993906) (xy 296.699432 -380.151386) (xy 296.698961 -380.161515) (xy 296.691233 -380.180241)
			(xy 296.676941 -380.194599) (xy 296.658251 -380.202414) (xy 296.648124 -380.202948) (xy 295.931844 -380.202948)
			(xy 295.921699 -380.202443) (xy 295.902957 -380.194671) (xy 295.888633 -380.1803) (xy 295.880924 -380.161533)
			(xy 295.880536 -380.151386) (xy 295.880536 -379.993906) (xy 295.880115 -379.98472) (xy 295.873608 -379.967536)
			(xy 295.867836 -379.960378) (xy 295.846016 -379.934676) (xy 295.807924 -379.879048) (xy 295.776769 -379.819257)
			(xy 295.753 -379.756165) (xy 295.736961 -379.69068) (xy 295.728881 -379.623745) (xy 295.728876 -379.556324)
			(xy 295.736948 -379.489388) (xy 295.75298 -379.423901) (xy 295.776741 -379.360806) (xy 295.807888 -379.301012)
			(xy 295.845974 -379.245379) (xy 295.867836 -379.219714) (xy 295.873656 -379.212586) (xy 295.880156 -379.195382)
			(xy 295.880536 -379.186186) (xy 295.880536 -378.693934) (xy 295.880101 -378.68475) (xy 295.873604 -378.667565)
			(xy 295.867836 -378.660406) (xy 295.845945 -378.634762) (xy 295.807855 -378.579126) (xy 295.776703 -378.519327)
			(xy 295.752939 -378.456227) (xy 295.736904 -378.390735) (xy 295.72883 -378.323794) (xy 292.450785 -378.323794)
			(xy 292.44275 -378.390553) (xy 292.426779 -378.455934) (xy 292.403109 -378.518938) (xy 292.372077 -378.57866)
			(xy 292.334131 -378.634246) (xy 292.312344 -378.659898) (xy 292.306559 -378.667051) (xy 292.300039 -378.684236)
			(xy 292.299644 -378.693426) (xy 292.299644 -379.186694) (xy 292.30007 -379.195879) (xy 292.306574 -379.213063)
			(xy 292.312344 -379.220222) (xy 292.334178 -379.245837) (xy 292.372126 -379.301428) (xy 292.403158 -379.361157)
			(xy 292.426829 -379.424166) (xy 292.4428 -379.489553) (xy 292.45084 -379.55638) (xy 292.450836 -379.623689)
			(xy 292.442787 -379.690515) (xy 292.426809 -379.7559) (xy 292.40313 -379.818907) (xy 292.372091 -379.878631)
			(xy 292.334135 -379.934218) (xy 292.312344 -379.95987) (xy 292.306528 -379.967001) (xy 292.300027 -379.984203)
			(xy 292.299644 -379.993398) (xy 292.299644 -380.151386) (xy 292.299224 -380.161559) (xy 292.291441 -380.180357)
			(xy 292.277054 -380.194743) (xy 292.258255 -380.202525) (xy 292.248082 -380.202948) (xy 291.531802 -380.202948)
			(xy 291.521629 -380.202534) (xy 291.502831 -380.194747) (xy 291.488446 -380.180358) (xy 291.480663 -380.161559)
			(xy 291.48024 -380.151386) (xy 291.48024 -379.993398) (xy 291.479822 -379.984212) (xy 291.473313 -379.967028)
			(xy 291.46754 -379.95987) (xy 291.445798 -379.934181) (xy 291.407847 -379.878599) (xy 291.376812 -379.818881)
			(xy 291.353137 -379.755881) (xy 291.337161 -379.690504) (xy 291.329113 -379.623685) (xy 291.329109 -379.556384)
			(xy 291.337148 -379.489564) (xy 291.353116 -379.424185) (xy 291.376784 -379.361182) (xy 291.407812 -379.30146)
			(xy 291.445755 -379.245874) (xy 291.46754 -379.220222) (xy 291.473357 -379.213092) (xy 291.479859 -379.19589)
			(xy 291.48024 -379.186694) (xy 291.48024 -378.693426) (xy 291.479809 -378.684241) (xy 291.473309 -378.667057)
			(xy 291.46754 -378.659898) (xy 291.445727 -378.634267) (xy 291.407778 -378.578678) (xy 291.376746 -378.518951)
			(xy 291.353075 -378.455944) (xy 291.337104 -378.390559) (xy 291.329062 -378.323734) (xy 288.051024 -378.323734)
			(xy 288.051024 -378.323792) (xy 288.04295 -378.390729) (xy 288.026915 -378.456218) (xy 288.003152 -378.519314)
			(xy 287.972001 -378.579109) (xy 287.933912 -378.634742) (xy 287.912048 -378.660406) (xy 287.90626 -378.667557)
			(xy 287.899742 -378.684743) (xy 287.899348 -378.693934) (xy 287.899348 -379.186186) (xy 287.899776 -379.195371)
			(xy 287.906279 -379.212555) (xy 287.912048 -379.219714) (xy 287.933959 -379.245341) (xy 287.97205 -379.30098)
			(xy 288.003201 -379.360781) (xy 288.026965 -379.423883) (xy 288.042999 -379.489377) (xy 288.051072 -379.55632)
			(xy 288.051068 -379.623749) (xy 288.042987 -379.690691) (xy 288.026945 -379.756183) (xy 288.003173 -379.819282)
			(xy 287.972014 -379.879079) (xy 287.933917 -379.934714) (xy 287.912048 -379.960378) (xy 287.906229 -379.967507)
			(xy 287.899729 -379.98471) (xy 287.899348 -379.993906) (xy 287.899348 -380.151386) (xy 287.898862 -380.161513)
			(xy 287.891136 -380.180236) (xy 287.87685 -380.194594) (xy 287.858165 -380.202411) (xy 287.84804 -380.202948)
			(xy 287.13176 -380.202948) (xy 287.121655 -380.202449) (xy 287.102985 -380.194707) (xy 287.088693 -380.180415)
			(xy 287.080951 -380.161745) (xy 287.080452 -380.15164) (xy 287.080452 -379.993906) (xy 287.080027 -379.984721)
			(xy 287.073523 -379.967537) (xy 287.067752 -379.960378) (xy 287.045931 -379.934676) (xy 287.007838 -379.879048)
			(xy 286.976682 -379.819258) (xy 286.952913 -379.756165) (xy 286.936873 -379.69068) (xy 286.928793 -379.623745)
			(xy 286.928788 -379.556324) (xy 286.936861 -379.489388) (xy 286.952893 -379.423901) (xy 286.976654 -379.360806)
			(xy 287.007802 -379.301011) (xy 287.045889 -379.245378) (xy 287.067752 -379.219714) (xy 287.073574 -379.212587)
			(xy 287.080072 -379.195382) (xy 287.080452 -379.186186) (xy 287.080452 -378.693934) (xy 287.080014 -378.68475)
			(xy 287.073519 -378.667566) (xy 287.067752 -378.660406) (xy 287.045861 -378.634763) (xy 287.007769 -378.579126)
			(xy 286.976617 -378.519328) (xy 286.952852 -378.456228) (xy 286.936817 -378.390735) (xy 286.928742 -378.323794)
			(xy 274.077801 -378.323794) (xy 274.085782 -378.367343) (xy 274.101882 -378.499931) (xy 274.109946 -378.633249)
			(xy 274.11045 -378.70003) (xy 274.109946 -378.766811) (xy 274.101882 -378.900129) (xy 274.085782 -379.032717)
			(xy 274.061707 -379.164091) (xy 274.029744 -379.293772) (xy 273.990009 -379.421286) (xy 273.942647 -379.546169)
			(xy 273.887832 -379.667964) (xy 273.825762 -379.786227) (xy 273.756666 -379.900526) (xy 273.680794 -380.010446)
			(xy 273.598424 -380.115583) (xy 273.509856 -380.215556) (xy 273.415414 -380.309998) (xy 273.315441 -380.398566)
			(xy 273.210304 -380.480936) (xy 273.100384 -380.556808) (xy 272.986085 -380.625904) (xy 272.92786 -380.656463)
			(xy 289.128932 -380.656463) (xy 289.136975 -380.589641) (xy 289.152947 -380.524259) (xy 289.17662 -380.461255)
			(xy 289.207654 -380.401532) (xy 289.245604 -380.345947) (xy 289.267392 -380.320296) (xy 289.273172 -380.313139)
			(xy 289.279697 -380.295958) (xy 289.280092 -380.286768) (xy 289.280092 -379.7935) (xy 289.279684 -379.784313)
			(xy 289.273169 -379.767128) (xy 289.267392 -379.759972) (xy 289.24565 -379.734282) (xy 289.207696 -379.678702)
			(xy 289.176658 -379.618984) (xy 289.15298 -379.555985) (xy 289.137002 -379.490606) (xy 289.128953 -379.423787)
			(xy 289.128949 -379.356485) (xy 289.136989 -379.289665) (xy 289.152959 -379.224284) (xy 289.176628 -379.161282)
			(xy 289.207659 -379.10156) (xy 289.245606 -379.045975) (xy 289.267392 -379.020324) (xy 289.273202 -379.013189)
			(xy 289.279709 -378.995991) (xy 289.280092 -378.986796) (xy 289.280092 -378.828554) (xy 289.280595 -378.818399)
			(xy 289.288376 -378.799638) (xy 289.302738 -378.785276) (xy 289.321499 -378.777495) (xy 289.331654 -378.776992)
			(xy 290.047934 -378.776992) (xy 290.058088 -378.777504) (xy 290.076849 -378.785281) (xy 290.091212 -378.799641)
			(xy 290.098993 -378.8184) (xy 290.099496 -378.828554) (xy 290.099496 -378.986796) (xy 290.099909 -378.995983)
			(xy 290.106421 -379.013167) (xy 290.112196 -379.020324) (xy 290.13403 -379.045938) (xy 290.171975 -379.101531)
			(xy 290.203004 -379.16126) (xy 290.226673 -379.224269) (xy 290.242641 -379.289656) (xy 290.250681 -379.356482)
			(xy 290.250677 -379.42379) (xy 290.242628 -379.490615) (xy 290.226651 -379.556) (xy 290.202975 -379.619006)
			(xy 290.171938 -379.678731) (xy 290.133986 -379.734319) (xy 290.112196 -379.759972) (xy 290.106386 -379.767108)
			(xy 290.099879 -379.784305) (xy 290.099496 -379.7935) (xy 290.099496 -380.286768) (xy 290.099922 -380.295953)
			(xy 290.106425 -380.313138) (xy 290.112196 -380.320296) (xy 290.134002 -380.345932) (xy 290.171948 -380.401522)
			(xy 290.202979 -380.461248) (xy 290.226649 -380.524255) (xy 290.242619 -380.589638) (xy 290.250654 -380.656404)
			(xy 293.528724 -380.656404) (xy 293.536798 -380.589467) (xy 293.552831 -380.52398) (xy 293.576592 -380.460884)
			(xy 293.60774 -380.401088) (xy 293.645826 -380.345453) (xy 293.667688 -380.319788) (xy 293.673471 -380.312633)
			(xy 293.679994 -380.29545) (xy 293.680388 -380.28626) (xy 293.680388 -379.794008) (xy 293.679977 -379.784821)
			(xy 293.673464 -379.767636) (xy 293.667688 -379.76048) (xy 293.645872 -379.734776) (xy 293.607782 -379.679146)
			(xy 293.57663 -379.619356) (xy 293.552864 -379.556264) (xy 293.536825 -379.49078) (xy 293.528746 -379.423846)
			(xy 293.528741 -379.356426) (xy 293.536812 -379.289491) (xy 293.552842 -379.224005) (xy 293.576601 -379.16091)
			(xy 293.607745 -379.101115) (xy 293.645827 -379.045481) (xy 293.667688 -379.019816) (xy 293.673501 -379.012683)
			(xy 293.680006 -378.995483) (xy 293.680388 -378.986288) (xy 293.680388 -378.828554) (xy 293.680887 -378.818431)
			(xy 293.688621 -378.799718) (xy 293.702902 -378.785366) (xy 293.721575 -378.777539) (xy 293.731696 -378.776992)
			(xy 294.447976 -378.776992) (xy 294.458096 -378.777435) (xy 294.476798 -378.785174) (xy 294.491112 -378.799482)
			(xy 294.49886 -378.81818) (xy 294.499284 -378.8283) (xy 294.499284 -378.986288) (xy 294.499704 -378.995474)
			(xy 294.506211 -379.012658) (xy 294.511984 -379.019816) (xy 294.533896 -379.045442) (xy 294.571984 -379.101082)
			(xy 294.603134 -379.160883) (xy 294.626896 -379.223985) (xy 294.642928 -379.289479) (xy 294.651001 -379.356422)
			(xy 294.650996 -379.42385) (xy 294.642915 -379.490792) (xy 294.626874 -379.556284) (xy 294.603104 -379.619383)
			(xy 294.571947 -379.67918) (xy 294.533851 -379.734815) (xy 294.511984 -379.76048) (xy 294.506169 -379.767612)
			(xy 294.499666 -379.784813) (xy 294.499284 -379.794008) (xy 294.499284 -380.28626) (xy 294.499717 -380.295445)
			(xy 294.506215 -380.312629) (xy 294.511984 -380.319788) (xy 294.533868 -380.345437) (xy 294.571957 -380.401073)
			(xy 294.603108 -380.460872) (xy 294.626872 -380.523971) (xy 294.642906 -380.589462) (xy 294.650981 -380.656402)
			(xy 294.650981 -380.656463) (xy 297.92902 -380.656463) (xy 297.937062 -380.589641) (xy 297.953034 -380.52426)
			(xy 297.976707 -380.461256) (xy 298.00774 -380.401533) (xy 298.045688 -380.345948) (xy 298.067476 -380.320296)
			(xy 298.073254 -380.313137) (xy 298.079781 -380.295957) (xy 298.080176 -380.286768) (xy 298.080176 -379.7935)
			(xy 298.079771 -379.784312) (xy 298.073254 -379.767128) (xy 298.067476 -379.759972) (xy 298.045734 -379.734282)
			(xy 298.007782 -379.678701) (xy 297.976744 -379.618984) (xy 297.953067 -379.555984) (xy 297.93709 -379.490606)
			(xy 297.929041 -379.423787) (xy 297.929037 -379.356485) (xy 297.937077 -379.289665) (xy 297.953046 -379.224285)
			(xy 297.976715 -379.161283) (xy 298.007745 -379.101561) (xy 298.04569 -379.045976) (xy 298.067476 -379.020324)
			(xy 298.073285 -379.013187) (xy 298.079793 -378.99599) (xy 298.080176 -378.986796) (xy 298.080176 -378.828554)
			(xy 298.080597 -378.818389) (xy 298.088393 -378.799611) (xy 298.102782 -378.785246) (xy 298.121572 -378.77748)
			(xy 298.131738 -378.776992) (xy 298.848018 -378.776992) (xy 298.858171 -378.777517) (xy 298.876932 -378.785289)
			(xy 298.891295 -378.799644) (xy 298.899077 -378.818401) (xy 298.89958 -378.828554) (xy 298.89958 -378.986796)
			(xy 298.899996 -378.995982) (xy 298.906506 -379.013167) (xy 298.91228 -379.020324) (xy 298.934114 -379.045938)
			(xy 298.972061 -379.10153) (xy 299.003091 -379.161259) (xy 299.02676 -379.224269) (xy 299.042729 -379.289655)
			(xy 299.050769 -379.356482) (xy 299.050765 -379.42379) (xy 299.042716 -379.490616) (xy 299.026739 -379.556)
			(xy 299.003061 -379.619007) (xy 298.972023 -379.678732) (xy 298.93407 -379.73432) (xy 298.91228 -379.759972)
			(xy 298.906468 -379.767106) (xy 298.899963 -379.784305) (xy 298.89958 -379.7935) (xy 298.89958 -380.286768)
			(xy 298.90001 -380.295953) (xy 298.90651 -380.313137) (xy 298.91228 -380.320296) (xy 298.934087 -380.345932)
			(xy 298.972034 -380.401521) (xy 299.003065 -380.461247) (xy 299.026736 -380.524254) (xy 299.042707 -380.589638)
			(xy 299.050742 -380.656404) (xy 302.328812 -380.656404) (xy 302.336886 -380.589468) (xy 302.352918 -380.52398)
			(xy 302.376679 -380.460884) (xy 302.407826 -380.401089) (xy 302.44591 -380.345454) (xy 302.467772 -380.319788)
			(xy 302.473565 -380.312641) (xy 302.48008 -380.295451) (xy 302.480472 -380.28626) (xy 302.480472 -379.794008)
			(xy 302.480064 -379.78482) (xy 302.47355 -379.767636) (xy 302.467772 -379.76048) (xy 302.445956 -379.734775)
			(xy 302.407868 -379.679146) (xy 302.376717 -379.619355) (xy 302.352951 -379.556263) (xy 302.336913 -379.490779)
			(xy 302.328834 -379.423846) (xy 302.328829 -379.356426) (xy 302.3369 -379.289492) (xy 302.35293 -379.224006)
			(xy 302.376687 -379.160911) (xy 302.407831 -379.101116) (xy 302.445912 -379.045482) (xy 302.467772 -379.019816)
			(xy 302.473595 -379.01269) (xy 302.480092 -378.995485) (xy 302.480472 -378.986288) (xy 302.480472 -378.828554)
			(xy 302.48089 -378.81842) (xy 302.488639 -378.799692) (xy 302.502946 -378.785336) (xy 302.521648 -378.777525)
			(xy 302.53178 -378.776992) (xy 303.24806 -378.776992) (xy 303.258211 -378.777454) (xy 303.27696 -378.785235)
			(xy 303.291285 -378.79962) (xy 303.298987 -378.818402) (xy 303.299368 -378.828554) (xy 303.299368 -378.986288)
			(xy 303.299791 -378.995474) (xy 303.306296 -379.012658) (xy 303.312068 -379.019816) (xy 303.33398 -379.045442)
			(xy 303.37207 -379.101081) (xy 303.40322 -379.160883) (xy 303.426983 -379.223985) (xy 303.443016 -379.289479)
			(xy 303.451089 -379.356422) (xy 303.451084 -379.42385) (xy 303.443003 -379.490792) (xy 303.426962 -379.556284)
			(xy 303.403191 -379.619383) (xy 303.372032 -379.679181) (xy 303.333936 -379.734815) (xy 303.312068 -379.76048)
			(xy 303.306251 -379.76761) (xy 303.299749 -379.784812) (xy 303.299368 -379.794008) (xy 303.299368 -380.28626)
			(xy 303.299805 -380.295444) (xy 303.306301 -380.312628) (xy 303.312068 -380.319788) (xy 303.333953 -380.345436)
			(xy 303.372043 -380.401073) (xy 303.403195 -380.460871) (xy 303.426959 -380.52397) (xy 303.442994 -380.589461)
			(xy 303.451069 -380.656402) (xy 303.451069 -380.656404) (xy 333.128842 -380.656404) (xy 333.136916 -380.589467)
			(xy 333.15295 -380.523979) (xy 333.176713 -380.460883) (xy 333.207862 -380.401087) (xy 333.245949 -380.345453)
			(xy 333.267812 -380.319788) (xy 333.273598 -380.312635) (xy 333.280118 -380.29545) (xy 333.280512 -380.28626)
			(xy 333.280512 -379.794008) (xy 333.280095 -379.784822) (xy 333.273586 -379.767637) (xy 333.267812 -379.76048)
			(xy 333.245995 -379.734776) (xy 333.207904 -379.679147) (xy 333.17675 -379.619357) (xy 333.152983 -379.556265)
			(xy 333.136944 -379.49078) (xy 333.128864 -379.423846) (xy 333.12886 -379.356426) (xy 333.136931 -379.289491)
			(xy 333.152962 -379.224004) (xy 333.176721 -379.160909) (xy 333.207867 -379.101115) (xy 333.24595 -379.045481)
			(xy 333.267812 -379.019816) (xy 333.273628 -379.012685) (xy 333.280131 -378.995483) (xy 333.280512 -378.986288)
			(xy 333.280512 -378.828554) (xy 333.280988 -378.818428) (xy 333.288726 -378.799711) (xy 333.303015 -378.785357)
			(xy 333.321696 -378.777535) (xy 333.33182 -378.776992) (xy 334.0481 -378.776992) (xy 334.058253 -378.777422)
			(xy 334.077004 -378.785216) (xy 334.091327 -378.79961) (xy 334.099028 -378.818399) (xy 334.099408 -378.828554)
			(xy 334.099408 -378.986288) (xy 334.099822 -378.995475) (xy 334.106333 -379.012659) (xy 334.112108 -379.019816)
			(xy 334.134019 -379.045442) (xy 334.172106 -379.101083) (xy 334.203254 -379.160884) (xy 334.227015 -379.223986)
			(xy 334.243047 -379.28948) (xy 334.251119 -379.356422) (xy 334.251114 -379.42385) (xy 334.243034 -379.490791)
			(xy 334.226994 -379.556283) (xy 334.203224 -379.619382) (xy 334.172068 -379.679179) (xy 334.133975 -379.734815)
			(xy 334.112108 -379.76048) (xy 334.106296 -379.767614) (xy 334.09979 -379.784813) (xy 334.099408 -379.794008)
			(xy 334.099408 -380.28626) (xy 334.099836 -380.295445) (xy 334.106337 -380.31263) (xy 334.112108 -380.319788)
			(xy 334.133991 -380.345437) (xy 334.172079 -380.401074) (xy 334.203228 -380.460873) (xy 334.226991 -380.523972)
			(xy 334.243025 -380.589463) (xy 334.251099 -380.656402) (xy 334.251099 -380.656464) (xy 337.529162 -380.656464)
			(xy 337.537203 -380.589643) (xy 337.553173 -380.524262) (xy 337.576842 -380.461259) (xy 337.607871 -380.401536)
			(xy 337.645815 -380.345949) (xy 337.6676 -380.320296) (xy 337.673381 -380.31314) (xy 337.679905 -380.295958)
			(xy 337.6803 -380.286768) (xy 337.6803 -379.7935) (xy 337.67989 -379.784313) (xy 337.673376 -379.767129)
			(xy 337.6676 -379.759972) (xy 337.645861 -379.734281) (xy 337.607913 -379.678699) (xy 337.57688 -379.61898)
			(xy 337.553206 -379.555981) (xy 337.537231 -379.490604) (xy 337.529183 -379.423786) (xy 337.529179 -379.356486)
			(xy 337.537218 -379.289667) (xy 337.553185 -379.224288) (xy 337.57685 -379.161286) (xy 337.607876 -379.101563)
			(xy 337.645816 -379.045977) (xy 337.6676 -379.020324) (xy 337.673411 -379.013189) (xy 337.679917 -378.995991)
			(xy 337.6803 -378.986796) (xy 337.6803 -378.828554) (xy 337.680795 -378.818398) (xy 337.688577 -378.799635)
			(xy 337.702942 -378.785273) (xy 337.721706 -378.777493) (xy 337.731862 -378.776992) (xy 338.448142 -378.776992)
			(xy 338.458297 -378.777498) (xy 338.477058 -378.785278) (xy 338.49142 -378.799639) (xy 338.499201 -378.818399)
			(xy 338.499704 -378.828554) (xy 338.499704 -378.986796) (xy 338.500115 -378.995983) (xy 338.506628 -379.013167)
			(xy 338.512404 -379.020324) (xy 338.534237 -379.045938) (xy 338.572182 -379.101531) (xy 338.603211 -379.16126)
			(xy 338.626879 -379.22427) (xy 338.642847 -379.289656) (xy 338.650887 -379.356482) (xy 338.650883 -379.42379)
			(xy 338.642834 -379.490615) (xy 338.626858 -379.556) (xy 338.603181 -379.619006) (xy 338.572145 -379.678731)
			(xy 338.534193 -379.734319) (xy 338.512404 -379.759972) (xy 338.506595 -379.767108) (xy 338.500088 -379.784306)
			(xy 338.499704 -379.7935) (xy 338.499704 -380.286768) (xy 338.500129 -380.295954) (xy 338.506632 -380.313138)
			(xy 338.512404 -380.320296) (xy 338.53421 -380.345933) (xy 338.572155 -380.401522) (xy 338.603185 -380.461248)
			(xy 338.626855 -380.524255) (xy 338.642826 -380.589639) (xy 338.65086 -380.656404) (xy 341.92893 -380.656404)
			(xy 341.937004 -380.589467) (xy 341.953037 -380.523979) (xy 341.976799 -380.460883) (xy 342.007947 -380.401088)
			(xy 342.046033 -380.345453) (xy 342.067896 -380.319788) (xy 342.07368 -380.312634) (xy 342.080202 -380.29545)
			(xy 342.080596 -380.28626) (xy 342.080596 -379.794008) (xy 342.080183 -379.784821) (xy 342.073671 -379.767637)
			(xy 342.067896 -379.76048) (xy 342.046079 -379.734776) (xy 342.007989 -379.679147) (xy 341.976837 -379.619356)
			(xy 341.95307 -379.556264) (xy 341.937032 -379.49078) (xy 341.928952 -379.423846) (xy 341.928948 -379.356426)
			(xy 341.937019 -379.289491) (xy 341.953049 -379.224005) (xy 341.976807 -379.16091) (xy 342.007952 -379.101115)
			(xy 342.046035 -379.045481) (xy 342.067896 -379.019816) (xy 342.07371 -379.012683) (xy 342.080215 -378.995483)
			(xy 342.080596 -378.986288) (xy 342.080596 -378.828554) (xy 342.081088 -378.81843) (xy 342.088822 -378.799716)
			(xy 342.103106 -378.785363) (xy 342.121782 -378.777538) (xy 342.131904 -378.776992) (xy 342.848184 -378.776992)
			(xy 342.858336 -378.777434) (xy 342.877087 -378.785223) (xy 342.89141 -378.799614) (xy 342.899112 -378.8184)
			(xy 342.899492 -378.828554) (xy 342.899492 -378.986288) (xy 342.89991 -378.995474) (xy 342.906418 -379.012659)
			(xy 342.912192 -379.019816) (xy 342.934103 -379.045442) (xy 342.972191 -379.101082) (xy 343.00334 -379.160884)
			(xy 343.027102 -379.223986) (xy 343.043135 -379.28948) (xy 343.051207 -379.356422) (xy 343.051202 -379.42385)
			(xy 343.043122 -379.490792) (xy 343.027081 -379.556283) (xy 343.003311 -379.619382) (xy 342.972154 -379.67918)
			(xy 342.934059 -379.734815) (xy 342.912192 -379.76048) (xy 342.906378 -379.767613) (xy 342.899874 -379.784813)
			(xy 342.899492 -379.794008) (xy 342.899492 -380.28626) (xy 342.899923 -380.295445) (xy 342.906422 -380.312629)
			(xy 342.912192 -380.319788) (xy 342.934076 -380.345437) (xy 342.972165 -380.401074) (xy 343.003315 -380.460872)
			(xy 343.027078 -380.523971) (xy 343.043113 -380.589462) (xy 343.051187 -380.656402) (xy 343.051187 -380.656463)
			(xy 346.329226 -380.656463) (xy 346.337269 -380.589641) (xy 346.353241 -380.524259) (xy 346.376913 -380.461255)
			(xy 346.407947 -380.401533) (xy 346.445896 -380.345948) (xy 346.467684 -380.320296) (xy 346.473463 -380.313138)
			(xy 346.479989 -380.295957) (xy 346.480384 -380.286768) (xy 346.480384 -379.7935) (xy 346.479977 -379.784312)
			(xy 346.473462 -379.767128) (xy 346.467684 -379.759972) (xy 346.445942 -379.734282) (xy 346.407989 -379.678702)
			(xy 346.376951 -379.618984) (xy 346.353274 -379.555984) (xy 346.337296 -379.490606) (xy 346.329247 -379.423787)
			(xy 346.329243 -379.356485) (xy 346.337283 -379.289665) (xy 346.353252 -379.224285) (xy 346.376922 -379.161282)
			(xy 346.407952 -379.10156) (xy 346.445898 -379.045976) (xy 346.467684 -379.020324) (xy 346.473493 -379.013188)
			(xy 346.480001 -378.99599) (xy 346.480384 -378.986796) (xy 346.480384 -378.828554) (xy 346.480797 -378.818388)
			(xy 346.488595 -378.799609) (xy 346.502986 -378.785243) (xy 346.521779 -378.777479) (xy 346.531946 -378.776992)
			(xy 347.248226 -378.776992) (xy 347.25838 -378.777511) (xy 347.277141 -378.785285) (xy 347.291504 -378.799642)
			(xy 347.299285 -378.8184) (xy 347.299788 -378.828554) (xy 347.299788 -378.986796) (xy 347.300203 -378.995983)
			(xy 347.306714 -379.013167) (xy 347.312488 -379.020324) (xy 347.334322 -379.045938) (xy 347.372268 -379.10153)
			(xy 347.403297 -379.161259) (xy 347.426966 -379.224269) (xy 347.442935 -379.289656) (xy 347.450975 -379.356482)
			(xy 347.450971 -379.42379) (xy 347.442922 -379.490616) (xy 347.426945 -379.556) (xy 347.403268 -379.619007)
			(xy 347.372231 -379.678732) (xy 347.334278 -379.734319) (xy 347.312488 -379.759972) (xy 347.306677 -379.767107)
			(xy 347.300171 -379.784305) (xy 347.299788 -379.7935) (xy 347.299788 -380.286768) (xy 347.300216 -380.295953)
			(xy 347.306718 -380.313138) (xy 347.312488 -380.320296) (xy 347.334295 -380.345932) (xy 347.372241 -380.401522)
			(xy 347.403272 -380.461248) (xy 347.426942 -380.524254) (xy 347.442913 -380.589638) (xy 347.450948 -380.656404)
			(xy 377.128751 -380.656404) (xy 377.136826 -380.589466) (xy 377.15286 -380.523978) (xy 377.176623 -380.460882)
			(xy 377.207772 -380.401087) (xy 377.24586 -380.345453) (xy 377.267724 -380.319788) (xy 377.273511 -380.312636)
			(xy 377.280031 -380.295451) (xy 377.280424 -380.28626) (xy 377.280424 -379.794008) (xy 377.280005 -379.784822)
			(xy 377.273497 -379.767638) (xy 377.267724 -379.76048) (xy 377.245906 -379.734776) (xy 377.207815 -379.679148)
			(xy 377.17666 -379.619357) (xy 377.152893 -379.556265) (xy 377.136853 -379.490781) (xy 377.128773 -379.423846)
			(xy 377.128769 -379.356426) (xy 377.13684 -379.28949) (xy 377.152871 -379.224004) (xy 377.176631 -379.160909)
			(xy 377.207777 -379.101114) (xy 377.245862 -379.045481) (xy 377.267724 -379.019816) (xy 377.273542 -379.012686)
			(xy 377.280043 -378.995484) (xy 377.280424 -378.986288) (xy 377.280424 -378.828554) (xy 377.280888 -378.818426)
			(xy 377.288628 -378.799707) (xy 377.302921 -378.785353) (xy 377.321607 -378.777533) (xy 377.331732 -378.776992)
			(xy 378.048012 -378.776992) (xy 378.058166 -378.777411) (xy 378.076917 -378.785209) (xy 378.09124 -378.799607)
			(xy 378.098941 -378.818398) (xy 378.09932 -378.828554) (xy 378.09932 -378.986288) (xy 378.099731 -378.995475)
			(xy 378.106244 -379.01266) (xy 378.11202 -379.019816) (xy 378.13393 -379.045443) (xy 378.172016 -379.101083)
			(xy 378.203164 -379.160885) (xy 378.226924 -379.223987) (xy 378.242956 -379.28948) (xy 378.251028 -379.356423)
			(xy 378.251023 -379.42385) (xy 378.242943 -379.490791) (xy 378.226903 -379.556282) (xy 378.203134 -379.619381)
			(xy 378.171979 -379.679179) (xy 378.133886 -379.734814) (xy 378.11202 -379.76048) (xy 378.106209 -379.767615)
			(xy 378.099702 -379.784813) (xy 378.09932 -379.794008) (xy 378.09932 -380.28626) (xy 378.099745 -380.295446)
			(xy 378.106248 -380.312631) (xy 378.11202 -380.319788) (xy 378.133903 -380.345437) (xy 378.17199 -380.401075)
			(xy 378.203138 -380.460873) (xy 378.226901 -380.523972) (xy 378.242934 -380.589463) (xy 378.251008 -380.656403)
			(xy 378.251008 -380.656464) (xy 381.529071 -380.656464) (xy 381.537113 -380.589643) (xy 381.553083 -380.524262)
			(xy 381.576752 -380.461258) (xy 381.607782 -380.401535) (xy 381.645726 -380.345948) (xy 381.667512 -380.320296)
			(xy 381.673294 -380.313141) (xy 381.679817 -380.295958) (xy 381.680212 -380.286768) (xy 381.680212 -379.7935)
			(xy 381.679799 -379.784313) (xy 381.673287 -379.767129) (xy 381.667512 -379.759972) (xy 381.645773 -379.73428)
			(xy 381.607824 -379.678699) (xy 381.57679 -379.618981) (xy 381.553116 -379.555981) (xy 381.537141 -379.490604)
			(xy 381.529093 -379.423786) (xy 381.529089 -379.356486) (xy 381.537128 -379.289667) (xy 381.553095 -379.224288)
			(xy 381.576761 -379.161285) (xy 381.607787 -379.101563) (xy 381.645728 -379.045977) (xy 381.667512 -379.020324)
			(xy 381.673325 -379.01319) (xy 381.679829 -378.995991) (xy 381.680212 -378.986796) (xy 381.680212 -378.828554)
			(xy 381.680695 -378.818397) (xy 381.68848 -378.799631) (xy 381.702848 -378.785269) (xy 381.721616 -378.777491)
			(xy 381.731774 -378.776992) (xy 382.448054 -378.776992) (xy 382.458203 -378.77757) (xy 382.476962 -378.785321)
			(xy 382.491328 -378.79966) (xy 382.499112 -378.818406) (xy 382.499616 -378.828554) (xy 382.499616 -378.986796)
			(xy 382.500025 -378.995983) (xy 382.506539 -379.013168) (xy 382.512316 -379.020324) (xy 382.534153 -379.045936)
			(xy 382.572103 -379.101528) (xy 382.603137 -379.161256) (xy 382.626809 -379.224266) (xy 382.64278 -379.289654)
			(xy 382.650821 -379.356481) (xy 382.650816 -379.423791) (xy 382.642767 -379.490618) (xy 382.626787 -379.556003)
			(xy 382.603107 -379.61901) (xy 382.572066 -379.678734) (xy 382.534108 -379.734321) (xy 382.512316 -379.759972)
			(xy 382.506508 -379.767109) (xy 382.5 -379.784306) (xy 382.499616 -379.7935) (xy 382.499616 -380.286768)
			(xy 382.500038 -380.295954) (xy 382.506543 -380.313139) (xy 382.512316 -380.320296) (xy 382.534125 -380.345931)
			(xy 382.572076 -380.401519) (xy 382.603111 -380.461245) (xy 382.626784 -380.524251) (xy 382.642757 -380.589636)
			(xy 382.650793 -380.656404) (xy 385.928839 -380.656404) (xy 385.936913 -380.589467) (xy 385.952947 -380.523979)
			(xy 385.976709 -380.460883) (xy 386.007858 -380.401087) (xy 386.045945 -380.345453) (xy 386.067808 -380.319788)
			(xy 386.073593 -380.312635) (xy 386.080114 -380.29545) (xy 386.080508 -380.28626) (xy 386.080508 -379.794008)
			(xy 386.080092 -379.784821) (xy 386.073582 -379.767637) (xy 386.067808 -379.76048) (xy 386.045991 -379.734776)
			(xy 386.0079 -379.679147) (xy 385.976747 -379.619356) (xy 385.95298 -379.556265) (xy 385.936941 -379.49078)
			(xy 385.928861 -379.423846) (xy 385.928857 -379.356426) (xy 385.936928 -379.289491) (xy 385.952958 -379.224004)
			(xy 385.976718 -379.160909) (xy 386.007863 -379.101115) (xy 386.045947 -379.045481) (xy 386.067808 -379.019816)
			(xy 386.073624 -379.012684) (xy 386.080127 -378.995483) (xy 386.080508 -378.986288) (xy 386.080508 -378.828554)
			(xy 386.080988 -378.818428) (xy 386.088725 -378.799712) (xy 386.103012 -378.785359) (xy 386.121693 -378.777535)
			(xy 386.131816 -378.776992) (xy 386.848096 -378.776992) (xy 386.858249 -378.777425) (xy 386.877 -378.785218)
			(xy 386.891323 -378.799611) (xy 386.899024 -378.818399) (xy 386.899404 -378.828554) (xy 386.899404 -378.986288)
			(xy 386.899819 -378.995475) (xy 386.906329 -379.012659) (xy 386.912104 -379.019816) (xy 386.934015 -379.045442)
			(xy 386.972102 -379.101083) (xy 387.00325 -379.160884) (xy 387.027012 -379.223986) (xy 387.043044 -379.28948)
			(xy 387.051116 -379.356422) (xy 387.051111 -379.42385) (xy 387.043031 -379.490791) (xy 387.02699 -379.556283)
			(xy 387.003221 -379.619382) (xy 386.972065 -379.679179) (xy 386.933971 -379.734815) (xy 386.912104 -379.76048)
			(xy 386.906291 -379.767614) (xy 386.899786 -379.784813) (xy 386.899404 -379.794008) (xy 386.899404 -380.28626)
			(xy 386.899832 -380.295445) (xy 386.906333 -380.31263) (xy 386.912104 -380.319788) (xy 386.933987 -380.345437)
			(xy 386.972075 -380.401074) (xy 387.003225 -380.460872) (xy 387.026988 -380.523971) (xy 387.043022 -380.589462)
			(xy 387.051096 -380.656402) (xy 387.051096 -380.656464) (xy 390.329159 -380.656464) (xy 390.3372 -380.589643)
			(xy 390.35317 -380.524263) (xy 390.376839 -380.461259) (xy 390.407867 -380.401536) (xy 390.445811 -380.345949)
			(xy 390.467596 -380.320296) (xy 390.473376 -380.313139) (xy 390.479901 -380.295958) (xy 390.480296 -380.286768)
			(xy 390.480296 -379.7935) (xy 390.479887 -379.784313) (xy 390.473372 -379.767128) (xy 390.467596 -379.759972)
			(xy 390.445857 -379.73428) (xy 390.407909 -379.678699) (xy 390.376876 -379.61898) (xy 390.353203 -379.555981)
			(xy 390.337228 -379.490604) (xy 390.32918 -379.423786) (xy 390.329176 -379.356486) (xy 390.337215 -379.289667)
			(xy 390.353181 -379.224288) (xy 390.376847 -379.161286) (xy 390.407872 -379.101563) (xy 390.445812 -379.045977)
			(xy 390.467596 -379.020324) (xy 390.473407 -379.013189) (xy 390.479913 -378.995991) (xy 390.480296 -378.986796)
			(xy 390.480296 -378.828554) (xy 390.480795 -378.818398) (xy 390.488576 -378.799636) (xy 390.50294 -378.785274)
			(xy 390.521702 -378.777494) (xy 390.531858 -378.776992) (xy 391.248138 -378.776992) (xy 391.258293 -378.777501)
			(xy 391.277054 -378.785279) (xy 391.291416 -378.79964) (xy 391.299197 -378.8184) (xy 391.2997 -378.828554)
			(xy 391.2997 -378.986796) (xy 391.300112 -378.995983) (xy 391.306625 -379.013167) (xy 391.3124 -379.020324)
			(xy 391.334234 -379.045938) (xy 391.372178 -379.101531) (xy 391.403207 -379.16126) (xy 391.426876 -379.224269)
			(xy 391.442844 -379.289656) (xy 391.450884 -379.356482) (xy 391.45088 -379.42379) (xy 391.442831 -379.490615)
			(xy 391.426855 -379.556) (xy 391.403178 -379.619006) (xy 391.372141 -379.678731) (xy 391.334189 -379.734319)
			(xy 391.3124 -379.759972) (xy 391.30659 -379.767108) (xy 391.300083 -379.784306) (xy 391.2997 -379.7935)
			(xy 391.2997 -380.286768) (xy 391.300126 -380.295954) (xy 391.306629 -380.313138) (xy 391.3124 -380.320296)
			(xy 391.334206 -380.345933) (xy 391.372152 -380.401522) (xy 391.403182 -380.461248) (xy 391.426852 -380.524255)
			(xy 391.442822 -380.589638) (xy 391.450857 -380.656404) (xy 421.12866 -380.656404) (xy 421.136735 -380.589466)
			(xy 421.152769 -380.523978) (xy 421.176533 -380.460881) (xy 421.207683 -380.401086) (xy 421.245772 -380.345453)
			(xy 421.267636 -380.319788) (xy 421.273425 -380.312637) (xy 421.279943 -380.295451) (xy 421.280336 -380.28626)
			(xy 421.280336 -379.794008) (xy 421.279914 -379.784822) (xy 421.273408 -379.767638) (xy 421.267636 -379.76048)
			(xy 421.245818 -379.734776) (xy 421.207725 -379.679148) (xy 421.176571 -379.619358) (xy 421.152802 -379.556266)
			(xy 421.136762 -379.490781) (xy 421.128682 -379.423846) (xy 421.128678 -379.356426) (xy 421.136749 -379.28949)
			(xy 421.152781 -379.224003) (xy 421.176541 -379.160908) (xy 421.207688 -379.101114) (xy 421.245774 -379.045481)
			(xy 421.267636 -379.019816) (xy 421.273455 -379.012687) (xy 421.279956 -378.995484) (xy 421.280336 -378.986288)
			(xy 421.280336 -378.828554) (xy 421.280789 -378.818425) (xy 421.288531 -378.799703) (xy 421.302827 -378.785349)
			(xy 421.321517 -378.777531) (xy 421.331644 -378.776992) (xy 422.047924 -378.776992) (xy 422.058033 -378.777465)
			(xy 422.076711 -378.785209) (xy 422.091004 -378.79951) (xy 422.09874 -378.81819) (xy 422.099232 -378.8283)
			(xy 422.099232 -378.986288) (xy 422.099663 -378.995473) (xy 422.106164 -379.012656) (xy 422.111932 -379.019816)
			(xy 422.133842 -379.045443) (xy 422.171927 -379.101084) (xy 422.203074 -379.160885) (xy 422.226834 -379.223987)
			(xy 422.242865 -379.289481) (xy 422.250937 -379.356423) (xy 422.250932 -379.423849) (xy 422.242852 -379.49079)
			(xy 422.226813 -379.556282) (xy 422.203045 -379.61938) (xy 422.17189 -379.679178) (xy 422.133798 -379.734814)
			(xy 422.111932 -379.76048) (xy 422.106111 -379.767607) (xy 422.099613 -379.784812) (xy 422.099232 -379.794008)
			(xy 422.099232 -380.28626) (xy 422.099677 -380.295443) (xy 422.106168 -380.312627) (xy 422.111932 -380.319788)
			(xy 422.133814 -380.345438) (xy 422.171901 -380.401075) (xy 422.203049 -380.460874) (xy 422.22681 -380.523973)
			(xy 422.242843 -380.589463) (xy 422.250917 -380.656403) (xy 422.250917 -380.656463) (xy 425.52898 -380.656463)
			(xy 425.537022 -380.589642) (xy 425.552992 -380.524262) (xy 425.576662 -380.461258) (xy 425.607692 -380.401535)
			(xy 425.645638 -380.345948) (xy 425.667424 -380.320296) (xy 425.673208 -380.313142) (xy 425.679729 -380.295958)
			(xy 425.680124 -380.286768) (xy 425.680124 -379.7935) (xy 425.679709 -379.784313) (xy 425.673198 -379.767129)
			(xy 425.667424 -379.759972) (xy 425.645684 -379.734281) (xy 425.607735 -379.678699) (xy 425.5767 -379.618981)
			(xy 425.553026 -379.555982) (xy 425.53705 -379.490605) (xy 425.529002 -379.423787) (xy 425.528998 -379.356486)
			(xy 425.537037 -379.289667) (xy 425.553004 -379.224287) (xy 425.576671 -379.161285) (xy 425.607698 -379.101563)
			(xy 425.64564 -379.045977) (xy 425.667424 -379.020324) (xy 425.673238 -379.013191) (xy 425.679742 -378.995991)
			(xy 425.680124 -378.986796) (xy 425.680124 -378.828554) (xy 425.680595 -378.818395) (xy 425.688382 -378.799628)
			(xy 425.702754 -378.785264) (xy 425.721527 -378.777489) (xy 425.731686 -378.776992) (xy 426.447966 -378.776992)
			(xy 426.458116 -378.77756) (xy 426.476875 -378.785315) (xy 426.49124 -378.799657) (xy 426.499024 -378.818405)
			(xy 426.499528 -378.828554) (xy 426.499528 -378.986796) (xy 426.499934 -378.995984) (xy 426.50645 -379.013168)
			(xy 426.512228 -379.020324) (xy 426.534064 -379.045937) (xy 426.572014 -379.101528) (xy 426.603047 -379.161257)
			(xy 426.626718 -379.224267) (xy 426.642689 -379.289654) (xy 426.65073 -379.356481) (xy 426.650725 -379.423791)
			(xy 426.642676 -379.490617) (xy 426.626697 -379.556003) (xy 426.603017 -379.619009) (xy 426.571977 -379.678734)
			(xy 426.53402 -379.73432) (xy 426.512228 -379.759972) (xy 426.50641 -379.767101) (xy 426.49991 -379.784304)
			(xy 426.499528 -379.7935) (xy 426.499528 -380.286768) (xy 426.499947 -380.295954) (xy 426.506454 -380.313139)
			(xy 426.512228 -380.320296) (xy 426.534036 -380.345932) (xy 426.571987 -380.40152) (xy 426.603021 -380.461245)
			(xy 426.626694 -380.524252) (xy 426.642667 -380.589636) (xy 426.650703 -380.656404) (xy 429.928748 -380.656404)
			(xy 429.936823 -380.589467) (xy 429.952857 -380.523978) (xy 429.976619 -380.460882) (xy 430.007769 -380.401087)
			(xy 430.045857 -380.345453) (xy 430.06772 -380.319788) (xy 430.073506 -380.312636) (xy 430.080027 -380.295451)
			(xy 430.08042 -380.28626) (xy 430.08042 -379.794008) (xy 430.080001 -379.784822) (xy 430.073493 -379.767638)
			(xy 430.06772 -379.76048) (xy 430.045902 -379.734776) (xy 430.007811 -379.679148) (xy 429.976657 -379.619357)
			(xy 429.952889 -379.556265) (xy 429.93685 -379.490781) (xy 429.92877 -379.423846) (xy 429.928766 -379.356426)
			(xy 429.936837 -379.289491) (xy 429.952868 -379.224004) (xy 429.976628 -379.160909) (xy 430.007774 -379.101114)
			(xy 430.045858 -379.045481) (xy 430.06772 -379.019816) (xy 430.073537 -379.012685) (xy 430.080039 -378.995484)
			(xy 430.08042 -378.986288) (xy 430.08042 -378.828554) (xy 430.080888 -378.818427) (xy 430.088628 -378.799708)
			(xy 430.102919 -378.785354) (xy 430.121603 -378.777533) (xy 430.131728 -378.776992) (xy 430.848008 -378.776992)
			(xy 430.858162 -378.777415) (xy 430.876913 -378.785212) (xy 430.891235 -378.799608) (xy 430.898936 -378.818398)
			(xy 430.899316 -378.828554) (xy 430.899316 -378.986288) (xy 430.899728 -378.995475) (xy 430.90624 -379.01266)
			(xy 430.912016 -379.019816) (xy 430.933927 -379.045443) (xy 430.972013 -379.101083) (xy 431.003161 -379.160885)
			(xy 431.026921 -379.223987) (xy 431.042953 -379.28948) (xy 431.051025 -379.356422) (xy 431.05102 -379.42385)
			(xy 431.04294 -379.490791) (xy 431.0269 -379.556282) (xy 431.003131 -379.619381) (xy 430.971976 -379.679179)
			(xy 430.933882 -379.734814) (xy 430.912016 -379.76048) (xy 430.906205 -379.767615) (xy 430.899698 -379.784813)
			(xy 430.899316 -379.794008) (xy 430.899316 -380.28626) (xy 430.899742 -380.295446) (xy 430.906244 -380.31263)
			(xy 430.912016 -380.319788) (xy 430.933899 -380.345437) (xy 430.971986 -380.401074) (xy 431.003135 -380.460873)
			(xy 431.026897 -380.523972) (xy 431.042931 -380.589463) (xy 431.051005 -380.656403) (xy 431.051005 -380.656464)
			(xy 434.329068 -380.656464) (xy 434.33711 -380.589643) (xy 434.35308 -380.524262) (xy 434.376749 -380.461259)
			(xy 434.407778 -380.401535) (xy 434.445722 -380.345949) (xy 434.467508 -380.320296) (xy 434.47329 -380.31314)
			(xy 434.479813 -380.295958) (xy 434.480208 -380.286768) (xy 434.480208 -379.7935) (xy 434.479796 -379.784313)
			(xy 434.473283 -379.767129) (xy 434.467508 -379.759972) (xy 434.445769 -379.73428) (xy 434.407821 -379.678699)
			(xy 434.376787 -379.61898) (xy 434.353113 -379.555981) (xy 434.337137 -379.490604) (xy 434.32909 -379.423786)
			(xy 434.329086 -379.356486) (xy 434.337125 -379.289667) (xy 434.353091 -379.224288) (xy 434.376757 -379.161286)
			(xy 434.407783 -379.101563) (xy 434.445724 -379.045977) (xy 434.467508 -379.020324) (xy 434.47332 -379.01319)
			(xy 434.479825 -378.995991) (xy 434.480208 -378.986796) (xy 434.480208 -378.828554) (xy 434.480695 -378.818397)
			(xy 434.488479 -378.799633) (xy 434.502846 -378.78527) (xy 434.521613 -378.777492) (xy 434.53177 -378.776992)
			(xy 435.24805 -378.776992) (xy 435.258213 -378.777504) (xy 435.276998 -378.785264) (xy 435.291383 -378.799622)
			(xy 435.299177 -378.818392) (xy 435.299612 -378.828554) (xy 435.299612 -378.986796) (xy 435.300021 -378.995983)
			(xy 435.306535 -379.013168) (xy 435.312312 -379.020324) (xy 435.334148 -379.045937) (xy 435.372099 -379.101528)
			(xy 435.403133 -379.161256) (xy 435.426805 -379.224266) (xy 435.442776 -379.289654) (xy 435.450817 -379.356481)
			(xy 435.450813 -379.423791) (xy 435.442763 -379.490618) (xy 435.426784 -379.556003) (xy 435.403103 -379.61901)
			(xy 435.372062 -379.678734) (xy 435.334104 -379.73432) (xy 435.312312 -379.759972) (xy 435.306504 -379.767109)
			(xy 435.299996 -379.784306) (xy 435.299612 -379.7935) (xy 435.299612 -380.286768) (xy 435.300035 -380.295954)
			(xy 435.306539 -380.313139) (xy 435.312312 -380.320296) (xy 435.334121 -380.345931) (xy 435.372072 -380.401519)
			(xy 435.403107 -380.461244) (xy 435.426781 -380.524251) (xy 435.442754 -380.589636) (xy 435.450797 -380.656461)
			(xy 435.450796 -380.723769) (xy 435.442749 -380.790594) (xy 435.426772 -380.855977) (xy 435.403095 -380.918983)
			(xy 435.372057 -380.978707) (xy 435.334102 -381.034292) (xy 435.312312 -381.059944) (xy 435.306516 -381.067089)
			(xy 435.3 -381.08428) (xy 435.299612 -381.093472) (xy 435.299612 -381.251206) (xy 435.29924 -381.261384)
			(xy 435.291444 -381.280189) (xy 435.277041 -381.294575) (xy 435.258229 -381.302351) (xy 435.24805 -381.302768)
			(xy 434.53177 -381.302768) (xy 434.521611 -381.302291) (xy 434.502842 -381.294508) (xy 434.488478 -381.280138)
			(xy 434.480704 -381.261365) (xy 434.480208 -381.251206) (xy 434.480208 -381.093472) (xy 434.47981 -381.084284)
			(xy 434.473288 -381.067099) (xy 434.467508 -381.059944) (xy 434.445741 -381.034275) (xy 434.407793 -380.97869)
			(xy 434.376761 -380.918969) (xy 434.353088 -380.855967) (xy 434.337115 -380.790587) (xy 434.32907 -380.723766)
			(xy 434.329068 -380.656464) (xy 431.051005 -380.656464) (xy 431.051003 -380.723827) (xy 431.042926 -380.790767)
			(xy 431.026889 -380.856257) (xy 431.003123 -380.919354) (xy 430.971971 -380.979151) (xy 430.933881 -381.034786)
			(xy 430.912016 -381.060452) (xy 430.906217 -381.067595) (xy 430.899703 -381.084787) (xy 430.899316 -381.09398)
			(xy 430.899316 -381.251206) (xy 430.898877 -381.261338) (xy 430.891139 -381.280068) (xy 430.876838 -381.294426)
			(xy 430.858138 -381.302237) (xy 430.848008 -381.302768) (xy 430.131728 -381.302768) (xy 430.121572 -381.302355)
			(xy 430.102814 -381.294563) (xy 430.088488 -381.280163) (xy 430.080793 -381.261364) (xy 430.08042 -381.251206)
			(xy 430.08042 -381.09398) (xy 430.080015 -381.084792) (xy 430.073497 -381.067608) (xy 430.06772 -381.060452)
			(xy 430.045875 -381.034771) (xy 430.007784 -380.979139) (xy 429.976632 -380.919345) (xy 429.952865 -380.85625)
			(xy 429.936828 -380.790763) (xy 429.92875 -380.723826) (xy 429.928748 -380.656404) (xy 426.650703 -380.656404)
			(xy 426.65071 -380.656461) (xy 426.650708 -380.723769) (xy 426.642661 -380.790593) (xy 426.626685 -380.855977)
			(xy 426.603009 -380.918982) (xy 426.571971 -380.978706) (xy 426.534018 -381.034292) (xy 426.512228 -381.059944)
			(xy 426.506422 -381.067082) (xy 426.499915 -381.084278) (xy 426.499528 -381.093472) (xy 426.499528 -381.251206)
			(xy 426.49914 -381.261382) (xy 426.491347 -381.280184) (xy 426.47695 -381.294569) (xy 426.458143 -381.302348)
			(xy 426.447966 -381.302768) (xy 425.731686 -381.302768) (xy 425.721528 -381.302278) (xy 425.70276 -381.2945)
			(xy 425.688395 -381.280133) (xy 425.68062 -381.261364) (xy 425.680124 -381.251206) (xy 425.680124 -381.093472)
			(xy 425.679722 -381.084284) (xy 425.673202 -381.0671) (xy 425.667424 -381.059944) (xy 425.645656 -381.034276)
			(xy 425.607708 -380.978691) (xy 425.576675 -380.91897) (xy 425.553001 -380.855967) (xy 425.537027 -380.790587)
			(xy 425.528982 -380.723767) (xy 425.52898 -380.656463) (xy 422.250917 -380.656463) (xy 422.250915 -380.723827)
			(xy 422.242838 -380.790766) (xy 422.226801 -380.856256) (xy 422.203036 -380.919354) (xy 422.171885 -380.979151)
			(xy 422.133796 -381.034786) (xy 422.111932 -381.060452) (xy 422.106123 -381.067588) (xy 422.099618 -381.084786)
			(xy 422.099232 -381.09398) (xy 422.099232 -381.251206) (xy 422.098777 -381.261337) (xy 422.091042 -381.280063)
			(xy 422.076746 -381.29442) (xy 422.058052 -381.302234) (xy 422.047924 -381.302768) (xy 421.331644 -381.302768)
			(xy 421.32152 -381.302347) (xy 421.302812 -381.294608) (xy 421.288495 -381.280292) (xy 421.280754 -381.261584)
			(xy 421.280336 -381.25146) (xy 421.280336 -381.09398) (xy 421.279927 -381.084793) (xy 421.273412 -381.067609)
			(xy 421.267636 -381.060452) (xy 421.24579 -381.034771) (xy 421.207699 -380.97914) (xy 421.176545 -380.919346)
			(xy 421.152778 -380.856251) (xy 421.13674 -380.790764) (xy 421.128662 -380.723826) (xy 421.12866 -380.656404)
			(xy 391.450857 -380.656404) (xy 391.450864 -380.656462) (xy 391.450863 -380.723768) (xy 391.442817 -380.790591)
			(xy 391.426843 -380.855974) (xy 391.40317 -380.918979) (xy 391.372136 -380.978704) (xy 391.334188 -381.034291)
			(xy 391.3124 -381.059944) (xy 391.306602 -381.067088) (xy 391.300088 -381.08428) (xy 391.2997 -381.093472)
			(xy 391.2997 -381.251206) (xy 391.299172 -381.261359) (xy 391.291403 -381.280121) (xy 391.277048 -381.294485)
			(xy 391.258291 -381.302266) (xy 391.248138 -381.302768) (xy 390.531858 -381.302768) (xy 390.521698 -381.302301)
			(xy 390.502929 -381.294514) (xy 390.488566 -381.28014) (xy 390.480792 -381.261366) (xy 390.480296 -381.251206)
			(xy 390.480296 -381.093472) (xy 390.4799 -381.084283) (xy 390.473377 -381.067099) (xy 390.467596 -381.059944)
			(xy 390.445829 -381.034275) (xy 390.407883 -380.97869) (xy 390.376851 -380.918968) (xy 390.353179 -380.855966)
			(xy 390.337206 -380.790586) (xy 390.329161 -380.723766) (xy 390.329159 -380.656464) (xy 387.051096 -380.656464)
			(xy 387.051094 -380.723828) (xy 387.043016 -380.790767) (xy 387.026979 -380.856257) (xy 387.003213 -380.919355)
			(xy 386.97206 -380.979152) (xy 386.933969 -381.034787) (xy 386.912104 -381.060452) (xy 386.906303 -381.067594)
			(xy 386.899791 -381.084787) (xy 386.899404 -381.09398) (xy 386.899404 -381.251206) (xy 386.89888 -381.261328)
			(xy 386.891158 -381.280041) (xy 386.876884 -381.294395) (xy 386.858215 -381.302222) (xy 386.848096 -381.302768)
			(xy 386.131816 -381.302768) (xy 386.121659 -381.302365) (xy 386.102901 -381.294568) (xy 386.088576 -381.280166)
			(xy 386.080881 -381.261365) (xy 386.080508 -381.251206) (xy 386.080508 -381.09398) (xy 386.080106 -381.084792)
			(xy 386.073587 -381.067608) (xy 386.067808 -381.060452) (xy 386.045963 -381.034771) (xy 386.007874 -380.979139)
			(xy 385.976722 -380.919345) (xy 385.952956 -380.85625) (xy 385.936919 -380.790763) (xy 385.928841 -380.723826)
			(xy 385.928839 -380.656404) (xy 382.650793 -380.656404) (xy 382.6508 -380.656461) (xy 382.650799 -380.723769)
			(xy 382.642752 -380.790593) (xy 382.626775 -380.855977) (xy 382.603098 -380.918983) (xy 382.57206 -380.978707)
			(xy 382.534106 -381.034292) (xy 382.512316 -381.059944) (xy 382.50652 -381.06709) (xy 382.500005 -381.08428)
			(xy 382.499616 -381.093472) (xy 382.499616 -381.251206) (xy 382.49924 -381.261384) (xy 382.491444 -381.280187)
			(xy 382.477044 -381.294574) (xy 382.458232 -381.30235) (xy 382.448054 -381.302768) (xy 381.731774 -381.302768)
			(xy 381.721615 -381.302288) (xy 381.702847 -381.294506) (xy 381.688482 -381.280137) (xy 381.680708 -381.261365)
			(xy 381.680212 -381.251206) (xy 381.680212 -381.093472) (xy 381.679813 -381.084284) (xy 381.673291 -381.0671)
			(xy 381.667512 -381.059944) (xy 381.645745 -381.034275) (xy 381.607797 -380.978691) (xy 381.576764 -380.918969)
			(xy 381.553092 -380.855967) (xy 381.537118 -380.790587) (xy 381.529073 -380.723767) (xy 381.529071 -380.656464)
			(xy 378.251008 -380.656464) (xy 378.251006 -380.723827) (xy 378.242929 -380.790767) (xy 378.226892 -380.856257)
			(xy 378.203126 -380.919354) (xy 378.171974 -380.979151) (xy 378.133884 -381.034786) (xy 378.11202 -381.060452)
			(xy 378.106221 -381.067596) (xy 378.099707 -381.084787) (xy 378.09932 -381.09398) (xy 378.09932 -381.251206)
			(xy 378.098877 -381.261338) (xy 378.09114 -381.280067) (xy 378.07684 -381.294424) (xy 378.058142 -381.302236)
			(xy 378.048012 -381.302768) (xy 377.331732 -381.302768) (xy 377.321576 -381.302352) (xy 377.302818 -381.294561)
			(xy 377.288492 -381.280162) (xy 377.280797 -381.261364) (xy 377.280424 -381.251206) (xy 377.280424 -381.09398)
			(xy 377.280018 -381.084792) (xy 377.273501 -381.067608) (xy 377.267724 -381.060452) (xy 377.245879 -381.034771)
			(xy 377.207788 -380.979139) (xy 377.176635 -380.919345) (xy 377.152869 -380.856251) (xy 377.136831 -380.790763)
			(xy 377.128753 -380.723826) (xy 377.128751 -380.656404) (xy 347.450948 -380.656404) (xy 347.450955 -380.656462)
			(xy 347.450954 -380.723768) (xy 347.442908 -380.790592) (xy 347.426934 -380.855975) (xy 347.40326 -380.91898)
			(xy 347.372226 -380.978704) (xy 347.334276 -381.034291) (xy 347.312488 -381.059944) (xy 347.306689 -381.067087)
			(xy 347.300176 -381.084279) (xy 347.299788 -381.093472) (xy 347.299788 -381.251206) (xy 347.299272 -381.261361)
			(xy 347.2915 -381.280125) (xy 347.277142 -381.294489) (xy 347.258381 -381.302268) (xy 347.248226 -381.302768)
			(xy 346.531946 -381.302768) (xy 346.521778 -381.302299) (xy 346.502986 -381.29453) (xy 346.488599 -381.280158)
			(xy 346.480812 -381.261373) (xy 346.480384 -381.251206) (xy 346.480384 -381.093472) (xy 346.479991 -381.084283)
			(xy 346.473466 -381.067099) (xy 346.467684 -381.059944) (xy 346.445915 -381.034276) (xy 346.407962 -380.978693)
			(xy 346.376926 -380.918972) (xy 346.35325 -380.85597) (xy 346.337274 -380.790589) (xy 346.329228 -380.723767)
			(xy 346.329226 -380.656463) (xy 343.051187 -380.656463) (xy 343.051185 -380.723828) (xy 343.043107 -380.790767)
			(xy 343.027069 -380.856258) (xy 343.003303 -380.919356) (xy 342.972149 -380.979152) (xy 342.934057 -381.034787)
			(xy 342.912192 -381.060452) (xy 342.90639 -381.067593) (xy 342.899879 -381.084787) (xy 342.899492 -381.09398)
			(xy 342.899492 -381.251206) (xy 342.898979 -381.261329) (xy 342.891255 -381.280044) (xy 342.876978 -381.294399)
			(xy 342.858304 -381.302224) (xy 342.848184 -381.302768) (xy 342.131904 -381.302768) (xy 342.121746 -381.302374)
			(xy 342.102988 -381.294574) (xy 342.088663 -381.280168) (xy 342.080969 -381.261366) (xy 342.080596 -381.251206)
			(xy 342.080596 -381.09398) (xy 342.080196 -381.084792) (xy 342.073675 -381.067608) (xy 342.067896 -381.060452)
			(xy 342.046052 -381.03477) (xy 342.007963 -380.979138) (xy 341.976811 -380.919344) (xy 341.953046 -380.856249)
			(xy 341.93701 -380.790762) (xy 341.928932 -380.723826) (xy 341.92893 -380.656404) (xy 338.65086 -380.656404)
			(xy 338.650867 -380.656462) (xy 338.650866 -380.723768) (xy 338.64282 -380.790591) (xy 338.626846 -380.855974)
			(xy 338.603173 -380.918979) (xy 338.57214 -380.978704) (xy 338.534192 -381.034291) (xy 338.512404 -381.059944)
			(xy 338.506607 -381.067089) (xy 338.500092 -381.08428) (xy 338.499704 -381.093472) (xy 338.499704 -381.251206)
			(xy 338.499172 -381.261359) (xy 338.491404 -381.28012) (xy 338.47705 -381.294484) (xy 338.458295 -381.302265)
			(xy 338.448142 -381.302768) (xy 337.731862 -381.302768) (xy 337.721703 -381.302298) (xy 337.702934 -381.294512)
			(xy 337.68857 -381.280139) (xy 337.680796 -381.261366) (xy 337.6803 -381.251206) (xy 337.6803 -381.093472)
			(xy 337.679904 -381.084283) (xy 337.67338 -381.067099) (xy 337.6676 -381.059944) (xy 337.645833 -381.034275)
			(xy 337.607886 -380.97869) (xy 337.576854 -380.918969) (xy 337.553182 -380.855966) (xy 337.537209 -380.790587)
			(xy 337.529164 -380.723766) (xy 337.529162 -380.656464) (xy 334.251099 -380.656464) (xy 334.251097 -380.723828)
			(xy 334.243019 -380.790767) (xy 334.226982 -380.856257) (xy 334.203216 -380.919355) (xy 334.172063 -380.979152)
			(xy 334.133973 -381.034787) (xy 334.112108 -381.060452) (xy 334.106308 -381.067595) (xy 334.099795 -381.084787)
			(xy 334.099408 -381.09398) (xy 334.099408 -381.251206) (xy 334.09888 -381.261327) (xy 334.091159 -381.280039)
			(xy 334.076886 -381.294394) (xy 334.058218 -381.302221) (xy 334.0481 -381.302768) (xy 333.33182 -381.302768)
			(xy 333.321663 -381.302362) (xy 333.302905 -381.294567) (xy 333.28858 -381.280165) (xy 333.280885 -381.261365)
			(xy 333.280512 -381.251206) (xy 333.280512 -381.09398) (xy 333.280109 -381.084792) (xy 333.27359 -381.067608)
			(xy 333.267812 -381.060452) (xy 333.245967 -381.034771) (xy 333.207877 -380.979139) (xy 333.176725 -380.919345)
			(xy 333.152959 -380.85625) (xy 333.136922 -380.790763) (xy 333.128844 -380.723826) (xy 333.128842 -380.656404)
			(xy 303.451069 -380.656404) (xy 303.451067 -380.723828) (xy 303.442989 -380.790768) (xy 303.42695 -380.856259)
			(xy 303.403182 -380.919357) (xy 303.372027 -380.979153) (xy 303.333934 -381.034787) (xy 303.312068 -381.060452)
			(xy 303.306263 -381.067591) (xy 303.299754 -381.084786) (xy 303.299368 -381.09398) (xy 303.299368 -381.251206)
			(xy 303.298878 -381.261332) (xy 303.29115 -381.280052) (xy 303.276865 -381.294408) (xy 303.258184 -381.302228)
			(xy 303.24806 -381.302768) (xy 302.53178 -381.302768) (xy 302.521621 -381.302394) (xy 302.502861 -381.294586)
			(xy 302.488538 -381.280174) (xy 302.480844 -381.261368) (xy 302.480472 -381.251206) (xy 302.480472 -381.09398)
			(xy 302.480078 -381.084791) (xy 302.473554 -381.067607) (xy 302.467772 -381.060452) (xy 302.445929 -381.03477)
			(xy 302.407841 -380.979137) (xy 302.376691 -380.919343) (xy 302.352927 -380.856248) (xy 302.336891 -380.790762)
			(xy 302.328814 -380.723826) (xy 302.328812 -380.656404) (xy 299.050742 -380.656404) (xy 299.050749 -380.656462)
			(xy 299.050747 -380.723768) (xy 299.042702 -380.790592) (xy 299.026727 -380.855975) (xy 299.003053 -380.91898)
			(xy 298.972018 -380.978704) (xy 298.934068 -381.034292) (xy 298.91228 -381.059944) (xy 298.90648 -381.067087)
			(xy 298.899968 -381.084279) (xy 298.89958 -381.093472) (xy 298.89958 -381.251206) (xy 298.899072 -381.261362)
			(xy 298.891299 -381.280128) (xy 298.876938 -381.294492) (xy 298.858174 -381.302269) (xy 298.848018 -381.302768)
			(xy 298.131738 -381.302768) (xy 298.12157 -381.302305) (xy 298.102777 -381.294534) (xy 298.088391 -381.28016)
			(xy 298.080604 -381.261374) (xy 298.080176 -381.251206) (xy 298.080176 -381.093472) (xy 298.079785 -381.084283)
			(xy 298.073258 -381.067098) (xy 298.067476 -381.059944) (xy 298.045707 -381.034276) (xy 298.007755 -380.978693)
			(xy 297.976719 -380.918972) (xy 297.953043 -380.855969) (xy 297.937068 -380.790589) (xy 297.929022 -380.723767)
			(xy 297.92902 -380.656463) (xy 294.650981 -380.656463) (xy 294.650979 -380.723828) (xy 294.642901 -380.790768)
			(xy 294.626863 -380.856258) (xy 294.603096 -380.919356) (xy 294.571942 -380.979153) (xy 294.53385 -381.034787)
			(xy 294.511984 -381.060452) (xy 294.506181 -381.067593) (xy 294.499671 -381.084787) (xy 294.499284 -381.09398)
			(xy 294.499284 -381.251206) (xy 294.498779 -381.26133) (xy 294.491054 -381.280047) (xy 294.476773 -381.294402)
			(xy 294.458097 -381.302225) (xy 294.447976 -381.302768) (xy 293.731696 -381.302768) (xy 293.721569 -381.302386)
			(xy 293.70286 -381.294631) (xy 293.688544 -381.280303) (xy 293.680805 -381.261587) (xy 293.680388 -381.25146)
			(xy 293.680388 -381.09398) (xy 293.67999 -381.084791) (xy 293.673468 -381.067607) (xy 293.667688 -381.060452)
			(xy 293.645844 -381.03477) (xy 293.607756 -380.979138) (xy 293.576605 -380.919344) (xy 293.55284 -380.856249)
			(xy 293.536803 -380.790762) (xy 293.528726 -380.723826) (xy 293.528724 -380.656404) (xy 290.250654 -380.656404)
			(xy 290.250661 -380.656462) (xy 290.25066 -380.723768) (xy 290.242614 -380.790591) (xy 290.22664 -380.855974)
			(xy 290.202966 -380.918979) (xy 290.171933 -380.978704) (xy 290.133984 -381.034291) (xy 290.112196 -381.059944)
			(xy 290.106398 -381.067088) (xy 290.099884 -381.084279) (xy 290.099496 -381.093472) (xy 290.099496 -381.251206)
			(xy 290.098972 -381.26136) (xy 290.091202 -381.280123) (xy 290.076846 -381.294486) (xy 290.058088 -381.302267)
			(xy 290.047934 -381.302768) (xy 289.331654 -381.302768) (xy 289.321494 -381.302304) (xy 289.302725 -381.294516)
			(xy 289.288362 -381.280141) (xy 289.280588 -381.261366) (xy 289.280092 -381.251206) (xy 289.280092 -381.093472)
			(xy 289.279697 -381.084283) (xy 289.273173 -381.067099) (xy 289.267392 -381.059944) (xy 289.245622 -381.034276)
			(xy 289.207669 -380.978693) (xy 289.176632 -380.918972) (xy 289.152956 -380.85597) (xy 289.13698 -380.790589)
			(xy 289.128934 -380.723767) (xy 289.128932 -380.656463) (xy 272.92786 -380.656463) (xy 272.867822 -380.687974)
			(xy 272.746027 -380.742789) (xy 272.621144 -380.790151) (xy 272.49363 -380.829886) (xy 272.363949 -380.861849)
			(xy 272.232575 -380.885924) (xy 272.099987 -380.902024) (xy 271.966669 -380.910088) (xy 271.833107 -380.910088)
			(xy 271.699789 -380.902024) (xy 271.567201 -380.885924) (xy 271.435827 -380.861849) (xy 271.306146 -380.829886)
			(xy 271.178632 -380.790151) (xy 271.053749 -380.742789) (xy 270.931954 -380.687974) (xy 270.813691 -380.625904)
			(xy 270.699392 -380.556808) (xy 270.589472 -380.480936) (xy 270.484335 -380.398566) (xy 270.384362 -380.309998)
			(xy 270.28992 -380.215556) (xy 270.201352 -380.115583) (xy 270.118982 -380.010446) (xy 270.04311 -379.900526)
			(xy 269.974014 -379.786227) (xy 269.911944 -379.667964) (xy 269.857129 -379.546169) (xy 269.809767 -379.421286)
			(xy 269.770032 -379.293772) (xy 269.738069 -379.164091) (xy 269.713994 -379.032717) (xy 269.697894 -378.900129)
			(xy 269.68983 -378.766811) (xy 236.356885 -378.766811) (xy 237.084108 -379.494034) (xy 237.084616 -379.494542)
			(xy 237.093852 -379.502751) (xy 237.116722 -379.512039) (xy 237.129066 -379.512576) (xy 239.773968 -379.512576)
			(xy 239.786313 -379.512049) (xy 239.809185 -379.502755) (xy 239.818418 -379.494542) (xy 239.818926 -379.494034)
			(xy 240.443004 -378.869702) (xy 240.450409 -378.862868) (xy 240.469004 -378.855145) (xy 240.479072 -378.854716)
			(xy 262.036814 -378.854716) (xy 262.046885 -378.85513) (xy 262.065482 -378.862858) (xy 262.072882 -378.869702)
			(xy 262.259318 -379.056138) (xy 262.26617 -379.063529) (xy 262.273882 -379.082135) (xy 262.274304 -379.092206)
			(xy 262.274304 -382.223705) (xy 286.928753 -382.223705) (xy 286.928754 -382.15628) (xy 286.936832 -382.08934)
			(xy 286.95287 -382.02385) (xy 286.976638 -381.960752) (xy 287.007792 -381.900956) (xy 287.045886 -381.845322)
			(xy 287.067752 -381.819658) (xy 287.073555 -381.812518) (xy 287.080065 -381.795323) (xy 287.080452 -381.78613)
			(xy 287.080452 -381.628904) (xy 287.080987 -381.618801) (xy 287.088715 -381.600133) (xy 287.102996 -381.585839)
			(xy 287.121658 -381.578096) (xy 287.13176 -381.577596) (xy 287.84804 -381.577596) (xy 287.858151 -381.578052)
			(xy 287.876829 -381.585802) (xy 287.891122 -381.600108) (xy 287.898856 -381.618793) (xy 287.899348 -381.628904)
			(xy 287.899348 -381.78613) (xy 287.899755 -381.795317) (xy 287.906272 -381.812501) (xy 287.912048 -381.819658)
			(xy 287.933904 -381.84533) (xy 287.971996 -381.900963) (xy 288.00315 -381.960757) (xy 288.026917 -382.023853)
			(xy 288.042955 -382.089342) (xy 288.051033 -382.156281) (xy 288.051034 -382.223645) (xy 291.329073 -382.223645)
			(xy 291.329074 -382.15634) (xy 291.337119 -382.089516) (xy 291.353093 -382.024133) (xy 291.376767 -381.961128)
			(xy 291.407801 -381.901405) (xy 291.445751 -381.845818) (xy 291.46754 -381.820166) (xy 291.473339 -381.813022)
			(xy 291.479851 -381.795831) (xy 291.48024 -381.786638) (xy 291.48024 -381.628904) (xy 291.48062 -381.618777)
			(xy 291.488375 -381.600066) (xy 291.502703 -381.58575) (xy 291.52142 -381.578012) (xy 291.531548 -381.577596)
			(xy 292.248082 -381.577596) (xy 292.258202 -381.57814) (xy 292.276915 -381.585854) (xy 292.29127 -381.600122)
			(xy 292.299098 -381.618787) (xy 292.299644 -381.628904) (xy 292.299644 -381.786638) (xy 292.300049 -381.795826)
			(xy 292.306568 -381.813009) (xy 292.312344 -381.820166) (xy 292.334122 -381.845826) (xy 292.372072 -381.901411)
			(xy 292.403107 -381.961133) (xy 292.426781 -382.024137) (xy 292.442755 -382.089518) (xy 292.450801 -382.15634)
			(xy 292.450801 -382.223645) (xy 292.450794 -382.223705) (xy 295.728841 -382.223705) (xy 295.728842 -382.15628)
			(xy 295.73692 -382.08934) (xy 295.752957 -382.02385) (xy 295.776724 -381.960753) (xy 295.807878 -381.900957)
			(xy 295.84597 -381.845323) (xy 295.867836 -381.819658) (xy 295.873637 -381.812516) (xy 295.880148 -381.795323)
			(xy 295.880536 -381.78613) (xy 295.880536 -381.628904) (xy 295.88092 -381.618777) (xy 295.888674 -381.600067)
			(xy 295.903001 -381.585751) (xy 295.921717 -381.578012) (xy 295.931844 -381.577596) (xy 296.648124 -381.577596)
			(xy 296.658234 -381.578065) (xy 296.676912 -381.58581) (xy 296.691206 -381.600112) (xy 296.69894 -381.618794)
			(xy 296.699432 -381.628904) (xy 296.699432 -381.78613) (xy 296.699843 -381.795317) (xy 296.706358 -381.8125)
			(xy 296.712132 -381.819658) (xy 296.733985 -381.845332) (xy 296.772072 -381.900966) (xy 296.803221 -381.960761)
			(xy 296.826985 -382.023857) (xy 296.84302 -382.089345) (xy 296.851096 -382.156281) (xy 296.851097 -382.223704)
			(xy 296.851097 -382.223705) (xy 300.128632 -382.223705) (xy 300.128633 -382.15628) (xy 300.13671 -382.089341)
			(xy 300.152748 -382.023851) (xy 300.176514 -381.960753) (xy 300.207667 -381.900957) (xy 300.245759 -381.845323)
			(xy 300.267624 -381.819658) (xy 300.273424 -381.812515) (xy 300.279936 -381.795323) (xy 300.280324 -381.78613)
			(xy 300.280324 -381.628904) (xy 300.28072 -381.618779) (xy 300.288471 -381.600071) (xy 300.302794 -381.585755)
			(xy 300.321507 -381.578014) (xy 300.331632 -381.577596) (xy 301.047912 -381.577596) (xy 301.058021 -381.578075)
			(xy 301.076699 -381.585816) (xy 301.090993 -381.600115) (xy 301.098728 -381.618795) (xy 301.09922 -381.628904)
			(xy 301.09922 -381.78613) (xy 301.099611 -381.795319) (xy 301.106138 -381.812504) (xy 301.11192 -381.819658)
			(xy 301.133773 -381.845332) (xy 301.171861 -381.900965) (xy 301.203011 -381.960761) (xy 301.226775 -382.023856)
			(xy 301.242811 -382.089344) (xy 301.250887 -382.156281) (xy 301.250888 -382.223646) (xy 330.929191 -382.223646)
			(xy 330.929192 -382.156339) (xy 330.937238 -382.089516) (xy 330.953213 -382.024133) (xy 330.976888 -381.961128)
			(xy 331.007923 -381.901404) (xy 331.045875 -381.845818) (xy 331.067664 -381.820166) (xy 331.073465 -381.813025)
			(xy 331.079975 -381.795831) (xy 331.080364 -381.786638) (xy 331.080364 -381.628904) (xy 331.080824 -381.618755)
			(xy 331.088612 -381.600009) (xy 331.102996 -381.585687) (xy 331.121775 -381.577981) (xy 331.131926 -381.577596)
			(xy 331.848206 -381.577596) (xy 331.858328 -381.57812) (xy 331.877041 -381.585842) (xy 331.891395 -381.600116)
			(xy 331.899222 -381.618785) (xy 331.899768 -381.628904) (xy 331.899768 -381.786638) (xy 331.900167 -381.795826)
			(xy 331.906689 -381.81301) (xy 331.912468 -381.820166) (xy 331.934246 -381.845826) (xy 331.972195 -381.901412)
			(xy 332.003228 -381.961134) (xy 332.026901 -382.024138) (xy 332.042874 -382.089519) (xy 332.050919 -382.15634)
			(xy 332.05092 -382.223645) (xy 332.050913 -382.223704) (xy 335.328984 -382.223704) (xy 335.328985 -382.156281)
			(xy 335.337061 -382.089342) (xy 335.353096 -382.023853) (xy 335.37686 -381.960756) (xy 335.40801 -381.900959)
			(xy 335.446097 -381.845324) (xy 335.46796 -381.819658) (xy 335.473764 -381.812519) (xy 335.480273 -381.795323)
			(xy 335.48066 -381.78613) (xy 335.48066 -381.628904) (xy 335.481187 -381.6188) (xy 335.488916 -381.60013)
			(xy 335.5032 -381.585837) (xy 335.521865 -381.578095) (xy 335.531968 -381.577596) (xy 336.248248 -381.577596)
			(xy 336.258359 -381.578046) (xy 336.277038 -381.585799) (xy 336.291331 -381.600106) (xy 336.299064 -381.618792)
			(xy 336.299556 -381.628904) (xy 336.299556 -381.78613) (xy 336.299962 -381.795317) (xy 336.30648 -381.812501)
			(xy 336.312256 -381.819658) (xy 336.334112 -381.845331) (xy 336.372204 -381.900963) (xy 336.403357 -381.960758)
			(xy 336.427124 -382.023854) (xy 336.443161 -382.089342) (xy 336.451239 -382.156281) (xy 336.45124 -382.223645)
			(xy 339.729279 -382.223645) (xy 339.72928 -382.156339) (xy 339.737325 -382.089516) (xy 339.753299 -382.024133)
			(xy 339.776974 -381.961128) (xy 339.808009 -381.901404) (xy 339.845959 -381.845818) (xy 339.867748 -381.820166)
			(xy 339.873547 -381.813023) (xy 339.880059 -381.795831) (xy 339.880448 -381.786638) (xy 339.880448 -381.628904)
			(xy 339.880924 -381.618757) (xy 339.888708 -381.600014) (xy 339.903088 -381.585693) (xy 339.921861 -381.577984)
			(xy 339.93201 -381.577596) (xy 340.64829 -381.577596) (xy 340.658411 -381.578133) (xy 340.677123 -381.58585)
			(xy 340.691478 -381.60012) (xy 340.699306 -381.618786) (xy 340.699852 -381.628904) (xy 340.699852 -381.786638)
			(xy 340.700255 -381.795826) (xy 340.706775 -381.813009) (xy 340.712552 -381.820166) (xy 340.73433 -381.845826)
			(xy 340.77228 -381.901411) (xy 340.803314 -381.961134) (xy 340.826988 -382.024137) (xy 340.842962 -382.089518)
			(xy 340.851007 -382.15634) (xy 340.851007 -382.223645) (xy 344.12907 -382.223645) (xy 344.129071 -382.15634)
			(xy 344.137116 -382.089516) (xy 344.15309 -382.024134) (xy 344.176764 -381.961129) (xy 344.207798 -381.901405)
			(xy 344.245748 -381.845818) (xy 344.267536 -381.820166) (xy 344.273334 -381.813022) (xy 344.279847 -381.79583)
			(xy 344.280236 -381.786638) (xy 344.280236 -381.628904) (xy 344.280626 -381.618746) (xy 344.288427 -381.599986)
			(xy 344.302834 -381.585662) (xy 344.321637 -381.577968) (xy 344.331798 -381.577596) (xy 345.048078 -381.577596)
			(xy 345.058198 -381.578143) (xy 345.07691 -381.585856) (xy 345.091266 -381.600123) (xy 345.099094 -381.618787)
			(xy 345.09964 -381.628904) (xy 345.09964 -381.786638) (xy 345.100045 -381.795825) (xy 345.106564 -381.813009)
			(xy 345.11234 -381.820166) (xy 345.134118 -381.845826) (xy 345.172069 -381.901411) (xy 345.203104 -381.961133)
			(xy 345.226778 -382.024137) (xy 345.242752 -382.089518) (xy 345.250798 -382.15634) (xy 345.250798 -382.223645)
			(xy 345.250798 -382.223646) (xy 374.9291 -382.223646) (xy 374.929101 -382.156339) (xy 374.937147 -382.089515)
			(xy 374.953122 -382.024132) (xy 374.976798 -381.961127) (xy 375.007834 -381.901404) (xy 375.045787 -381.845818)
			(xy 375.067576 -381.820166) (xy 375.073367 -381.813016) (xy 375.079886 -381.795829) (xy 375.080276 -381.786638)
			(xy 375.080276 -381.628904) (xy 375.080724 -381.618753) (xy 375.088514 -381.600005) (xy 375.102902 -381.585683)
			(xy 375.121685 -381.577979) (xy 375.131838 -381.577596) (xy 375.848118 -381.577596) (xy 375.85824 -381.57811)
			(xy 375.876954 -381.585836) (xy 375.891308 -381.600113) (xy 375.899134 -381.618784) (xy 375.89968 -381.628904)
			(xy 375.89968 -381.786638) (xy 375.900076 -381.795827) (xy 375.9066 -381.813011) (xy 375.91238 -381.820166)
			(xy 375.934157 -381.845826) (xy 375.972105 -381.901412) (xy 376.003138 -381.961135) (xy 376.02681 -382.024138)
			(xy 376.042784 -382.089519) (xy 376.050828 -382.156341) (xy 376.050829 -382.223644) (xy 376.050822 -382.223704)
			(xy 379.328893 -382.223704) (xy 379.328894 -382.156281) (xy 379.33697 -382.089342) (xy 379.353006 -382.023853)
			(xy 379.37677 -381.960756) (xy 379.40792 -381.900959) (xy 379.446008 -381.845324) (xy 379.467872 -381.819658)
			(xy 379.473678 -381.81252) (xy 379.480185 -381.795324) (xy 379.480572 -381.78613) (xy 379.480572 -381.628904)
			(xy 379.481088 -381.618799) (xy 379.488819 -381.600126) (xy 379.503106 -381.585832) (xy 379.521775 -381.578092)
			(xy 379.53188 -381.577596) (xy 380.24816 -381.577596) (xy 380.258279 -381.578049) (xy 380.276981 -381.585783)
			(xy 380.291297 -381.600088) (xy 380.299044 -381.618785) (xy 380.299468 -381.628904) (xy 380.299468 -381.78613)
			(xy 380.299871 -381.795318) (xy 380.30639 -381.812502) (xy 380.312168 -381.819658) (xy 380.334023 -381.845331)
			(xy 380.372114 -381.900963) (xy 380.403267 -381.960758) (xy 380.427033 -382.023854) (xy 380.443071 -382.089343)
			(xy 380.451148 -382.156281) (xy 380.451149 -382.223646) (xy 383.729188 -382.223646) (xy 383.729189 -382.156339)
			(xy 383.737235 -382.089516) (xy 383.753209 -382.024133) (xy 383.776884 -381.961128) (xy 383.80792 -381.901404)
			(xy 383.845871 -381.845818) (xy 383.86766 -381.820166) (xy 383.873461 -381.813024) (xy 383.879971 -381.795831)
			(xy 383.88036 -381.786638) (xy 383.88036 -381.628904) (xy 383.880824 -381.618755) (xy 383.888611 -381.600011)
			(xy 383.902994 -381.585689) (xy 383.921771 -381.577981) (xy 383.931922 -381.577596) (xy 384.648202 -381.577596)
			(xy 384.658323 -381.578124) (xy 384.677036 -381.585844) (xy 384.691391 -381.600117) (xy 384.699218 -381.618786)
			(xy 384.699764 -381.628904) (xy 384.699764 -381.786638) (xy 384.700164 -381.795826) (xy 384.706686 -381.81301)
			(xy 384.712464 -381.820166) (xy 384.734242 -381.845826) (xy 384.772191 -381.901412) (xy 384.803224 -381.961134)
			(xy 384.826898 -382.024137) (xy 384.842871 -382.089519) (xy 384.850916 -382.15634) (xy 384.850917 -382.223645)
			(xy 388.128979 -382.223645) (xy 388.12898 -382.156339) (xy 388.137025 -382.089516) (xy 388.152999 -382.024133)
			(xy 388.176674 -381.961128) (xy 388.207709 -381.901404) (xy 388.245659 -381.845818) (xy 388.267448 -381.820166)
			(xy 388.273247 -381.813023) (xy 388.279759 -381.795831) (xy 388.280148 -381.786638) (xy 388.280148 -381.628904)
			(xy 388.280624 -381.618757) (xy 388.288408 -381.600014) (xy 388.302788 -381.585693) (xy 388.321561 -381.577984)
			(xy 388.33171 -381.577596) (xy 389.04799 -381.577596) (xy 389.058111 -381.578133) (xy 389.076823 -381.58585)
			(xy 389.091178 -381.60012) (xy 389.099006 -381.618786) (xy 389.099552 -381.628904) (xy 389.099552 -381.786638)
			(xy 389.099955 -381.795826) (xy 389.106475 -381.813009) (xy 389.112252 -381.820166) (xy 389.13403 -381.845826)
			(xy 389.17198 -381.901411) (xy 389.203014 -381.961134) (xy 389.226688 -382.024137) (xy 389.242662 -382.089518)
			(xy 389.250707 -382.15634) (xy 389.250707 -382.223645) (xy 389.250707 -382.223646) (xy 418.92901 -382.223646)
			(xy 418.92901 -382.156339) (xy 418.937056 -382.089515) (xy 418.953032 -382.024132) (xy 418.976708 -381.961127)
			(xy 419.007745 -381.901403) (xy 419.045698 -381.845818) (xy 419.067488 -381.820166) (xy 419.07328 -381.813018)
			(xy 419.079798 -381.79583) (xy 419.080188 -381.786638) (xy 419.080188 -381.628904) (xy 419.080688 -381.618797)
			(xy 419.088422 -381.600121) (xy 419.102714 -381.585827) (xy 419.121389 -381.57809) (xy 419.131496 -381.577596)
			(xy 419.84803 -381.577596) (xy 419.858153 -381.578101) (xy 419.876867 -381.58583) (xy 419.89122 -381.60011)
			(xy 419.899046 -381.618783) (xy 419.899592 -381.628904) (xy 419.899592 -381.786638) (xy 419.899986 -381.795827)
			(xy 419.906511 -381.813011) (xy 419.912292 -381.820166) (xy 419.934069 -381.845827) (xy 419.972016 -381.901413)
			(xy 420.003048 -381.961135) (xy 420.02672 -382.024139) (xy 420.042693 -382.089519) (xy 420.050737 -382.156341)
			(xy 420.050738 -382.223644) (xy 420.050731 -382.223705) (xy 423.328802 -382.223705) (xy 423.328803 -382.15628)
			(xy 423.33688 -382.089342) (xy 423.352916 -382.023852) (xy 423.37668 -381.960755) (xy 423.407831 -381.900959)
			(xy 423.44592 -381.845324) (xy 423.467784 -381.819658) (xy 423.473579 -381.812512) (xy 423.480095 -381.795322)
			(xy 423.480484 -381.78613) (xy 423.480484 -381.628904) (xy 423.480988 -381.618798) (xy 423.488721 -381.600122)
			(xy 423.503012 -381.585828) (xy 423.521686 -381.57809) (xy 423.531792 -381.577596) (xy 424.248072 -381.577596)
			(xy 424.258192 -381.578039) (xy 424.276895 -381.585777) (xy 424.29121 -381.600085) (xy 424.298957 -381.618784)
			(xy 424.29938 -381.628904) (xy 424.29938 -381.78613) (xy 424.29978 -381.795318) (xy 424.306301 -381.812502)
			(xy 424.31208 -381.819658) (xy 424.333935 -381.845331) (xy 424.372025 -381.900964) (xy 424.403177 -381.960759)
			(xy 424.426943 -382.023855) (xy 424.44298 -382.089343) (xy 424.451057 -382.156281) (xy 424.451058 -382.223646)
			(xy 427.729097 -382.223646) (xy 427.729098 -382.156339) (xy 427.737144 -382.089515) (xy 427.753119 -382.024132)
			(xy 427.776794 -381.961127) (xy 427.807831 -381.901404) (xy 427.845783 -381.845818) (xy 427.867572 -381.820166)
			(xy 427.873374 -381.813025) (xy 427.879883 -381.795831) (xy 427.880272 -381.786638) (xy 427.880272 -381.628904)
			(xy 427.880724 -381.618754) (xy 427.888513 -381.600007) (xy 427.9029 -381.585684) (xy 427.921682 -381.577979)
			(xy 427.931834 -381.577596) (xy 428.648114 -381.577596) (xy 428.658236 -381.578114) (xy 428.676949 -381.585838)
			(xy 428.691303 -381.600114) (xy 428.69913 -381.618785) (xy 428.699676 -381.628904) (xy 428.699676 -381.786638)
			(xy 428.700073 -381.795826) (xy 428.706596 -381.81301) (xy 428.712376 -381.820166) (xy 428.734154 -381.845826)
			(xy 428.772102 -381.901412) (xy 428.803135 -381.961135) (xy 428.826807 -382.024138) (xy 428.84278 -382.089519)
			(xy 428.850825 -382.15634) (xy 428.850826 -382.223644) (xy 428.850826 -382.223646) (xy 432.128888 -382.223646)
			(xy 432.128889 -382.156339) (xy 432.136935 -382.089516) (xy 432.152909 -382.024133) (xy 432.176584 -381.961128)
			(xy 432.20762 -381.901404) (xy 432.245571 -381.845818) (xy 432.26736 -381.820166) (xy 432.273161 -381.813024)
			(xy 432.279671 -381.795831) (xy 432.28006 -381.786638) (xy 432.28006 -381.628904) (xy 432.280524 -381.618755)
			(xy 432.288311 -381.600011) (xy 432.302694 -381.585689) (xy 432.321471 -381.577981) (xy 432.331622 -381.577596)
			(xy 433.047902 -381.577596) (xy 433.058023 -381.578124) (xy 433.076736 -381.585844) (xy 433.091091 -381.600117)
			(xy 433.098918 -381.618786) (xy 433.099464 -381.628904) (xy 433.099464 -381.786638) (xy 433.099864 -381.795826)
			(xy 433.106386 -381.81301) (xy 433.112164 -381.820166) (xy 433.133942 -381.845826) (xy 433.171891 -381.901412)
			(xy 433.202924 -381.961134) (xy 433.226598 -382.024137) (xy 433.242571 -382.089519) (xy 433.250616 -382.15634)
			(xy 433.250617 -382.223645) (xy 433.242574 -382.290466) (xy 433.226602 -382.355848) (xy 433.202931 -382.418852)
			(xy 433.171899 -382.478576) (xy 433.133951 -382.534162) (xy 433.112164 -382.559814) (xy 433.106374 -382.566964)
			(xy 433.099856 -382.584151) (xy 433.099464 -382.593342) (xy 433.099464 -383.086864) (xy 433.0999 -383.096048)
			(xy 433.106397 -383.113232) (xy 433.112164 -383.120392) (xy 433.133967 -383.146031) (xy 433.171916 -383.20162)
			(xy 433.202948 -383.261345) (xy 433.226386 -383.323727) (xy 434.32903 -383.323727) (xy 434.329034 -383.256419)
			(xy 434.337081 -383.189595) (xy 434.353057 -383.124211) (xy 434.376732 -383.061205) (xy 434.407768 -383.00148)
			(xy 434.445719 -382.945893) (xy 434.467508 -382.92024) (xy 434.473313 -382.913101) (xy 434.479823 -382.895906)
			(xy 434.480208 -382.886712) (xy 434.480208 -382.728724) (xy 434.480641 -382.71857) (xy 434.48843 -382.699817)
			(xy 434.502824 -382.685492) (xy 434.521614 -382.677793) (xy 434.53177 -382.677416) (xy 435.24805 -382.677416)
			(xy 435.258171 -382.677967) (xy 435.276886 -382.685674) (xy 435.291243 -382.69994) (xy 435.299068 -382.718607)
			(xy 435.299612 -382.728724) (xy 435.299612 -382.886712) (xy 435.300014 -382.8959) (xy 435.306533 -382.913084)
			(xy 435.312312 -382.92024) (xy 435.334066 -382.945921) (xy 435.372019 -383.001502) (xy 435.403056 -383.061221)
			(xy 435.426733 -383.124222) (xy 435.44271 -383.189601) (xy 435.450758 -383.256421) (xy 435.450761 -383.323724)
			(xy 435.44272 -383.390546) (xy 435.426749 -383.455926) (xy 435.403079 -383.518929) (xy 435.372047 -383.578652)
			(xy 435.334099 -383.634237) (xy 435.312312 -383.659888) (xy 435.306497 -383.66702) (xy 435.299993 -383.684221)
			(xy 435.299612 -383.693416) (xy 435.299612 -384.186684) (xy 435.300027 -384.195871) (xy 435.306537 -384.213055)
			(xy 435.312312 -384.220212) (xy 435.334137 -384.245834) (xy 435.372087 -384.301424) (xy 435.403122 -384.361151)
			(xy 435.426795 -384.42416) (xy 435.442767 -384.489546) (xy 435.450809 -384.556373) (xy 435.450805 -384.623681)
			(xy 435.442757 -384.690507) (xy 435.426779 -384.755892) (xy 435.4031 -384.818898) (xy 435.37206 -384.878623)
			(xy 435.334103 -384.934208) (xy 435.312312 -384.95986) (xy 435.306509 -384.967001) (xy 435.299998 -384.984195)
			(xy 435.299612 -384.993388) (xy 435.299612 -385.151376) (xy 435.299159 -385.161527) (xy 435.291374 -385.180277)
			(xy 435.276987 -385.194601) (xy 435.258203 -385.202303) (xy 435.24805 -385.202684) (xy 434.53177 -385.202684)
			(xy 434.521644 -385.202199) (xy 434.502927 -385.194466) (xy 434.488573 -385.180179) (xy 434.48075 -385.161499)
			(xy 434.480208 -385.151376) (xy 434.480208 -384.993388) (xy 434.479802 -384.9842) (xy 434.473285 -384.967016)
			(xy 434.467508 -384.95986) (xy 434.445757 -384.934178) (xy 434.407809 -384.878595) (xy 434.376776 -384.818876)
			(xy 434.353102 -384.755875) (xy 434.337128 -384.690497) (xy 434.329081 -384.623678) (xy 434.329078 -384.556376)
			(xy 434.337118 -384.489557) (xy 434.353086 -384.424177) (xy 434.376753 -384.361174) (xy 434.407781 -384.301451)
			(xy 434.445723 -384.245864) (xy 434.467508 -384.220212) (xy 434.473325 -384.213082) (xy 434.479827 -384.19588)
			(xy 434.480208 -384.186684) (xy 434.480208 -383.693416) (xy 434.479788 -383.68423) (xy 434.473281 -383.667046)
			(xy 434.467508 -383.659888) (xy 434.445686 -383.634265) (xy 434.40774 -383.578673) (xy 434.37671 -383.518945)
			(xy 434.353041 -383.455937) (xy 434.337071 -383.390552) (xy 434.32903 -383.323727) (xy 433.226386 -383.323727)
			(xy 433.22662 -383.324351) (xy 433.242592 -383.389735) (xy 433.250634 -383.456559) (xy 433.250633 -383.523865)
			(xy 433.242587 -383.590689) (xy 433.226613 -383.656072) (xy 433.202938 -383.719077) (xy 433.171903 -383.778801)
			(xy 433.133953 -383.834388) (xy 433.112164 -383.86004) (xy 433.106363 -383.867182) (xy 433.099852 -383.884375)
			(xy 433.099464 -383.893568) (xy 433.099464 -384.051556) (xy 433.099042 -384.061712) (xy 433.091254 -384.08047)
			(xy 433.076856 -384.094796) (xy 433.05806 -384.102491) (xy 433.047902 -384.102864) (xy 432.331622 -384.102864)
			(xy 432.321497 -384.102356) (xy 432.302777 -384.094636) (xy 432.28842 -384.080356) (xy 432.2806 -384.061678)
			(xy 432.28006 -384.051556) (xy 432.28006 -383.893568) (xy 432.279652 -383.884381) (xy 432.273135 -383.867197)
			(xy 432.26736 -383.86004) (xy 432.245587 -383.834375) (xy 432.207637 -383.778791) (xy 432.176602 -383.719069)
			(xy 432.152927 -383.656066) (xy 432.136952 -383.590686) (xy 432.128907 -383.523864) (xy 432.128905 -383.45656)
			(xy 432.136948 -383.389738) (xy 432.15292 -383.324357) (xy 432.176592 -383.261353) (xy 432.207624 -383.20163)
			(xy 432.245573 -383.146044) (xy 432.26736 -383.120392) (xy 432.27315 -383.113242) (xy 432.279667 -383.096055)
			(xy 432.28006 -383.086864) (xy 432.28006 -382.593342) (xy 432.279616 -382.584159) (xy 432.273125 -382.566975)
			(xy 432.26736 -382.559814) (xy 432.245562 -382.53417) (xy 432.207612 -382.478583) (xy 432.176578 -382.418858)
			(xy 432.152905 -382.355853) (xy 432.136932 -382.290469) (xy 432.128888 -382.223646) (xy 428.850826 -382.223646)
			(xy 428.842783 -382.290466) (xy 428.826812 -382.355848) (xy 428.803141 -382.418852) (xy 428.772109 -382.478575)
			(xy 428.734163 -382.534162) (xy 428.712376 -382.559814) (xy 428.706588 -382.566965) (xy 428.700069 -382.584151)
			(xy 428.699676 -382.593342) (xy 428.699676 -383.086864) (xy 428.700109 -383.096049) (xy 428.706607 -383.113233)
			(xy 428.712376 -383.120392) (xy 428.734179 -383.146031) (xy 428.772126 -383.20162) (xy 428.803158 -383.261345)
			(xy 428.826616 -383.323786) (xy 429.928711 -383.323786) (xy 429.928714 -383.25636) (xy 429.936794 -383.189418)
			(xy 429.952834 -383.123927) (xy 429.976603 -383.060829) (xy 430.007759 -383.001032) (xy 430.045853 -382.945397)
			(xy 430.06772 -382.919732) (xy 430.07353 -382.912597) (xy 430.080036 -382.895398) (xy 430.08042 -382.886204)
			(xy 430.08042 -382.728724) (xy 430.080836 -382.718601) (xy 430.08858 -382.699894) (xy 430.102897 -382.685578)
			(xy 430.121605 -382.677835) (xy 430.131728 -382.677416) (xy 430.848008 -382.677416) (xy 430.858133 -382.67781)
			(xy 430.87684 -382.685564) (xy 430.891154 -382.699887) (xy 430.898896 -382.718599) (xy 430.899316 -382.728724)
			(xy 430.899316 -382.886204) (xy 430.899721 -382.895392) (xy 430.906238 -382.912576) (xy 430.912016 -382.919732)
			(xy 430.933844 -382.945427) (xy 430.971933 -383.001057) (xy 431.003084 -383.06085) (xy 431.02685 -383.123943)
			(xy 431.042887 -383.189428) (xy 431.050966 -383.256363) (xy 431.050969 -383.323783) (xy 431.042897 -383.390719)
			(xy 431.026866 -383.456206) (xy 431.003106 -383.519301) (xy 430.971961 -383.579096) (xy 430.933877 -383.634731)
			(xy 430.912016 -383.660396) (xy 430.90624 -383.667556) (xy 430.899713 -383.684735) (xy 430.899316 -383.693924)
			(xy 430.899316 -384.186176) (xy 430.899734 -384.195362) (xy 430.906242 -384.212547) (xy 430.912016 -384.219704)
			(xy 430.933915 -384.24534) (xy 430.972001 -384.300979) (xy 431.00315 -384.36078) (xy 431.026911 -384.42388)
			(xy 431.042944 -384.489373) (xy 431.051016 -384.556314) (xy 431.051013 -384.62374) (xy 431.042934 -384.690681)
			(xy 431.026895 -384.756171) (xy 431.003128 -384.81927) (xy 430.971974 -384.879067) (xy 430.933882 -384.934702)
			(xy 430.912016 -384.960368) (xy 430.90621 -384.967507) (xy 430.8997 -384.984702) (xy 430.899316 -384.993896)
			(xy 430.899316 -385.151376) (xy 430.898865 -385.161495) (xy 430.891128 -385.180195) (xy 430.876822 -385.19451)
			(xy 430.858127 -385.202259) (xy 430.848008 -385.202684) (xy 430.131728 -385.202684) (xy 430.121605 -385.202261)
			(xy 430.102899 -385.194519) (xy 430.088583 -385.180204) (xy 430.08084 -385.161499) (xy 430.08042 -385.151376)
			(xy 430.08042 -384.993896) (xy 430.080008 -384.984709) (xy 430.073495 -384.967525) (xy 430.06772 -384.960368)
			(xy 430.045891 -384.934674) (xy 430.0078 -384.879044) (xy 429.976646 -384.819252) (xy 429.952879 -384.756159)
			(xy 429.936841 -384.690673) (xy 429.928761 -384.623738) (xy 429.928758 -384.556316) (xy 429.936831 -384.48938)
			(xy 429.952863 -384.423893) (xy 429.976624 -384.360797) (xy 430.007772 -384.301002) (xy 430.045857 -384.245369)
			(xy 430.06772 -384.219704) (xy 430.0735 -384.212547) (xy 430.080024 -384.195365) (xy 430.08042 -384.186176)
			(xy 430.08042 -383.693924) (xy 430.079994 -383.684739) (xy 430.073491 -383.667554) (xy 430.06772 -383.660396)
			(xy 430.04582 -383.63476) (xy 430.007731 -383.579122) (xy 429.976581 -383.519322) (xy 429.952818 -383.456221)
			(xy 429.936784 -383.390728) (xy 429.928711 -383.323786) (xy 428.826616 -383.323786) (xy 428.826829 -383.324352)
			(xy 428.842801 -383.389735) (xy 428.850843 -383.456559) (xy 428.850842 -383.523865) (xy 428.842797 -383.590688)
			(xy 428.826822 -383.656071) (xy 428.803148 -383.719077) (xy 428.772114 -383.778801) (xy 428.734164 -383.834388)
			(xy 428.712376 -383.86004) (xy 428.706577 -383.867183) (xy 428.700065 -383.884375) (xy 428.699676 -383.893568)
			(xy 428.699676 -384.051556) (xy 428.699242 -384.06171) (xy 428.691456 -384.080466) (xy 428.677063 -384.094792)
			(xy 428.65827 -384.102489) (xy 428.648114 -384.102864) (xy 427.931834 -384.102864) (xy 427.92171 -384.102345)
			(xy 427.90299 -384.09463) (xy 427.888633 -384.080353) (xy 427.880812 -384.061677) (xy 427.880272 -384.051556)
			(xy 427.880272 -383.893568) (xy 427.879883 -383.884378) (xy 427.873355 -383.867194) (xy 427.867572 -383.86004)
			(xy 427.845799 -383.834375) (xy 427.807848 -383.778791) (xy 427.776812 -383.71907) (xy 427.753137 -383.656067)
			(xy 427.737162 -383.590686) (xy 427.729116 -383.523864) (xy 427.729114 -383.45656) (xy 427.737157 -383.389738)
			(xy 427.75313 -383.324356) (xy 427.776802 -383.261352) (xy 427.807835 -383.201629) (xy 427.845784 -383.146044)
			(xy 427.867572 -383.120392) (xy 427.873363 -383.113243) (xy 427.879879 -383.096055) (xy 427.880272 -383.086864)
			(xy 427.880272 -382.593342) (xy 427.879848 -382.584156) (xy 427.873344 -382.566971) (xy 427.867572 -382.559814)
			(xy 427.845774 -382.53417) (xy 427.807823 -382.478583) (xy 427.776788 -382.418859) (xy 427.753115 -382.355853)
			(xy 427.737141 -382.29047) (xy 427.729097 -382.223646) (xy 424.451058 -382.223646) (xy 424.451058 -382.223704)
			(xy 424.442983 -382.290642) (xy 424.426948 -382.356131) (xy 424.403184 -382.419227) (xy 424.372033 -382.479023)
			(xy 424.333944 -382.534657) (xy 424.31208 -382.560322) (xy 424.306289 -382.567471) (xy 424.299772 -382.584659)
			(xy 424.29938 -382.59385) (xy 424.29938 -383.086356) (xy 424.299816 -383.09554) (xy 424.306312 -383.112725)
			(xy 424.31208 -383.119884) (xy 424.33396 -383.145536) (xy 424.37205 -383.201172) (xy 424.403201 -383.26097)
			(xy 424.426837 -383.323727) (xy 425.528942 -383.323727) (xy 425.528946 -383.256419) (xy 425.536993 -383.189594)
			(xy 425.55297 -383.12421) (xy 425.576646 -383.061204) (xy 425.607682 -383.00148) (xy 425.645635 -382.945892)
			(xy 425.667424 -382.92024) (xy 425.673231 -382.913103) (xy 425.679739 -382.895906) (xy 425.680124 -382.886712)
			(xy 425.680124 -382.728724) (xy 425.680536 -382.7186) (xy 425.688281 -382.699892) (xy 425.702599 -382.685576)
			(xy 425.721308 -382.677834) (xy 425.731432 -382.677416) (xy 426.447966 -382.677416) (xy 426.458088 -382.677954)
			(xy 426.476803 -382.685666) (xy 426.49116 -382.699937) (xy 426.498984 -382.718606) (xy 426.499528 -382.728724)
			(xy 426.499528 -382.886712) (xy 426.499926 -382.895901) (xy 426.506447 -382.913085) (xy 426.512228 -382.92024)
			(xy 426.533981 -382.945921) (xy 426.571933 -383.001502) (xy 426.60297 -383.061222) (xy 426.626646 -383.124223)
			(xy 426.642623 -383.189602) (xy 426.65067 -383.256422) (xy 426.650673 -383.323724) (xy 426.642632 -383.390545)
			(xy 426.626662 -383.455926) (xy 426.602992 -383.518929) (xy 426.571961 -383.578651) (xy 426.534014 -383.634236)
			(xy 426.512228 -383.659888) (xy 426.506403 -383.667013) (xy 426.499907 -383.684219) (xy 426.499528 -383.693416)
			(xy 426.499528 -384.186684) (xy 426.499939 -384.195871) (xy 426.506451 -384.213056) (xy 426.512228 -384.220212)
			(xy 426.534052 -384.245834) (xy 426.572002 -384.301424) (xy 426.603036 -384.361152) (xy 426.626708 -384.42416)
			(xy 426.64268 -384.489546) (xy 426.650721 -384.556373) (xy 426.650718 -384.623681) (xy 426.64267 -384.690507)
			(xy 426.626692 -384.755892) (xy 426.603014 -384.818898) (xy 426.571974 -384.878622) (xy 426.534019 -384.934208)
			(xy 426.512228 -384.95986) (xy 426.506415 -384.966993) (xy 426.499912 -384.984193) (xy 426.499528 -384.993388)
			(xy 426.499528 -385.151376) (xy 426.499065 -385.161494) (xy 426.49133 -385.180191) (xy 426.477028 -385.194505)
			(xy 426.458337 -385.202257) (xy 426.44822 -385.202684) (xy 425.731686 -385.202684) (xy 425.721561 -385.202185)
			(xy 425.702845 -385.194457) (xy 425.68849 -385.180175) (xy 425.680667 -385.161498) (xy 425.680124 -385.151376)
			(xy 425.680124 -384.993388) (xy 425.679714 -384.984201) (xy 425.6732 -384.967017) (xy 425.667424 -384.95986)
			(xy 425.645672 -384.934178) (xy 425.607723 -384.878596) (xy 425.576689 -384.818876) (xy 425.553015 -384.755876)
			(xy 425.53704 -384.690497) (xy 425.528994 -384.623678) (xy 425.52899 -384.556376) (xy 425.537031 -384.489556)
			(xy 425.552999 -384.424176) (xy 425.576667 -384.361173) (xy 425.607696 -384.301451) (xy 425.645639 -384.245865)
			(xy 425.667424 -384.220212) (xy 425.673243 -384.213083) (xy 425.679744 -384.19588) (xy 425.680124 -384.186684)
			(xy 425.680124 -383.693416) (xy 425.679701 -383.68423) (xy 425.673195 -383.667046) (xy 425.667424 -383.659888)
			(xy 425.645601 -383.634265) (xy 425.607655 -383.578674) (xy 425.576624 -383.518946) (xy 425.552954 -383.455938)
			(xy 425.536984 -383.390552) (xy 425.528942 -383.323727) (xy 424.426837 -383.323727) (xy 424.426965 -383.324068)
			(xy 424.443 -383.389559) (xy 424.451075 -383.456499) (xy 424.451074 -383.523925) (xy 424.442996 -383.590864)
			(xy 424.426958 -383.656355) (xy 424.403191 -383.719452) (xy 424.372038 -383.779249) (xy 424.333946 -383.834883)
			(xy 424.31208 -383.860548) (xy 424.306278 -383.867689) (xy 424.299767 -383.884883) (xy 424.29938 -383.894076)
			(xy 424.29938 -384.051556) (xy 424.298947 -384.061678) (xy 424.29121 -384.080385) (xy 424.276898 -384.094701)
			(xy 424.258194 -384.102444) (xy 424.248072 -384.102864) (xy 423.531792 -384.102864) (xy 423.521665 -384.10249)
			(xy 423.502954 -384.094732) (xy 423.488639 -384.080402) (xy 423.4809 -384.061684) (xy 423.480484 -384.051556)
			(xy 423.480484 -383.894076) (xy 423.480089 -383.884887) (xy 423.473565 -383.867703) (xy 423.467784 -383.860548)
			(xy 423.445936 -383.83487) (xy 423.407848 -383.779237) (xy 423.376698 -383.719442) (xy 423.352933 -383.656347)
			(xy 423.336897 -383.59086) (xy 423.32882 -383.523923) (xy 423.328819 -383.456501) (xy 423.336893 -383.389564)
			(xy 423.352926 -383.324076) (xy 423.376688 -383.26098) (xy 423.407836 -383.201184) (xy 423.445922 -383.145549)
			(xy 423.467784 -383.119884) (xy 423.473568 -383.11273) (xy 423.480091 -383.095546) (xy 423.480484 -383.086356)
			(xy 423.480484 -382.59385) (xy 423.480054 -382.584665) (xy 423.473554 -382.56748) (xy 423.467784 -382.560322)
			(xy 423.445911 -382.534665) (xy 423.407823 -382.479029) (xy 423.376674 -382.419231) (xy 423.352911 -382.356133)
			(xy 423.336877 -382.290643) (xy 423.328802 -382.223705) (xy 420.050731 -382.223705) (xy 420.042695 -382.290466)
			(xy 420.026725 -382.355847) (xy 420.003054 -382.418851) (xy 419.972024 -382.478574) (xy 419.934078 -382.534161)
			(xy 419.912292 -382.559814) (xy 419.906506 -382.566967) (xy 419.899985 -382.584151) (xy 419.899592 -382.593342)
			(xy 419.899592 -383.086864) (xy 419.900021 -383.096049) (xy 419.906522 -383.113234) (xy 419.912292 -383.120392)
			(xy 419.934094 -383.146032) (xy 419.972041 -383.201621) (xy 420.003072 -383.261346) (xy 420.02653 -383.323787)
			(xy 421.128623 -383.323787) (xy 421.128626 -383.256359) (xy 421.136706 -383.189418) (xy 421.152747 -383.123926)
			(xy 421.176516 -383.060828) (xy 421.207673 -383.001031) (xy 421.245769 -382.945397) (xy 421.267636 -382.919732)
			(xy 421.273449 -382.912598) (xy 421.279953 -382.895399) (xy 421.280336 -382.886204) (xy 421.280336 -382.728724)
			(xy 421.280736 -382.718599) (xy 421.288483 -382.699889) (xy 421.302805 -382.685572) (xy 421.321518 -382.677832)
			(xy 421.331644 -382.677416) (xy 422.047924 -382.677416) (xy 422.058036 -382.677866) (xy 422.076718 -382.685614)
			(xy 422.091013 -382.699922) (xy 422.098744 -382.718611) (xy 422.099232 -382.728724) (xy 422.099232 -382.886204)
			(xy 422.099656 -382.895389) (xy 422.106162 -382.912573) (xy 422.111932 -382.919732) (xy 422.133759 -382.945427)
			(xy 422.171847 -383.001058) (xy 422.202998 -383.06085) (xy 422.226762 -383.123943) (xy 422.242799 -383.189428)
			(xy 422.250878 -383.256363) (xy 422.250881 -383.323783) (xy 422.242809 -383.390718) (xy 422.226778 -383.456205)
			(xy 422.20302 -383.5193) (xy 422.171875 -383.579096) (xy 422.133793 -383.63473) (xy 422.111932 -383.660396)
			(xy 422.106146 -383.667549) (xy 422.099627 -383.684734) (xy 422.099232 -383.693924) (xy 422.099232 -384.186176)
			(xy 422.099669 -384.19536) (xy 422.106166 -384.212544) (xy 422.111932 -384.219704) (xy 422.13383 -384.245341)
			(xy 422.171916 -384.30098) (xy 422.203063 -384.36078) (xy 422.226824 -384.423881) (xy 422.242856 -384.489373)
			(xy 422.250928 -384.556314) (xy 422.250925 -384.62374) (xy 422.242846 -384.69068) (xy 422.226808 -384.756171)
			(xy 422.203041 -384.819269) (xy 422.171888 -384.879066) (xy 422.133797 -384.934702) (xy 422.111932 -384.960368)
			(xy 422.106116 -384.967499) (xy 422.099615 -384.984701) (xy 422.099232 -384.993896) (xy 422.099232 -385.151376)
			(xy 422.098696 -385.161479) (xy 422.090972 -385.180151) (xy 422.076691 -385.194445) (xy 422.058027 -385.202187)
			(xy 422.047924 -385.202684) (xy 421.331644 -385.202684) (xy 421.321522 -385.202247) (xy 421.302817 -385.194511)
			(xy 421.2885 -385.1802) (xy 421.280756 -385.161497) (xy 421.280336 -385.151376) (xy 421.280336 -384.993896)
			(xy 421.27992 -384.98471) (xy 421.27341 -384.967526) (xy 421.267636 -384.960368) (xy 421.245806 -384.934674)
			(xy 421.207714 -384.879045) (xy 421.17656 -384.819253) (xy 421.152792 -384.756159) (xy 421.136753 -384.690673)
			(xy 421.128674 -384.623738) (xy 421.12867 -384.556316) (xy 421.136743 -384.48938) (xy 421.152776 -384.423892)
			(xy 421.176538 -384.360797) (xy 421.207686 -384.301002) (xy 421.245773 -384.245369) (xy 421.267636 -384.219704)
			(xy 421.273418 -384.212549) (xy 421.27994 -384.195366) (xy 421.280336 -384.186176) (xy 421.280336 -383.693924)
			(xy 421.279906 -383.684739) (xy 421.273405 -383.667555) (xy 421.267636 -383.660396) (xy 421.245735 -383.634761)
			(xy 421.207645 -383.579123) (xy 421.176494 -383.519323) (xy 421.152731 -383.456222) (xy 421.136696 -383.390729)
			(xy 421.128623 -383.323787) (xy 420.02653 -383.323787) (xy 420.026742 -383.324352) (xy 420.042713 -383.389736)
			(xy 420.050756 -383.456559) (xy 420.050754 -383.523865) (xy 420.042709 -383.590688) (xy 420.026735 -383.656071)
			(xy 420.003062 -383.719076) (xy 419.972028 -383.7788) (xy 419.93408 -383.834387) (xy 419.912292 -383.86004)
			(xy 419.906495 -383.867185) (xy 419.899981 -383.884376) (xy 419.899592 -383.893568) (xy 419.899592 -384.051556)
			(xy 419.899148 -384.061677) (xy 419.891413 -384.080381) (xy 419.877104 -384.094697) (xy 419.858404 -384.102442)
			(xy 419.848284 -384.102864) (xy 419.13175 -384.102864) (xy 419.121627 -384.102333) (xy 419.102908 -384.094622)
			(xy 419.08855 -384.080349) (xy 419.080728 -384.061676) (xy 419.080188 -384.051556) (xy 419.080188 -383.893568)
			(xy 419.079796 -383.884379) (xy 419.07327 -383.867194) (xy 419.067488 -383.86004) (xy 419.045715 -383.834376)
			(xy 419.007762 -383.778792) (xy 418.976725 -383.719071) (xy 418.95305 -383.656068) (xy 418.937074 -383.590686)
			(xy 418.929028 -383.523864) (xy 418.929026 -383.45656) (xy 418.93707 -383.389737) (xy 418.953042 -383.324355)
			(xy 418.976716 -383.261351) (xy 419.00775 -383.201629) (xy 419.0457 -383.146043) (xy 419.067488 -383.120392)
			(xy 419.073269 -383.113236) (xy 419.079793 -383.096054) (xy 419.080188 -383.086864) (xy 419.080188 -382.593342)
			(xy 419.07976 -382.584157) (xy 419.073259 -382.566972) (xy 419.067488 -382.559814) (xy 419.045689 -382.534171)
			(xy 419.007737 -382.478584) (xy 418.976702 -382.41886) (xy 418.953027 -382.355854) (xy 418.937054 -382.29047)
			(xy 418.92901 -382.223646) (xy 389.250707 -382.223646) (xy 389.242664 -382.290467) (xy 389.226692 -382.355848)
			(xy 389.20302 -382.418853) (xy 389.171987 -382.478576) (xy 389.134039 -382.534162) (xy 389.112252 -382.559814)
			(xy 389.106461 -382.566963) (xy 389.099944 -382.584151) (xy 389.099552 -382.593342) (xy 389.099552 -383.086864)
			(xy 389.09999 -383.096048) (xy 389.106485 -383.113232) (xy 389.112252 -383.120392) (xy 389.134056 -383.146031)
			(xy 389.172005 -383.201619) (xy 389.203038 -383.261344) (xy 389.226475 -383.323726) (xy 390.329121 -383.323726)
			(xy 390.329125 -383.256419) (xy 390.337172 -383.189595) (xy 390.353147 -383.124211) (xy 390.376822 -383.061206)
			(xy 390.407857 -383.001481) (xy 390.445807 -382.945893) (xy 390.467596 -382.92024) (xy 390.4734 -382.9131)
			(xy 390.47991 -382.895906) (xy 390.480296 -382.886712) (xy 390.480296 -382.728724) (xy 390.480741 -382.718572)
			(xy 390.488528 -382.699821) (xy 390.502918 -382.685497) (xy 390.521704 -382.677795) (xy 390.531858 -382.677416)
			(xy 391.248138 -382.677416) (xy 391.258264 -382.677895) (xy 391.276982 -382.685631) (xy 391.291336 -382.699919)
			(xy 391.299158 -382.7186) (xy 391.2997 -382.728724) (xy 391.2997 -382.886712) (xy 391.300105 -382.8959)
			(xy 391.306622 -382.913084) (xy 391.3124 -382.92024) (xy 391.334151 -382.945922) (xy 391.372099 -383.001505)
			(xy 391.403131 -383.061225) (xy 391.426804 -383.124225) (xy 391.442779 -383.189603) (xy 391.450825 -383.256422)
			(xy 391.450828 -383.323724) (xy 391.442788 -383.390543) (xy 391.42682 -383.455923) (xy 391.403153 -383.518926)
			(xy 391.372126 -383.578649) (xy 391.334184 -383.634235) (xy 391.3124 -383.659888) (xy 391.306584 -383.667019)
			(xy 391.300081 -383.68422) (xy 391.2997 -383.693416) (xy 391.2997 -384.186684) (xy 391.300118 -384.19587)
			(xy 391.306626 -384.213055) (xy 391.3124 -384.220212) (xy 391.334222 -384.245836) (xy 391.372167 -384.301427)
			(xy 391.403197 -384.361155) (xy 391.426866 -384.424163) (xy 391.442835 -384.489548) (xy 391.450876 -384.556374)
			(xy 391.450872 -384.623681) (xy 391.442825 -384.690505) (xy 391.42685 -384.755889) (xy 391.403175 -384.818895)
			(xy 391.372139 -384.878619) (xy 391.334189 -384.934207) (xy 391.3124 -384.95986) (xy 391.306595 -384.967)
			(xy 391.300086 -384.984194) (xy 391.2997 -384.993388) (xy 391.2997 -385.151376) (xy 391.299259 -385.161529)
			(xy 391.291471 -385.180281) (xy 391.27708 -385.194605) (xy 391.258292 -385.202305) (xy 391.248138 -385.202684)
			(xy 390.531858 -385.202684) (xy 390.521732 -385.202209) (xy 390.503014 -385.194471) (xy 390.48866 -385.180182)
			(xy 390.480838 -385.1615) (xy 390.480296 -385.151376) (xy 390.480296 -384.993388) (xy 390.479892 -384.9842)
			(xy 390.473374 -384.967016) (xy 390.467596 -384.95986) (xy 390.445845 -384.934178) (xy 390.407898 -384.878595)
			(xy 390.376865 -384.818875) (xy 390.353192 -384.755875) (xy 390.337218 -384.690496) (xy 390.329172 -384.623678)
			(xy 390.329169 -384.556376) (xy 390.337209 -384.489557) (xy 390.353176 -384.424177) (xy 390.376843 -384.361174)
			(xy 390.40787 -384.301452) (xy 390.445812 -384.245865) (xy 390.467596 -384.220212) (xy 390.473412 -384.21308)
			(xy 390.479915 -384.19588) (xy 390.480296 -384.186684) (xy 390.480296 -383.693416) (xy 390.479879 -383.68423)
			(xy 390.47337 -383.667045) (xy 390.467596 -383.659888) (xy 390.445774 -383.634264) (xy 390.407829 -383.578673)
			(xy 390.3768 -383.518945) (xy 390.353131 -383.455937) (xy 390.337162 -383.390552) (xy 390.329121 -383.323726)
			(xy 389.226475 -383.323726) (xy 389.22671 -383.324351) (xy 389.242682 -383.389735) (xy 389.250725 -383.456559)
			(xy 389.250724 -383.523865) (xy 389.242678 -383.590689) (xy 389.226703 -383.656072) (xy 389.203028 -383.719078)
			(xy 389.171992 -383.778802) (xy 389.134041 -383.834388) (xy 389.112252 -383.86004) (xy 389.10645 -383.867181)
			(xy 389.09994 -383.884375) (xy 389.099552 -383.893568) (xy 389.099552 -384.051556) (xy 389.099043 -384.061701)
			(xy 389.091272 -384.080442) (xy 389.076902 -384.094765) (xy 389.058136 -384.102476) (xy 389.04799 -384.102864)
			(xy 388.33171 -384.102864) (xy 388.321584 -384.102365) (xy 388.302864 -384.094642) (xy 388.288508 -384.080359)
			(xy 388.280687 -384.061679) (xy 388.280148 -384.051556) (xy 388.280148 -383.893568) (xy 388.279742 -383.884381)
			(xy 388.273224 -383.867197) (xy 388.267448 -383.86004) (xy 388.245676 -383.834375) (xy 388.207726 -383.778791)
			(xy 388.176692 -383.719069) (xy 388.153018 -383.656066) (xy 388.137043 -383.590685) (xy 388.128998 -383.523864)
			(xy 388.128996 -383.45656) (xy 388.137039 -383.389738) (xy 388.15301 -383.324357) (xy 388.176682 -383.261353)
			(xy 388.207714 -383.20163) (xy 388.245661 -383.146044) (xy 388.267448 -383.120392) (xy 388.273236 -383.113241)
			(xy 388.279755 -383.096055) (xy 388.280148 -383.086864) (xy 388.280148 -382.593342) (xy 388.279707 -382.584158)
			(xy 388.273213 -382.566974) (xy 388.267448 -382.559814) (xy 388.24565 -382.53417) (xy 388.207701 -382.478583)
			(xy 388.176668 -382.418858) (xy 388.152995 -382.355852) (xy 388.137022 -382.290469) (xy 388.128979 -382.223645)
			(xy 384.850917 -382.223645) (xy 384.842874 -382.290466) (xy 384.826902 -382.355848) (xy 384.803231 -382.418852)
			(xy 384.772199 -382.478576) (xy 384.734251 -382.534162) (xy 384.712464 -382.559814) (xy 384.706674 -382.566964)
			(xy 384.700156 -382.584151) (xy 384.699764 -382.593342) (xy 384.699764 -383.086864) (xy 384.7002 -383.096048)
			(xy 384.706697 -383.113232) (xy 384.712464 -383.120392) (xy 384.734267 -383.146031) (xy 384.772216 -383.20162)
			(xy 384.803248 -383.261345) (xy 384.826708 -383.323786) (xy 385.928802 -383.323786) (xy 385.928805 -383.25636)
			(xy 385.936885 -383.189419) (xy 385.952924 -383.123928) (xy 385.976693 -383.060829) (xy 386.007848 -383.001032)
			(xy 386.045942 -382.945397) (xy 386.067808 -382.919732) (xy 386.073617 -382.912596) (xy 386.080124 -382.895398)
			(xy 386.080508 -382.886204) (xy 386.080508 -382.728724) (xy 386.080936 -382.718602) (xy 386.088677 -382.699897)
			(xy 386.102991 -382.685582) (xy 386.121694 -382.677837) (xy 386.131816 -382.677416) (xy 386.848096 -382.677416)
			(xy 386.85822 -382.67782) (xy 386.876927 -382.685569) (xy 386.891242 -382.69989) (xy 386.898984 -382.7186)
			(xy 386.899404 -382.728724) (xy 386.899404 -382.886204) (xy 386.899811 -382.895391) (xy 386.906327 -382.912576)
			(xy 386.912104 -382.919732) (xy 386.933932 -382.945426) (xy 386.972022 -383.001057) (xy 387.003174 -383.060849)
			(xy 387.02694 -383.123942) (xy 387.042978 -383.189428) (xy 387.051057 -383.256363) (xy 387.05106 -383.323783)
			(xy 387.042988 -383.390719) (xy 387.026956 -383.456206) (xy 387.003196 -383.519301) (xy 386.97205 -383.579097)
			(xy 386.933966 -383.634731) (xy 386.912104 -383.660396) (xy 386.906327 -383.667555) (xy 386.899801 -383.684735)
			(xy 386.899404 -383.693924) (xy 386.899404 -384.186176) (xy 386.899825 -384.195362) (xy 386.906331 -384.212547)
			(xy 386.912104 -384.219704) (xy 386.934003 -384.24534) (xy 386.972091 -384.300979) (xy 387.003239 -384.360779)
			(xy 387.027001 -384.42388) (xy 387.043034 -384.489372) (xy 387.051107 -384.556314) (xy 387.051104 -384.62374)
			(xy 387.043025 -384.690681) (xy 387.026985 -384.756172) (xy 387.003217 -384.81927) (xy 386.972063 -384.879068)
			(xy 386.93397 -384.934703) (xy 386.912104 -384.960368) (xy 386.906297 -384.967506) (xy 386.899788 -384.984702)
			(xy 386.899404 -384.993896) (xy 386.899404 -385.151376) (xy 386.898965 -385.161496) (xy 386.891225 -385.180199)
			(xy 386.876916 -385.194514) (xy 386.858216 -385.202261) (xy 386.848096 -385.202684) (xy 386.131816 -385.202684)
			(xy 386.121693 -385.202271) (xy 386.102986 -385.194525) (xy 386.088671 -385.180207) (xy 386.080928 -385.1615)
			(xy 386.080508 -385.151376) (xy 386.080508 -384.993896) (xy 386.080098 -384.984709) (xy 386.073584 -384.967525)
			(xy 386.067808 -384.960368) (xy 386.045979 -384.934674) (xy 386.007889 -384.879044) (xy 385.976736 -384.819251)
			(xy 385.95297 -384.756158) (xy 385.936931 -384.690673) (xy 385.928852 -384.623738) (xy 385.928849 -384.556317)
			(xy 385.936922 -384.489381) (xy 385.952954 -384.423893) (xy 385.976714 -384.360798) (xy 386.007861 -384.301003)
			(xy 386.045946 -384.245369) (xy 386.067808 -384.219704) (xy 386.073586 -384.212546) (xy 386.080112 -384.195365)
			(xy 386.080508 -384.186176) (xy 386.080508 -383.693924) (xy 386.080084 -383.684738) (xy 386.07358 -383.667554)
			(xy 386.067808 -383.660396) (xy 386.045908 -383.63476) (xy 386.00782 -383.579122) (xy 385.976671 -383.519321)
			(xy 385.952908 -383.456221) (xy 385.936875 -383.390728) (xy 385.928802 -383.323786) (xy 384.826708 -383.323786)
			(xy 384.82692 -383.324351) (xy 384.842892 -383.389735) (xy 384.850934 -383.456559) (xy 384.850933 -383.523865)
			(xy 384.842887 -383.590689) (xy 384.826913 -383.656072) (xy 384.803238 -383.719077) (xy 384.772203 -383.778801)
			(xy 384.734253 -383.834388) (xy 384.712464 -383.86004) (xy 384.706663 -383.867182) (xy 384.700152 -383.884375)
			(xy 384.699764 -383.893568) (xy 384.699764 -384.051556) (xy 384.699342 -384.061712) (xy 384.691554 -384.08047)
			(xy 384.677156 -384.094796) (xy 384.65836 -384.102491) (xy 384.648202 -384.102864) (xy 383.931922 -384.102864)
			(xy 383.921797 -384.102356) (xy 383.903077 -384.094636) (xy 383.88872 -384.080356) (xy 383.8809 -384.061678)
			(xy 383.88036 -384.051556) (xy 383.88036 -383.893568) (xy 383.879952 -383.884381) (xy 383.873435 -383.867197)
			(xy 383.86766 -383.86004) (xy 383.845887 -383.834375) (xy 383.807937 -383.778791) (xy 383.776902 -383.719069)
			(xy 383.753227 -383.656066) (xy 383.737252 -383.590686) (xy 383.729207 -383.523864) (xy 383.729205 -383.45656)
			(xy 383.737248 -383.389738) (xy 383.75322 -383.324357) (xy 383.776892 -383.261353) (xy 383.807924 -383.20163)
			(xy 383.845873 -383.146044) (xy 383.86766 -383.120392) (xy 383.87345 -383.113242) (xy 383.879967 -383.096055)
			(xy 383.88036 -383.086864) (xy 383.88036 -382.593342) (xy 383.879916 -382.584159) (xy 383.873425 -382.566975)
			(xy 383.86766 -382.559814) (xy 383.845862 -382.53417) (xy 383.807912 -382.478583) (xy 383.776878 -382.418858)
			(xy 383.753205 -382.355853) (xy 383.737232 -382.290469) (xy 383.729188 -382.223646) (xy 380.451149 -382.223646)
			(xy 380.451149 -382.223704) (xy 380.443073 -382.290642) (xy 380.427038 -382.356131) (xy 380.403273 -382.419228)
			(xy 380.372122 -382.479024) (xy 380.334032 -382.534657) (xy 380.312168 -382.560322) (xy 380.306375 -382.56747)
			(xy 380.299859 -382.584658) (xy 380.299468 -382.59385) (xy 380.299468 -383.086356) (xy 380.299907 -383.09554)
			(xy 380.306401 -383.112724) (xy 380.312168 -383.119884) (xy 380.334049 -383.145536) (xy 380.372139 -383.201171)
			(xy 380.403291 -383.260969) (xy 380.426928 -383.323727) (xy 381.529033 -383.323727) (xy 381.529037 -383.256419)
			(xy 381.537084 -383.189595) (xy 381.55306 -383.124211) (xy 381.576736 -383.061205) (xy 381.607772 -383.00148)
			(xy 381.645723 -382.945893) (xy 381.667512 -382.92024) (xy 381.673318 -382.913101) (xy 381.679827 -382.895906)
			(xy 381.680212 -382.886712) (xy 381.680212 -382.728724) (xy 381.680641 -382.71857) (xy 381.688431 -382.699816)
			(xy 381.702826 -382.685491) (xy 381.721618 -382.677793) (xy 381.731774 -382.677416) (xy 382.448054 -382.677416)
			(xy 382.458175 -382.677964) (xy 382.47689 -382.685672) (xy 382.491247 -382.699939) (xy 382.499072 -382.718606)
			(xy 382.499616 -382.728724) (xy 382.499616 -382.886712) (xy 382.500017 -382.8959) (xy 382.506537 -382.913085)
			(xy 382.512316 -382.92024) (xy 382.53407 -382.945921) (xy 382.572023 -383.001502) (xy 382.60306 -383.061221)
			(xy 382.626737 -383.124222) (xy 382.642713 -383.189601) (xy 382.650761 -383.256421) (xy 382.650764 -383.323724)
			(xy 382.642723 -383.390545) (xy 382.626753 -383.455926) (xy 382.603082 -383.518929) (xy 382.57205 -383.578652)
			(xy 382.534103 -383.634236) (xy 382.512316 -383.659888) (xy 382.506501 -383.667021) (xy 382.499997 -383.684221)
			(xy 382.499616 -383.693416) (xy 382.499616 -384.186684) (xy 382.50003 -384.195871) (xy 382.506541 -384.213055)
			(xy 382.512316 -384.220212) (xy 382.53414 -384.245834) (xy 382.572091 -384.301424) (xy 382.603125 -384.361151)
			(xy 382.626798 -384.42416) (xy 382.64277 -384.489546) (xy 382.650812 -384.556373) (xy 382.650808 -384.623681)
			(xy 382.64276 -384.690507) (xy 382.626782 -384.755892) (xy 382.603103 -384.818898) (xy 382.572063 -384.878622)
			(xy 382.534107 -384.934208) (xy 382.512316 -384.95986) (xy 382.506513 -384.967001) (xy 382.500002 -384.984195)
			(xy 382.499616 -384.993388) (xy 382.499616 -385.151376) (xy 382.499159 -385.161527) (xy 382.491375 -385.180275)
			(xy 382.476989 -385.194599) (xy 382.458206 -385.202303) (xy 382.448054 -385.202684) (xy 381.731774 -385.202684)
			(xy 381.721649 -385.202196) (xy 381.702931 -385.194464) (xy 381.688577 -385.180179) (xy 381.680754 -385.161499)
			(xy 381.680212 -385.151376) (xy 381.680212 -384.993388) (xy 381.679805 -384.984201) (xy 381.673289 -384.967016)
			(xy 381.667512 -384.95986) (xy 381.64576 -384.934178) (xy 381.607812 -384.878596) (xy 381.576779 -384.818876)
			(xy 381.553105 -384.755875) (xy 381.537131 -384.690497) (xy 381.529084 -384.623678) (xy 381.529081 -384.556376)
			(xy 381.537121 -384.489557) (xy 381.553089 -384.424177) (xy 381.576757 -384.361174) (xy 381.607784 -384.301451)
			(xy 381.645727 -384.245864) (xy 381.667512 -384.220212) (xy 381.67333 -384.213082) (xy 381.679831 -384.19588)
			(xy 381.680212 -384.186684) (xy 381.680212 -383.693416) (xy 381.679791 -383.68423) (xy 381.673285 -383.667046)
			(xy 381.667512 -383.659888) (xy 381.64569 -383.634265) (xy 381.607744 -383.578673) (xy 381.576714 -383.518946)
			(xy 381.553044 -383.455937) (xy 381.537074 -383.390552) (xy 381.529033 -383.323727) (xy 380.426928 -383.323727)
			(xy 380.427056 -383.324068) (xy 380.443091 -383.389559) (xy 380.451166 -383.456499) (xy 380.451165 -383.523925)
			(xy 380.443087 -383.590865) (xy 380.427049 -383.656355) (xy 380.403281 -383.719453) (xy 380.372127 -383.779249)
			(xy 380.334034 -383.834883) (xy 380.312168 -383.860548) (xy 380.306364 -383.867688) (xy 380.299855 -383.884883)
			(xy 380.299468 -383.894076) (xy 380.299468 -384.051556) (xy 380.299047 -384.06168) (xy 380.291308 -384.080388)
			(xy 380.276992 -384.094705) (xy 380.258284 -384.102446) (xy 380.24816 -384.102864) (xy 379.53188 -384.102864)
			(xy 379.521752 -384.1025) (xy 379.503041 -384.094738) (xy 379.488726 -384.080405) (xy 379.480988 -384.061685)
			(xy 379.480572 -384.051556) (xy 379.480572 -383.894076) (xy 379.48018 -383.884887) (xy 379.473654 -383.867702)
			(xy 379.467872 -383.860548) (xy 379.446025 -383.834869) (xy 379.407937 -383.779236) (xy 379.376788 -383.719441)
			(xy 379.353024 -383.656346) (xy 379.336988 -383.590859) (xy 379.328911 -383.523923) (xy 379.32891 -383.456501)
			(xy 379.336984 -383.389564) (xy 379.353017 -383.324077) (xy 379.376778 -383.260981) (xy 379.407925 -383.201185)
			(xy 379.44601 -383.14555) (xy 379.467872 -383.119884) (xy 379.473667 -383.112738) (xy 379.48018 -383.095548)
			(xy 379.480572 -383.086356) (xy 379.480572 -382.59385) (xy 379.480144 -382.584665) (xy 379.473643 -382.56748)
			(xy 379.467872 -382.560322) (xy 379.445999 -382.534664) (xy 379.407913 -382.479028) (xy 379.376764 -382.419231)
			(xy 379.353002 -382.356133) (xy 379.336968 -382.290643) (xy 379.328893 -382.223704) (xy 376.050822 -382.223704)
			(xy 376.042786 -382.290466) (xy 376.026815 -382.355847) (xy 376.003144 -382.418851) (xy 375.972113 -382.478575)
			(xy 375.934167 -382.534162) (xy 375.91238 -382.559814) (xy 375.906593 -382.566966) (xy 375.900073 -382.584151)
			(xy 375.89968 -382.593342) (xy 375.89968 -383.086864) (xy 375.900112 -383.096049) (xy 375.906611 -383.113233)
			(xy 375.91238 -383.120392) (xy 375.934183 -383.146031) (xy 375.97213 -383.20162) (xy 376.003162 -383.261346)
			(xy 376.02662 -383.323786) (xy 377.128714 -383.323786) (xy 377.128717 -383.256359) (xy 377.136797 -383.189418)
			(xy 377.152837 -383.123927) (xy 377.176606 -383.060828) (xy 377.207762 -383.001031) (xy 377.245857 -382.945397)
			(xy 377.267724 -382.919732) (xy 377.273535 -382.912597) (xy 377.28004 -382.895399) (xy 377.280424 -382.886204)
			(xy 377.280424 -382.728724) (xy 377.280836 -382.7186) (xy 377.288581 -382.699892) (xy 377.302899 -382.685576)
			(xy 377.321608 -382.677834) (xy 377.331732 -382.677416) (xy 378.048012 -382.677416) (xy 378.058137 -382.677806)
			(xy 378.076844 -382.685561) (xy 378.091159 -382.699886) (xy 378.098901 -382.718598) (xy 378.09932 -382.728724)
			(xy 378.09932 -382.886204) (xy 378.099724 -382.895392) (xy 378.106241 -382.912576) (xy 378.11202 -382.919732)
			(xy 378.133848 -382.945427) (xy 378.171936 -383.001058) (xy 378.203088 -383.06085) (xy 378.226853 -383.123943)
			(xy 378.24289 -383.189428) (xy 378.250969 -383.256363) (xy 378.250972 -383.323783) (xy 378.2429 -383.390719)
			(xy 378.226869 -383.456205) (xy 378.20311 -383.519301) (xy 378.171964 -383.579096) (xy 378.133881 -383.63473)
			(xy 378.11202 -383.660396) (xy 378.106245 -383.667557) (xy 378.099717 -383.684735) (xy 378.09932 -383.693924)
			(xy 378.09932 -384.186176) (xy 378.099737 -384.195363) (xy 378.106245 -384.212547) (xy 378.11202 -384.219704)
			(xy 378.133919 -384.24534) (xy 378.172005 -384.30098) (xy 378.203153 -384.36078) (xy 378.226914 -384.423881)
			(xy 378.242947 -384.489373) (xy 378.251019 -384.556314) (xy 378.251016 -384.62374) (xy 378.242937 -384.69068)
			(xy 378.226898 -384.756171) (xy 378.203131 -384.81927) (xy 378.171977 -384.879067) (xy 378.133885 -384.934702)
			(xy 378.11202 -384.960368) (xy 378.106214 -384.967507) (xy 378.099704 -384.984702) (xy 378.09932 -384.993896)
			(xy 378.09932 -385.151376) (xy 378.098865 -385.161494) (xy 378.091128 -385.180194) (xy 378.076824 -385.194508)
			(xy 378.05813 -385.202258) (xy 378.048012 -385.202684) (xy 377.331732 -385.202684) (xy 377.32161 -385.202258)
			(xy 377.302903 -385.194517) (xy 377.288587 -385.180203) (xy 377.280844 -385.161498) (xy 377.280424 -385.151376)
			(xy 377.280424 -384.993896) (xy 377.280011 -384.984709) (xy 377.273499 -384.967525) (xy 377.267724 -384.960368)
			(xy 377.245895 -384.934674) (xy 377.207803 -384.879044) (xy 377.17665 -384.819252) (xy 377.152882 -384.756159)
			(xy 377.136844 -384.690673) (xy 377.128765 -384.623738) (xy 377.128761 -384.556316) (xy 377.136834 -384.48938)
			(xy 377.152866 -384.423893) (xy 377.176627 -384.360797) (xy 377.207775 -384.301002) (xy 377.245861 -384.245369)
			(xy 377.267724 -384.219704) (xy 377.273504 -384.212547) (xy 377.280028 -384.195365) (xy 377.280424 -384.186176)
			(xy 377.280424 -383.693924) (xy 377.279997 -383.684739) (xy 377.273494 -383.667555) (xy 377.267724 -383.660396)
			(xy 377.245824 -383.63476) (xy 377.207735 -383.579122) (xy 377.176584 -383.519322) (xy 377.152821 -383.456221)
			(xy 377.136787 -383.390728) (xy 377.128714 -383.323786) (xy 376.02662 -383.323786) (xy 376.026833 -383.324352)
			(xy 376.042804 -383.389735) (xy 376.050846 -383.456559) (xy 376.050845 -383.523865) (xy 376.0428 -383.590688)
			(xy 376.026826 -383.656071) (xy 376.003152 -383.719076) (xy 375.972118 -383.778801) (xy 375.934168 -383.834388)
			(xy 375.91238 -383.86004) (xy 375.906582 -383.867184) (xy 375.900069 -383.884375) (xy 375.89968 -383.893568)
			(xy 375.89968 -384.051556) (xy 375.899242 -384.06171) (xy 375.891457 -384.080465) (xy 375.877065 -384.094791)
			(xy 375.858274 -384.102488) (xy 375.848118 -384.102864) (xy 375.131838 -384.102864) (xy 375.121714 -384.102342)
			(xy 375.102995 -384.094628) (xy 375.088637 -384.080352) (xy 375.080816 -384.061677) (xy 375.080276 -384.051556)
			(xy 375.080276 -383.893568) (xy 375.079886 -383.884379) (xy 375.073359 -383.867194) (xy 375.067576 -383.86004)
			(xy 375.045803 -383.834375) (xy 375.007851 -383.778792) (xy 374.976815 -383.71907) (xy 374.95314 -383.656067)
			(xy 374.937165 -383.590686) (xy 374.929119 -383.523864) (xy 374.929117 -383.45656) (xy 374.93716 -383.389738)
			(xy 374.953133 -383.324356) (xy 374.976805 -383.261352) (xy 375.007839 -383.201629) (xy 375.045788 -383.146044)
			(xy 375.067576 -383.120392) (xy 375.073356 -383.113235) (xy 375.079881 -383.096054) (xy 375.080276 -383.086864)
			(xy 375.080276 -382.593342) (xy 375.079851 -382.584156) (xy 375.073348 -382.566971) (xy 375.067576 -382.559814)
			(xy 375.045777 -382.53417) (xy 375.007826 -382.478584) (xy 374.976792 -382.418859) (xy 374.953118 -382.355853)
			(xy 374.937144 -382.29047) (xy 374.9291 -382.223646) (xy 345.250798 -382.223646) (xy 345.242755 -382.290467)
			(xy 345.226782 -382.355849) (xy 345.20311 -382.418853) (xy 345.172077 -382.478576) (xy 345.134128 -382.534162)
			(xy 345.11234 -382.559814) (xy 345.106548 -382.566962) (xy 345.100032 -382.584151) (xy 345.09964 -382.593342)
			(xy 345.09964 -383.086864) (xy 345.100081 -383.096048) (xy 345.106575 -383.113232) (xy 345.11234 -383.120392)
			(xy 345.134144 -383.146031) (xy 345.172094 -383.201619) (xy 345.203127 -383.261344) (xy 345.226566 -383.323727)
			(xy 346.329188 -383.323727) (xy 346.329192 -383.256419) (xy 346.33724 -383.189593) (xy 346.353218 -383.124208)
			(xy 346.376897 -383.061202) (xy 346.407937 -383.001478) (xy 346.445893 -382.945892) (xy 346.467684 -382.92024)
			(xy 346.473487 -382.913099) (xy 346.479998 -382.895905) (xy 346.480384 -382.886712) (xy 346.480384 -382.728724)
			(xy 346.480841 -382.718573) (xy 346.488625 -382.699825) (xy 346.503011 -382.685501) (xy 346.521794 -382.677797)
			(xy 346.531946 -382.677416) (xy 347.248226 -382.677416) (xy 347.258351 -382.677904) (xy 347.277069 -382.685636)
			(xy 347.291423 -382.699921) (xy 347.299246 -382.718601) (xy 347.299788 -382.728724) (xy 347.299788 -382.886712)
			(xy 347.300195 -382.895899) (xy 347.306711 -382.913084) (xy 347.312488 -382.92024) (xy 347.33424 -382.945922)
			(xy 347.372188 -383.001504) (xy 347.403221 -383.061224) (xy 347.426895 -383.124225) (xy 347.442869 -383.189603)
			(xy 347.450916 -383.256422) (xy 347.450919 -383.323724) (xy 347.442879 -383.390543) (xy 347.426911 -383.455923)
			(xy 347.403243 -383.518926) (xy 347.372216 -383.578649) (xy 347.334273 -383.634236) (xy 347.312488 -383.659888)
			(xy 347.30667 -383.667018) (xy 347.300169 -383.68422) (xy 347.299788 -383.693416) (xy 347.299788 -384.186684)
			(xy 347.300209 -384.19587) (xy 347.306715 -384.213054) (xy 347.312488 -384.220212) (xy 347.33431 -384.245835)
			(xy 347.372256 -384.301427) (xy 347.403286 -384.361154) (xy 347.426956 -384.424163) (xy 347.442926 -384.489548)
			(xy 347.450967 -384.556373) (xy 347.450963 -384.623681) (xy 347.442916 -384.690505) (xy 347.42694 -384.755889)
			(xy 347.403264 -384.818895) (xy 347.372228 -384.87862) (xy 347.334277 -384.934207) (xy 347.312488 -384.95986)
			(xy 347.306682 -384.966999) (xy 347.300173 -384.984194) (xy 347.299788 -384.993388) (xy 347.299788 -385.151376)
			(xy 347.299359 -385.16153) (xy 347.291569 -385.180284) (xy 347.277174 -385.194609) (xy 347.258382 -385.202307)
			(xy 347.248226 -385.202684) (xy 346.531946 -385.202684) (xy 346.521825 -385.202136) (xy 346.50311 -385.194428)
			(xy 346.488753 -385.180161) (xy 346.480928 -385.161494) (xy 346.480384 -385.151376) (xy 346.480384 -384.993388)
			(xy 346.479983 -384.9842) (xy 346.473463 -384.967015) (xy 346.467684 -384.95986) (xy 346.44593 -384.934179)
			(xy 346.407977 -384.878598) (xy 346.37694 -384.818879) (xy 346.353263 -384.755878) (xy 346.337287 -384.690499)
			(xy 346.329239 -384.623679) (xy 346.329236 -384.556376) (xy 346.337277 -384.489555) (xy 346.353247 -384.424174)
			(xy 346.376918 -384.361171) (xy 346.40795 -384.301448) (xy 346.445897 -384.245864) (xy 346.467684 -384.220212)
			(xy 346.473499 -384.213079) (xy 346.480003 -384.195879) (xy 346.480384 -384.186684) (xy 346.480384 -383.693416)
			(xy 346.47997 -383.684229) (xy 346.473459 -383.667045) (xy 346.467684 -383.659888) (xy 346.44586 -383.634266)
			(xy 346.407909 -383.578676) (xy 346.376875 -383.518949) (xy 346.353202 -383.45594) (xy 346.33723 -383.390554)
			(xy 346.329188 -383.323727) (xy 345.226566 -383.323727) (xy 345.2268 -383.32435) (xy 345.242773 -383.389734)
			(xy 345.250816 -383.456559) (xy 345.250814 -383.523865) (xy 345.242768 -383.590689) (xy 345.226793 -383.656073)
			(xy 345.203118 -383.719078) (xy 345.172081 -383.778802) (xy 345.134129 -383.834388) (xy 345.11234 -383.86004)
			(xy 345.106537 -383.86718) (xy 345.100028 -383.884375) (xy 345.09964 -383.893568) (xy 345.09964 -384.051556)
			(xy 345.099143 -384.061702) (xy 345.09137 -384.080446) (xy 345.076996 -384.094769) (xy 345.058226 -384.102478)
			(xy 345.048078 -384.102864) (xy 344.331798 -384.102864) (xy 344.321672 -384.102375) (xy 344.302951 -384.094647)
			(xy 344.288595 -384.080362) (xy 344.280775 -384.06168) (xy 344.280236 -384.051556) (xy 344.280236 -383.893568)
			(xy 344.279833 -383.88438) (xy 344.273313 -383.867196) (xy 344.267536 -383.86004) (xy 344.245764 -383.834375)
			(xy 344.207815 -383.77879) (xy 344.176781 -383.719068) (xy 344.153108 -383.656066) (xy 344.137134 -383.590685)
			(xy 344.129089 -383.523864) (xy 344.129087 -383.45656) (xy 344.13713 -383.389739) (xy 344.153101 -383.324358)
			(xy 344.176772 -383.261354) (xy 344.207803 -383.201631) (xy 344.24575 -383.146044) (xy 344.267536 -383.120392)
			(xy 344.273323 -383.11324) (xy 344.279843 -383.096055) (xy 344.280236 -383.086864) (xy 344.280236 -382.593342)
			(xy 344.279797 -382.584158) (xy 344.273303 -382.566974) (xy 344.267536 -382.559814) (xy 344.245738 -382.53417)
			(xy 344.20779 -382.478582) (xy 344.176757 -382.418858) (xy 344.153085 -382.355852) (xy 344.137113 -382.290469)
			(xy 344.12907 -382.223645) (xy 340.851007 -382.223645) (xy 340.842964 -382.290467) (xy 340.826992 -382.355848)
			(xy 340.80332 -382.418853) (xy 340.772287 -382.478576) (xy 340.734339 -382.534162) (xy 340.712552 -382.559814)
			(xy 340.706761 -382.566963) (xy 340.700244 -382.584151) (xy 340.699852 -382.593342) (xy 340.699852 -383.086864)
			(xy 340.70029 -383.096048) (xy 340.706785 -383.113232) (xy 340.712552 -383.120392) (xy 340.734356 -383.146031)
			(xy 340.772305 -383.201619) (xy 340.803338 -383.261344) (xy 340.826798 -383.323786) (xy 341.928893 -383.323786)
			(xy 341.928896 -383.25636) (xy 341.936975 -383.189419) (xy 341.953015 -383.123928) (xy 341.976783 -383.06083)
			(xy 342.007937 -383.001032) (xy 342.04603 -382.945397) (xy 342.067896 -382.919732) (xy 342.073703 -382.912594)
			(xy 342.080212 -382.895398) (xy 342.080596 -382.886204) (xy 342.080596 -382.728724) (xy 342.081035 -382.718604)
			(xy 342.088775 -382.699901) (xy 342.103084 -382.685586) (xy 342.121784 -382.677839) (xy 342.131904 -382.677416)
			(xy 342.848184 -382.677416) (xy 342.858307 -382.677829) (xy 342.877014 -382.685575) (xy 342.891329 -382.699893)
			(xy 342.899072 -382.7186) (xy 342.899492 -382.728724) (xy 342.899492 -382.886204) (xy 342.899902 -382.895391)
			(xy 342.906416 -382.912575) (xy 342.912192 -382.919732) (xy 342.934021 -382.945426) (xy 342.972111 -383.001056)
			(xy 343.003264 -383.060849) (xy 343.02703 -383.123942) (xy 343.043069 -383.189427) (xy 343.051148 -383.256362)
			(xy 343.051151 -383.323783) (xy 343.043078 -383.390719) (xy 343.027046 -383.456207) (xy 343.003286 -383.519302)
			(xy 342.972139 -383.579097) (xy 342.934054 -383.634731) (xy 342.912192 -383.660396) (xy 342.906414 -383.667554)
			(xy 342.899888 -383.684735) (xy 342.899492 -383.693924) (xy 342.899492 -384.186176) (xy 342.899916 -384.195362)
			(xy 342.90642 -384.212546) (xy 342.912192 -384.219704) (xy 342.934092 -384.24534) (xy 342.97218 -384.300978)
			(xy 343.003329 -384.360779) (xy 343.027092 -384.423879) (xy 343.043125 -384.489372) (xy 343.051198 -384.556314)
			(xy 343.051195 -384.62374) (xy 343.043115 -384.690681) (xy 343.027076 -384.756172) (xy 343.003307 -384.819271)
			(xy 342.972152 -384.879068) (xy 342.934058 -384.934703) (xy 342.912192 -384.960368) (xy 342.906383 -384.967504)
			(xy 342.899876 -384.984702) (xy 342.899492 -384.993896) (xy 342.899492 -385.151376) (xy 342.899064 -385.161498)
			(xy 342.891323 -385.180203) (xy 342.877009 -385.194518) (xy 342.858306 -385.202263) (xy 342.848184 -385.202684)
			(xy 342.131904 -385.202684) (xy 342.12178 -385.20228) (xy 342.103073 -385.194531) (xy 342.088758 -385.18021)
			(xy 342.081016 -385.1615) (xy 342.080596 -385.151376) (xy 342.080596 -384.993896) (xy 342.080189 -384.984709)
			(xy 342.073673 -384.967524) (xy 342.067896 -384.960368) (xy 342.046068 -384.934674) (xy 342.007978 -384.879043)
			(xy 341.976826 -384.819251) (xy 341.95306 -384.756158) (xy 341.937022 -384.690672) (xy 341.928943 -384.623737)
			(xy 341.92894 -384.556317) (xy 341.937012 -384.489381) (xy 341.953044 -384.423894) (xy 341.976804 -384.360799)
			(xy 342.00795 -384.301003) (xy 342.046034 -384.245369) (xy 342.067896 -384.219704) (xy 342.073673 -384.212545)
			(xy 342.080199 -384.195365) (xy 342.080596 -384.186176) (xy 342.080596 -383.693924) (xy 342.080175 -383.684738)
			(xy 342.073669 -383.667553) (xy 342.067896 -383.660396) (xy 342.045997 -383.63476) (xy 342.007909 -383.579121)
			(xy 341.976761 -383.519321) (xy 341.952999 -383.45622) (xy 341.936966 -383.390728) (xy 341.928893 -383.323786)
			(xy 340.826798 -383.323786) (xy 340.82701 -383.324351) (xy 340.842982 -383.389735) (xy 340.851025 -383.456559)
			(xy 340.851024 -383.523865) (xy 340.842978 -383.590689) (xy 340.827003 -383.656072) (xy 340.803328 -383.719078)
			(xy 340.772292 -383.778802) (xy 340.734341 -383.834388) (xy 340.712552 -383.86004) (xy 340.70675 -383.867181)
			(xy 340.70024 -383.884375) (xy 340.699852 -383.893568) (xy 340.699852 -384.051556) (xy 340.699343 -384.061701)
			(xy 340.691572 -384.080442) (xy 340.677202 -384.094765) (xy 340.658436 -384.102476) (xy 340.64829 -384.102864)
			(xy 339.93201 -384.102864) (xy 339.921884 -384.102365) (xy 339.903164 -384.094642) (xy 339.888808 -384.080359)
			(xy 339.880987 -384.061679) (xy 339.880448 -384.051556) (xy 339.880448 -383.893568) (xy 339.880042 -383.884381)
			(xy 339.873524 -383.867197) (xy 339.867748 -383.86004) (xy 339.845976 -383.834375) (xy 339.808026 -383.778791)
			(xy 339.776992 -383.719069) (xy 339.753318 -383.656066) (xy 339.737343 -383.590685) (xy 339.729298 -383.523864)
			(xy 339.729296 -383.45656) (xy 339.737339 -383.389738) (xy 339.75331 -383.324357) (xy 339.776982 -383.261353)
			(xy 339.808014 -383.20163) (xy 339.845961 -383.146044) (xy 339.867748 -383.120392) (xy 339.873536 -383.113241)
			(xy 339.880055 -383.096055) (xy 339.880448 -383.086864) (xy 339.880448 -382.593342) (xy 339.880007 -382.584158)
			(xy 339.873513 -382.566974) (xy 339.867748 -382.559814) (xy 339.84595 -382.53417) (xy 339.808001 -382.478583)
			(xy 339.776968 -382.418858) (xy 339.753295 -382.355852) (xy 339.737322 -382.290469) (xy 339.729279 -382.223645)
			(xy 336.45124 -382.223645) (xy 336.45124 -382.223704) (xy 336.443164 -382.290643) (xy 336.427128 -382.356132)
			(xy 336.403363 -382.419228) (xy 336.372211 -382.479024) (xy 336.334121 -382.534658) (xy 336.312256 -382.560322)
			(xy 336.306462 -382.567469) (xy 336.299947 -382.584658) (xy 336.299556 -382.59385) (xy 336.299556 -383.086356)
			(xy 336.299997 -383.09554) (xy 336.306491 -383.112724) (xy 336.312256 -383.119884) (xy 336.334137 -383.145536)
			(xy 336.372228 -383.201171) (xy 336.403381 -383.260969) (xy 336.427018 -383.323726) (xy 337.529124 -383.323726)
			(xy 337.529128 -383.256419) (xy 337.537175 -383.189595) (xy 337.55315 -383.124211) (xy 337.576825 -383.061205)
			(xy 337.607861 -383.001481) (xy 337.645811 -382.945893) (xy 337.6676 -382.92024) (xy 337.673405 -382.9131)
			(xy 337.679914 -382.895906) (xy 337.6803 -382.886712) (xy 337.6803 -382.728724) (xy 337.680741 -382.718571)
			(xy 337.688529 -382.699819) (xy 337.70292 -382.685495) (xy 337.721708 -382.677795) (xy 337.731862 -382.677416)
			(xy 338.448142 -382.677416) (xy 338.458268 -382.677891) (xy 338.476986 -382.685629) (xy 338.49134 -382.699918)
			(xy 338.499162 -382.7186) (xy 338.499704 -382.728724) (xy 338.499704 -382.886712) (xy 338.500108 -382.8959)
			(xy 338.506626 -382.913084) (xy 338.512404 -382.92024) (xy 338.534155 -382.945922) (xy 338.572102 -383.001505)
			(xy 338.603135 -383.061225) (xy 338.626808 -383.124225) (xy 338.642782 -383.189604) (xy 338.650828 -383.256422)
			(xy 338.650831 -383.323724) (xy 338.642791 -383.390543) (xy 338.626824 -383.455923) (xy 338.603157 -383.518926)
			(xy 338.57213 -383.578648) (xy 338.534188 -383.634235) (xy 338.512404 -383.659888) (xy 338.506588 -383.66702)
			(xy 338.500085 -383.68422) (xy 338.499704 -383.693416) (xy 338.499704 -384.186684) (xy 338.500121 -384.19587)
			(xy 338.50663 -384.213055) (xy 338.512404 -384.220212) (xy 338.534226 -384.245836) (xy 338.572171 -384.301427)
			(xy 338.6032 -384.361155) (xy 338.626869 -384.424163) (xy 338.642838 -384.489548) (xy 338.650879 -384.556374)
			(xy 338.650875 -384.623681) (xy 338.642828 -384.690505) (xy 338.626853 -384.755889) (xy 338.603178 -384.818894)
			(xy 338.572143 -384.878619) (xy 338.534193 -384.934207) (xy 338.512404 -384.95986) (xy 338.5066 -384.967)
			(xy 338.50009 -384.984194) (xy 338.499704 -384.993388) (xy 338.499704 -385.151376) (xy 338.499259 -385.161528)
			(xy 338.491472 -385.180279) (xy 338.477082 -385.194603) (xy 338.458296 -385.202305) (xy 338.448142 -385.202684)
			(xy 337.731862 -385.202684) (xy 337.721736 -385.202205) (xy 337.703018 -385.194469) (xy 337.688664 -385.180181)
			(xy 337.680842 -385.1615) (xy 337.6803 -385.151376) (xy 337.6803 -384.993388) (xy 337.679895 -384.9842)
			(xy 337.673378 -384.967016) (xy 337.6676 -384.95986) (xy 337.645849 -384.934178) (xy 337.607901 -384.878595)
			(xy 337.576869 -384.818875) (xy 337.553196 -384.755875) (xy 337.537221 -384.690497) (xy 337.529175 -384.623678)
			(xy 337.529172 -384.556376) (xy 337.537212 -384.489557) (xy 337.55318 -384.424177) (xy 337.576847 -384.361174)
			(xy 337.607874 -384.301451) (xy 337.645816 -384.245865) (xy 337.6676 -384.220212) (xy 337.673416 -384.213081)
			(xy 337.679919 -384.19588) (xy 337.6803 -384.186684) (xy 337.6803 -383.693416) (xy 337.679882 -383.68423)
			(xy 337.673374 -383.667045) (xy 337.6676 -383.659888) (xy 337.645778 -383.634264) (xy 337.607833 -383.578673)
			(xy 337.576803 -383.518945) (xy 337.553134 -383.455937) (xy 337.537165 -383.390552) (xy 337.529124 -383.323726)
			(xy 336.427018 -383.323726) (xy 336.427146 -383.324067) (xy 336.443182 -383.389559) (xy 336.451257 -383.456499)
			(xy 336.451256 -383.523925) (xy 336.443177 -383.590865) (xy 336.427139 -383.656356) (xy 336.403371 -383.719453)
			(xy 336.372216 -383.77925) (xy 336.334122 -383.834883) (xy 336.312256 -383.860548) (xy 336.306451 -383.867687)
			(xy 336.299943 -383.884882) (xy 336.299556 -383.894076) (xy 336.299556 -384.051556) (xy 336.29898 -384.061655)
			(xy 336.291267 -384.080321) (xy 336.276999 -384.094616) (xy 336.258346 -384.102362) (xy 336.248248 -384.102864)
			(xy 335.531968 -384.102864) (xy 335.521839 -384.102509) (xy 335.503128 -384.094744) (xy 335.488813 -384.080408)
			(xy 335.481076 -384.061686) (xy 335.48066 -384.051556) (xy 335.48066 -383.894076) (xy 335.480248 -383.884889)
			(xy 335.473734 -383.867706) (xy 335.46796 -383.860548) (xy 335.446113 -383.834869) (xy 335.408027 -383.779236)
			(xy 335.376877 -383.719441) (xy 335.353114 -383.656346) (xy 335.337079 -383.590859) (xy 335.329002 -383.523923)
			(xy 335.329001 -383.456501) (xy 335.337074 -383.389565) (xy 335.353107 -383.324077) (xy 335.376868 -383.260981)
			(xy 335.408014 -383.201185) (xy 335.446098 -383.14555) (xy 335.46796 -383.119884) (xy 335.473753 -383.112737)
			(xy 335.480268 -383.095548) (xy 335.48066 -383.086356) (xy 335.48066 -382.59385) (xy 335.480213 -382.584667)
			(xy 335.473723 -382.567483) (xy 335.46796 -382.560322) (xy 335.446088 -382.534664) (xy 335.408002 -382.479028)
			(xy 335.376854 -382.41923) (xy 335.353092 -382.356132) (xy 335.337058 -382.290643) (xy 335.328984 -382.223704)
			(xy 332.050913 -382.223704) (xy 332.042877 -382.290466) (xy 332.026905 -382.355848) (xy 332.003234 -382.418852)
			(xy 331.972202 -382.478575) (xy 331.934255 -382.534162) (xy 331.912468 -382.559814) (xy 331.906679 -382.566964)
			(xy 331.90016 -382.584151) (xy 331.899768 -382.593342) (xy 331.899768 -383.086864) (xy 331.900203 -383.096048)
			(xy 331.9067 -383.113233) (xy 331.912468 -383.120392) (xy 331.934271 -383.146031) (xy 331.972219 -383.20162)
			(xy 332.003251 -383.261345) (xy 332.026711 -383.323786) (xy 333.128805 -383.323786) (xy 333.128808 -383.25636)
			(xy 333.136888 -383.189419) (xy 333.152927 -383.123927) (xy 333.176696 -383.060829) (xy 333.207852 -383.001032)
			(xy 333.245945 -382.945397) (xy 333.267812 -382.919732) (xy 333.273621 -382.912596) (xy 333.280128 -382.895398)
			(xy 333.280512 -382.886204) (xy 333.280512 -382.728724) (xy 333.280936 -382.718602) (xy 333.288678 -382.699896)
			(xy 333.302993 -382.685581) (xy 333.321698 -382.677837) (xy 333.33182 -382.677416) (xy 334.0481 -382.677416)
			(xy 334.058224 -382.677816) (xy 334.076931 -382.685568) (xy 334.091246 -382.699889) (xy 334.098988 -382.718599)
			(xy 334.099408 -382.728724) (xy 334.099408 -382.886204) (xy 334.099815 -382.895392) (xy 334.106331 -382.912576)
			(xy 334.112108 -382.919732) (xy 334.133936 -382.945427) (xy 334.172026 -383.001057) (xy 334.203177 -383.060849)
			(xy 334.226943 -383.123942) (xy 334.242981 -383.189428) (xy 334.25106 -383.256363) (xy 334.251063 -383.323783)
			(xy 334.242991 -383.390719) (xy 334.226959 -383.456206) (xy 334.2032 -383.519301) (xy 334.172053 -383.579096)
			(xy 334.13397 -383.634731) (xy 334.112108 -383.660396) (xy 334.106332 -383.667556) (xy 334.099805 -383.684735)
			(xy 334.099408 -383.693924) (xy 334.099408 -384.186176) (xy 334.099828 -384.195362) (xy 334.106335 -384.212547)
			(xy 334.112108 -384.219704) (xy 334.134007 -384.24534) (xy 334.172094 -384.300979) (xy 334.203243 -384.360779)
			(xy 334.227005 -384.42388) (xy 334.243037 -384.489373) (xy 334.25111 -384.556314) (xy 334.251107 -384.62374)
			(xy 334.243028 -384.690681) (xy 334.226989 -384.756172) (xy 334.203221 -384.81927) (xy 334.172066 -384.879067)
			(xy 334.133974 -384.934703) (xy 334.112108 -384.960368) (xy 334.106301 -384.967506) (xy 334.099792 -384.984702)
			(xy 334.099408 -384.993896) (xy 334.099408 -385.151376) (xy 334.098965 -385.161496) (xy 334.091226 -385.180198)
			(xy 334.076918 -385.194512) (xy 334.05822 -385.20226) (xy 334.0481 -385.202684) (xy 333.33182 -385.202684)
			(xy 333.321697 -385.202267) (xy 333.302991 -385.194523) (xy 333.288675 -385.180206) (xy 333.280932 -385.161499)
			(xy 333.280512 -385.151376) (xy 333.280512 -384.993896) (xy 333.280101 -384.984709) (xy 333.273587 -384.967525)
			(xy 333.267812 -384.960368) (xy 333.245983 -384.934674) (xy 333.207892 -384.879044) (xy 333.176739 -384.819252)
			(xy 333.152973 -384.756158) (xy 333.136934 -384.690673) (xy 333.128855 -384.623738) (xy 333.128852 -384.556316)
			(xy 333.136925 -384.48938) (xy 333.152957 -384.423893) (xy 333.176717 -384.360798) (xy 333.207865 -384.301003)
			(xy 333.24595 -384.245369) (xy 333.267812 -384.219704) (xy 333.273591 -384.212546) (xy 333.280116 -384.195365)
			(xy 333.280512 -384.186176) (xy 333.280512 -383.693924) (xy 333.280088 -383.684738) (xy 333.273583 -383.667554)
			(xy 333.267812 -383.660396) (xy 333.245912 -383.63476) (xy 333.207824 -383.579122) (xy 333.176674 -383.519322)
			(xy 333.152911 -383.456221) (xy 333.136878 -383.390728) (xy 333.128805 -383.323786) (xy 332.026711 -383.323786)
			(xy 332.026923 -383.324351) (xy 332.042895 -383.389735) (xy 332.050937 -383.456559) (xy 332.050936 -383.523865)
			(xy 332.04289 -383.590689) (xy 332.026916 -383.656072) (xy 332.003242 -383.719077) (xy 331.972207 -383.778801)
			(xy 331.934257 -383.834388) (xy 331.912468 -383.86004) (xy 331.906668 -383.867183) (xy 331.900156 -383.884375)
			(xy 331.899768 -383.893568) (xy 331.899768 -384.051556) (xy 331.899342 -384.061711) (xy 331.891555 -384.080469)
			(xy 331.877159 -384.094795) (xy 331.858363 -384.10249) (xy 331.848206 -384.102864) (xy 331.131926 -384.102864)
			(xy 331.121801 -384.102352) (xy 331.103082 -384.094634) (xy 331.088724 -384.080355) (xy 331.080904 -384.061678)
			(xy 331.080364 -384.051556) (xy 331.080364 -383.893568) (xy 331.079955 -383.884381) (xy 331.073439 -383.867198)
			(xy 331.067664 -383.86004) (xy 331.045891 -383.834375) (xy 331.00794 -383.778791) (xy 330.976905 -383.71907)
			(xy 330.95323 -383.656067) (xy 330.937256 -383.590686) (xy 330.92921 -383.523864) (xy 330.929208 -383.45656)
			(xy 330.937251 -383.389738) (xy 330.953223 -383.324356) (xy 330.976895 -383.261352) (xy 331.007928 -383.20163)
			(xy 331.045877 -383.146044) (xy 331.067664 -383.120392) (xy 331.073454 -383.113243) (xy 331.079971 -383.096055)
			(xy 331.080364 -383.086864) (xy 331.080364 -382.593342) (xy 331.079919 -382.584159) (xy 331.073428 -382.566975)
			(xy 331.067664 -382.559814) (xy 331.045866 -382.53417) (xy 331.007916 -382.478583) (xy 330.976881 -382.418859)
			(xy 330.953208 -382.355853) (xy 330.937235 -382.29047) (xy 330.929191 -382.223646) (xy 301.250888 -382.223646)
			(xy 301.250888 -382.223704) (xy 301.242813 -382.290641) (xy 301.226779 -382.356129) (xy 301.203017 -382.419226)
			(xy 301.171869 -382.479022) (xy 301.133783 -382.534656) (xy 301.11192 -382.560322) (xy 301.106134 -382.567475)
			(xy 301.099612 -382.584659) (xy 301.09922 -382.59385) (xy 301.09922 -383.086356) (xy 301.099647 -383.095542)
			(xy 301.106148 -383.112726) (xy 301.11192 -383.119884) (xy 301.133799 -383.145537) (xy 301.171886 -383.201173)
			(xy 301.203035 -383.260972) (xy 301.22669 -383.323786) (xy 302.328775 -383.323786) (xy 302.328778 -383.25636)
			(xy 302.336857 -383.18942) (xy 302.352895 -383.123929) (xy 302.376662 -383.060831) (xy 302.407816 -383.001033)
			(xy 302.445907 -382.945398) (xy 302.467772 -382.919732) (xy 302.473589 -382.912601) (xy 302.480089 -382.895399)
			(xy 302.480472 -382.886204) (xy 302.480472 -382.728724) (xy 302.480935 -382.718606) (xy 302.48867 -382.699909)
			(xy 302.502972 -382.685595) (xy 302.521663 -382.677843) (xy 302.53178 -382.677416) (xy 303.24806 -382.677416)
			(xy 303.258182 -382.677849) (xy 303.276888 -382.685587) (xy 303.291204 -382.699899) (xy 303.298948 -382.718602)
			(xy 303.299368 -382.728724) (xy 303.299368 -382.886204) (xy 303.299783 -382.89539) (xy 303.306294 -382.912575)
			(xy 303.312068 -382.919732) (xy 303.333898 -382.945426) (xy 303.37199 -383.001056) (xy 303.403144 -383.060847)
			(xy 303.426911 -383.123941) (xy 303.44295 -383.189427) (xy 303.451029 -383.256362) (xy 303.451033 -383.323784)
			(xy 303.44296 -383.39072) (xy 303.426927 -383.456208) (xy 303.403166 -383.519303) (xy 303.372017 -383.579098)
			(xy 303.333931 -383.634731) (xy 303.312068 -383.660396) (xy 303.306286 -383.667552) (xy 303.299764 -383.684734)
			(xy 303.299368 -383.693924) (xy 303.299368 -384.186176) (xy 303.299797 -384.195361) (xy 303.306299 -384.212545)
			(xy 303.312068 -384.219704) (xy 303.333968 -384.24534) (xy 303.372058 -384.300978) (xy 303.403209 -384.360778)
			(xy 303.426973 -384.423878) (xy 303.443007 -384.489371) (xy 303.45108 -384.556313) (xy 303.451077 -384.623741)
			(xy 303.442997 -384.690682) (xy 303.426957 -384.756173) (xy 303.403187 -384.819272) (xy 303.37203 -384.879069)
			(xy 303.333935 -384.934703) (xy 303.312068 -384.960368) (xy 303.306256 -384.967502) (xy 303.299751 -384.984701)
			(xy 303.299368 -384.993896) (xy 303.299368 -385.151376) (xy 303.298964 -385.161501) (xy 303.291218 -385.18021)
			(xy 303.276897 -385.194527) (xy 303.258185 -385.202267) (xy 303.24806 -385.202684) (xy 302.53178 -385.202684)
			(xy 302.521654 -385.2023) (xy 302.502947 -385.194542) (xy 302.488633 -385.180216) (xy 302.480891 -385.161502)
			(xy 302.480472 -385.151376) (xy 302.480472 -384.993896) (xy 302.48007 -384.984708) (xy 302.473551 -384.967523)
			(xy 302.467772 -384.960368) (xy 302.445944 -384.934673) (xy 302.407856 -384.879042) (xy 302.376706 -384.81925)
			(xy 302.352941 -384.756157) (xy 302.336904 -384.690672) (xy 302.328825 -384.623737) (xy 302.328822 -384.556317)
			(xy 302.336894 -384.489382) (xy 302.352925 -384.423895) (xy 302.376684 -384.3608) (xy 302.407829 -384.301004)
			(xy 302.445911 -384.24537) (xy 302.467772 -384.219704) (xy 302.473558 -384.212552) (xy 302.480077 -384.195366)
			(xy 302.480472 -384.186176) (xy 302.480472 -383.693924) (xy 302.480057 -383.684737) (xy 302.473547 -383.667552)
			(xy 302.467772 -383.660396) (xy 302.445874 -383.634759) (xy 302.407788 -383.57912) (xy 302.37664 -383.51932)
			(xy 302.352879 -383.456219) (xy 302.336847 -383.390727) (xy 302.328775 -383.323786) (xy 301.22669 -383.323786)
			(xy 301.226797 -383.32407) (xy 301.242831 -383.38956) (xy 301.250905 -383.4565) (xy 301.250904 -383.523924)
			(xy 301.242827 -383.590863) (xy 301.22679 -383.656353) (xy 301.203025 -383.71945) (xy 301.171874 -383.779247)
			(xy 301.133784 -383.834882) (xy 301.11192 -383.860548) (xy 301.106123 -383.867693) (xy 301.099608 -383.884884)
			(xy 301.09922 -383.894076) (xy 301.09922 -384.051556) (xy 301.098748 -384.061673) (xy 301.091018 -384.080372)
			(xy 301.076719 -384.094687) (xy 301.058029 -384.102437) (xy 301.047912 -384.102864) (xy 300.331632 -384.102864)
			(xy 300.321507 -384.102457) (xy 300.302797 -384.094713) (xy 300.28848 -384.080393) (xy 300.28074 -384.061681)
			(xy 300.280324 -384.051556) (xy 300.280324 -383.894076) (xy 300.27992 -383.884888) (xy 300.273402 -383.867704)
			(xy 300.267624 -383.860548) (xy 300.245775 -383.83487) (xy 300.207684 -383.779238) (xy 300.176531 -383.719444)
			(xy 300.152765 -383.656349) (xy 300.136728 -383.590861) (xy 300.12865 -383.523923) (xy 300.128649 -383.456501)
			(xy 300.136724 -383.389563) (xy 300.152758 -383.324074) (xy 300.176522 -383.260978) (xy 300.207672 -383.201183)
			(xy 300.24576 -383.145549) (xy 300.267624 -383.119884) (xy 300.273413 -383.112733) (xy 300.279931 -383.095547)
			(xy 300.280324 -383.086356) (xy 300.280324 -382.59385) (xy 300.279884 -382.584666) (xy 300.273391 -382.567482)
			(xy 300.267624 -382.560322) (xy 300.245749 -382.534665) (xy 300.207659 -382.47903) (xy 300.176508 -382.419233)
			(xy 300.152743 -382.356135) (xy 300.136708 -382.290645) (xy 300.128632 -382.223705) (xy 296.851097 -382.223705)
			(xy 296.843022 -382.290641) (xy 296.826989 -382.356129) (xy 296.803227 -382.419225) (xy 296.77208 -382.479021)
			(xy 296.733994 -382.534656) (xy 296.712132 -382.560322) (xy 296.706335 -382.567467) (xy 296.699823 -382.584658)
			(xy 296.699432 -382.59385) (xy 296.699432 -383.086356) (xy 296.699878 -383.095539) (xy 296.706368 -383.112723)
			(xy 296.712132 -383.119884) (xy 296.734011 -383.145537) (xy 296.772097 -383.201174) (xy 296.803245 -383.260972)
			(xy 296.826877 -383.323727) (xy 297.928982 -383.323727) (xy 297.928985 -383.256419) (xy 297.937033 -383.189593)
			(xy 297.953011 -383.124208) (xy 297.97669 -383.061202) (xy 298.007729 -383.001478) (xy 298.045685 -382.945891)
			(xy 298.067476 -382.92024) (xy 298.073278 -382.913098) (xy 298.07979 -382.895905) (xy 298.080176 -382.886712)
			(xy 298.080176 -382.728724) (xy 298.080641 -382.718574) (xy 298.088424 -382.699827) (xy 298.102807 -382.685504)
			(xy 298.121587 -382.677799) (xy 298.131738 -382.677416) (xy 298.848018 -382.677416) (xy 298.858143 -382.677911)
			(xy 298.87686 -382.68564) (xy 298.891215 -382.699923) (xy 298.899038 -382.718602) (xy 298.89958 -382.728724)
			(xy 298.89958 -382.886712) (xy 298.899989 -382.895899) (xy 298.906504 -382.913083) (xy 298.91228 -382.92024)
			(xy 298.934031 -382.945922) (xy 298.97198 -383.001504) (xy 299.003014 -383.061224) (xy 299.026688 -383.124225)
			(xy 299.042663 -383.189603) (xy 299.050709 -383.256422) (xy 299.050713 -383.323724) (xy 299.042672 -383.390544)
			(xy 299.026704 -383.455924) (xy 299.003036 -383.518926) (xy 298.972008 -383.578649) (xy 298.934065 -383.634235)
			(xy 298.91228 -383.659888) (xy 298.906461 -383.667017) (xy 298.89996 -383.68422) (xy 298.89958 -383.693416)
			(xy 298.89958 -384.186684) (xy 298.900003 -384.19587) (xy 298.906508 -384.213054) (xy 298.91228 -384.220212)
			(xy 298.934103 -384.245835) (xy 298.972049 -384.301426) (xy 299.00308 -384.361154) (xy 299.02675 -384.424162)
			(xy 299.04272 -384.489548) (xy 299.050761 -384.556373) (xy 299.050757 -384.623681) (xy 299.04271 -384.690506)
			(xy 299.026734 -384.75589) (xy 299.003058 -384.818895) (xy 298.972021 -384.87862) (xy 298.934069 -384.934208)
			(xy 298.91228 -384.95986) (xy 298.906473 -384.966998) (xy 298.899965 -384.984194) (xy 298.89958 -384.993388)
			(xy 298.89958 -385.151376) (xy 298.899159 -385.161531) (xy 298.891367 -385.180287) (xy 298.87697 -385.194612)
			(xy 298.858175 -385.202309) (xy 298.848018 -385.202684) (xy 298.131738 -385.202684) (xy 298.121617 -385.202143)
			(xy 298.102901 -385.194432) (xy 298.088544 -385.180162) (xy 298.08072 -385.161494) (xy 298.080176 -385.151376)
			(xy 298.080176 -384.993388) (xy 298.079777 -384.9842) (xy 298.073256 -384.967015) (xy 298.067476 -384.95986)
			(xy 298.045723 -384.934179) (xy 298.00777 -384.878598) (xy 297.976733 -384.818878) (xy 297.953057 -384.755878)
			(xy 297.93708 -384.690499) (xy 297.929033 -384.623679) (xy 297.92903 -384.556376) (xy 297.937071 -384.489555)
			(xy 297.953041 -384.424174) (xy 297.976711 -384.361171) (xy 298.007742 -384.301449) (xy 298.045689 -384.245864)
			(xy 298.067476 -384.220212) (xy 298.07329 -384.213079) (xy 298.079795 -384.195879) (xy 298.080176 -384.186684)
			(xy 298.080176 -383.693416) (xy 298.079764 -383.684229) (xy 298.073252 -383.667044) (xy 298.067476 -383.659888)
			(xy 298.045651 -383.634266) (xy 298.007701 -383.578676) (xy 297.976668 -383.518948) (xy 297.952995 -383.45594)
			(xy 297.937024 -383.390554) (xy 297.928982 -383.323727) (xy 296.826877 -383.323727) (xy 296.827007 -383.324071)
			(xy 296.84304 -383.389561) (xy 296.851114 -383.4565) (xy 296.851113 -383.523924) (xy 296.843036 -383.590863)
			(xy 296.827 -383.656352) (xy 296.803235 -383.71945) (xy 296.772084 -383.779247) (xy 296.733996 -383.834882)
			(xy 296.712132 -383.860548) (xy 296.706324 -383.867685) (xy 296.699818 -383.884882) (xy 296.699432 -383.894076)
			(xy 296.699432 -384.051556) (xy 296.698949 -384.061672) (xy 296.691221 -384.080368) (xy 296.676925 -384.094683)
			(xy 296.658239 -384.102435) (xy 296.648124 -384.102864) (xy 295.931844 -384.102864) (xy 295.92172 -384.102447)
			(xy 295.90301 -384.094707) (xy 295.888693 -384.08039) (xy 295.880953 -384.06168) (xy 295.880536 -384.051556)
			(xy 295.880536 -383.894076) (xy 295.880129 -383.884889) (xy 295.873612 -383.867705) (xy 295.867836 -383.860548)
			(xy 295.845986 -383.83487) (xy 295.807895 -383.779238) (xy 295.776742 -383.719444) (xy 295.752975 -383.656349)
			(xy 295.736937 -383.590861) (xy 295.728859 -383.523924) (xy 295.728858 -383.4565) (xy 295.736933 -383.389563)
			(xy 295.752968 -383.324074) (xy 295.776732 -383.260978) (xy 295.807883 -383.201182) (xy 295.845972 -383.145549)
			(xy 295.867836 -383.119884) (xy 295.873626 -383.112735) (xy 295.880144 -383.095547) (xy 295.880536 -383.086356)
			(xy 295.880536 -382.59385) (xy 295.880094 -382.584666) (xy 295.873601 -382.567482) (xy 295.867836 -382.560322)
			(xy 295.845961 -382.534665) (xy 295.80787 -382.479031) (xy 295.776718 -382.419233) (xy 295.752953 -382.356135)
			(xy 295.736917 -382.290645) (xy 295.728841 -382.223705) (xy 292.450794 -382.223705) (xy 292.442758 -382.290467)
			(xy 292.426786 -382.355849) (xy 292.403113 -382.418853) (xy 292.37208 -382.478576) (xy 292.334131 -382.534162)
			(xy 292.312344 -382.559814) (xy 292.306552 -382.566962) (xy 292.300036 -382.584151) (xy 292.299644 -382.593342)
			(xy 292.299644 -383.086864) (xy 292.300084 -383.096048) (xy 292.306578 -383.113232) (xy 292.312344 -383.120392)
			(xy 292.334148 -383.146031) (xy 292.372098 -383.201619) (xy 292.403131 -383.261344) (xy 292.426592 -383.323786)
			(xy 293.528687 -383.323786) (xy 293.52869 -383.25636) (xy 293.536769 -383.189419) (xy 293.552808 -383.123928)
			(xy 293.576576 -383.06083) (xy 293.60773 -383.001033) (xy 293.645822 -382.945397) (xy 293.667688 -382.919732)
			(xy 293.673495 -382.912594) (xy 293.680004 -382.895398) (xy 293.680388 -382.886204) (xy 293.680388 -382.728724)
			(xy 293.680835 -382.718605) (xy 293.688573 -382.699904) (xy 293.70288 -382.685589) (xy 293.721577 -382.677841)
			(xy 293.731696 -382.677416) (xy 294.447976 -382.677416) (xy 294.458099 -382.677836) (xy 294.476805 -382.685579)
			(xy 294.491121 -382.699895) (xy 294.498864 -382.718601) (xy 294.499284 -382.728724) (xy 294.499284 -382.886204)
			(xy 294.499696 -382.895391) (xy 294.506209 -382.912575) (xy 294.511984 -382.919732) (xy 294.533813 -382.945426)
			(xy 294.571904 -383.001056) (xy 294.603057 -383.060848) (xy 294.626824 -383.123941) (xy 294.642863 -383.189427)
			(xy 294.650942 -383.256362) (xy 294.650945 -383.323784) (xy 294.642872 -383.39072) (xy 294.62684 -383.456207)
			(xy 294.603079 -383.519302) (xy 294.571932 -383.579097) (xy 294.533846 -383.634731) (xy 294.511984 -383.660396)
			(xy 294.506205 -383.667553) (xy 294.49968 -383.684735) (xy 294.499284 -383.693924) (xy 294.499284 -384.186176)
			(xy 294.499709 -384.195361) (xy 294.506213 -384.212546) (xy 294.511984 -384.219704) (xy 294.533884 -384.24534)
			(xy 294.571973 -384.300978) (xy 294.603123 -384.360778) (xy 294.626885 -384.423879) (xy 294.642919 -384.489372)
			(xy 294.650992 -384.556314) (xy 294.650989 -384.62374) (xy 294.642909 -384.690681) (xy 294.626869 -384.756173)
			(xy 294.603101 -384.819271) (xy 294.571945 -384.879068) (xy 294.533851 -384.934703) (xy 294.511984 -384.960368)
			(xy 294.506174 -384.967504) (xy 294.499668 -384.984702) (xy 294.499284 -384.993896) (xy 294.499284 -385.151376)
			(xy 294.498864 -385.161499) (xy 294.491121 -385.180205) (xy 294.476805 -385.194521) (xy 294.458099 -385.202264)
			(xy 294.447976 -385.202684) (xy 293.731696 -385.202684) (xy 293.721571 -385.202287) (xy 293.702865 -385.194534)
			(xy 293.68855 -385.180212) (xy 293.680808 -385.161501) (xy 293.680388 -385.151376) (xy 293.680388 -384.993896)
			(xy 293.679982 -384.984708) (xy 293.673466 -384.967524) (xy 293.667688 -384.960368) (xy 293.64586 -384.934673)
			(xy 293.607771 -384.879043) (xy 293.576619 -384.819251) (xy 293.552854 -384.756158) (xy 293.536816 -384.690672)
			(xy 293.528737 -384.623737) (xy 293.528734 -384.556317) (xy 293.536806 -384.489381) (xy 293.552838 -384.423894)
			(xy 293.576597 -384.360799) (xy 293.607743 -384.301004) (xy 293.645827 -384.245369) (xy 293.667688 -384.219704)
			(xy 293.673464 -384.212544) (xy 293.679991 -384.195365) (xy 293.680388 -384.186176) (xy 293.680388 -383.693924)
			(xy 293.679969 -383.684738) (xy 293.673462 -383.667553) (xy 293.667688 -383.660396) (xy 293.645789 -383.63476)
			(xy 293.607702 -383.579121) (xy 293.576554 -383.51932) (xy 293.552792 -383.45622) (xy 293.53676 -383.390727)
			(xy 293.528687 -383.323786) (xy 292.426592 -383.323786) (xy 292.426804 -383.32435) (xy 292.442776 -383.389734)
			(xy 292.450819 -383.456559) (xy 292.450818 -383.523865) (xy 292.442772 -383.590689) (xy 292.426797 -383.656073)
			(xy 292.403121 -383.719078) (xy 292.372085 -383.778802) (xy 292.334133 -383.834388) (xy 292.312344 -383.86004)
			(xy 292.306541 -383.86718) (xy 292.300032 -383.884375) (xy 292.299644 -383.893568) (xy 292.299644 -384.051556)
			(xy 292.299149 -384.06167) (xy 292.291423 -384.080364) (xy 292.277132 -384.094679) (xy 292.258449 -384.102433)
			(xy 292.248336 -384.102864) (xy 291.531802 -384.102864) (xy 291.521676 -384.102372) (xy 291.502956 -384.094645)
			(xy 291.488599 -384.080361) (xy 291.480779 -384.06168) (xy 291.48024 -384.051556) (xy 291.48024 -383.893568)
			(xy 291.479836 -383.88438) (xy 291.473317 -383.867197) (xy 291.46754 -383.86004) (xy 291.445768 -383.834375)
			(xy 291.407819 -383.77879) (xy 291.376785 -383.719068) (xy 291.353111 -383.656066) (xy 291.337137 -383.590685)
			(xy 291.329092 -383.523864) (xy 291.32909 -383.45656) (xy 291.337133 -383.389739) (xy 291.353104 -383.324357)
			(xy 291.376775 -383.261354) (xy 291.407806 -383.20163) (xy 291.445753 -383.146044) (xy 291.46754 -383.120392)
			(xy 291.473328 -383.113241) (xy 291.479847 -383.096055) (xy 291.48024 -383.086864) (xy 291.48024 -382.593342)
			(xy 291.4798 -382.584158) (xy 291.473306 -382.566974) (xy 291.46754 -382.559814) (xy 291.445742 -382.53417)
			(xy 291.407794 -382.478582) (xy 291.376761 -382.418858) (xy 291.353088 -382.355852) (xy 291.337116 -382.290469)
			(xy 291.329073 -382.223645) (xy 288.051034 -382.223645) (xy 288.051034 -382.223704) (xy 288.042958 -382.290643)
			(xy 288.026922 -382.356132) (xy 288.003157 -382.419229) (xy 287.972004 -382.479024) (xy 287.933913 -382.534658)
			(xy 287.912048 -382.560322) (xy 287.906253 -382.567468) (xy 287.899739 -382.584658) (xy 287.899348 -382.59385)
			(xy 287.899348 -383.086356) (xy 287.899791 -383.095539) (xy 287.906283 -383.112723) (xy 287.912048 -383.119884)
			(xy 287.93393 -383.145535) (xy 287.972021 -383.201171) (xy 288.003174 -383.260968) (xy 288.026812 -383.323727)
			(xy 289.128894 -383.323727) (xy 289.128898 -383.256418) (xy 289.136946 -383.189593) (xy 289.152924 -383.124208)
			(xy 289.176604 -383.061202) (xy 289.207644 -383.001477) (xy 289.245601 -382.945891) (xy 289.267392 -382.92024)
			(xy 289.273196 -382.9131) (xy 289.279706 -382.895905) (xy 289.280092 -382.886712) (xy 289.280092 -382.728724)
			(xy 289.280535 -382.718604) (xy 289.288274 -382.699902) (xy 289.302582 -382.685588) (xy 289.32128 -382.67784)
			(xy 289.3314 -382.677416) (xy 290.047934 -382.677416) (xy 290.05806 -382.677898) (xy 290.076777 -382.685632)
			(xy 290.091132 -382.69992) (xy 290.098954 -382.7186) (xy 290.099496 -382.728724) (xy 290.099496 -382.886712)
			(xy 290.099901 -382.8959) (xy 290.106419 -382.913084) (xy 290.112196 -382.92024) (xy 290.133947 -382.945922)
			(xy 290.171895 -383.001505) (xy 290.202928 -383.061225) (xy 290.226601 -383.124225) (xy 290.242576 -383.189603)
			(xy 290.250622 -383.256422) (xy 290.250625 -383.323724) (xy 290.242585 -383.390543) (xy 290.226617 -383.455923)
			(xy 290.20295 -383.518926) (xy 290.171923 -383.578649) (xy 290.133981 -383.634235) (xy 290.112196 -383.659888)
			(xy 290.106379 -383.667019) (xy 290.099877 -383.68422) (xy 290.099496 -383.693416) (xy 290.099496 -384.186684)
			(xy 290.099915 -384.19587) (xy 290.106423 -384.213055) (xy 290.112196 -384.220212) (xy 290.134018 -384.245836)
			(xy 290.171963 -384.301427) (xy 290.202993 -384.361155) (xy 290.226662 -384.424163) (xy 290.242632 -384.489548)
			(xy 290.250673 -384.556373) (xy 290.250669 -384.623681) (xy 290.242622 -384.690505) (xy 290.226646 -384.755889)
			(xy 290.202971 -384.818895) (xy 290.171936 -384.87862) (xy 290.133985 -384.934207) (xy 290.112196 -384.95986)
			(xy 290.106391 -384.966999) (xy 290.099881 -384.984194) (xy 290.099496 -384.993388) (xy 290.099496 -385.151376)
			(xy 290.099064 -385.161497) (xy 290.091323 -385.180201) (xy 290.077011 -385.194517) (xy 290.058309 -385.202262)
			(xy 290.048188 -385.202684) (xy 289.331654 -385.202684) (xy 289.321527 -385.202212) (xy 289.30281 -385.194473)
			(xy 289.288456 -385.180183) (xy 289.280634 -385.1615) (xy 289.280092 -385.151376) (xy 289.280092 -384.993388)
			(xy 289.279689 -384.9842) (xy 289.273171 -384.967016) (xy 289.267392 -384.95986) (xy 289.245638 -384.934179)
			(xy 289.207685 -384.878598) (xy 289.176647 -384.818879) (xy 289.15297 -384.755878) (xy 289.136993 -384.690499)
			(xy 289.128945 -384.623679) (xy 289.128942 -384.556375) (xy 289.136983 -384.489554) (xy 289.152954 -384.424174)
			(xy 289.176625 -384.36117) (xy 289.207657 -384.301448) (xy 289.245605 -384.245863) (xy 289.267392 -384.220212)
			(xy 289.273208 -384.21308) (xy 289.279711 -384.195879) (xy 289.280092 -384.186684) (xy 289.280092 -383.693416)
			(xy 289.279676 -383.684229) (xy 289.273167 -383.667045) (xy 289.267392 -383.659888) (xy 289.245567 -383.634266)
			(xy 289.207616 -383.578676) (xy 289.176581 -383.518949) (xy 289.152908 -383.45594) (xy 289.136936 -383.390554)
			(xy 289.128894 -383.323727) (xy 288.026812 -383.323727) (xy 288.02694 -383.324067) (xy 288.042976 -383.389558)
			(xy 288.051051 -383.456499) (xy 288.05105 -383.523925) (xy 288.042971 -383.590865) (xy 288.026933 -383.656356)
			(xy 288.003164 -383.719454) (xy 287.972009 -383.77925) (xy 287.933915 -383.834884) (xy 287.912048 -383.860548)
			(xy 287.906242 -383.867686) (xy 287.899734 -383.884882) (xy 287.899348 -383.894076) (xy 287.899348 -384.051556)
			(xy 287.898849 -384.06167) (xy 287.891124 -384.080363) (xy 287.876834 -384.094677) (xy 287.858153 -384.102432)
			(xy 287.84804 -384.102864) (xy 287.13176 -384.102864) (xy 287.12163 -384.102516) (xy 287.102919 -384.094748)
			(xy 287.088605 -384.08041) (xy 287.080868 -384.061686) (xy 287.080452 -384.051556) (xy 287.080452 -383.894076)
			(xy 287.080042 -383.884889) (xy 287.073527 -383.867705) (xy 287.067752 -383.860548) (xy 287.045902 -383.834871)
			(xy 287.007809 -383.779239) (xy 286.976655 -383.719445) (xy 286.952888 -383.65635) (xy 286.936849 -383.590862)
			(xy 286.928772 -383.523924) (xy 286.92877 -383.4565) (xy 286.936845 -383.389562) (xy 286.952881 -383.324073)
			(xy 286.976645 -383.260977) (xy 287.007797 -383.201182) (xy 287.045887 -383.145548) (xy 287.067752 -383.119884)
			(xy 287.073544 -383.112736) (xy 287.08006 -383.095547) (xy 287.080452 -383.086356) (xy 287.080452 -382.59385)
			(xy 287.080006 -382.584667) (xy 287.073516 -382.567483) (xy 287.067752 -382.560322) (xy 287.045876 -382.534666)
			(xy 287.007785 -382.479031) (xy 286.976631 -382.419234) (xy 286.952865 -382.356136) (xy 286.936829 -382.290645)
			(xy 286.928753 -382.223705) (xy 262.274304 -382.223705) (xy 262.274304 -385.608376) (xy 454.303373 -385.608376)
			(xy 454.303373 -385.479236) (xy 454.311323 -385.350341) (xy 454.327193 -385.222181) (xy 454.350922 -385.09524)
			(xy 454.382421 -384.970001) (xy 454.42157 -384.846938) (xy 454.468221 -384.726519) (xy 454.522196 -384.6092)
			(xy 454.583291 -384.495426) (xy 454.651274 -384.385629) (xy 454.725888 -384.280226) (xy 454.806849 -384.179616)
			(xy 454.893849 -384.084181) (xy 454.98656 -383.994282) (xy 455.08463 -383.910261) (xy 455.187685 -383.832437)
			(xy 455.295336 -383.761105) (xy 455.407175 -383.696535) (xy 455.522776 -383.638973) (xy 455.641701 -383.588636)
			(xy 455.7635 -383.545716) (xy 455.88771 -383.510375) (xy 456.013859 -383.482748) (xy 456.141471 -383.462939)
			(xy 456.27006 -383.451023) (xy 456.399138 -383.447047) (xy 456.528216 -383.451023) (xy 456.656805 -383.462939)
			(xy 456.784417 -383.482748) (xy 456.910566 -383.510375) (xy 457.034776 -383.545716) (xy 457.156575 -383.588636)
			(xy 457.2755 -383.638973) (xy 457.391101 -383.696535) (xy 457.50294 -383.761105) (xy 457.610591 -383.832437)
			(xy 457.713646 -383.910261) (xy 457.811716 -383.994282) (xy 457.904427 -384.084181) (xy 457.991427 -384.179616)
			(xy 458.072388 -384.280226) (xy 458.147002 -384.385629) (xy 458.214985 -384.495426) (xy 458.27608 -384.6092)
			(xy 458.330055 -384.726519) (xy 458.376706 -384.846938) (xy 458.415855 -384.970001) (xy 458.447354 -385.09524)
			(xy 458.471083 -385.222181) (xy 458.486953 -385.350341) (xy 458.494903 -385.479236) (xy 458.4954 -385.543806)
			(xy 458.494903 -385.608376) (xy 458.486953 -385.737271) (xy 458.471083 -385.865431) (xy 458.447354 -385.992372)
			(xy 458.415855 -386.117611) (xy 458.376706 -386.240674) (xy 458.330055 -386.361093) (xy 458.27608 -386.478412)
			(xy 458.214985 -386.592186) (xy 458.147002 -386.701983) (xy 458.072388 -386.807386) (xy 457.991427 -386.907996)
			(xy 457.904427 -387.003431) (xy 457.811716 -387.09333) (xy 457.713646 -387.177351) (xy 457.610591 -387.255175)
			(xy 457.50294 -387.326507) (xy 457.391101 -387.391077) (xy 457.2755 -387.448639) (xy 457.156575 -387.498976)
			(xy 457.034776 -387.541896) (xy 456.910566 -387.577237) (xy 456.784417 -387.604864) (xy 456.656805 -387.624673)
			(xy 456.528216 -387.636589) (xy 456.399138 -387.640566) (xy 456.27006 -387.636589) (xy 456.141471 -387.624673)
			(xy 456.013859 -387.604864) (xy 455.88771 -387.577237) (xy 455.7635 -387.541896) (xy 455.641701 -387.498976)
			(xy 455.522776 -387.448639) (xy 455.407175 -387.391077) (xy 455.295336 -387.326507) (xy 455.187685 -387.255175)
			(xy 455.08463 -387.177351) (xy 454.98656 -387.09333) (xy 454.893849 -387.003431) (xy 454.806849 -386.907996)
			(xy 454.725888 -386.807386) (xy 454.651274 -386.701983) (xy 454.583291 -386.592186) (xy 454.522196 -386.478412)
			(xy 454.468221 -386.361093) (xy 454.42157 -386.240674) (xy 454.382421 -386.117611) (xy 454.350922 -385.992372)
			(xy 454.327193 -385.865431) (xy 454.311323 -385.737271) (xy 454.303373 -385.608376) (xy 262.274304 -385.608376)
			(xy 262.274304 -387.892798) (xy 262.273903 -387.902871) (xy 262.266168 -387.92147) (xy 262.259318 -387.928866)
			(xy 259.197602 -390.990582) (xy 259.190193 -390.997411) (xy 259.171601 -391.005138) (xy 259.161534 -391.005568)
			(xy 245.155466 -391.005568) (xy 245.143121 -391.006101) (xy 245.120249 -391.015389) (xy 245.111016 -391.023602)
			(xy 245.110508 -391.02411) (xy 244.084602 -392.050016) (xy 244.076151 -392.059207) (xy 244.066584 -392.082246)
			(xy 244.06606 -392.09472) (xy 244.06606 -397.823885) (xy 286.928734 -397.823885) (xy 286.928737 -397.756458)
			(xy 286.936817 -397.689516) (xy 286.952859 -397.624024) (xy 286.976629 -397.560925) (xy 287.007787 -397.501128)
			(xy 287.045884 -397.445494) (xy 287.067752 -397.41983) (xy 287.073567 -397.412698) (xy 287.080069 -397.395497)
			(xy 287.080452 -397.386302) (xy 287.080452 -396.89405) (xy 287.080006 -396.884867) (xy 287.073516 -396.867683)
			(xy 287.067752 -396.860522) (xy 287.045876 -396.834866) (xy 287.007785 -396.779231) (xy 286.976631 -396.719434)
			(xy 286.952865 -396.656336) (xy 286.936829 -396.590845) (xy 286.928753 -396.523905) (xy 286.928754 -396.45648)
			(xy 286.936832 -396.38954) (xy 286.95287 -396.32405) (xy 286.976638 -396.260952) (xy 287.007792 -396.201156)
			(xy 287.045886 -396.145522) (xy 287.067752 -396.119858) (xy 287.073555 -396.112718) (xy 287.080065 -396.095523)
			(xy 287.080452 -396.08633) (xy 287.080452 -395.92885) (xy 287.080968 -395.918725) (xy 287.088682 -395.900003)
			(xy 287.102959 -395.885644) (xy 287.121638 -395.877825) (xy 287.13176 -395.877288) (xy 287.84804 -395.877288)
			(xy 287.858195 -395.877689) (xy 287.876946 -395.885495) (xy 287.891268 -395.899898) (xy 287.898968 -395.918693)
			(xy 287.899348 -395.92885) (xy 287.899348 -396.08633) (xy 287.899755 -396.095517) (xy 287.906272 -396.112701)
			(xy 287.912048 -396.119858) (xy 287.933904 -396.14553) (xy 287.971996 -396.201163) (xy 288.00315 -396.260957)
			(xy 288.026917 -396.324053) (xy 288.042955 -396.389542) (xy 288.051033 -396.456481) (xy 288.051034 -396.523904)
			(xy 288.042958 -396.590843) (xy 288.026922 -396.656332) (xy 288.003157 -396.719429) (xy 287.972004 -396.779224)
			(xy 287.933913 -396.834858) (xy 287.912048 -396.860522) (xy 287.906253 -396.867668) (xy 287.899739 -396.884858)
			(xy 287.899348 -396.89405) (xy 287.899348 -397.386302) (xy 287.899769 -397.395488) (xy 287.906276 -397.412672)
			(xy 287.912048 -397.41983) (xy 287.933876 -397.445525) (xy 287.97197 -397.501154) (xy 288.000733 -397.556355)
			(xy 289.128926 -397.556355) (xy 289.13697 -397.489532) (xy 289.152943 -397.42415) (xy 289.176617 -397.361145)
			(xy 289.207652 -397.301423) (xy 289.245603 -397.245837) (xy 289.267392 -397.220186) (xy 289.273176 -397.213032)
			(xy 289.279698 -397.195848) (xy 289.280092 -397.186658) (xy 289.280092 -397.028924) (xy 289.280541 -397.018772)
			(xy 289.288327 -397.000022) (xy 289.302715 -396.985698) (xy 289.321501 -396.977996) (xy 289.331654 -396.977616)
			(xy 290.047934 -396.977616) (xy 290.05806 -396.978098) (xy 290.076777 -396.985832) (xy 290.091132 -397.00012)
			(xy 290.098954 -397.0188) (xy 290.099496 -397.028924) (xy 290.099496 -397.186658) (xy 290.099927 -397.195843)
			(xy 290.106426 -397.213027) (xy 290.112196 -397.220186) (xy 290.133992 -397.245831) (xy 290.171939 -397.301419)
			(xy 290.20297 -397.361144) (xy 290.22664 -397.424149) (xy 290.242612 -397.489532) (xy 290.250654 -397.556355)
			(xy 290.250653 -397.62366) (xy 290.242609 -397.690483) (xy 290.226636 -397.755865) (xy 290.202963 -397.81887)
			(xy 290.200388 -397.823825) (xy 291.329053 -397.823825) (xy 291.329057 -397.756517) (xy 291.337105 -397.689692)
			(xy 291.353082 -397.624308) (xy 291.376759 -397.561302) (xy 291.407796 -397.501577) (xy 291.44575 -397.44599)
			(xy 291.46754 -397.420338) (xy 291.47335 -397.413203) (xy 291.479856 -397.396004) (xy 291.48024 -397.38681)
			(xy 291.48024 -396.893542) (xy 291.4798 -396.884358) (xy 291.473306 -396.867174) (xy 291.46754 -396.860014)
			(xy 291.445742 -396.83437) (xy 291.407794 -396.778782) (xy 291.376761 -396.719058) (xy 291.353088 -396.656052)
			(xy 291.337116 -396.590669) (xy 291.329073 -396.523845) (xy 291.329074 -396.45654) (xy 291.337119 -396.389716)
			(xy 291.353093 -396.324333) (xy 291.376767 -396.261328) (xy 291.407801 -396.201605) (xy 291.445751 -396.146018)
			(xy 291.46754 -396.120366) (xy 291.473339 -396.113222) (xy 291.479851 -396.096031) (xy 291.48024 -396.086838)
			(xy 291.48024 -395.92885) (xy 291.480705 -395.918681) (xy 291.488474 -395.899887) (xy 291.502847 -395.885501)
			(xy 291.521634 -395.877714) (xy 291.531802 -395.877288) (xy 292.248082 -395.877288) (xy 292.258259 -395.87768)
			(xy 292.277063 -395.885468) (xy 292.29145 -395.899864) (xy 292.299227 -395.918673) (xy 292.299644 -395.92885)
			(xy 292.299644 -396.086838) (xy 292.300049 -396.096026) (xy 292.306568 -396.113209) (xy 292.312344 -396.120366)
			(xy 292.334122 -396.146026) (xy 292.372072 -396.201611) (xy 292.403107 -396.261333) (xy 292.426781 -396.324337)
			(xy 292.442755 -396.389718) (xy 292.450801 -396.45654) (xy 292.450801 -396.523845) (xy 292.442758 -396.590667)
			(xy 292.426786 -396.656049) (xy 292.403113 -396.719053) (xy 292.37208 -396.778776) (xy 292.334131 -396.834362)
			(xy 292.312344 -396.860014) (xy 292.306552 -396.867162) (xy 292.300036 -396.884351) (xy 292.299644 -396.893542)
			(xy 292.299644 -397.38681) (xy 292.300062 -397.395996) (xy 292.306572 -397.41318) (xy 292.312344 -397.420338)
			(xy 292.334095 -397.446021) (xy 292.372046 -397.501602) (xy 292.40047 -397.556296) (xy 293.528718 -397.556296)
			(xy 293.536793 -397.489359) (xy 293.552827 -397.42387) (xy 293.576589 -397.360774) (xy 293.607738 -397.300978)
			(xy 293.645825 -397.245343) (xy 293.667688 -397.219678) (xy 293.673475 -397.212526) (xy 293.679996 -397.195341)
			(xy 293.680388 -397.18615) (xy 293.680388 -397.028924) (xy 293.680835 -397.018805) (xy 293.688573 -397.000104)
			(xy 293.70288 -396.985789) (xy 293.721577 -396.978041) (xy 293.731696 -396.977616) (xy 294.447976 -396.977616)
			(xy 294.458099 -396.978036) (xy 294.476805 -396.985779) (xy 294.491121 -397.000095) (xy 294.498864 -397.018801)
			(xy 294.499284 -397.028924) (xy 294.499284 -397.18615) (xy 294.499722 -397.195334) (xy 294.506217 -397.212519)
			(xy 294.511984 -397.219678) (xy 294.533858 -397.245335) (xy 294.571948 -397.30097) (xy 294.603099 -397.360767)
			(xy 294.626863 -397.423865) (xy 294.642899 -397.489356) (xy 294.650974 -397.556295) (xy 294.650973 -397.62372)
			(xy 294.642896 -397.690659) (xy 294.626859 -397.756149) (xy 294.603093 -397.819246) (xy 294.600676 -397.823885)
			(xy 295.728821 -397.823885) (xy 295.728825 -397.756458) (xy 295.736905 -397.689516) (xy 295.752946 -397.624025)
			(xy 295.776716 -397.560926) (xy 295.807873 -397.501129) (xy 295.845969 -397.445495) (xy 295.867836 -397.41983)
			(xy 295.873649 -397.412697) (xy 295.880153 -397.395497) (xy 295.880536 -397.386302) (xy 295.880536 -396.89405)
			(xy 295.880094 -396.884866) (xy 295.873601 -396.867682) (xy 295.867836 -396.860522) (xy 295.845961 -396.834865)
			(xy 295.80787 -396.779231) (xy 295.776718 -396.719433) (xy 295.752953 -396.656335) (xy 295.736917 -396.590845)
			(xy 295.728841 -396.523905) (xy 295.728842 -396.45648) (xy 295.73692 -396.38954) (xy 295.752957 -396.32405)
			(xy 295.776724 -396.260953) (xy 295.807878 -396.201157) (xy 295.84597 -396.145523) (xy 295.867836 -396.119858)
			(xy 295.873637 -396.112716) (xy 295.880148 -396.095523) (xy 295.880536 -396.08633) (xy 295.880536 -395.92885)
			(xy 295.881067 -395.918727) (xy 295.888778 -395.900008) (xy 295.903051 -395.88565) (xy 295.921724 -395.877828)
			(xy 295.931844 -395.877288) (xy 296.648124 -395.877288) (xy 296.658278 -395.877702) (xy 296.677029 -395.885503)
			(xy 296.691351 -395.899902) (xy 296.699052 -395.918694) (xy 296.699432 -395.92885) (xy 296.699432 -396.08633)
			(xy 296.699843 -396.095517) (xy 296.706358 -396.1127) (xy 296.712132 -396.119858) (xy 296.733985 -396.145532)
			(xy 296.772072 -396.201166) (xy 296.803221 -396.260961) (xy 296.826985 -396.324057) (xy 296.84302 -396.389545)
			(xy 296.851096 -396.456481) (xy 296.851097 -396.523904) (xy 296.843022 -396.590841) (xy 296.826989 -396.656329)
			(xy 296.803227 -396.719425) (xy 296.77208 -396.779221) (xy 296.733994 -396.834856) (xy 296.712132 -396.860522)
			(xy 296.706335 -396.867667) (xy 296.699823 -396.884858) (xy 296.699432 -396.89405) (xy 296.699432 -397.386302)
			(xy 296.699856 -397.395487) (xy 296.706362 -397.412671) (xy 296.712132 -397.41983) (xy 296.733958 -397.445527)
			(xy 296.772045 -397.501157) (xy 296.800802 -397.556355) (xy 297.929014 -397.556355) (xy 297.937057 -397.489532)
			(xy 297.95303 -397.42415) (xy 297.976704 -397.361146) (xy 298.007738 -397.301423) (xy 298.045688 -397.245838)
			(xy 298.067476 -397.220186) (xy 298.073258 -397.21303) (xy 298.079782 -397.195848) (xy 298.080176 -397.186658)
			(xy 298.080176 -397.028924) (xy 298.080641 -397.018774) (xy 298.088424 -397.000027) (xy 298.102807 -396.985704)
			(xy 298.121587 -396.977999) (xy 298.131738 -396.977616) (xy 298.848018 -396.977616) (xy 298.858143 -396.978111)
			(xy 298.87686 -396.98584) (xy 298.891215 -397.000123) (xy 298.899038 -397.018802) (xy 298.89958 -397.028924)
			(xy 298.89958 -397.186658) (xy 298.900015 -397.195842) (xy 298.906512 -397.213027) (xy 298.91228 -397.220186)
			(xy 298.934077 -397.24583) (xy 298.972024 -397.301418) (xy 299.003056 -397.361143) (xy 299.026728 -397.424149)
			(xy 299.042699 -397.489532) (xy 299.050742 -397.556355) (xy 299.050741 -397.62366) (xy 299.042697 -397.690483)
			(xy 299.026723 -397.755866) (xy 299.00305 -397.818871) (xy 299.000445 -397.823885) (xy 300.128612 -397.823885)
			(xy 300.128616 -397.756458) (xy 300.136696 -397.689517) (xy 300.152736 -397.624025) (xy 300.176506 -397.560927)
			(xy 300.207662 -397.501129) (xy 300.245757 -397.445495) (xy 300.267624 -397.41983) (xy 300.273436 -397.412696)
			(xy 300.27994 -397.395497) (xy 300.280324 -397.386302) (xy 300.280324 -396.89405) (xy 300.279884 -396.884866)
			(xy 300.273391 -396.867682) (xy 300.267624 -396.860522) (xy 300.245749 -396.834865) (xy 300.207659 -396.77923)
			(xy 300.176508 -396.719433) (xy 300.152743 -396.656335) (xy 300.136708 -396.590845) (xy 300.128632 -396.523905)
			(xy 300.128633 -396.45648) (xy 300.13671 -396.389541) (xy 300.152748 -396.324051) (xy 300.176514 -396.260953)
			(xy 300.207667 -396.201157) (xy 300.245759 -396.145523) (xy 300.267624 -396.119858) (xy 300.273424 -396.112715)
			(xy 300.279936 -396.095523) (xy 300.280324 -396.08633) (xy 300.280324 -395.92885) (xy 300.280867 -395.918728)
			(xy 300.288576 -395.900011) (xy 300.302845 -395.885654) (xy 300.321514 -395.87783) (xy 300.331632 -395.877288)
			(xy 301.047912 -395.877288) (xy 301.058065 -395.877711) (xy 301.076816 -395.885509) (xy 301.091138 -395.899904)
			(xy 301.09884 -395.918694) (xy 301.09922 -395.92885) (xy 301.09922 -396.08633) (xy 301.099611 -396.095519)
			(xy 301.106138 -396.112704) (xy 301.11192 -396.119858) (xy 301.133773 -396.145532) (xy 301.171861 -396.201165)
			(xy 301.203011 -396.260961) (xy 301.226775 -396.324056) (xy 301.242811 -396.389544) (xy 301.250887 -396.456481)
			(xy 301.250888 -396.523904) (xy 301.242813 -396.590841) (xy 301.226779 -396.656329) (xy 301.203017 -396.719426)
			(xy 301.171869 -396.779222) (xy 301.133783 -396.834856) (xy 301.11192 -396.860522) (xy 301.106134 -396.867675)
			(xy 301.099612 -396.884859) (xy 301.09922 -396.89405) (xy 301.09922 -397.386302) (xy 301.099625 -397.39549)
			(xy 301.106142 -397.412674) (xy 301.11192 -397.41983) (xy 301.133746 -397.445526) (xy 301.171834 -397.501157)
			(xy 301.200562 -397.556296) (xy 302.328806 -397.556296) (xy 302.336881 -397.489359) (xy 302.352914 -397.423871)
			(xy 302.376676 -397.360775) (xy 302.407824 -397.300979) (xy 302.44591 -397.245344) (xy 302.467772 -397.219678)
			(xy 302.473569 -397.212534) (xy 302.480081 -397.195342) (xy 302.480472 -397.18615) (xy 302.480472 -397.028924)
			(xy 302.480935 -397.018806) (xy 302.48867 -397.000109) (xy 302.502972 -396.985795) (xy 302.521663 -396.978043)
			(xy 302.53178 -396.977616) (xy 303.24806 -396.977616) (xy 303.258182 -396.978049) (xy 303.276888 -396.985787)
			(xy 303.291204 -397.000099) (xy 303.298948 -397.018802) (xy 303.299368 -397.028924) (xy 303.299368 -397.18615)
			(xy 303.299809 -397.195334) (xy 303.306302 -397.212518) (xy 303.312068 -397.219678) (xy 303.333943 -397.245335)
			(xy 303.372033 -397.30097) (xy 303.403185 -397.360767) (xy 303.426951 -397.423865) (xy 303.442986 -397.489355)
			(xy 303.451062 -397.556295) (xy 303.451061 -397.62372) (xy 303.442984 -397.69066) (xy 303.426946 -397.75615)
			(xy 303.403179 -397.819247) (xy 303.372026 -397.879043) (xy 303.333934 -397.934677) (xy 303.312068 -397.960342)
			(xy 303.306267 -397.967484) (xy 303.299756 -397.984677) (xy 303.299368 -397.99387) (xy 303.299368 -398.486376)
			(xy 303.299797 -398.495561) (xy 303.306299 -398.512745) (xy 303.312068 -398.519904) (xy 303.333968 -398.54554)
			(xy 303.372058 -398.601178) (xy 303.403209 -398.660978) (xy 303.426973 -398.724078) (xy 303.443007 -398.789571)
			(xy 303.45108 -398.856513) (xy 303.451077 -398.923941) (xy 303.442997 -398.990882) (xy 303.426957 -399.056373)
			(xy 303.403187 -399.119472) (xy 303.37203 -399.179269) (xy 303.333935 -399.234903) (xy 303.312068 -399.260568)
			(xy 303.306256 -399.267702) (xy 303.299751 -399.284901) (xy 303.299368 -399.294096) (xy 303.299368 -399.451576)
			(xy 303.298964 -399.461701) (xy 303.291218 -399.48041) (xy 303.276897 -399.494727) (xy 303.258185 -399.502467)
			(xy 303.24806 -399.502884) (xy 302.53178 -399.502884) (xy 302.521654 -399.5025) (xy 302.502947 -399.494742)
			(xy 302.488633 -399.480416) (xy 302.480891 -399.461702) (xy 302.480472 -399.451576) (xy 302.480472 -399.294096)
			(xy 302.48007 -399.284908) (xy 302.473551 -399.267723) (xy 302.467772 -399.260568) (xy 302.445944 -399.234873)
			(xy 302.407856 -399.179242) (xy 302.376706 -399.11945) (xy 302.352941 -399.056357) (xy 302.336904 -398.990872)
			(xy 302.328825 -398.923937) (xy 302.328822 -398.856517) (xy 302.336894 -398.789582) (xy 302.352925 -398.724095)
			(xy 302.376684 -398.661) (xy 302.407829 -398.601204) (xy 302.445911 -398.54557) (xy 302.467772 -398.519904)
			(xy 302.473558 -398.512752) (xy 302.480077 -398.495566) (xy 302.480472 -398.486376) (xy 302.480472 -397.99387)
			(xy 302.480082 -397.98468) (xy 302.473555 -397.967496) (xy 302.467772 -397.960342) (xy 302.445919 -397.934668)
			(xy 302.407832 -397.879034) (xy 302.376682 -397.819239) (xy 302.352919 -397.756143) (xy 302.336883 -397.690656)
			(xy 302.328807 -397.623719) (xy 302.328806 -397.556296) (xy 301.200562 -397.556296) (xy 301.202986 -397.560949)
			(xy 301.226751 -397.624042) (xy 301.242789 -397.689527) (xy 301.250867 -397.756461) (xy 301.250871 -397.823882)
			(xy 301.242799 -397.890817) (xy 301.226768 -397.956304) (xy 301.203009 -398.019399) (xy 301.171864 -398.079194)
			(xy 301.133781 -398.134828) (xy 301.11192 -398.160494) (xy 301.106146 -398.167655) (xy 301.099617 -398.184833)
			(xy 301.09922 -398.194022) (xy 301.09922 -398.351502) (xy 301.098774 -398.361634) (xy 301.091038 -398.380362)
			(xy 301.076739 -398.39472) (xy 301.058042 -398.402532) (xy 301.047912 -398.403064) (xy 300.331632 -398.403064)
			(xy 300.321475 -398.402652) (xy 300.302717 -398.39486) (xy 300.288391 -398.38046) (xy 300.280696 -398.361661)
			(xy 300.280324 -398.351502) (xy 300.280324 -398.194022) (xy 300.279898 -398.184837) (xy 300.273395 -398.167652)
			(xy 300.267624 -398.160494) (xy 300.245722 -398.13486) (xy 300.207633 -398.079222) (xy 300.176482 -398.019421)
			(xy 300.152719 -397.95632) (xy 300.136686 -397.890827) (xy 300.128612 -397.823885) (xy 299.000445 -397.823885)
			(xy 298.972017 -397.878595) (xy 298.934068 -397.934182) (xy 298.91228 -397.959834) (xy 298.906484 -397.96698)
			(xy 298.89997 -397.98417) (xy 298.89958 -397.993362) (xy 298.89958 -398.486884) (xy 298.900003 -398.49607)
			(xy 298.906508 -398.513254) (xy 298.91228 -398.520412) (xy 298.934103 -398.546035) (xy 298.972049 -398.601626)
			(xy 299.00308 -398.661354) (xy 299.02675 -398.724362) (xy 299.04272 -398.789748) (xy 299.050761 -398.856573)
			(xy 299.050757 -398.923881) (xy 299.04271 -398.990706) (xy 299.026734 -399.05609) (xy 299.003058 -399.119095)
			(xy 298.972021 -399.17882) (xy 298.934069 -399.234408) (xy 298.91228 -399.26006) (xy 298.906473 -399.267198)
			(xy 298.899965 -399.284394) (xy 298.89958 -399.293588) (xy 298.89958 -399.451576) (xy 298.899159 -399.461731)
			(xy 298.891367 -399.480487) (xy 298.87697 -399.494812) (xy 298.858175 -399.502509) (xy 298.848018 -399.502884)
			(xy 298.131738 -399.502884) (xy 298.121617 -399.502343) (xy 298.102901 -399.494632) (xy 298.088544 -399.480362)
			(xy 298.08072 -399.461694) (xy 298.080176 -399.451576) (xy 298.080176 -399.293588) (xy 298.079777 -399.2844)
			(xy 298.073256 -399.267215) (xy 298.067476 -399.26006) (xy 298.045723 -399.234379) (xy 298.00777 -399.178798)
			(xy 297.976733 -399.119078) (xy 297.953057 -399.056078) (xy 297.93708 -398.990699) (xy 297.929033 -398.923879)
			(xy 297.92903 -398.856576) (xy 297.937071 -398.789755) (xy 297.953041 -398.724374) (xy 297.976711 -398.661371)
			(xy 298.007742 -398.601649) (xy 298.045689 -398.546064) (xy 298.067476 -398.520412) (xy 298.07329 -398.513279)
			(xy 298.079795 -398.496079) (xy 298.080176 -398.486884) (xy 298.080176 -397.993362) (xy 298.079789 -397.984172)
			(xy 298.07326 -397.966988) (xy 298.067476 -397.959834) (xy 298.045697 -397.934174) (xy 298.007746 -397.87859)
			(xy 297.97671 -397.818868) (xy 297.953035 -397.755864) (xy 297.93706 -397.690482) (xy 297.929015 -397.62366)
			(xy 297.929014 -397.556355) (xy 296.800802 -397.556355) (xy 296.803196 -397.56095) (xy 296.826961 -397.624042)
			(xy 296.842998 -397.689527) (xy 296.851076 -397.756461) (xy 296.85108 -397.823881) (xy 296.843008 -397.890817)
			(xy 296.826978 -397.956303) (xy 296.803219 -398.019398) (xy 296.772075 -398.079194) (xy 296.733993 -398.134828)
			(xy 296.712132 -398.160494) (xy 296.706347 -398.167647) (xy 296.699827 -398.184832) (xy 296.699432 -398.194022)
			(xy 296.699432 -398.351502) (xy 296.698974 -398.361632) (xy 296.691241 -398.380359) (xy 296.676945 -398.394716)
			(xy 296.658252 -398.40253) (xy 296.648124 -398.403064) (xy 295.931844 -398.403064) (xy 295.921688 -398.402642)
			(xy 295.90293 -398.394854) (xy 295.888604 -398.380456) (xy 295.880909 -398.36166) (xy 295.880536 -398.351502)
			(xy 295.880536 -398.194022) (xy 295.880107 -398.184837) (xy 295.873606 -398.167653) (xy 295.867836 -398.160494)
			(xy 295.845933 -398.13486) (xy 295.807843 -398.079222) (xy 295.776692 -398.019422) (xy 295.752929 -397.956321)
			(xy 295.736895 -397.890827) (xy 295.728821 -397.823885) (xy 294.600676 -397.823885) (xy 294.57194 -397.879043)
			(xy 294.533849 -397.934677) (xy 294.511984 -397.960342) (xy 294.506185 -397.967486) (xy 294.499672 -397.984677)
			(xy 294.499284 -397.99387) (xy 294.499284 -398.486376) (xy 294.499709 -398.495561) (xy 294.506213 -398.512746)
			(xy 294.511984 -398.519904) (xy 294.533884 -398.54554) (xy 294.571973 -398.601178) (xy 294.603123 -398.660978)
			(xy 294.626885 -398.724079) (xy 294.642919 -398.789572) (xy 294.650992 -398.856514) (xy 294.650989 -398.92394)
			(xy 294.642909 -398.990881) (xy 294.626869 -399.056373) (xy 294.603101 -399.119471) (xy 294.571945 -399.179268)
			(xy 294.533851 -399.234903) (xy 294.511984 -399.260568) (xy 294.506174 -399.267704) (xy 294.499668 -399.284902)
			(xy 294.499284 -399.294096) (xy 294.499284 -399.451576) (xy 294.498864 -399.461699) (xy 294.491121 -399.480405)
			(xy 294.476805 -399.494721) (xy 294.458099 -399.502464) (xy 294.447976 -399.502884) (xy 293.731696 -399.502884)
			(xy 293.721571 -399.502487) (xy 293.702865 -399.494734) (xy 293.68855 -399.480412) (xy 293.680808 -399.461701)
			(xy 293.680388 -399.451576) (xy 293.680388 -399.294096) (xy 293.679982 -399.284908) (xy 293.673466 -399.267724)
			(xy 293.667688 -399.260568) (xy 293.64586 -399.234873) (xy 293.607771 -399.179243) (xy 293.576619 -399.119451)
			(xy 293.552854 -399.056358) (xy 293.536816 -398.990872) (xy 293.528737 -398.923937) (xy 293.528734 -398.856517)
			(xy 293.536806 -398.789581) (xy 293.552838 -398.724094) (xy 293.576597 -398.660999) (xy 293.607743 -398.601204)
			(xy 293.645827 -398.545569) (xy 293.667688 -398.519904) (xy 293.673464 -398.512744) (xy 293.679991 -398.495565)
			(xy 293.680388 -398.486376) (xy 293.680388 -397.99387) (xy 293.679995 -397.984681) (xy 293.673469 -397.967497)
			(xy 293.667688 -397.960342) (xy 293.645834 -397.934668) (xy 293.607746 -397.879035) (xy 293.576596 -397.81924)
			(xy 293.552831 -397.756144) (xy 293.536796 -397.690656) (xy 293.528719 -397.623719) (xy 293.528718 -397.556296)
			(xy 292.40047 -397.556296) (xy 292.403082 -397.561322) (xy 292.426757 -397.624322) (xy 292.442733 -397.689701)
			(xy 292.450781 -397.75652) (xy 292.450784 -397.823823) (xy 292.442744 -397.890643) (xy 292.426774 -397.956023)
			(xy 292.403105 -398.019026) (xy 292.372075 -398.078748) (xy 292.33413 -398.134334) (xy 292.312344 -398.159986)
			(xy 292.306522 -398.167113) (xy 292.300024 -398.184318) (xy 292.299644 -398.193514) (xy 292.299644 -398.351502)
			(xy 292.299237 -398.361676) (xy 292.291448 -398.380474) (xy 292.277057 -398.39486) (xy 292.258256 -398.402641)
			(xy 292.248082 -398.403064) (xy 291.531802 -398.403064) (xy 291.521645 -398.402565) (xy 291.502876 -398.394792)
			(xy 291.488511 -398.380427) (xy 291.480736 -398.361659) (xy 291.48024 -398.351502) (xy 291.48024 -398.193514)
			(xy 291.479814 -398.184329) (xy 291.473311 -398.167145) (xy 291.46754 -398.159986) (xy 291.445715 -398.134365)
			(xy 291.407767 -398.078774) (xy 291.376735 -398.019046) (xy 291.353065 -397.956037) (xy 291.337094 -397.890651)
			(xy 291.329053 -397.823825) (xy 290.200388 -397.823825) (xy 290.171931 -397.878594) (xy 290.133983 -397.934181)
			(xy 290.112196 -397.959834) (xy 290.106402 -397.966981) (xy 290.099886 -397.98417) (xy 290.099496 -397.993362)
			(xy 290.099496 -398.486884) (xy 290.099915 -398.49607) (xy 290.106423 -398.513255) (xy 290.112196 -398.520412)
			(xy 290.134018 -398.546036) (xy 290.171963 -398.601627) (xy 290.202993 -398.661355) (xy 290.226662 -398.724363)
			(xy 290.242632 -398.789748) (xy 290.250673 -398.856573) (xy 290.250669 -398.923881) (xy 290.242622 -398.990705)
			(xy 290.226646 -399.056089) (xy 290.202971 -399.119095) (xy 290.171936 -399.17882) (xy 290.133985 -399.234407)
			(xy 290.112196 -399.26006) (xy 290.106391 -399.267199) (xy 290.099881 -399.284394) (xy 290.099496 -399.293588)
			(xy 290.099496 -399.451576) (xy 290.099059 -399.461729) (xy 290.09127 -399.480482) (xy 290.076878 -399.494806)
			(xy 290.058089 -399.502506) (xy 290.047934 -399.502884) (xy 289.331654 -399.502884) (xy 289.321527 -399.502412)
			(xy 289.30281 -399.494673) (xy 289.288456 -399.480383) (xy 289.280634 -399.4617) (xy 289.280092 -399.451576)
			(xy 289.280092 -399.293588) (xy 289.279689 -399.2844) (xy 289.273171 -399.267216) (xy 289.267392 -399.26006)
			(xy 289.245638 -399.234379) (xy 289.207685 -399.178798) (xy 289.176647 -399.119079) (xy 289.15297 -399.056078)
			(xy 289.136993 -398.990699) (xy 289.128945 -398.923879) (xy 289.128942 -398.856575) (xy 289.136983 -398.789754)
			(xy 289.152954 -398.724374) (xy 289.176625 -398.66137) (xy 289.207657 -398.601648) (xy 289.245605 -398.546063)
			(xy 289.267392 -398.520412) (xy 289.273208 -398.51328) (xy 289.279711 -398.496079) (xy 289.280092 -398.486884)
			(xy 289.280092 -397.993362) (xy 289.279702 -397.984173) (xy 289.273175 -397.966988) (xy 289.267392 -397.959834)
			(xy 289.245612 -397.934174) (xy 289.20766 -397.87859) (xy 289.176623 -397.818868) (xy 289.152948 -397.755865)
			(xy 289.136972 -397.690483) (xy 289.128927 -397.62366) (xy 289.128926 -397.556355) (xy 288.000733 -397.556355)
			(xy 288.003125 -397.560946) (xy 288.026894 -397.624039) (xy 288.042933 -397.689525) (xy 288.051013 -397.756461)
			(xy 288.051016 -397.823882) (xy 288.042944 -397.890819) (xy 288.026911 -397.956307) (xy 288.003148 -398.019402)
			(xy 287.971999 -398.079197) (xy 287.933912 -398.13483) (xy 287.912048 -398.160494) (xy 287.906265 -398.167649)
			(xy 287.899744 -398.184832) (xy 287.899348 -398.194022) (xy 287.899348 -398.351502) (xy 287.898875 -398.36163)
			(xy 287.891144 -398.380354) (xy 287.876853 -398.39471) (xy 287.858166 -398.402527) (xy 287.84804 -398.403064)
			(xy 287.13176 -398.403064) (xy 287.121599 -398.40271) (xy 287.102839 -398.394895) (xy 287.088515 -398.380477)
			(xy 287.080824 -398.361666) (xy 287.080452 -398.351502) (xy 287.080452 -398.194022) (xy 287.08002 -398.184837)
			(xy 287.07352 -398.167653) (xy 287.067752 -398.160494) (xy 287.045849 -398.13486) (xy 287.007758 -398.079223)
			(xy 286.976606 -398.019423) (xy 286.952842 -397.956321) (xy 286.936807 -397.890828) (xy 286.928734 -397.823885)
			(xy 244.06606 -397.823885) (xy 244.06606 -399.830544) (xy 244.065668 -399.840617) (xy 244.057925 -399.859215)
			(xy 244.051074 -399.866612) (xy 243.052346 -400.865594) (xy 243.044923 -400.872406) (xy 243.026341 -400.880142)
			(xy 243.016278 -400.88058) (xy 238.99114 -400.88058) (xy 238.978794 -400.881097) (xy 238.955921 -400.890396)
			(xy 238.94669 -400.898614) (xy 238.946182 -400.899122) (xy 238.121507 -401.723797) (xy 286.928745 -401.723797)
			(xy 286.928747 -401.65637) (xy 286.936826 -401.58943) (xy 286.952865 -401.523939) (xy 286.976634 -401.460841)
			(xy 287.00779 -401.401044) (xy 287.045885 -401.34541) (xy 287.067752 -401.319746) (xy 287.07356 -401.312609)
			(xy 287.080067 -401.295412) (xy 287.080452 -401.286218) (xy 287.080452 -400.793966) (xy 287.080046 -400.784779)
			(xy 287.073528 -400.767595) (xy 287.067752 -400.760438) (xy 287.045892 -400.734769) (xy 287.0078 -400.679136)
			(xy 286.976646 -400.619341) (xy 286.952879 -400.556244) (xy 286.936842 -400.490755) (xy 286.928764 -400.423817)
			(xy 286.928764 -400.356392) (xy 286.93684 -400.289454) (xy 286.952876 -400.223964) (xy 286.976642 -400.160867)
			(xy 287.007795 -400.101072) (xy 287.045887 -400.045438) (xy 287.067752 -400.019774) (xy 287.073549 -400.012629)
			(xy 287.080062 -399.995438) (xy 287.080452 -399.986246) (xy 287.080452 -399.828766) (xy 287.080899 -399.818636)
			(xy 287.08864 -399.799911) (xy 287.102939 -399.785556) (xy 287.121632 -399.77774) (xy 287.13176 -399.777204)
			(xy 287.84804 -399.777204) (xy 287.858197 -399.777589) (xy 287.876951 -399.785399) (xy 287.891273 -399.799806)
			(xy 287.898971 -399.818606) (xy 287.899348 -399.828766) (xy 287.899348 -399.986246) (xy 287.899796 -399.995429)
			(xy 287.906285 -400.012613) (xy 287.912048 -400.019774) (xy 287.93392 -400.045433) (xy 287.972012 -400.101068)
			(xy 288.003165 -400.160864) (xy 288.026931 -400.223962) (xy 288.042968 -400.289452) (xy 288.051044 -400.356392)
			(xy 288.051043 -400.423817) (xy 288.042966 -400.490757) (xy 288.026928 -400.556247) (xy 288.003161 -400.619344)
			(xy 287.972007 -400.67914) (xy 287.933914 -400.734774) (xy 287.912048 -400.760438) (xy 287.906246 -400.767579)
			(xy 287.899736 -400.784773) (xy 287.899348 -400.793966) (xy 287.899348 -401.286218) (xy 287.899761 -401.295405)
			(xy 287.906274 -401.312588) (xy 287.912048 -401.319746) (xy 287.933892 -401.345428) (xy 287.971985 -401.401059)
			(xy 288.00314 -401.460852) (xy 288.026907 -401.523947) (xy 288.042946 -401.589435) (xy 288.051024 -401.656372)
			(xy 288.051026 -401.723795) (xy 288.042952 -401.790733) (xy 288.026917 -401.856221) (xy 288.003153 -401.919317)
			(xy 287.972002 -401.979113) (xy 287.933912 -402.034746) (xy 287.912048 -402.06041) (xy 287.906258 -402.06756)
			(xy 287.899741 -402.084747) (xy 287.899348 -402.093938) (xy 287.899348 -402.251418) (xy 287.898888 -402.261547)
			(xy 287.891152 -402.280271) (xy 287.876858 -402.294627) (xy 287.858167 -402.302444) (xy 287.84804 -402.30298)
			(xy 287.13176 -402.30298) (xy 287.121601 -402.302611) (xy 287.102844 -402.294798) (xy 287.088521 -402.280385)
			(xy 287.080826 -402.26158) (xy 287.080452 -402.251418) (xy 287.080452 -402.093938) (xy 287.080012 -402.084754)
			(xy 287.073518 -402.06757) (xy 287.067752 -402.06041) (xy 287.045865 -402.034763) (xy 287.007773 -401.979127)
			(xy 286.97662 -401.919329) (xy 286.952855 -401.85623) (xy 286.93682 -401.790738) (xy 286.928745 -401.723797)
			(xy 238.121507 -401.723797) (xy 237.044738 -402.800566) (xy 237.036256 -402.809732) (xy 237.030424 -402.823819)
			(xy 289.128886 -402.823819) (xy 289.12889 -402.756509) (xy 289.13694 -402.689682) (xy 289.15292 -402.624297)
			(xy 289.1766 -402.56129) (xy 289.207642 -402.501565) (xy 289.2456 -402.445979) (xy 289.267392 -402.420328)
			(xy 289.273201 -402.413191) (xy 289.279708 -402.395994) (xy 289.280092 -402.3868) (xy 289.280092 -401.893532)
			(xy 289.279668 -401.884346) (xy 289.273164 -401.867162) (xy 289.267392 -401.860004) (xy 289.245583 -401.834369)
			(xy 289.207631 -401.778781) (xy 289.176596 -401.719056) (xy 289.152922 -401.656049) (xy 289.136949 -401.590664)
			(xy 289.128906 -401.523839) (xy 289.128907 -401.456531) (xy 289.136954 -401.389706) (xy 289.152931 -401.324322)
			(xy 289.176608 -401.261317) (xy 289.207647 -401.201593) (xy 289.245601 -401.146007) (xy 289.267392 -401.120356)
			(xy 289.273189 -401.113211) (xy 289.279704 -401.09602) (xy 289.280092 -401.086828) (xy 289.280092 -400.92884)
			(xy 289.280554 -400.918689) (xy 289.288335 -400.89994) (xy 289.30272 -400.885615) (xy 289.321502 -400.877913)
			(xy 289.331654 -400.877532) (xy 290.047934 -400.877532) (xy 290.058062 -400.877998) (xy 290.076782 -400.885736)
			(xy 290.091137 -400.900028) (xy 290.098957 -400.918714) (xy 290.099496 -400.92884) (xy 290.099496 -401.086828)
			(xy 290.099893 -401.096017) (xy 290.106416 -401.113201) (xy 290.112196 -401.120356) (xy 290.133963 -401.146025)
			(xy 290.17191 -401.20161) (xy 290.202942 -401.261331) (xy 290.226615 -401.324334) (xy 290.242588 -401.389713)
			(xy 290.250633 -401.456534) (xy 290.250635 -401.523836) (xy 290.242593 -401.590657) (xy 290.226624 -401.656038)
			(xy 290.202955 -401.719041) (xy 290.200515 -401.723737) (xy 291.329064 -401.723737) (xy 291.329066 -401.65643)
			(xy 291.337113 -401.589606) (xy 291.353088 -401.524222) (xy 291.376763 -401.461217) (xy 291.407799 -401.401493)
			(xy 291.445751 -401.345906) (xy 291.46754 -401.320254) (xy 291.473344 -401.313114) (xy 291.479853 -401.295919)
			(xy 291.48024 -401.286726) (xy 291.48024 -400.793458) (xy 291.479841 -400.78427) (xy 291.473319 -400.767086)
			(xy 291.46754 -400.75993) (xy 291.445758 -400.734273) (xy 291.407809 -400.678687) (xy 291.376776 -400.618964)
			(xy 291.353103 -400.55596) (xy 291.337129 -400.490579) (xy 291.329085 -400.423757) (xy 291.329084 -400.356452)
			(xy 291.337128 -400.28963) (xy 291.3531 -400.224248) (xy 291.376772 -400.161244) (xy 291.407805 -400.101521)
			(xy 291.445753 -400.045934) (xy 291.46754 -400.020282) (xy 291.473332 -400.013134) (xy 291.479848 -399.995945)
			(xy 291.48024 -399.986754) (xy 291.48024 -399.828766) (xy 291.480706 -399.818606) (xy 291.488492 -399.799835)
			(xy 291.502866 -399.785471) (xy 291.521641 -399.777698) (xy 291.531802 -399.777204) (xy 292.248082 -399.777204)
			(xy 292.258234 -399.777747) (xy 292.276997 -399.785509) (xy 292.291361 -399.79986) (xy 292.299143 -399.818614)
			(xy 292.299644 -399.828766) (xy 292.299644 -399.986754) (xy 292.300089 -399.995937) (xy 292.30658 -400.013121)
			(xy 292.312344 -400.020282) (xy 292.334138 -400.045929) (xy 292.372088 -400.101516) (xy 292.403122 -400.16124)
			(xy 292.426795 -400.224245) (xy 292.442768 -400.289628) (xy 292.450812 -400.356452) (xy 292.450811 -400.423757)
			(xy 292.442766 -400.490581) (xy 292.426792 -400.555963) (xy 292.403118 -400.618968) (xy 292.372083 -400.678692)
			(xy 292.334132 -400.734278) (xy 292.312344 -400.75993) (xy 292.306545 -400.767073) (xy 292.300033 -400.784266)
			(xy 292.299644 -400.793458) (xy 292.299644 -401.286726) (xy 292.300054 -401.295913) (xy 292.306569 -401.313097)
			(xy 292.312344 -401.320254) (xy 292.33411 -401.345924) (xy 292.372061 -401.401507) (xy 292.403096 -401.461228)
			(xy 292.426771 -401.524231) (xy 292.442746 -401.589611) (xy 292.450792 -401.656432) (xy 292.450794 -401.723735)
			(xy 292.442752 -401.790557) (xy 292.426781 -401.855938) (xy 292.40311 -401.918941) (xy 292.372078 -401.978664)
			(xy 292.334131 -402.03425) (xy 292.312344 -402.059902) (xy 292.306557 -402.067054) (xy 292.300038 -402.084239)
			(xy 292.299644 -402.09343) (xy 292.299644 -402.251418) (xy 292.299181 -402.261579) (xy 292.291397 -402.280352)
			(xy 292.277022 -402.294718) (xy 292.258244 -402.302488) (xy 292.248082 -402.30298) (xy 291.531802 -402.30298)
			(xy 291.521647 -402.302465) (xy 291.502881 -402.294695) (xy 291.488516 -402.280336) (xy 291.480739 -402.261573)
			(xy 291.48024 -402.251418) (xy 291.48024 -402.09343) (xy 291.479806 -402.084246) (xy 291.473308 -402.067061)
			(xy 291.46754 -402.059902) (xy 291.44573 -402.034268) (xy 291.407782 -401.978679) (xy 291.37675 -401.918953)
			(xy 291.353078 -401.855946) (xy 291.337107 -401.790561) (xy 291.329064 -401.723737) (xy 290.200515 -401.723737)
			(xy 290.171926 -401.778764) (xy 290.133981 -401.834351) (xy 290.112196 -401.860004) (xy 290.106415 -401.86716)
			(xy 290.099891 -401.884342) (xy 290.099496 -401.893532) (xy 290.099496 -402.3868) (xy 290.099907 -402.395987)
			(xy 290.10642 -402.413171) (xy 290.112196 -402.420328) (xy 290.133935 -402.44602) (xy 290.171883 -402.501601)
			(xy 290.202916 -402.56132) (xy 290.22659 -402.624319) (xy 290.242566 -402.689696) (xy 290.250613 -402.756514)
			(xy 290.250617 -402.823814) (xy 290.250609 -402.823878) (xy 293.528678 -402.823878) (xy 293.528683 -402.75645)
			(xy 293.536763 -402.689509) (xy 293.552803 -402.624017) (xy 293.576572 -402.560919) (xy 293.607728 -402.501121)
			(xy 293.645822 -402.445485) (xy 293.667688 -402.41982) (xy 293.6735 -402.412685) (xy 293.680006 -402.395487)
			(xy 293.680388 -402.386292) (xy 293.680388 -401.89404) (xy 293.679961 -401.884854) (xy 293.67346 -401.86767)
			(xy 293.667688 -401.860512) (xy 293.645805 -401.834863) (xy 293.607717 -401.779226) (xy 293.576568 -401.719427)
			(xy 293.552806 -401.656328) (xy 293.536772 -401.590837) (xy 293.528698 -401.523897) (xy 293.5287 -401.456472)
			(xy 293.536777 -401.389533) (xy 293.552815 -401.324043) (xy 293.576581 -401.260945) (xy 293.607733 -401.201149)
			(xy 293.645823 -401.145513) (xy 293.667688 -401.119848) (xy 293.673488 -401.112705) (xy 293.680001 -401.095513)
			(xy 293.680388 -401.08632) (xy 293.680388 -400.92884) (xy 293.680849 -400.918722) (xy 293.688581 -400.900021)
			(xy 293.702884 -400.885706) (xy 293.721578 -400.877957) (xy 293.731696 -400.877532) (xy 294.447976 -400.877532)
			(xy 294.458101 -400.877936) (xy 294.47681 -400.885682) (xy 294.491127 -400.900003) (xy 294.498867 -400.918715)
			(xy 294.499284 -400.92884) (xy 294.499284 -401.08632) (xy 294.499688 -401.095508) (xy 294.506206 -401.112692)
			(xy 294.511984 -401.119848) (xy 294.533829 -401.145529) (xy 294.571919 -401.201161) (xy 294.603072 -401.260955)
			(xy 294.626838 -401.32405) (xy 294.642875 -401.389537) (xy 294.650953 -401.456474) (xy 294.650955 -401.523896)
			(xy 294.64288 -401.590833) (xy 294.626847 -401.656322) (xy 294.603084 -401.719418) (xy 294.600803 -401.723797)
			(xy 295.728833 -401.723797) (xy 295.728835 -401.65637) (xy 295.736913 -401.58943) (xy 295.752952 -401.523939)
			(xy 295.77672 -401.460841) (xy 295.807876 -401.401045) (xy 295.845969 -401.345411) (xy 295.867836 -401.319746)
			(xy 295.873643 -401.312608) (xy 295.88015 -401.295412) (xy 295.880536 -401.286218) (xy 295.880536 -400.793966)
			(xy 295.880134 -400.784778) (xy 295.873614 -400.767594) (xy 295.867836 -400.760438) (xy 295.845977 -400.734769)
			(xy 295.807885 -400.679135) (xy 295.776732 -400.61934) (xy 295.752966 -400.556244) (xy 295.736929 -400.490755)
			(xy 295.728852 -400.423816) (xy 295.728852 -400.356393) (xy 295.736928 -400.289454) (xy 295.752964 -400.223965)
			(xy 295.776729 -400.160868) (xy 295.807881 -400.101072) (xy 295.845971 -400.045439) (xy 295.867836 -400.019774)
			(xy 295.873631 -400.012628) (xy 295.880146 -399.995438) (xy 295.880536 -399.986246) (xy 295.880536 -399.828766)
			(xy 295.880999 -399.818638) (xy 295.888737 -399.799916) (xy 295.90303 -399.785561) (xy 295.921718 -399.777743)
			(xy 295.931844 -399.777204) (xy 296.648124 -399.777204) (xy 296.65828 -399.777602) (xy 296.677034 -399.785406)
			(xy 296.691357 -399.79981) (xy 296.699055 -399.818608) (xy 296.699432 -399.828766) (xy 296.699432 -399.986246)
			(xy 296.699883 -399.995429) (xy 296.70637 -400.012613) (xy 296.712132 -400.019774) (xy 296.734001 -400.045435)
			(xy 296.772087 -400.101071) (xy 296.803236 -400.160868) (xy 296.826998 -400.223965) (xy 296.843032 -400.289455)
			(xy 296.851107 -400.356393) (xy 296.851107 -400.423816) (xy 296.843031 -400.490754) (xy 296.826996 -400.556243)
			(xy 296.803232 -400.61934) (xy 296.772083 -400.679137) (xy 296.733995 -400.734772) (xy 296.712132 -400.760438)
			(xy 296.706329 -400.767578) (xy 296.69982 -400.784773) (xy 296.699432 -400.793966) (xy 296.699432 -401.286218)
			(xy 296.699849 -401.295404) (xy 296.70636 -401.312588) (xy 296.712132 -401.319746) (xy 296.733973 -401.34543)
			(xy 296.77206 -401.401062) (xy 296.80321 -401.460856) (xy 296.826974 -401.523951) (xy 296.84301 -401.589437)
			(xy 296.851088 -401.656373) (xy 296.85109 -401.723794) (xy 296.843016 -401.79073) (xy 296.826984 -401.856218)
			(xy 296.803224 -401.919314) (xy 296.772078 -401.979109) (xy 296.733994 -402.034744) (xy 296.712132 -402.06041)
			(xy 296.70634 -402.067558) (xy 296.699825 -402.084747) (xy 296.699432 -402.093938) (xy 296.699432 -402.251418)
			(xy 296.698988 -402.261549) (xy 296.691249 -402.280276) (xy 296.676949 -402.294633) (xy 296.658253 -402.302447)
			(xy 296.648124 -402.30298) (xy 295.931844 -402.30298) (xy 295.92169 -402.302542) (xy 295.902935 -402.294757)
			(xy 295.888609 -402.280365) (xy 295.880912 -402.261574) (xy 295.880536 -402.251418) (xy 295.880536 -402.093938)
			(xy 295.880099 -402.084754) (xy 295.873603 -402.06757) (xy 295.867836 -402.06041) (xy 295.845949 -402.034763)
			(xy 295.807859 -401.979127) (xy 295.776707 -401.919328) (xy 295.752942 -401.856229) (xy 295.736907 -401.790737)
			(xy 295.728833 -401.723797) (xy 294.600803 -401.723797) (xy 294.571935 -401.779213) (xy 294.533847 -401.834847)
			(xy 294.511984 -401.860512) (xy 294.506198 -401.867665) (xy 294.499678 -401.88485) (xy 294.499284 -401.89404)
			(xy 294.499284 -402.386292) (xy 294.499702 -402.395478) (xy 294.506211 -402.412662) (xy 294.511984 -402.41982)
			(xy 294.533801 -402.445524) (xy 294.571893 -402.501152) (xy 294.603046 -402.560943) (xy 294.626814 -402.624035)
			(xy 294.642853 -402.68952) (xy 294.650933 -402.756454) (xy 294.650937 -402.823819) (xy 297.928973 -402.823819)
			(xy 297.928978 -402.756509) (xy 297.937027 -402.689683) (xy 297.953006 -402.624297) (xy 297.976686 -402.561291)
			(xy 298.007727 -402.501566) (xy 298.045684 -402.445979) (xy 298.067476 -402.420328) (xy 298.073283 -402.41319)
			(xy 298.079792 -402.395994) (xy 298.080176 -402.3868) (xy 298.080176 -401.893532) (xy 298.079756 -401.884346)
			(xy 298.07325 -401.867161) (xy 298.067476 -401.860004) (xy 298.045668 -401.834368) (xy 298.007717 -401.77878)
			(xy 297.976683 -401.719055) (xy 297.953009 -401.656048) (xy 297.937037 -401.590664) (xy 297.928993 -401.523839)
			(xy 297.928995 -401.456531) (xy 297.937042 -401.389707) (xy 297.953018 -401.324323) (xy 297.976695 -401.261318)
			(xy 298.007732 -401.201594) (xy 298.045686 -401.146008) (xy 298.067476 -401.120356) (xy 298.073271 -401.113209)
			(xy 298.079787 -401.09602) (xy 298.080176 -401.086828) (xy 298.080176 -400.92884) (xy 298.080654 -400.918691)
			(xy 298.088432 -400.899945) (xy 298.102811 -400.885621) (xy 298.121588 -400.877915) (xy 298.131738 -400.877532)
			(xy 298.848018 -400.877532) (xy 298.858145 -400.878011) (xy 298.876865 -400.885744) (xy 298.89122 -400.900032)
			(xy 298.89904 -400.918716) (xy 298.89958 -400.92884) (xy 298.89958 -401.086828) (xy 298.899981 -401.096016)
			(xy 298.906502 -401.1132) (xy 298.91228 -401.120356) (xy 298.934048 -401.146024) (xy 298.971996 -401.201609)
			(xy 299.003029 -401.261331) (xy 299.026702 -401.324333) (xy 299.042676 -401.389713) (xy 299.050721 -401.456533)
			(xy 299.050723 -401.523837) (xy 299.042681 -401.590657) (xy 299.026711 -401.656038) (xy 299.003041 -401.719042)
			(xy 299.000571 -401.723796) (xy 300.128624 -401.723796) (xy 300.128626 -401.656371) (xy 300.136704 -401.58943)
			(xy 300.152743 -401.52394) (xy 300.17651 -401.460842) (xy 300.207665 -401.401045) (xy 300.245758 -401.345411)
			(xy 300.267624 -401.319746) (xy 300.273429 -401.312607) (xy 300.279938 -401.295412) (xy 300.280324 -401.286218)
			(xy 300.280324 -400.793966) (xy 300.279925 -400.784778) (xy 300.273403 -400.767594) (xy 300.267624 -400.760438)
			(xy 300.245765 -400.734768) (xy 300.207675 -400.679135) (xy 300.176522 -400.61934) (xy 300.152757 -400.556243)
			(xy 300.13672 -400.490755) (xy 300.128643 -400.423816) (xy 300.128643 -400.356393) (xy 300.136719 -400.289454)
			(xy 300.152754 -400.223965) (xy 300.176519 -400.160869) (xy 300.20767 -400.101073) (xy 300.24576 -400.045439)
			(xy 300.267624 -400.019774) (xy 300.273417 -400.012626) (xy 300.279933 -399.995438) (xy 300.280324 -399.986246)
			(xy 300.280324 -399.828766) (xy 300.280798 -399.818639) (xy 300.288534 -399.79992) (xy 300.302824 -399.785566)
			(xy 300.321507 -399.777745) (xy 300.331632 -399.777204) (xy 301.047912 -399.777204) (xy 301.058067 -399.777612)
			(xy 301.076821 -399.785412) (xy 301.091144 -399.799813) (xy 301.098843 -399.818608) (xy 301.09922 -399.828766)
			(xy 301.09922 -399.986246) (xy 301.099652 -399.995431) (xy 301.10615 -400.012616) (xy 301.11192 -400.019774)
			(xy 301.133789 -400.045435) (xy 301.171876 -400.10107) (xy 301.203026 -400.160867) (xy 301.226789 -400.223965)
			(xy 301.242823 -400.289454) (xy 301.250898 -400.356393) (xy 301.250898 -400.423816) (xy 301.242821 -400.490755)
			(xy 301.226786 -400.556244) (xy 301.203022 -400.619341) (xy 301.171872 -400.679137) (xy 301.133784 -400.734772)
			(xy 301.11192 -400.760438) (xy 301.106127 -400.767586) (xy 301.09961 -400.784774) (xy 301.09922 -400.793966)
			(xy 301.09922 -401.286218) (xy 301.099617 -401.295407) (xy 301.106139 -401.312591) (xy 301.11192 -401.319746)
			(xy 301.133762 -401.345429) (xy 301.17185 -401.401062) (xy 301.203 -401.460856) (xy 301.226765 -401.52395)
			(xy 301.242801 -401.589437) (xy 301.250878 -401.656373) (xy 301.25088 -401.723794) (xy 301.242807 -401.790731)
			(xy 301.226775 -401.856218) (xy 301.203014 -401.919314) (xy 301.171867 -401.97911) (xy 301.133782 -402.034744)
			(xy 301.11192 -402.06041) (xy 301.106139 -402.067566) (xy 301.099614 -402.084748) (xy 301.09922 -402.093938)
			(xy 301.09922 -402.251418) (xy 301.098787 -402.261551) (xy 301.091046 -402.28028) (xy 301.076743 -402.294637)
			(xy 301.058043 -402.302449) (xy 301.047912 -402.30298) (xy 300.331632 -402.30298) (xy 300.321477 -402.302552)
			(xy 300.302722 -402.294763) (xy 300.288396 -402.280368) (xy 300.280699 -402.261575) (xy 300.280324 -402.251418)
			(xy 300.280324 -402.093938) (xy 300.27989 -402.084753) (xy 300.273392 -402.067569) (xy 300.267624 -402.06041)
			(xy 300.245738 -402.034763) (xy 300.207648 -401.979126) (xy 300.176497 -401.919328) (xy 300.152733 -401.856229)
			(xy 300.136698 -401.790737) (xy 300.128624 -401.723796) (xy 299.000571 -401.723796) (xy 298.972011 -401.778765)
			(xy 298.934066 -401.834352) (xy 298.91228 -401.860004) (xy 298.906497 -401.867159) (xy 298.899975 -401.884342)
			(xy 298.89958 -401.893532) (xy 298.89958 -402.3868) (xy 298.899994 -402.395987) (xy 298.906505 -402.413171)
			(xy 298.91228 -402.420328) (xy 298.93402 -402.446019) (xy 298.971969 -402.501601) (xy 299.003003 -402.561319)
			(xy 299.026678 -402.624318) (xy 299.042653 -402.689696) (xy 299.050701 -402.756513) (xy 299.050705 -402.823814)
			(xy 299.050697 -402.823877) (xy 302.328766 -402.823877) (xy 302.328771 -402.75645) (xy 302.336851 -402.689509)
			(xy 302.35289 -402.624018) (xy 302.376659 -402.560919) (xy 302.407814 -402.501122) (xy 302.445906 -402.445486)
			(xy 302.467772 -402.41982) (xy 302.473594 -402.412693) (xy 302.480091 -402.395488) (xy 302.480472 -402.386292)
			(xy 302.480472 -401.89404) (xy 302.480049 -401.884854) (xy 302.473545 -401.867669) (xy 302.467772 -401.860512)
			(xy 302.445889 -401.834863) (xy 302.407803 -401.779225) (xy 302.376655 -401.719426) (xy 302.352893 -401.656328)
			(xy 302.33686 -401.590837) (xy 302.328786 -401.523897) (xy 302.328788 -401.456473) (xy 302.336865 -401.389534)
			(xy 302.352902 -401.324044) (xy 302.376667 -401.260946) (xy 302.407819 -401.201149) (xy 302.445908 -401.145514)
			(xy 302.467772 -401.119848) (xy 302.473582 -401.112713) (xy 302.480087 -401.095514) (xy 302.480472 -401.08632)
			(xy 302.480472 -400.92884) (xy 302.480948 -400.918724) (xy 302.488678 -400.900026) (xy 302.502976 -400.885712)
			(xy 302.521664 -400.87796) (xy 302.53178 -400.877532) (xy 303.24806 -400.877532) (xy 303.258184 -400.87795)
			(xy 303.276893 -400.885691) (xy 303.291209 -400.900007) (xy 303.29895 -400.918716) (xy 303.299368 -400.92884)
			(xy 303.299368 -401.08632) (xy 303.299776 -401.095507) (xy 303.306292 -401.112691) (xy 303.312068 -401.119848)
			(xy 303.333913 -401.145529) (xy 303.372005 -401.20116) (xy 303.403158 -401.260954) (xy 303.426925 -401.324049)
			(xy 303.442963 -401.389537) (xy 303.451041 -401.456474) (xy 303.451043 -401.523896) (xy 303.442968 -401.590834)
			(xy 303.426934 -401.656322) (xy 303.40317 -401.719418) (xy 303.37202 -401.779214) (xy 303.333932 -401.834847)
			(xy 303.312068 -401.860512) (xy 303.30628 -401.867663) (xy 303.299761 -401.884849) (xy 303.299368 -401.89404)
			(xy 303.299368 -402.386292) (xy 303.299789 -402.395478) (xy 303.306296 -402.412662) (xy 303.312068 -402.41982)
			(xy 303.333886 -402.445524) (xy 303.371978 -402.501152) (xy 303.403133 -402.560942) (xy 303.426901 -402.624034)
			(xy 303.442941 -402.689519) (xy 303.451021 -402.756454) (xy 303.451025 -402.823874) (xy 303.442954 -402.89081)
			(xy 303.426922 -402.956297) (xy 303.403162 -403.019392) (xy 303.372015 -403.079186) (xy 303.33393 -403.134819)
			(xy 303.312068 -403.160484) (xy 303.306249 -403.167613) (xy 303.299749 -403.184816) (xy 303.299368 -403.194012)
			(xy 303.299368 -403.351492) (xy 303.298977 -403.361618) (xy 303.291225 -403.380328) (xy 303.276901 -403.394643)
			(xy 303.258186 -403.402383) (xy 303.24806 -403.4028) (xy 302.53178 -403.4028) (xy 302.52167 -403.402331)
			(xy 302.502991 -403.394587) (xy 302.488697 -403.380285) (xy 302.480963 -403.361602) (xy 302.480472 -403.351492)
			(xy 302.480472 -403.194012) (xy 302.480062 -403.184825) (xy 302.473549 -403.16764) (xy 302.467772 -403.160484)
			(xy 302.445862 -403.134857) (xy 302.407776 -403.079216) (xy 302.376629 -403.019415) (xy 302.352869 -402.956313)
			(xy 302.336838 -402.890819) (xy 302.328766 -402.823877) (xy 299.050697 -402.823877) (xy 299.042666 -402.890633)
			(xy 299.026699 -402.956013) (xy 299.003032 -403.019015) (xy 298.972006 -403.078737) (xy 298.934064 -403.134323)
			(xy 298.91228 -403.159976) (xy 298.906466 -403.167109) (xy 298.899963 -403.184309) (xy 298.89958 -403.193504)
			(xy 298.89958 -403.351492) (xy 298.899171 -403.361648) (xy 298.891375 -403.380404) (xy 298.876974 -403.394729)
			(xy 298.858176 -403.402425) (xy 298.848018 -403.4028) (xy 298.131738 -403.4028) (xy 298.121619 -403.402243)
			(xy 298.102906 -403.394535) (xy 298.08855 -403.380271) (xy 298.080722 -403.361608) (xy 298.080176 -403.351492)
			(xy 298.080176 -403.193504) (xy 298.079769 -403.184316) (xy 298.073254 -403.167132) (xy 298.067476 -403.159976)
			(xy 298.04564 -403.134363) (xy 298.00769 -403.078772) (xy 297.976657 -403.019043) (xy 297.952985 -402.956034)
			(xy 297.937014 -402.890646) (xy 297.928973 -402.823819) (xy 294.650937 -402.823819) (xy 294.650937 -402.823874)
			(xy 294.642866 -402.890809) (xy 294.626835 -402.956296) (xy 294.603076 -403.019391) (xy 294.57193 -403.079186)
			(xy 294.533846 -403.134819) (xy 294.511984 -403.160484) (xy 294.506167 -403.167615) (xy 294.499665 -403.184816)
			(xy 294.499284 -403.194012) (xy 294.499284 -403.351492) (xy 294.498877 -403.361616) (xy 294.491129 -403.380322)
			(xy 294.476809 -403.394638) (xy 294.4581 -403.40238) (xy 294.447976 -403.4028) (xy 293.731696 -403.4028)
			(xy 293.721573 -403.402387) (xy 293.70287 -403.394638) (xy 293.688556 -403.38032) (xy 293.68081 -403.361615)
			(xy 293.680388 -403.351492) (xy 293.680388 -403.194012) (xy 293.679975 -403.184825) (xy 293.673464 -403.167641)
			(xy 293.667688 -403.160484) (xy 293.645777 -403.134857) (xy 293.607691 -403.079217) (xy 293.576543 -403.019415)
			(xy 293.552782 -402.956314) (xy 293.53675 -402.89082) (xy 293.528678 -402.823878) (xy 290.250609 -402.823878)
			(xy 290.242579 -402.890633) (xy 290.226612 -402.956012) (xy 290.202946 -403.019014) (xy 290.17192 -403.078737)
			(xy 290.133979 -403.134323) (xy 290.112196 -403.159976) (xy 290.106384 -403.16711) (xy 290.099879 -403.184309)
			(xy 290.099496 -403.193504) (xy 290.099496 -403.351492) (xy 290.099072 -403.361646) (xy 290.091278 -403.380399)
			(xy 290.076882 -403.394723) (xy 290.05809 -403.402422) (xy 290.047934 -403.4028) (xy 289.331654 -403.4028)
			(xy 289.321529 -403.402312) (xy 289.302815 -403.394577) (xy 289.288461 -403.380292) (xy 289.280637 -403.361614)
			(xy 289.280092 -403.351492) (xy 289.280092 -403.193504) (xy 289.279682 -403.184317) (xy 289.273168 -403.167132)
			(xy 289.267392 -403.159976) (xy 289.245556 -403.134363) (xy 289.207605 -403.078772) (xy 289.176571 -403.019044)
			(xy 289.152898 -402.956034) (xy 289.136927 -402.890647) (xy 289.128886 -402.823819) (xy 237.030424 -402.823819)
			(xy 237.026709 -402.832791) (xy 237.026196 -402.84527) (xy 237.026196 -405.623708) (xy 286.928756 -405.623708)
			(xy 286.928757 -405.556283) (xy 286.936834 -405.489343) (xy 286.952872 -405.423853) (xy 286.976639 -405.360756)
			(xy 287.007793 -405.30096) (xy 287.045886 -405.245326) (xy 287.067752 -405.219662) (xy 287.073554 -405.212521)
			(xy 287.080064 -405.195327) (xy 287.080452 -405.186134) (xy 287.080452 -404.693882) (xy 287.080039 -404.684695)
			(xy 287.073526 -404.667512) (xy 287.067752 -404.660354) (xy 287.045908 -404.634672) (xy 287.007815 -404.579041)
			(xy 286.97666 -404.519248) (xy 286.952893 -404.456153) (xy 286.936854 -404.390665) (xy 286.928776 -404.323728)
			(xy 286.928774 -404.256305) (xy 286.936848 -404.189367) (xy 286.952883 -404.123879) (xy 286.976647 -404.060783)
			(xy 287.007798 -404.000987) (xy 287.045888 -403.945354) (xy 287.067752 -403.91969) (xy 287.073542 -403.91254)
			(xy 287.080059 -403.895353) (xy 287.080452 -403.886162) (xy 287.080452 -403.728682) (xy 287.080912 -403.718553)
			(xy 287.088648 -403.699829) (xy 287.102942 -403.685473) (xy 287.121633 -403.677656) (xy 287.13176 -403.67712)
			(xy 287.84804 -403.67712) (xy 287.858199 -403.677489) (xy 287.876956 -403.685302) (xy 287.891279 -403.699715)
			(xy 287.898974 -403.71852) (xy 287.899348 -403.728682) (xy 287.899348 -403.886162) (xy 287.899788 -403.895346)
			(xy 287.906282 -403.91253) (xy 287.912048 -403.91969) (xy 287.933935 -403.945337) (xy 287.972027 -404.000973)
			(xy 288.00318 -404.060771) (xy 288.026945 -404.12387) (xy 288.04298 -404.189362) (xy 288.051055 -404.256303)
			(xy 288.051053 -404.32373) (xy 288.042974 -404.39067) (xy 288.026935 -404.456161) (xy 288.003166 -404.519259)
			(xy 287.97201 -404.579056) (xy 287.933915 -404.63469) (xy 287.912048 -404.660354) (xy 287.90624 -404.667491)
			(xy 287.899733 -404.684688) (xy 287.899348 -404.693882) (xy 287.899348 -405.186134) (xy 287.899754 -405.195321)
			(xy 287.906272 -405.212505) (xy 287.912048 -405.219662) (xy 287.933908 -405.245331) (xy 287.972 -405.300964)
			(xy 288.003154 -405.360759) (xy 288.026921 -405.423856) (xy 288.042958 -405.489345) (xy 288.051036 -405.556283)
			(xy 288.051036 -405.623708) (xy 288.04296 -405.690646) (xy 288.026924 -405.756136) (xy 288.003158 -405.819233)
			(xy 287.972005 -405.879028) (xy 287.933913 -405.934662) (xy 287.912048 -405.960326) (xy 287.906251 -405.967471)
			(xy 287.899738 -405.984662) (xy 287.899348 -405.993854) (xy 287.899348 -406.151334) (xy 287.898901 -406.161464)
			(xy 287.89116 -406.180189) (xy 287.876861 -406.194544) (xy 287.858168 -406.20236) (xy 287.84804 -406.202896)
			(xy 287.13176 -406.202896) (xy 287.121603 -406.202511) (xy 287.102849 -406.194701) (xy 287.088527 -406.180294)
			(xy 287.080829 -406.161494) (xy 287.080452 -406.151334) (xy 287.080452 -405.993854) (xy 287.080004 -405.984671)
			(xy 287.073515 -405.967487) (xy 287.067752 -405.960326) (xy 287.04588 -405.934667) (xy 287.007788 -405.879032)
			(xy 286.976635 -405.819236) (xy 286.952869 -405.756138) (xy 286.936832 -405.690648) (xy 286.928756 -405.623708)
			(xy 237.026196 -405.623708) (xy 237.026196 -406.72373) (xy 289.128897 -406.72373) (xy 289.1289 -406.656422)
			(xy 289.136948 -406.589596) (xy 289.152926 -406.524211) (xy 289.176605 -406.461205) (xy 289.207645 -406.401481)
			(xy 289.245601 -406.345895) (xy 289.267392 -406.320244) (xy 289.273194 -406.313103) (xy 289.279706 -406.295909)
			(xy 289.280092 -406.286716) (xy 289.280092 -405.793448) (xy 289.279661 -405.784263) (xy 289.273162 -405.767078)
			(xy 289.267392 -405.75992) (xy 289.245599 -405.734272) (xy 289.207647 -405.678686) (xy 289.176611 -405.618962)
			(xy 289.152936 -405.555957) (xy 289.136961 -405.490574) (xy 289.128917 -405.42375) (xy 289.128917 -405.356444)
			(xy 289.136962 -405.28962) (xy 289.152937 -405.224237) (xy 289.176613 -405.161232) (xy 289.20765 -405.101509)
			(xy 289.245602 -405.045923) (xy 289.267392 -405.020272) (xy 289.273182 -405.013122) (xy 289.279701 -404.995935)
			(xy 289.280092 -404.986744) (xy 289.280092 -404.828756) (xy 289.280486 -404.8186) (xy 289.288294 -404.799848)
			(xy 289.302699 -404.785527) (xy 289.321496 -404.777827) (xy 289.331654 -404.777448) (xy 290.047934 -404.777448)
			(xy 290.058064 -404.777899) (xy 290.076787 -404.785639) (xy 290.091143 -404.799936) (xy 290.098959 -404.818628)
			(xy 290.099496 -404.828756) (xy 290.099496 -404.986744) (xy 290.099886 -404.995933) (xy 290.106414 -405.013117)
			(xy 290.112196 -405.020272) (xy 290.133979 -405.045928) (xy 290.171925 -405.101515) (xy 290.202957 -405.161238)
			(xy 290.226628 -405.224242) (xy 290.242601 -405.289623) (xy 290.250644 -405.356445) (xy 290.250645 -405.423749)
			(xy 290.242602 -405.490571) (xy 290.22663 -405.555952) (xy 290.202959 -405.618957) (xy 290.200522 -405.623648)
			(xy 291.329076 -405.623648) (xy 291.329076 -405.556343) (xy 291.337121 -405.48952) (xy 291.353095 -405.424137)
			(xy 291.376768 -405.361132) (xy 291.407802 -405.301409) (xy 291.445752 -405.245822) (xy 291.46754 -405.22017)
			(xy 291.473337 -405.213025) (xy 291.47985 -405.195834) (xy 291.48024 -405.186642) (xy 291.48024 -404.693374)
			(xy 291.479833 -404.684187) (xy 291.473316 -404.667003) (xy 291.46754 -404.659846) (xy 291.445774 -404.634176)
			(xy 291.407825 -404.578592) (xy 291.37679 -404.518871) (xy 291.353116 -404.455869) (xy 291.337142 -404.390489)
			(xy 291.329096 -404.323668) (xy 291.329094 -404.256365) (xy 291.337136 -404.189544) (xy 291.353106 -404.124163)
			(xy 291.376777 -404.061159) (xy 291.407808 -404.001436) (xy 291.445754 -403.94585) (xy 291.46754 -403.920198)
			(xy 291.473325 -403.913045) (xy 291.479846 -403.89586) (xy 291.48024 -403.88667) (xy 291.48024 -403.728682)
			(xy 291.480718 -403.718523) (xy 291.488499 -403.699753) (xy 291.50287 -403.685388) (xy 291.521643 -403.677615)
			(xy 291.531802 -403.67712) (xy 292.248082 -403.67712) (xy 292.258236 -403.677648) (xy 292.277002 -403.685413)
			(xy 292.291367 -403.699768) (xy 292.299145 -403.718528) (xy 292.299644 -403.728682) (xy 292.299644 -403.88667)
			(xy 292.300081 -403.895854) (xy 292.306577 -403.913038) (xy 292.312344 -403.920198) (xy 292.334154 -403.945832)
			(xy 292.372103 -404.001421) (xy 292.403137 -404.061147) (xy 292.426809 -404.124153) (xy 292.442781 -404.189538)
			(xy 292.450824 -404.256363) (xy 292.450822 -404.32367) (xy 292.442775 -404.390495) (xy 292.426799 -404.455878)
			(xy 292.403123 -404.518884) (xy 292.372086 -404.578608) (xy 292.334134 -404.634194) (xy 292.312344 -404.659846)
			(xy 292.306539 -404.666985) (xy 292.300031 -404.68418) (xy 292.299644 -404.693374) (xy 292.299644 -405.186642)
			(xy 292.300047 -405.19583) (xy 292.306567 -405.213013) (xy 292.312344 -405.22017) (xy 292.334126 -405.245827)
			(xy 292.372076 -405.301412) (xy 292.403111 -405.361135) (xy 292.426785 -405.424139) (xy 292.442758 -405.489521)
			(xy 292.450803 -405.556343) (xy 292.450804 -405.623648) (xy 292.44276 -405.69047) (xy 292.426787 -405.755852)
			(xy 292.403114 -405.818857) (xy 292.372081 -405.87858) (xy 292.334132 -405.934166) (xy 292.312344 -405.959818)
			(xy 292.30655 -405.966965) (xy 292.300035 -405.984154) (xy 292.299644 -405.993346) (xy 292.299644 -406.151334)
			(xy 292.299194 -406.161496) (xy 292.291405 -406.18027) (xy 292.277026 -406.194634) (xy 292.258245 -406.202404)
			(xy 292.248082 -406.202896) (xy 291.531802 -406.202896) (xy 291.521649 -406.202366) (xy 291.502886 -406.194598)
			(xy 291.488522 -406.180244) (xy 291.480741 -406.161487) (xy 291.48024 -406.151334) (xy 291.48024 -405.993346)
			(xy 291.479799 -405.984162) (xy 291.473306 -405.966978) (xy 291.46754 -405.959818) (xy 291.445746 -405.934171)
			(xy 291.407797 -405.878584) (xy 291.376764 -405.818859) (xy 291.353092 -405.755854) (xy 291.337119 -405.690471)
			(xy 291.329076 -405.623648) (xy 290.200522 -405.623648) (xy 290.171928 -405.67868) (xy 290.133982 -405.734267)
			(xy 290.112196 -405.75992) (xy 290.106408 -405.767071) (xy 290.099888 -405.784257) (xy 290.099496 -405.793448)
			(xy 290.099496 -406.286716) (xy 290.099899 -406.295904) (xy 290.106418 -406.313088) (xy 290.112196 -406.320244)
			(xy 290.133951 -406.345922) (xy 290.171899 -406.401506) (xy 290.202931 -406.461226) (xy 290.226605 -406.524227)
			(xy 290.242579 -406.589606) (xy 290.250625 -406.656425) (xy 290.250628 -406.723727) (xy 290.250621 -406.723789)
			(xy 293.52869 -406.723789) (xy 293.528692 -406.656363) (xy 293.536771 -406.589423) (xy 293.55281 -406.523932)
			(xy 293.576577 -406.460834) (xy 293.607731 -406.401037) (xy 293.645823 -406.345401) (xy 293.667688 -406.319736)
			(xy 293.673493 -406.312597) (xy 293.680003 -406.295402) (xy 293.680388 -406.286208) (xy 293.680388 -405.793956)
			(xy 293.680002 -405.784766) (xy 293.673472 -405.767582) (xy 293.667688 -405.760428) (xy 293.645821 -405.734766)
			(xy 293.607733 -405.679131) (xy 293.576583 -405.619334) (xy 293.552819 -405.556237) (xy 293.536785 -405.490747)
			(xy 293.528709 -405.423809) (xy 293.52871 -405.356385) (xy 293.536786 -405.289447) (xy 293.552821 -405.223958)
			(xy 293.576585 -405.160861) (xy 293.607736 -405.101064) (xy 293.645824 -405.045429) (xy 293.667688 -405.019764)
			(xy 293.673481 -405.012616) (xy 293.679998 -404.995428) (xy 293.680388 -404.986236) (xy 293.680388 -404.828756)
			(xy 293.680849 -404.818646) (xy 293.688599 -404.799969) (xy 293.702903 -404.785676) (xy 293.721586 -404.777941)
			(xy 293.731696 -404.777448) (xy 294.447976 -404.777448) (xy 294.458077 -404.778003) (xy 294.476745 -404.785723)
			(xy 294.491038 -404.799998) (xy 294.498783 -404.818656) (xy 294.499284 -404.828756) (xy 294.499284 -404.986236)
			(xy 294.49968 -404.995425) (xy 294.506204 -405.012609) (xy 294.511984 -405.019764) (xy 294.533845 -405.045432)
			(xy 294.571934 -405.101066) (xy 294.603086 -405.160862) (xy 294.626851 -405.223958) (xy 294.642888 -405.289447)
			(xy 294.650964 -405.356385) (xy 294.650964 -405.423809) (xy 294.642889 -405.490747) (xy 294.626853 -405.556236)
			(xy 294.603089 -405.619333) (xy 294.60081 -405.623708) (xy 295.728844 -405.623708) (xy 295.728845 -405.556283)
			(xy 295.736922 -405.489344) (xy 295.752959 -405.423854) (xy 295.776725 -405.360757) (xy 295.807879 -405.30096)
			(xy 295.84597 -405.245327) (xy 295.867836 -405.219662) (xy 295.873636 -405.212519) (xy 295.880148 -405.195327)
			(xy 295.880536 -405.186134) (xy 295.880536 -404.693882) (xy 295.880126 -404.684695) (xy 295.873611 -404.667511)
			(xy 295.867836 -404.660354) (xy 295.845992 -404.634672) (xy 295.807901 -404.57904) (xy 295.776747 -404.519247)
			(xy 295.75298 -404.456152) (xy 295.736942 -404.390665) (xy 295.728864 -404.323728) (xy 295.728862 -404.256305)
			(xy 295.736936 -404.189368) (xy 295.75297 -404.123879) (xy 295.776733 -404.060783) (xy 295.807884 -404.000988)
			(xy 295.845972 -403.945355) (xy 295.867836 -403.91969) (xy 295.873624 -403.912539) (xy 295.880143 -403.895353)
			(xy 295.880536 -403.886162) (xy 295.880536 -403.728682) (xy 295.881011 -403.718555) (xy 295.888744 -403.699834)
			(xy 295.903034 -403.685478) (xy 295.921719 -403.677659) (xy 295.931844 -403.67712) (xy 296.648124 -403.67712)
			(xy 296.658282 -403.677502) (xy 296.677039 -403.685309) (xy 296.691362 -403.699718) (xy 296.699058 -403.718521)
			(xy 296.699432 -403.728682) (xy 296.699432 -403.886162) (xy 296.699876 -403.895345) (xy 296.706368 -403.912529)
			(xy 296.712132 -403.91969) (xy 296.734016 -403.945338) (xy 296.772102 -404.000976) (xy 296.80325 -404.060775)
			(xy 296.827012 -404.123874) (xy 296.843045 -404.189364) (xy 296.851118 -404.256304) (xy 296.851117 -404.323729)
			(xy 296.843039 -404.390668) (xy 296.827002 -404.456158) (xy 296.803237 -404.519256) (xy 296.772085 -404.579053)
			(xy 296.733996 -404.634688) (xy 296.712132 -404.660354) (xy 296.706322 -404.667489) (xy 296.699817 -404.684688)
			(xy 296.699432 -404.693882) (xy 296.699432 -405.186134) (xy 296.699841 -405.195321) (xy 296.706357 -405.212505)
			(xy 296.712132 -405.219662) (xy 296.733989 -405.245333) (xy 296.772076 -405.300967) (xy 296.803225 -405.360763)
			(xy 296.826988 -405.423859) (xy 296.843023 -405.489347) (xy 296.851099 -405.556284) (xy 296.851099 -405.623707)
			(xy 296.843025 -405.690644) (xy 296.826991 -405.756132) (xy 296.803229 -405.819229) (xy 296.77208 -405.879025)
			(xy 296.733994 -405.93466) (xy 296.712132 -405.960326) (xy 296.706334 -405.96747) (xy 296.699822 -405.984662)
			(xy 296.699432 -405.993854) (xy 296.699432 -406.151334) (xy 296.699001 -406.161466) (xy 296.691256 -406.180194)
			(xy 296.676953 -406.19455) (xy 296.658254 -406.202363) (xy 296.648124 -406.202896) (xy 295.931844 -406.202896)
			(xy 295.921692 -406.202442) (xy 295.90294 -406.19466) (xy 295.888615 -406.180273) (xy 295.880915 -406.161487)
			(xy 295.880536 -406.151334) (xy 295.880536 -405.993854) (xy 295.880092 -405.984671) (xy 295.873601 -405.967486)
			(xy 295.867836 -405.960326) (xy 295.845965 -405.934666) (xy 295.807874 -405.879032) (xy 295.776722 -405.819235)
			(xy 295.752956 -405.756137) (xy 295.73692 -405.690647) (xy 295.728844 -405.623708) (xy 294.60081 -405.623708)
			(xy 294.571938 -405.679129) (xy 294.533848 -405.734763) (xy 294.511984 -405.760428) (xy 294.506191 -405.767576)
			(xy 294.499675 -405.784764) (xy 294.499284 -405.793956) (xy 294.499284 -406.286208) (xy 294.499694 -406.295395)
			(xy 294.506208 -406.312579) (xy 294.511984 -406.319736) (xy 294.533817 -406.345427) (xy 294.571908 -406.401057)
			(xy 294.603061 -406.46085) (xy 294.626827 -406.523943) (xy 294.642866 -406.58943) (xy 294.650944 -406.656365)
			(xy 294.650947 -406.72373) (xy 297.928985 -406.72373) (xy 297.928988 -406.656422) (xy 297.937036 -406.589596)
			(xy 297.953013 -406.524212) (xy 297.976691 -406.461206) (xy 298.00773 -406.401482) (xy 298.045685 -406.345896)
			(xy 298.067476 -406.320244) (xy 298.073276 -406.313101) (xy 298.079789 -406.295909) (xy 298.080176 -406.286716)
			(xy 298.080176 -405.793448) (xy 298.079748 -405.784263) (xy 298.073247 -405.767078) (xy 298.067476 -405.75992)
			(xy 298.045683 -405.734272) (xy 298.007732 -405.678685) (xy 297.976697 -405.618962) (xy 297.953023 -405.555957)
			(xy 297.937049 -405.490574) (xy 297.929005 -405.42375) (xy 297.929005 -405.356444) (xy 297.93705 -405.28962)
			(xy 297.953025 -405.224238) (xy 297.9767 -405.161233) (xy 298.007735 -405.101509) (xy 298.045687 -405.045924)
			(xy 298.067476 -405.020272) (xy 298.073264 -405.013121) (xy 298.079785 -404.995935) (xy 298.080176 -404.986744)
			(xy 298.080176 -404.828756) (xy 298.080585 -404.818602) (xy 298.088391 -404.799853) (xy 298.102791 -404.785532)
			(xy 298.121582 -404.77783) (xy 298.131738 -404.777448) (xy 298.848018 -404.777448) (xy 298.858147 -404.777912)
			(xy 298.87687 -404.785647) (xy 298.891226 -404.79994) (xy 298.899043 -404.818629) (xy 298.89958 -404.828756)
			(xy 298.89958 -404.986744) (xy 298.899973 -404.995933) (xy 298.906499 -405.013117) (xy 298.91228 -405.020272)
			(xy 298.934063 -405.045928) (xy 298.972011 -405.101514) (xy 299.003043 -405.161237) (xy 299.026716 -405.224241)
			(xy 299.042688 -405.289623) (xy 299.050732 -405.356445) (xy 299.050733 -405.423749) (xy 299.042689 -405.490571)
			(xy 299.026717 -405.555953) (xy 299.003046 -405.618957) (xy 299.000577 -405.623708) (xy 300.128635 -405.623708)
			(xy 300.128635 -405.556283) (xy 300.136712 -405.489344) (xy 300.152749 -405.423854) (xy 300.176515 -405.360757)
			(xy 300.207668 -405.300961) (xy 300.245759 -405.245327) (xy 300.267624 -405.219662) (xy 300.273422 -405.212518)
			(xy 300.279935 -405.195326) (xy 300.280324 -405.186134) (xy 300.280324 -404.693882) (xy 300.279917 -404.684695)
			(xy 300.273401 -404.66751) (xy 300.267624 -404.660354) (xy 300.245781 -404.634671) (xy 300.20769 -404.57904)
			(xy 300.176537 -404.519246) (xy 300.15277 -404.456152) (xy 300.136733 -404.390664) (xy 300.128655 -404.323728)
			(xy 300.128653 -404.256305) (xy 300.136727 -404.189368) (xy 300.152761 -404.12388) (xy 300.176523 -404.060784)
			(xy 300.207673 -404.000989) (xy 300.245761 -403.945355) (xy 300.267624 -403.91969) (xy 300.27341 -403.912538)
			(xy 300.27993 -403.895352) (xy 300.280324 -403.886162) (xy 300.280324 -403.728682) (xy 300.280811 -403.718556)
			(xy 300.288542 -403.699837) (xy 300.302828 -403.685482) (xy 300.321509 -403.677661) (xy 300.331632 -403.67712)
			(xy 301.047912 -403.67712) (xy 301.058069 -403.677512) (xy 301.076826 -403.685315) (xy 301.09115 -403.699721)
			(xy 301.098846 -403.718522) (xy 301.09922 -403.728682) (xy 301.09922 -403.886162) (xy 301.099644 -403.895348)
			(xy 301.106147 -403.912533) (xy 301.11192 -403.91969) (xy 301.133805 -403.945338) (xy 301.171892 -404.000975)
			(xy 301.20304 -404.060774) (xy 301.226802 -404.123873) (xy 301.242836 -404.189364) (xy 301.250909 -404.256304)
			(xy 301.250907 -404.323729) (xy 301.24283 -404.390668) (xy 301.226793 -404.456158) (xy 301.203027 -404.519256)
			(xy 301.171875 -404.579053) (xy 301.133785 -404.634688) (xy 301.11192 -404.660354) (xy 301.10612 -404.667497)
			(xy 301.099607 -404.684689) (xy 301.09922 -404.693882) (xy 301.09922 -405.186134) (xy 301.099609 -405.195323)
			(xy 301.106137 -405.212508) (xy 301.11192 -405.219662) (xy 301.133777 -405.245332) (xy 301.171865 -405.300967)
			(xy 301.203015 -405.360762) (xy 301.226778 -405.423859) (xy 301.242814 -405.489347) (xy 301.25089 -405.556284)
			(xy 301.25089 -405.623707) (xy 301.242815 -405.690644) (xy 301.226781 -405.756133) (xy 301.203018 -405.819229)
			(xy 301.17187 -405.879026) (xy 301.133783 -405.93466) (xy 301.11192 -405.960326) (xy 301.106132 -405.967478)
			(xy 301.099612 -405.984663) (xy 301.09922 -405.993854) (xy 301.09922 -406.151334) (xy 301.0988 -406.161468)
			(xy 301.091054 -406.180197) (xy 301.076747 -406.194554) (xy 301.058044 -406.202365) (xy 301.047912 -406.202896)
			(xy 300.331632 -406.202896) (xy 300.321479 -406.202452) (xy 300.302727 -406.194667) (xy 300.288402 -406.180276)
			(xy 300.280702 -406.161488) (xy 300.280324 -406.151334) (xy 300.280324 -405.993854) (xy 300.279882 -405.98467)
			(xy 300.27339 -405.967486) (xy 300.267624 -405.960326) (xy 300.245753 -405.934666) (xy 300.207663 -405.879031)
			(xy 300.176511 -405.819235) (xy 300.152747 -405.756137) (xy 300.136711 -405.690647) (xy 300.128635 -405.623708)
			(xy 299.000577 -405.623708) (xy 298.972014 -405.678681) (xy 298.934067 -405.734268) (xy 298.91228 -405.75992)
			(xy 298.90649 -405.76707) (xy 298.899972 -405.784257) (xy 298.89958 -405.793448) (xy 298.89958 -406.286716)
			(xy 298.899987 -406.295903) (xy 298.906503 -406.313088) (xy 298.91228 -406.320244) (xy 298.934035 -406.345922)
			(xy 298.971984 -406.401506) (xy 299.003018 -406.461226) (xy 299.026691 -406.524227) (xy 299.042666 -406.589606)
			(xy 299.050712 -406.656425) (xy 299.050715 -406.723727) (xy 299.050708 -406.723789) (xy 302.328777 -406.723789)
			(xy 302.32878 -406.656363) (xy 302.336859 -406.589423) (xy 302.352897 -406.523933) (xy 302.376664 -406.460835)
			(xy 302.407816 -406.401037) (xy 302.445907 -406.345402) (xy 302.467772 -406.319736) (xy 302.473587 -406.312604)
			(xy 302.480089 -406.295403) (xy 302.480472 -406.286208) (xy 302.480472 -405.793956) (xy 302.480089 -405.784766)
			(xy 302.473557 -405.767581) (xy 302.467772 -405.760428) (xy 302.445905 -405.734766) (xy 302.407818 -405.67913)
			(xy 302.376669 -405.619333) (xy 302.352907 -405.556236) (xy 302.336872 -405.490747) (xy 302.328797 -405.423809)
			(xy 302.328798 -405.356385) (xy 302.336873 -405.289447) (xy 302.352908 -405.223958) (xy 302.376672 -405.160861)
			(xy 302.407821 -405.101065) (xy 302.445909 -405.04543) (xy 302.467772 -405.019764) (xy 302.473575 -405.012624)
			(xy 302.480084 -404.995429) (xy 302.480472 -404.986236) (xy 302.480472 -404.828756) (xy 302.480948 -404.818648)
			(xy 302.488695 -404.799974) (xy 302.502994 -404.785682) (xy 302.521672 -404.777944) (xy 302.53178 -404.777448)
			(xy 303.24806 -404.777448) (xy 303.25816 -404.778017) (xy 303.276827 -404.785732) (xy 303.291121 -404.800002)
			(xy 303.298867 -404.818657) (xy 303.299368 -404.828756) (xy 303.299368 -404.986236) (xy 303.299768 -404.995424)
			(xy 303.30629 -405.012608) (xy 303.312068 -405.019764) (xy 303.333929 -405.045432) (xy 303.37202 -405.101065)
			(xy 303.403173 -405.160861) (xy 303.426939 -405.223957) (xy 303.442975 -405.289447) (xy 303.451052 -405.356385)
			(xy 303.451052 -405.423809) (xy 303.442976 -405.490748) (xy 303.42694 -405.556237) (xy 303.403175 -405.619334)
			(xy 303.372023 -405.67913) (xy 303.333933 -405.734763) (xy 303.312068 -405.760428) (xy 303.306273 -405.767574)
			(xy 303.299758 -405.784764) (xy 303.299368 -405.793956) (xy 303.299368 -406.286208) (xy 303.299781 -406.295395)
			(xy 303.306294 -406.312579) (xy 303.312068 -406.319736) (xy 303.333902 -406.345427) (xy 303.371993 -406.401057)
			(xy 303.403147 -406.460849) (xy 303.426915 -406.523943) (xy 303.442953 -406.589429) (xy 303.451032 -406.656365)
			(xy 303.451035 -406.723787) (xy 303.442962 -406.790724) (xy 303.426929 -406.856211) (xy 303.403167 -406.919307)
			(xy 303.372018 -406.979102) (xy 303.333931 -407.034735) (xy 303.312068 -407.0604) (xy 303.306285 -407.067555)
			(xy 303.299763 -407.084738) (xy 303.299368 -407.093928) (xy 303.299368 -407.251408) (xy 303.29899 -407.261535)
			(xy 303.291233 -407.280245) (xy 303.276904 -407.29456) (xy 303.258187 -407.302299) (xy 303.24806 -407.302716)
			(xy 302.53178 -407.302716) (xy 302.521672 -407.302232) (xy 302.502996 -407.294491) (xy 302.488703 -407.280194)
			(xy 302.480966 -407.261516) (xy 302.480472 -407.251408) (xy 302.480472 -407.093928) (xy 302.480055 -407.084741)
			(xy 302.473547 -407.067557) (xy 302.467772 -407.0604) (xy 302.445878 -407.03476) (xy 302.407792 -406.979121)
			(xy 302.376644 -406.919321) (xy 302.352883 -406.856221) (xy 302.33685 -406.790729) (xy 302.328777 -406.723789)
			(xy 299.050708 -406.723789) (xy 299.042674 -406.790547) (xy 299.026705 -406.855927) (xy 299.003037 -406.91893)
			(xy 298.972009 -406.978653) (xy 298.934065 -407.034239) (xy 298.91228 -407.059892) (xy 298.906502 -407.06705)
			(xy 298.899977 -407.084231) (xy 298.89958 -407.09342) (xy 298.89958 -407.251408) (xy 298.899184 -407.261565)
			(xy 298.891382 -407.280321) (xy 298.876978 -407.294645) (xy 298.858177 -407.302341) (xy 298.848018 -407.302716)
			(xy 298.131738 -407.302716) (xy 298.121608 -407.302241) (xy 298.10288 -407.294517) (xy 298.088521 -407.280227)
			(xy 298.080708 -407.261535) (xy 298.080176 -407.251408) (xy 298.080176 -407.09342) (xy 298.079762 -407.084233)
			(xy 298.073252 -407.067048) (xy 298.067476 -407.059892) (xy 298.045656 -407.034266) (xy 298.007706 -406.978677)
			(xy 297.976672 -406.91895) (xy 297.952999 -406.855942) (xy 297.937027 -406.790556) (xy 297.928985 -406.72373)
			(xy 294.650947 -406.72373) (xy 294.650947 -406.723787) (xy 294.642874 -406.790723) (xy 294.626842 -406.856211)
			(xy 294.60308 -406.919306) (xy 294.571933 -406.979101) (xy 294.533847 -407.034735) (xy 294.511984 -407.0604)
			(xy 294.506203 -407.067556) (xy 294.49968 -407.084738) (xy 294.499284 -407.093928) (xy 294.499284 -407.251408)
			(xy 294.49889 -407.261533) (xy 294.491136 -407.28024) (xy 294.476813 -407.294554) (xy 294.458101 -407.302296)
			(xy 294.447976 -407.302716) (xy 293.731696 -407.302716) (xy 293.721589 -407.302218) (xy 293.702914 -407.294482)
			(xy 293.68862 -407.28019) (xy 293.680882 -407.261515) (xy 293.680388 -407.251408) (xy 293.680388 -407.093928)
			(xy 293.679967 -407.084742) (xy 293.673461 -407.067557) (xy 293.667688 -407.0604) (xy 293.645793 -407.03476)
			(xy 293.607706 -406.979122) (xy 293.576557 -406.919322) (xy 293.552796 -406.856222) (xy 293.536763 -406.79073)
			(xy 293.52869 -406.723789) (xy 290.250621 -406.723789) (xy 290.242587 -406.790547) (xy 290.226619 -406.855927)
			(xy 290.202951 -406.91893) (xy 290.171924 -406.978653) (xy 290.133981 -407.034239) (xy 290.112196 -407.059892)
			(xy 290.10642 -407.067052) (xy 290.099893 -407.084231) (xy 290.099496 -407.09342) (xy 290.099496 -407.251408)
			(xy 290.099085 -407.261563) (xy 290.091286 -407.280316) (xy 290.076886 -407.29464) (xy 290.058091 -407.302338)
			(xy 290.047934 -407.302716) (xy 289.331654 -407.302716) (xy 289.321519 -407.30231) (xy 289.302788 -407.294559)
			(xy 289.288432 -407.280248) (xy 289.280622 -407.261541) (xy 289.280092 -407.251408) (xy 289.280092 -407.09342)
			(xy 289.279674 -407.084234) (xy 289.273166 -407.067049) (xy 289.267392 -407.059892) (xy 289.245571 -407.034266)
			(xy 289.20762 -406.978677) (xy 289.176585 -406.918951) (xy 289.152912 -406.855943) (xy 289.136939 -406.790557)
			(xy 289.128897 -406.72373) (xy 237.026196 -406.72373) (xy 237.026196 -409.523887) (xy 286.928735 -409.523887)
			(xy 286.928738 -409.456459) (xy 286.936818 -409.389518) (xy 286.952859 -409.324026) (xy 286.97663 -409.260927)
			(xy 287.007788 -409.20113) (xy 287.045884 -409.145496) (xy 287.067752 -409.119832) (xy 287.073566 -409.1127)
			(xy 287.080069 -409.095499) (xy 287.080452 -409.086304) (xy 287.080452 -408.594052) (xy 287.080005 -408.584869)
			(xy 287.073516 -408.567685) (xy 287.067752 -408.560524) (xy 287.045878 -408.534866) (xy 287.007786 -408.479232)
			(xy 286.976633 -408.419435) (xy 286.952867 -408.356337) (xy 286.936831 -408.290847) (xy 286.928755 -408.223907)
			(xy 286.928755 -408.156481) (xy 286.936833 -408.089542) (xy 286.952871 -408.024051) (xy 286.976638 -407.960954)
			(xy 287.007793 -407.901158) (xy 287.045886 -407.845524) (xy 287.067752 -407.81986) (xy 287.073554 -407.812719)
			(xy 287.080064 -407.795525) (xy 287.080452 -407.786332) (xy 287.080452 -407.628852) (xy 287.080945 -407.618746)
			(xy 287.088689 -407.600076) (xy 287.102983 -407.585785) (xy 287.121654 -407.578043) (xy 287.13176 -407.577544)
			(xy 287.84804 -407.577544) (xy 287.858144 -407.578051) (xy 287.876813 -407.585791) (xy 287.891104 -407.600081)
			(xy 287.898847 -407.618748) (xy 287.899348 -407.628852) (xy 287.899348 -407.786332) (xy 287.899755 -407.795519)
			(xy 287.906272 -407.812703) (xy 287.912048 -407.81986) (xy 287.933906 -407.845531) (xy 287.971998 -407.901163)
			(xy 288.003152 -407.960958) (xy 288.026919 -408.024055) (xy 288.042957 -408.089543) (xy 288.051034 -408.156482)
			(xy 288.051035 -408.223906) (xy 288.042959 -408.290845) (xy 288.026923 -408.356334) (xy 288.003157 -408.419431)
			(xy 287.972004 -408.479226) (xy 287.933913 -408.53486) (xy 287.912048 -408.560524) (xy 287.906252 -408.56767)
			(xy 287.899739 -408.58486) (xy 287.899348 -408.594052) (xy 287.899348 -409.086304) (xy 287.899768 -409.09549)
			(xy 287.906276 -409.112674) (xy 287.912048 -409.119832) (xy 287.933878 -409.145526) (xy 287.971972 -409.201155)
			(xy 288.003127 -409.260947) (xy 288.026895 -409.32404) (xy 288.042935 -409.389526) (xy 288.051014 -409.456462)
			(xy 288.051018 -409.523884) (xy 288.042945 -409.590821) (xy 288.026911 -409.656308) (xy 288.003149 -409.719404)
			(xy 287.971999 -409.779199) (xy 287.933912 -409.834832) (xy 287.912048 -409.860496) (xy 287.906264 -409.86765)
			(xy 287.899743 -409.884834) (xy 287.899348 -409.894024) (xy 287.899348 -410.051504) (xy 287.898819 -410.061607)
			(xy 287.891089 -410.080276) (xy 287.876806 -410.094569) (xy 287.858143 -410.102312) (xy 287.84804 -410.102812)
			(xy 287.13176 -410.102812) (xy 287.12165 -410.102348) (xy 287.102973 -410.094599) (xy 287.08868 -410.080296)
			(xy 287.080945 -410.061614) (xy 287.080452 -410.051504) (xy 287.080452 -409.894024) (xy 287.080019 -409.884839)
			(xy 287.07352 -409.867655) (xy 287.067752 -409.860496) (xy 287.045851 -409.834861) (xy 287.00776 -409.779223)
			(xy 286.976608 -409.719423) (xy 286.952843 -409.656322) (xy 286.936809 -409.590829) (xy 286.928735 -409.523887)
			(xy 237.026196 -409.523887) (xy 237.026196 -410.623642) (xy 289.128908 -410.623642) (xy 289.12891 -410.556334)
			(xy 289.136956 -410.48951) (xy 289.152933 -410.424126) (xy 289.176609 -410.361121) (xy 289.207648 -410.301397)
			(xy 289.245602 -410.245811) (xy 289.267392 -410.22016) (xy 289.273187 -410.213014) (xy 289.279703 -410.195824)
			(xy 289.280092 -410.186632) (xy 289.280092 -409.693364) (xy 289.279701 -409.684175) (xy 289.273174 -409.66699)
			(xy 289.267392 -409.659836) (xy 289.245614 -409.634175) (xy 289.207662 -409.578591) (xy 289.176625 -409.518869)
			(xy 289.152949 -409.455866) (xy 289.136974 -409.390484) (xy 289.128928 -409.323662) (xy 289.128927 -409.256356)
			(xy 289.136971 -409.189534) (xy 289.152944 -409.124152) (xy 289.176618 -409.061147) (xy 289.207653 -409.001425)
			(xy 289.245603 -408.945839) (xy 289.267392 -408.920188) (xy 289.273175 -408.913033) (xy 289.279698 -408.89585)
			(xy 289.280092 -408.88666) (xy 289.280092 -408.728672) (xy 289.280498 -408.718517) (xy 289.288302 -408.699766)
			(xy 289.302703 -408.685443) (xy 289.321497 -408.677743) (xy 289.331654 -408.677364) (xy 290.047934 -408.677364)
			(xy 290.058066 -408.677799) (xy 290.076792 -408.685543) (xy 290.091148 -408.699845) (xy 290.098962 -408.718542)
			(xy 290.099496 -408.728672) (xy 290.099496 -408.88666) (xy 290.099926 -408.895845) (xy 290.106426 -408.91303)
			(xy 290.112196 -408.920188) (xy 290.133994 -408.945831) (xy 290.171941 -409.00142) (xy 290.202971 -409.061145)
			(xy 290.226642 -409.12415) (xy 290.242613 -409.189533) (xy 290.250656 -409.256356) (xy 290.250655 -409.323662)
			(xy 290.24261 -409.390484) (xy 290.226637 -409.455867) (xy 290.202964 -409.518872) (xy 290.200389 -409.523827)
			(xy 291.329055 -409.523827) (xy 291.329058 -409.456519) (xy 291.337106 -409.389694) (xy 291.353082 -409.32431)
			(xy 291.376759 -409.261304) (xy 291.407797 -409.201579) (xy 291.44575 -409.145992) (xy 291.46754 -409.12034)
			(xy 291.47335 -409.113204) (xy 291.479855 -409.096006) (xy 291.48024 -409.086812) (xy 291.48024 -408.593544)
			(xy 291.4798 -408.58436) (xy 291.473306 -408.567176) (xy 291.46754 -408.560016) (xy 291.445744 -408.53437)
			(xy 291.407796 -408.478783) (xy 291.376763 -408.419059) (xy 291.35309 -408.356053) (xy 291.337118 -408.29067)
			(xy 291.329074 -408.223847) (xy 291.329075 -408.156541) (xy 291.33712 -408.089718) (xy 291.353094 -408.024335)
			(xy 291.376767 -407.96133) (xy 291.407802 -407.901607) (xy 291.445752 -407.84602) (xy 291.46754 -407.820368)
			(xy 291.473338 -407.813224) (xy 291.479851 -407.796032) (xy 291.48024 -407.78684) (xy 291.48024 -407.628852)
			(xy 291.480583 -407.61869) (xy 291.488402 -407.599929) (xy 291.502823 -407.585606) (xy 291.521637 -407.577915)
			(xy 291.531802 -407.577544) (xy 292.248082 -407.577544) (xy 292.258208 -407.578041) (xy 292.27693 -407.585764)
			(xy 292.291287 -407.600047) (xy 292.299106 -407.618729) (xy 292.299644 -407.628852) (xy 292.299644 -407.78684)
			(xy 292.300048 -407.796028) (xy 292.306567 -407.813211) (xy 292.312344 -407.820368) (xy 292.334124 -407.846026)
			(xy 292.372074 -407.901612) (xy 292.403109 -407.961334) (xy 292.426783 -408.024338) (xy 292.442757 -408.089719)
			(xy 292.450802 -408.156542) (xy 292.450803 -408.223846) (xy 292.442759 -408.290669) (xy 292.426786 -408.356051)
			(xy 292.403114 -408.419055) (xy 292.372081 -408.478778) (xy 292.334132 -408.534364) (xy 292.312344 -408.560016)
			(xy 292.306551 -408.567164) (xy 292.300036 -408.584353) (xy 292.299644 -408.593544) (xy 292.299644 -409.086812)
			(xy 292.300061 -409.095998) (xy 292.306571 -409.113182) (xy 292.312344 -409.12034) (xy 292.334097 -409.146021)
			(xy 292.372048 -409.201603) (xy 292.403083 -409.261322) (xy 292.426759 -409.324323) (xy 292.442735 -409.389702)
			(xy 292.450782 -409.456522) (xy 292.450786 -409.523824) (xy 292.442745 -409.590645) (xy 292.426775 -409.656025)
			(xy 292.403106 -409.719028) (xy 292.372076 -409.77875) (xy 292.33413 -409.834336) (xy 292.312344 -409.859988)
			(xy 292.306521 -409.867114) (xy 292.300024 -409.884319) (xy 292.299644 -409.893516) (xy 292.299644 -410.051504)
			(xy 292.299182 -410.061653) (xy 292.291394 -410.080397) (xy 292.27701 -410.094718) (xy 292.258233 -410.102426)
			(xy 292.248082 -410.102812) (xy 291.531802 -410.102812) (xy 291.521682 -410.102273) (xy 291.502971 -410.094556)
			(xy 291.488616 -410.080286) (xy 291.480788 -410.061621) (xy 291.48024 -410.051504) (xy 291.48024 -409.893516)
			(xy 291.479813 -409.884331) (xy 291.47331 -409.867147) (xy 291.46754 -409.859988) (xy 291.445717 -409.834365)
			(xy 291.407769 -409.778774) (xy 291.376737 -409.719047) (xy 291.353066 -409.656039) (xy 291.337096 -409.590653)
			(xy 291.329055 -409.523827) (xy 290.200389 -409.523827) (xy 290.171931 -409.578596) (xy 290.133983 -409.634183)
			(xy 290.112196 -409.659836) (xy 290.106401 -409.666982) (xy 290.099886 -409.684172) (xy 290.099496 -409.693364)
			(xy 290.099496 -410.186632) (xy 290.099891 -410.195821) (xy 290.106415 -410.213005) (xy 290.112196 -410.22016)
			(xy 290.133967 -410.245826) (xy 290.171914 -410.301411) (xy 290.202946 -410.361133) (xy 290.226618 -410.424136)
			(xy 290.242591 -410.489516) (xy 290.250636 -410.556336) (xy 290.250638 -410.62364) (xy 290.250631 -410.6237)
			(xy 293.528701 -410.6237) (xy 293.528702 -410.556276) (xy 293.53678 -410.489336) (xy 293.552816 -410.423847)
			(xy 293.576582 -410.360749) (xy 293.607734 -410.300952) (xy 293.645824 -410.245317) (xy 293.667688 -410.219652)
			(xy 293.673486 -410.212508) (xy 293.68 -410.195317) (xy 293.680388 -410.186124) (xy 293.680388 -409.693872)
			(xy 293.679994 -409.684683) (xy 293.673469 -409.667499) (xy 293.667688 -409.660344) (xy 293.645836 -409.634669)
			(xy 293.607748 -409.579035) (xy 293.576597 -409.519241) (xy 293.552833 -409.456145) (xy 293.536797 -409.390657)
			(xy 293.52872 -409.32372) (xy 293.528719 -409.256298) (xy 293.536794 -409.189361) (xy 293.552828 -409.123872)
			(xy 293.57659 -409.060776) (xy 293.607739 -409.00098) (xy 293.645825 -408.945345) (xy 293.667688 -408.91968)
			(xy 293.673474 -408.912527) (xy 293.679995 -408.895343) (xy 293.680388 -408.886152) (xy 293.680388 -408.728672)
			(xy 293.680862 -408.718563) (xy 293.688606 -408.699886) (xy 293.702907 -408.685593) (xy 293.721587 -408.677857)
			(xy 293.731696 -408.677364) (xy 294.447976 -408.677364) (xy 294.458079 -408.677904) (xy 294.47675 -408.685627)
			(xy 294.491044 -408.699907) (xy 294.498786 -408.71857) (xy 294.499284 -408.728672) (xy 294.499284 -408.886152)
			(xy 294.499721 -408.895336) (xy 294.506216 -408.912521) (xy 294.511984 -408.91968) (xy 294.53386 -408.945335)
			(xy 294.57195 -409.000971) (xy 294.603101 -409.060768) (xy 294.626865 -409.123866) (xy 294.6429 -409.189357)
			(xy 294.650975 -409.256297) (xy 294.650974 -409.323721) (xy 294.642897 -409.390661) (xy 294.62686 -409.456151)
			(xy 294.603093 -409.519248) (xy 294.600676 -409.523887) (xy 295.728823 -409.523887) (xy 295.728826 -409.456459)
			(xy 295.736906 -409.389518) (xy 295.752947 -409.324026) (xy 295.776716 -409.260928) (xy 295.807873 -409.201131)
			(xy 295.845969 -409.145497) (xy 295.867836 -409.119832) (xy 295.873649 -409.112698) (xy 295.880153 -409.095499)
			(xy 295.880536 -409.086304) (xy 295.880536 -408.594052) (xy 295.880093 -408.584869) (xy 295.873601 -408.567684)
			(xy 295.867836 -408.560524) (xy 295.845963 -408.534866) (xy 295.807872 -408.479231) (xy 295.77672 -408.419434)
			(xy 295.752954 -408.356336) (xy 295.736918 -408.290846) (xy 295.728843 -408.223907) (xy 295.728843 -408.156481)
			(xy 295.736921 -408.089542) (xy 295.752958 -408.024052) (xy 295.776725 -407.960955) (xy 295.807878 -407.901159)
			(xy 295.84597 -407.845525) (xy 295.867836 -407.81986) (xy 295.873637 -407.812718) (xy 295.880148 -407.795525)
			(xy 295.880536 -407.786332) (xy 295.880536 -407.628852) (xy 295.880947 -407.618736) (xy 295.888707 -407.60005)
			(xy 295.903027 -407.585755) (xy 295.921727 -407.578029) (xy 295.931844 -407.577544) (xy 296.648124 -407.577544)
			(xy 296.658227 -407.578064) (xy 296.676895 -407.585799) (xy 296.691187 -407.600084) (xy 296.698931 -407.618749)
			(xy 296.699432 -407.628852) (xy 296.699432 -407.786332) (xy 296.699842 -407.795519) (xy 296.706357 -407.812703)
			(xy 296.712132 -407.81986) (xy 296.733987 -407.845532) (xy 296.772074 -407.901167) (xy 296.803223 -407.960962)
			(xy 296.826986 -408.024058) (xy 296.843021 -408.089546) (xy 296.851097 -408.156483) (xy 296.851098 -408.223905)
			(xy 296.843024 -408.290842) (xy 296.82699 -408.356331) (xy 296.803228 -408.419427) (xy 296.77208 -408.479223)
			(xy 296.733994 -408.534858) (xy 296.712132 -408.560524) (xy 296.706334 -408.567668) (xy 296.699822 -408.58486)
			(xy 296.699432 -408.594052) (xy 296.699432 -409.086304) (xy 296.699856 -409.095489) (xy 296.706362 -409.112673)
			(xy 296.712132 -409.119832) (xy 296.733959 -409.145527) (xy 296.772047 -409.201158) (xy 296.803198 -409.26095)
			(xy 296.826962 -409.324043) (xy 296.842999 -409.389528) (xy 296.851078 -409.456463) (xy 296.851081 -409.523883)
			(xy 296.843009 -409.590818) (xy 296.826978 -409.656305) (xy 296.80322 -409.7194) (xy 296.772075 -409.779196)
			(xy 296.733993 -409.83483) (xy 296.712132 -409.860496) (xy 296.706346 -409.867649) (xy 296.699827 -409.884834)
			(xy 296.699432 -409.894024) (xy 296.699432 -410.051504) (xy 296.698919 -410.061609) (xy 296.691186 -410.080281)
			(xy 296.676898 -410.094575) (xy 296.658229 -410.102315) (xy 296.648124 -410.102812) (xy 295.931844 -410.102812)
			(xy 295.921726 -410.102348) (xy 295.903026 -410.094617) (xy 295.88871 -410.080315) (xy 295.880961 -410.061622)
			(xy 295.880536 -410.051504) (xy 295.880536 -409.894024) (xy 295.880106 -409.884839) (xy 295.873605 -409.867655)
			(xy 295.867836 -409.860496) (xy 295.845935 -409.834861) (xy 295.807845 -409.779223) (xy 295.776694 -409.719423)
			(xy 295.752931 -409.656322) (xy 295.736896 -409.590829) (xy 295.728823 -409.523887) (xy 294.600676 -409.523887)
			(xy 294.57194 -409.579045) (xy 294.533849 -409.634679) (xy 294.511984 -409.660344) (xy 294.506184 -409.667487)
			(xy 294.499672 -409.684679) (xy 294.499284 -409.693872) (xy 294.499284 -410.186124) (xy 294.499686 -410.195312)
			(xy 294.506206 -410.212496) (xy 294.511984 -410.219652) (xy 294.533833 -410.24533) (xy 294.571923 -410.300962)
			(xy 294.603075 -410.360757) (xy 294.626841 -410.423852) (xy 294.642878 -410.489339) (xy 294.650956 -410.556277)
			(xy 294.650957 -410.623641) (xy 297.928996 -410.623641) (xy 297.928998 -410.556334) (xy 297.937044 -410.48951)
			(xy 297.95302 -410.424127) (xy 297.976696 -410.361121) (xy 298.007733 -410.301398) (xy 298.045686 -410.245812)
			(xy 298.067476 -410.22016) (xy 298.073269 -410.213012) (xy 298.079787 -410.195824) (xy 298.080176 -410.186632)
			(xy 298.080176 -409.693364) (xy 298.079788 -409.684174) (xy 298.07326 -409.66699) (xy 298.067476 -409.659836)
			(xy 298.045699 -409.634175) (xy 298.007747 -409.57859) (xy 297.976712 -409.518868) (xy 297.953037 -409.455865)
			(xy 297.937062 -409.390484) (xy 297.929016 -409.323661) (xy 297.929015 -409.256357) (xy 297.937058 -409.189534)
			(xy 297.953031 -409.124152) (xy 297.976704 -409.061148) (xy 298.007738 -409.001425) (xy 298.045688 -408.94584)
			(xy 298.067476 -408.920188) (xy 298.073257 -408.913032) (xy 298.079782 -408.89585) (xy 298.080176 -408.88666)
			(xy 298.080176 -408.728672) (xy 298.080598 -408.718519) (xy 298.088398 -408.699771) (xy 298.102794 -408.685449)
			(xy 298.121583 -408.677746) (xy 298.131738 -408.677364) (xy 298.848018 -408.677364) (xy 298.858149 -408.677812)
			(xy 298.876875 -408.68555) (xy 298.891232 -408.699849) (xy 298.899046 -408.718543) (xy 298.89958 -408.728672)
			(xy 298.89958 -408.88666) (xy 298.900014 -408.895845) (xy 298.906512 -408.913029) (xy 298.91228 -408.920188)
			(xy 298.934079 -408.945831) (xy 298.972026 -409.001419) (xy 299.003058 -409.061144) (xy 299.026729 -409.12415)
			(xy 299.042701 -409.189533) (xy 299.050744 -409.256356) (xy 299.050743 -409.323662) (xy 299.042698 -409.390485)
			(xy 299.026724 -409.455868) (xy 299.003051 -409.518873) (xy 299.000446 -409.523886) (xy 300.128614 -409.523886)
			(xy 300.128617 -409.456459) (xy 300.136697 -409.389518) (xy 300.152737 -409.324027) (xy 300.176506 -409.260928)
			(xy 300.207662 -409.201131) (xy 300.245757 -409.145497) (xy 300.267624 -409.119832) (xy 300.273435 -409.112697)
			(xy 300.27994 -409.095499) (xy 300.280324 -409.086304) (xy 300.280324 -408.594052) (xy 300.279883 -408.584868)
			(xy 300.27339 -408.567684) (xy 300.267624 -408.560524) (xy 300.245751 -408.534866) (xy 300.207661 -408.479231)
			(xy 300.17651 -408.419434) (xy 300.152745 -408.356336) (xy 300.136709 -408.290846) (xy 300.128634 -408.223906)
			(xy 300.128634 -408.156482) (xy 300.136711 -408.089542) (xy 300.152748 -408.024053) (xy 300.176514 -407.960955)
			(xy 300.207667 -407.901159) (xy 300.245759 -407.845525) (xy 300.267624 -407.81986) (xy 300.273423 -407.812717)
			(xy 300.279935 -407.795525) (xy 300.280324 -407.786332) (xy 300.280324 -407.628852) (xy 300.280747 -407.618737)
			(xy 300.288504 -407.600053) (xy 300.302821 -407.585759) (xy 300.321516 -407.578031) (xy 300.331632 -407.577544)
			(xy 301.047912 -407.577544) (xy 301.058015 -407.578074) (xy 301.076682 -407.585805) (xy 301.090975 -407.600088)
			(xy 301.098719 -407.61875) (xy 301.09922 -407.628852) (xy 301.09922 -407.786332) (xy 301.09961 -407.795521)
			(xy 301.106137 -407.812706) (xy 301.11192 -407.81986) (xy 301.133775 -407.845532) (xy 301.171863 -407.901166)
			(xy 301.203013 -407.960962) (xy 301.226777 -408.024057) (xy 301.242812 -408.089545) (xy 301.250888 -408.156483)
			(xy 301.250889 -408.223905) (xy 301.242814 -408.290843) (xy 301.22678 -408.356331) (xy 301.203018 -408.419427)
			(xy 301.171869 -408.479224) (xy 301.133783 -408.534858) (xy 301.11192 -408.560524) (xy 301.106133 -408.567676)
			(xy 301.099612 -408.584861) (xy 301.09922 -408.594052) (xy 301.09922 -409.086304) (xy 301.099624 -409.095492)
			(xy 301.106141 -409.112676) (xy 301.11192 -409.119832) (xy 301.133748 -409.145527) (xy 301.171836 -409.201158)
			(xy 301.202988 -409.26095) (xy 301.226753 -409.324043) (xy 301.24279 -409.389528) (xy 301.250869 -409.456463)
			(xy 301.250872 -409.523883) (xy 301.2428 -409.590819) (xy 301.226769 -409.656305) (xy 301.20301 -409.719401)
			(xy 301.171864 -409.779196) (xy 301.133781 -409.83483) (xy 301.11192 -409.860496) (xy 301.106145 -409.867657)
			(xy 301.099617 -409.884835) (xy 301.09922 -409.894024) (xy 301.09922 -410.051504) (xy 301.098719 -410.06161)
			(xy 301.090983 -410.080285) (xy 301.076692 -410.094579) (xy 301.058018 -410.102317) (xy 301.047912 -410.102812)
			(xy 300.331632 -410.102812) (xy 300.321513 -410.102358) (xy 300.302812 -410.094623) (xy 300.288497 -410.080318)
			(xy 300.280749 -410.061623) (xy 300.280324 -410.051504) (xy 300.280324 -409.894024) (xy 300.279897 -409.884839)
			(xy 300.273394 -409.867655) (xy 300.267624 -409.860496) (xy 300.245724 -409.83486) (xy 300.207635 -409.779222)
			(xy 300.176484 -409.719422) (xy 300.152721 -409.656321) (xy 300.136687 -409.590828) (xy 300.128614 -409.523886)
			(xy 299.000446 -409.523886) (xy 298.972017 -409.578597) (xy 298.934068 -409.634184) (xy 298.91228 -409.659836)
			(xy 298.906483 -409.666981) (xy 298.899969 -409.684172) (xy 298.89958 -409.693364) (xy 298.89958 -410.186632)
			(xy 298.899979 -410.19582) (xy 298.906501 -410.213004) (xy 298.91228 -410.22016) (xy 298.934052 -410.245825)
			(xy 298.972 -410.30141) (xy 299.003032 -410.361132) (xy 299.026705 -410.424135) (xy 299.042679 -410.489515)
			(xy 299.050724 -410.556336) (xy 299.050725 -410.62364) (xy 299.050718 -410.6237) (xy 302.328789 -410.6237)
			(xy 302.32879 -410.556276) (xy 302.336867 -410.489337) (xy 302.352904 -410.423847) (xy 302.376668 -410.36075)
			(xy 302.407819 -410.300953) (xy 302.445908 -410.245318) (xy 302.467772 -410.219652) (xy 302.47358 -410.212515)
			(xy 302.480086 -410.195318) (xy 302.480472 -410.186124) (xy 302.480472 -409.693872) (xy 302.480082 -409.684683)
			(xy 302.473555 -409.667498) (xy 302.467772 -409.660344) (xy 302.445921 -409.634669) (xy 302.407834 -409.579035)
			(xy 302.376684 -409.51924) (xy 302.35292 -409.456144) (xy 302.336885 -409.390657) (xy 302.328808 -409.32372)
			(xy 302.328807 -409.256298) (xy 302.336882 -409.189361) (xy 302.352915 -409.123873) (xy 302.376677 -409.060777)
			(xy 302.407824 -409.000981) (xy 302.44591 -408.945346) (xy 302.467772 -408.91968) (xy 302.473568 -408.912535)
			(xy 302.480081 -408.895344) (xy 302.480472 -408.886152) (xy 302.480472 -408.728672) (xy 302.480961 -408.718565)
			(xy 302.488703 -408.699891) (xy 302.502998 -408.685599) (xy 302.521673 -408.67786) (xy 302.53178 -408.677364)
			(xy 303.24806 -408.677364) (xy 303.258175 -408.677848) (xy 303.276871 -408.685576) (xy 303.291186 -408.699872)
			(xy 303.298939 -408.718557) (xy 303.299368 -408.728672) (xy 303.299368 -408.886152) (xy 303.299809 -408.895336)
			(xy 303.306302 -408.91252) (xy 303.312068 -408.91968) (xy 303.333945 -408.945335) (xy 303.372035 -409.00097)
			(xy 303.403187 -409.060768) (xy 303.426952 -409.123866) (xy 303.442988 -409.189356) (xy 303.451063 -409.256296)
			(xy 303.451062 -409.323722) (xy 303.442985 -409.390661) (xy 303.426947 -409.456151) (xy 303.40318 -409.519249)
			(xy 303.372026 -409.579045) (xy 303.333934 -409.634679) (xy 303.312068 -409.660344) (xy 303.306266 -409.667485)
			(xy 303.299755 -409.684679) (xy 303.299368 -409.693872) (xy 303.299368 -410.186124) (xy 303.299774 -410.195312)
			(xy 303.306291 -410.212495) (xy 303.312068 -410.219652) (xy 303.333917 -410.24533) (xy 303.372009 -410.300962)
			(xy 303.403162 -410.360756) (xy 303.426928 -410.423851) (xy 303.442966 -410.489339) (xy 303.451044 -410.556276)
			(xy 303.451045 -410.6237) (xy 303.44297 -410.690637) (xy 303.426935 -410.756126) (xy 303.403172 -410.819222)
			(xy 303.372021 -410.879018) (xy 303.333932 -410.934651) (xy 303.312068 -410.960316) (xy 303.306278 -410.967466)
			(xy 303.29976 -410.984653) (xy 303.299368 -410.993844) (xy 303.299368 -411.151324) (xy 303.299003 -411.161452)
			(xy 303.291241 -411.180162) (xy 303.276909 -411.194477) (xy 303.258189 -411.202216) (xy 303.24806 -411.202632)
			(xy 302.53178 -411.202632) (xy 302.521674 -411.202132) (xy 302.503001 -411.194394) (xy 302.488708 -411.180102)
			(xy 302.480969 -411.16143) (xy 302.480472 -411.151324) (xy 302.480472 -410.993844) (xy 302.480047 -410.984658)
			(xy 302.473544 -410.967474) (xy 302.467772 -410.960316) (xy 302.445893 -410.934663) (xy 302.407807 -410.879026)
			(xy 302.376658 -410.819228) (xy 302.352896 -410.75613) (xy 302.336863 -410.690639) (xy 302.328789 -410.6237)
			(xy 299.050718 -410.6237) (xy 299.042683 -410.690461) (xy 299.026712 -410.755842) (xy 299.003042 -410.818846)
			(xy 298.972012 -410.878569) (xy 298.934066 -410.934156) (xy 298.91228 -410.959808) (xy 298.906495 -410.966961)
			(xy 298.899974 -410.984146) (xy 298.89958 -410.993336) (xy 298.89958 -411.151324) (xy 298.899198 -411.161482)
			(xy 298.891391 -411.180239) (xy 298.876982 -411.194562) (xy 298.858179 -411.202258) (xy 298.848018 -411.202632)
			(xy 298.131738 -411.202632) (xy 298.12161 -411.202141) (xy 298.102885 -411.194421) (xy 298.088526 -411.180135)
			(xy 298.080711 -411.161449) (xy 298.080176 -411.151324) (xy 298.080176 -410.993336) (xy 298.079754 -410.98415)
			(xy 298.073249 -410.966965) (xy 298.067476 -410.959808) (xy 298.045672 -410.934169) (xy 298.007721 -410.878582)
			(xy 297.976686 -410.818857) (xy 297.953013 -410.75585) (xy 297.93704 -410.690466) (xy 297.928996 -410.623641)
			(xy 294.650957 -410.623641) (xy 294.650957 -410.623699) (xy 294.642883 -410.690637) (xy 294.626848 -410.756125)
			(xy 294.603085 -410.819221) (xy 294.571935 -410.879017) (xy 294.533848 -410.934651) (xy 294.511984 -410.960316)
			(xy 294.506196 -410.967467) (xy 294.499677 -410.984653) (xy 294.499284 -410.993844) (xy 294.499284 -411.151324)
			(xy 294.498834 -411.161436) (xy 294.491086 -411.180118) (xy 294.476778 -411.194413) (xy 294.458089 -411.202144)
			(xy 294.447976 -411.202632) (xy 293.731696 -411.202632) (xy 293.721591 -411.202119) (xy 293.702919 -411.194386)
			(xy 293.688625 -411.180098) (xy 293.680885 -411.161429) (xy 293.680388 -411.151324) (xy 293.680388 -410.993844)
			(xy 293.679959 -410.984659) (xy 293.673459 -410.967474) (xy 293.667688 -410.960316) (xy 293.645809 -410.934664)
			(xy 293.607721 -410.879027) (xy 293.576572 -410.819229) (xy 293.552809 -410.75613) (xy 293.536775 -410.69064)
			(xy 293.528701 -410.6237) (xy 290.250631 -410.6237) (xy 290.242595 -410.69046) (xy 290.226625 -410.755841)
			(xy 290.202956 -410.818845) (xy 290.171926 -410.878568) (xy 290.133982 -410.934155) (xy 290.112196 -410.959808)
			(xy 290.106413 -410.966963) (xy 290.09989 -410.984146) (xy 290.099496 -410.993336) (xy 290.099496 -411.151324)
			(xy 290.099098 -411.16148) (xy 290.091294 -411.180234) (xy 290.07689 -411.194557) (xy 290.058092 -411.202255)
			(xy 290.047934 -411.202632) (xy 289.331654 -411.202632) (xy 289.321521 -411.20221) (xy 289.302793 -411.194462)
			(xy 289.288438 -411.180156) (xy 289.280625 -411.161455) (xy 289.280092 -411.151324) (xy 289.280092 -410.993336)
			(xy 289.279666 -410.98415) (xy 289.273164 -410.966966) (xy 289.267392 -410.959808) (xy 289.245587 -410.934169)
			(xy 289.207635 -410.878582) (xy 289.1766 -410.818857) (xy 289.152925 -410.755851) (xy 289.136952 -410.690467)
			(xy 289.128908 -410.623642) (xy 237.026196 -410.623642) (xy 237.026196 -412.022036) (xy 237.025817 -412.032111)
			(xy 237.018067 -412.05071) (xy 237.01121 -412.058104) (xy 235.742988 -413.326326) (xy 235.735589 -413.333168)
			(xy 235.716989 -413.340886) (xy 235.70692 -413.341312) (xy 208.85277 -413.341312) (xy 208.842696 -413.340925)
			(xy 208.824097 -413.33318) (xy 208.816702 -413.326326) (xy 207.328262 -411.83814) (xy 207.321442 -411.830725)
			(xy 207.313712 -411.812137) (xy 207.313276 -411.802072) (xy 207.313276 -389.778748) (xy 207.312741 -389.766404)
			(xy 207.303453 -389.743532) (xy 207.295242 -389.734298) (xy 207.294734 -389.73379) (xy 204.725778 -387.165088)
			(xy 204.718937 -387.157689) (xy 204.711218 -387.139089) (xy 204.710792 -387.12902) (xy 204.710792 -374.725946)
			(xy 204.710253 -374.713602) (xy 204.700967 -374.690731) (xy 204.692758 -374.681496) (xy 204.69225 -374.680988)
			(xy 204.627226 -374.615964) (xy 204.620381 -374.608567) (xy 204.612664 -374.589966) (xy 204.61224 -374.579896)
			(xy 204.61224 -371.090444) (xy 204.611612 -371.07799) (xy 204.602074 -371.054978) (xy 204.593698 -371.04574)
			(xy 204.485494 -370.93779) (xy 204.478656 -370.930388) (xy 204.470935 -370.91179) (xy 204.470508 -370.901722)
			(xy 173.519592 -370.901722) (xy 173.519592 -371.386862) (xy 173.520022 -371.396047) (xy 173.526522 -371.413231)
			(xy 173.532292 -371.42039) (xy 173.554093 -371.446031) (xy 173.592039 -371.50162) (xy 173.62307 -371.561345)
			(xy 173.646506 -371.623725) (xy 174.74915 -371.623725) (xy 174.749154 -371.556417) (xy 174.757201 -371.489592)
			(xy 174.773178 -371.424208) (xy 174.796855 -371.361202) (xy 174.827893 -371.301477) (xy 174.865846 -371.24589)
			(xy 174.887636 -371.220238) (xy 174.893446 -371.213102) (xy 174.899952 -371.195904) (xy 174.900336 -371.18671)
			(xy 174.900336 -371.028722) (xy 174.900782 -371.018552) (xy 174.908559 -370.999758) (xy 174.922938 -370.985373)
			(xy 174.941728 -370.977587) (xy 174.951898 -370.97716) (xy 175.668178 -370.97716) (xy 175.678351 -370.977583)
			(xy 175.697149 -370.985364) (xy 175.711536 -370.999751) (xy 175.719317 -371.018549) (xy 175.71974 -371.028722)
			(xy 175.71974 -371.18671) (xy 175.720159 -371.195896) (xy 175.726668 -371.21308) (xy 175.73244 -371.220238)
			(xy 175.754191 -371.245921) (xy 175.792142 -371.301502) (xy 175.823178 -371.361221) (xy 175.846854 -371.424222)
			(xy 175.86283 -371.489601) (xy 175.870878 -371.55642) (xy 175.870881 -371.623723) (xy 175.862841 -371.690543)
			(xy 175.846871 -371.755923) (xy 175.823202 -371.818926) (xy 175.792172 -371.878649) (xy 175.754226 -371.934234)
			(xy 175.73244 -371.959886) (xy 175.726617 -371.967012) (xy 175.72012 -371.984218) (xy 175.71974 -371.993414)
			(xy 175.71974 -372.486682) (xy 175.720172 -372.495867) (xy 175.726672 -372.51305) (xy 175.73244 -372.52021)
			(xy 175.754262 -372.545834) (xy 175.792211 -372.601424) (xy 175.823244 -372.661151) (xy 175.846916 -372.72416)
			(xy 175.862887 -372.789545) (xy 175.870929 -372.856371) (xy 175.870926 -372.92368) (xy 175.862878 -372.990505)
			(xy 175.846901 -373.055889) (xy 175.823223 -373.118895) (xy 175.792185 -373.17862) (xy 175.754231 -373.234206)
			(xy 175.73244 -373.259858) (xy 175.726629 -373.266993) (xy 175.720125 -373.284191) (xy 175.71974 -373.293386)
			(xy 175.71974 -373.451374) (xy 175.719314 -373.461547) (xy 175.711534 -373.480345) (xy 175.697148 -373.494731)
			(xy 175.678351 -373.502513) (xy 175.668178 -373.502936) (xy 174.951898 -373.502936) (xy 174.941723 -373.502537)
			(xy 174.922923 -373.494747) (xy 174.908538 -373.480353) (xy 174.900757 -373.461549) (xy 174.900336 -373.451374)
			(xy 174.900336 -373.293386) (xy 174.899925 -373.284199) (xy 174.893411 -373.267015) (xy 174.887636 -373.259858)
			(xy 174.865882 -373.234178) (xy 174.827932 -373.178596) (xy 174.796898 -373.118876) (xy 174.773223 -373.055875)
			(xy 174.757248 -372.990496) (xy 174.749201 -372.923677) (xy 174.749198 -372.856374) (xy 174.757239 -372.789554)
			(xy 174.773208 -372.724174) (xy 174.796877 -372.661171) (xy 174.827906 -372.601448) (xy 174.865851 -372.545862)
			(xy 174.887636 -372.52021) (xy 174.893458 -372.513083) (xy 174.899957 -372.495878) (xy 174.900336 -372.486682)
			(xy 174.900336 -371.993414) (xy 174.899911 -371.984229) (xy 174.893407 -371.967044) (xy 174.887636 -371.959886)
			(xy 174.865811 -371.934265) (xy 174.827863 -371.878674) (xy 174.796832 -371.818946) (xy 174.773161 -371.755937)
			(xy 174.757191 -371.690551) (xy 174.74915 -371.623725) (xy 173.646506 -371.623725) (xy 173.646741 -371.624351)
			(xy 173.662712 -371.689734) (xy 173.670754 -371.756558) (xy 173.670753 -371.823863) (xy 173.662708 -371.890686)
			(xy 173.646734 -371.956069) (xy 173.623061 -372.019074) (xy 173.592028 -372.078798) (xy 173.55408 -372.134385)
			(xy 173.532292 -372.160038) (xy 173.526496 -372.167183) (xy 173.519981 -372.184374) (xy 173.519592 -372.193566)
			(xy 173.519592 -372.351554) (xy 173.519099 -372.361719) (xy 173.511335 -372.380507) (xy 173.496971 -372.394892)
			(xy 173.478194 -372.402684) (xy 173.46803 -372.403116) (xy 172.75175 -372.403116) (xy 172.741576 -372.402694)
			(xy 172.722773 -372.394917) (xy 172.708385 -372.38053) (xy 172.700607 -372.361728) (xy 172.700188 -372.351554)
			(xy 172.700188 -372.193566) (xy 172.699797 -372.184377) (xy 172.69327 -372.167192) (xy 172.687488 -372.160038)
			(xy 172.665713 -372.134375) (xy 172.62776 -372.078791) (xy 172.596724 -372.01907) (xy 172.573048 -371.956067)
			(xy 172.557072 -371.890685) (xy 172.549026 -371.823863) (xy 172.549025 -371.756558) (xy 172.557069 -371.689736)
			(xy 172.573042 -371.624354) (xy 172.596715 -371.561349) (xy 172.627749 -371.501627) (xy 172.6657 -371.446041)
			(xy 172.687488 -371.42039) (xy 172.69327 -371.413234) (xy 172.699794 -371.396052) (xy 172.700188 -371.386862)
			(xy 172.700188 -370.89334) (xy 172.699761 -370.884154) (xy 172.69326 -370.86697) (xy 172.687488 -370.859812)
			(xy 172.665687 -370.83417) (xy 172.627735 -370.778583) (xy 172.5967 -370.718859) (xy 172.573026 -370.655853)
			(xy 172.557052 -370.590469) (xy 172.549008 -370.523644) (xy 169.270946 -370.523644) (xy 169.262904 -370.590464)
			(xy 169.246933 -370.655845) (xy 169.223264 -370.718849) (xy 169.192234 -370.778572) (xy 169.15429 -370.834159)
			(xy 169.132504 -370.859812) (xy 169.12672 -370.866966) (xy 169.120198 -370.88415) (xy 169.119804 -370.89334)
			(xy 169.119804 -371.386862) (xy 169.120231 -371.396047) (xy 169.126733 -371.413232) (xy 169.132504 -371.42039)
			(xy 169.154304 -371.446031) (xy 169.19225 -371.50162) (xy 169.22328 -371.561346) (xy 169.246737 -371.623785)
			(xy 170.348831 -371.623785) (xy 170.348834 -371.556358) (xy 170.356914 -371.489416) (xy 170.372955 -371.423924)
			(xy 170.396726 -371.360825) (xy 170.427884 -371.301029) (xy 170.46598 -371.245394) (xy 170.487848 -371.21973)
			(xy 170.493663 -371.212598) (xy 170.500165 -371.195397) (xy 170.500548 -371.186202) (xy 170.500548 -371.028722)
			(xy 170.501045 -371.018596) (xy 170.508767 -370.999873) (xy 170.52305 -370.985516) (xy 170.541732 -370.977698)
			(xy 170.551856 -370.97716) (xy 171.268136 -370.97716) (xy 171.278287 -370.977591) (xy 171.297033 -370.985391)
			(xy 171.311354 -370.999784) (xy 171.319059 -371.018568) (xy 171.319444 -371.028722) (xy 171.319444 -371.186202)
			(xy 171.319866 -371.195388) (xy 171.326373 -371.212571) (xy 171.332144 -371.21973) (xy 171.353973 -371.245425)
			(xy 171.392066 -371.301054) (xy 171.423222 -371.360846) (xy 171.44699 -371.423939) (xy 171.46303 -371.489425)
			(xy 171.47111 -371.556361) (xy 171.471113 -371.623782) (xy 171.46304 -371.690719) (xy 171.447007 -371.756207)
			(xy 171.423245 -371.819302) (xy 171.392096 -371.879097) (xy 171.354008 -371.93473) (xy 171.332144 -371.960394)
			(xy 171.326361 -371.967548) (xy 171.31984 -371.984732) (xy 171.319444 -371.993922) (xy 171.319444 -372.486174)
			(xy 171.319879 -372.495358) (xy 171.326377 -372.512542) (xy 171.332144 -372.519702) (xy 171.354043 -372.545339)
			(xy 171.392135 -372.600976) (xy 171.423287 -372.660776) (xy 171.447052 -372.723876) (xy 171.463087 -372.789369)
			(xy 171.471161 -372.856312) (xy 171.471158 -372.923739) (xy 171.463077 -372.990681) (xy 171.447037 -373.056172)
			(xy 171.423266 -373.119271) (xy 171.392108 -373.179068) (xy 171.354012 -373.234702) (xy 171.332144 -373.260366)
			(xy 171.32633 -373.267499) (xy 171.319827 -373.284699) (xy 171.319444 -373.293894) (xy 171.319444 -373.451374)
			(xy 171.318952 -373.461501) (xy 171.31123 -373.480225) (xy 171.296945 -373.494583) (xy 171.27826 -373.5024)
			(xy 171.268136 -373.502936) (xy 170.551856 -373.502936) (xy 170.541704 -373.502515) (xy 170.522957 -373.494712)
			(xy 170.508637 -373.480316) (xy 170.500932 -373.461529) (xy 170.500548 -373.451374) (xy 170.500548 -373.293894)
			(xy 170.50013 -373.284708) (xy 170.493621 -373.267524) (xy 170.487848 -373.260366) (xy 170.466016 -373.234674)
			(xy 170.427923 -373.179044) (xy 170.396768 -373.119252) (xy 170.373 -373.056159) (xy 170.356961 -372.990673)
			(xy 170.348881 -372.923736) (xy 170.348878 -372.856315) (xy 170.356951 -372.789378) (xy 170.372985 -372.72389)
			(xy 170.396747 -372.660794) (xy 170.427897 -372.600999) (xy 170.465984 -372.545366) (xy 170.487848 -372.519702)
			(xy 170.493632 -372.512548) (xy 170.500153 -372.495364) (xy 170.500548 -372.486174) (xy 170.500548 -371.993922)
			(xy 170.500117 -371.984737) (xy 170.493617 -371.967553) (xy 170.487848 -371.960394) (xy 170.465945 -371.93476)
			(xy 170.427854 -371.879122) (xy 170.396703 -371.819322) (xy 170.372938 -371.756221) (xy 170.356904 -371.690728)
			(xy 170.348831 -371.623785) (xy 169.246737 -371.623785) (xy 169.24695 -371.624352) (xy 169.262921 -371.689735)
			(xy 169.270963 -371.756558) (xy 169.270962 -371.823863) (xy 169.262917 -371.890686) (xy 169.246944 -371.956068)
			(xy 169.223271 -372.019073) (xy 169.192239 -372.078798) (xy 169.154291 -372.134385) (xy 169.132504 -372.160038)
			(xy 169.126709 -372.167185) (xy 169.120193 -372.184374) (xy 169.119804 -372.193566) (xy 169.119804 -372.351554)
			(xy 169.1193 -372.361717) (xy 169.111537 -372.380503) (xy 169.097177 -372.394888) (xy 169.078405 -372.402682)
			(xy 169.068242 -372.403116) (xy 168.351962 -372.403116) (xy 168.341782 -372.402766) (xy 168.322978 -372.39496)
			(xy 168.308593 -372.380552) (xy 168.300817 -372.361734) (xy 168.3004 -372.351554) (xy 168.3004 -372.193566)
			(xy 168.300006 -372.184377) (xy 168.293481 -372.167193) (xy 168.2877 -372.160038) (xy 168.265927 -372.134374)
			(xy 168.227981 -372.078788) (xy 168.196949 -372.019066) (xy 168.173277 -371.956063) (xy 168.157304 -371.890683)
			(xy 168.14926 -371.823862) (xy 168.149258 -371.756559) (xy 168.1573 -371.689738) (xy 168.173271 -371.624357)
			(xy 168.19694 -371.561353) (xy 168.22797 -371.50163) (xy 168.265914 -371.446043) (xy 168.2877 -371.42039)
			(xy 168.293483 -371.413235) (xy 168.300006 -371.396052) (xy 168.3004 -371.386862) (xy 168.3004 -370.89334)
			(xy 168.299971 -370.884155) (xy 168.29347 -370.86697) (xy 168.2877 -370.859812) (xy 168.265902 -370.834169)
			(xy 168.227956 -370.77858) (xy 168.196925 -370.718855) (xy 168.173255 -370.65585) (xy 168.157284 -370.590467)
			(xy 168.149241 -370.523644) (xy 164.871178 -370.523644) (xy 164.871178 -370.523702) (xy 164.863103 -370.59064)
			(xy 164.847069 -370.656128) (xy 164.823307 -370.719224) (xy 164.792158 -370.77902) (xy 164.754071 -370.834655)
			(xy 164.732208 -370.86032) (xy 164.726421 -370.867472) (xy 164.7199 -370.884657) (xy 164.719508 -370.893848)
			(xy 164.719508 -371.386354) (xy 164.719938 -371.395539) (xy 164.726438 -371.412724) (xy 164.732208 -371.419882)
			(xy 164.754085 -371.445536) (xy 164.792173 -371.501172) (xy 164.823323 -371.56097) (xy 164.846957 -371.623726)
			(xy 165.949062 -371.623726) (xy 165.949066 -371.556417) (xy 165.957114 -371.489592) (xy 165.973091 -371.424207)
			(xy 165.996769 -371.361201) (xy 166.027807 -371.301477) (xy 166.065761 -371.24589) (xy 166.087552 -371.220238)
			(xy 166.093364 -371.213104) (xy 166.099868 -371.195905) (xy 166.100252 -371.18671) (xy 166.100252 -371.028722)
			(xy 166.100682 -371.01855) (xy 166.108463 -370.999753) (xy 166.122847 -370.985367) (xy 166.141642 -370.977584)
			(xy 166.151814 -370.97716) (xy 166.868094 -370.97716) (xy 166.878268 -370.977569) (xy 166.897067 -370.985356)
			(xy 166.911453 -370.999747) (xy 166.919234 -371.018548) (xy 166.919656 -371.028722) (xy 166.919656 -371.18671)
			(xy 166.920071 -371.195896) (xy 166.926582 -371.21308) (xy 166.932356 -371.220238) (xy 166.954106 -371.245921)
			(xy 166.992057 -371.301503) (xy 167.023092 -371.361222) (xy 167.046767 -371.424223) (xy 167.062743 -371.489601)
			(xy 167.07079 -371.55642) (xy 167.070793 -371.623722) (xy 167.062753 -371.690543) (xy 167.046784 -371.755923)
			(xy 167.023115 -371.818926) (xy 166.992086 -371.878648) (xy 166.954141 -371.934234) (xy 166.932356 -371.959886)
			(xy 166.926535 -371.967014) (xy 166.920036 -371.984218) (xy 166.919656 -371.993414) (xy 166.919656 -372.486682)
			(xy 166.920085 -372.495867) (xy 166.926586 -372.513051) (xy 166.932356 -372.52021) (xy 166.954177 -372.545834)
			(xy 166.992126 -372.601425) (xy 167.023158 -372.661152) (xy 167.046829 -372.72416) (xy 167.0628 -372.789546)
			(xy 167.070841 -372.856372) (xy 167.070838 -372.923679) (xy 167.06279 -372.990504) (xy 167.046814 -373.055889)
			(xy 167.023137 -373.118895) (xy 166.992099 -373.178619) (xy 166.954146 -373.234206) (xy 166.932356 -373.259858)
			(xy 166.926547 -373.266994) (xy 166.920041 -373.284192) (xy 166.919656 -373.293386) (xy 166.919656 -373.451374)
			(xy 166.919215 -373.461545) (xy 166.911437 -373.48034) (xy 166.897057 -373.494726) (xy 166.878264 -373.502511)
			(xy 166.868094 -373.502936) (xy 166.151814 -373.502936) (xy 166.14164 -373.502524) (xy 166.122841 -373.494739)
			(xy 166.108454 -373.480349) (xy 166.100673 -373.461548) (xy 166.100252 -373.451374) (xy 166.100252 -373.293386)
			(xy 166.099837 -373.2842) (xy 166.093325 -373.267016) (xy 166.087552 -373.259858) (xy 166.065797 -373.234178)
			(xy 166.027847 -373.178596) (xy 165.996811 -373.118877) (xy 165.973136 -373.055876) (xy 165.95716 -372.990497)
			(xy 165.949113 -372.923677) (xy 165.94911 -372.856374) (xy 165.957151 -372.789554) (xy 165.973121 -372.724173)
			(xy 165.99679 -372.66117) (xy 166.02782 -372.601448) (xy 166.065766 -372.545862) (xy 166.087552 -372.52021)
			(xy 166.093376 -372.513084) (xy 166.099873 -372.495879) (xy 166.100252 -372.486682) (xy 166.100252 -371.993414)
			(xy 166.099824 -371.984229) (xy 166.093321 -371.967045) (xy 166.087552 -371.959886) (xy 166.065726 -371.934265)
			(xy 166.027778 -371.878674) (xy 165.996745 -371.818947) (xy 165.973074 -371.755938) (xy 165.957104 -371.690552)
			(xy 165.949062 -371.623726) (xy 164.846957 -371.623726) (xy 164.847086 -371.624068) (xy 164.86312 -371.689559)
			(xy 164.871195 -371.756498) (xy 164.871194 -371.823923) (xy 164.863116 -371.890862) (xy 164.84708 -371.956352)
			(xy 164.823314 -372.019449) (xy 164.792162 -372.079246) (xy 164.754073 -372.134881) (xy 164.732208 -372.160546)
			(xy 164.72641 -372.16769) (xy 164.719896 -372.184881) (xy 164.719508 -372.194074) (xy 164.719508 -372.351554)
			(xy 164.718937 -372.361672) (xy 164.711233 -372.380383) (xy 164.696973 -372.394739) (xy 164.678314 -372.402568)
			(xy 164.6682 -372.403116) (xy 163.95192 -372.403116) (xy 163.941769 -372.402662) (xy 163.92302 -372.394876)
			(xy 163.908697 -372.38049) (xy 163.900993 -372.361707) (xy 163.900612 -372.351554) (xy 163.900612 -372.194074)
			(xy 163.900212 -372.184886) (xy 163.893691 -372.167702) (xy 163.887912 -372.160546) (xy 163.866061 -372.13487)
			(xy 163.827971 -372.079237) (xy 163.796819 -372.019442) (xy 163.773054 -371.956347) (xy 163.757017 -371.890859)
			(xy 163.74894 -371.823922) (xy 163.748939 -371.756499) (xy 163.757013 -371.689562) (xy 163.773048 -371.624073)
			(xy 163.796811 -371.560977) (xy 163.827961 -371.501181) (xy 163.866048 -371.445547) (xy 163.887912 -371.419882)
			(xy 163.8937 -371.412731) (xy 163.900219 -371.395545) (xy 163.900612 -371.386354) (xy 163.900612 -370.893848)
			(xy 163.900176 -370.884664) (xy 163.89368 -370.867479) (xy 163.887912 -370.86032) (xy 163.866036 -370.834665)
			(xy 163.827947 -370.779029) (xy 163.796796 -370.719232) (xy 163.773032 -370.656133) (xy 163.756997 -370.590643)
			(xy 163.748922 -370.523703) (xy 160.470875 -370.523703) (xy 160.462839 -370.590466) (xy 160.446866 -370.655848)
			(xy 160.423192 -370.718852) (xy 160.392158 -370.778575) (xy 160.354208 -370.83416) (xy 160.33242 -370.859812)
			(xy 160.326638 -370.866968) (xy 160.320114 -370.88415) (xy 160.31972 -370.89334) (xy 160.31972 -371.386862)
			(xy 160.320144 -371.396048) (xy 160.326647 -371.413233) (xy 160.33242 -371.42039) (xy 160.354223 -371.44603)
			(xy 160.392174 -371.501618) (xy 160.423209 -371.561342) (xy 160.44667 -371.623784) (xy 161.548767 -371.623784)
			(xy 161.548771 -371.556358) (xy 161.55685 -371.489418) (xy 161.572888 -371.423928) (xy 161.596655 -371.360829)
			(xy 161.627808 -371.301032) (xy 161.665899 -371.245396) (xy 161.687764 -371.21973) (xy 161.693581 -371.212599)
			(xy 161.700082 -371.195397) (xy 161.700464 -371.186202) (xy 161.700464 -371.028722) (xy 161.700945 -371.018594)
			(xy 161.70867 -370.999868) (xy 161.722959 -370.985511) (xy 161.741646 -370.977695) (xy 161.751772 -370.97716)
			(xy 162.468052 -370.97716) (xy 162.478166 -370.977654) (xy 162.496861 -370.985379) (xy 162.511176 -370.999671)
			(xy 162.51893 -371.018354) (xy 162.51936 -371.028468) (xy 162.51936 -371.186202) (xy 162.519778 -371.195388)
			(xy 162.526287 -371.212572) (xy 162.53206 -371.21973) (xy 162.553888 -371.245425) (xy 162.591981 -371.301055)
			(xy 162.623135 -371.360846) (xy 162.646903 -371.423939) (xy 162.662942 -371.489425) (xy 162.671022 -371.556361)
			(xy 162.671025 -371.623782) (xy 162.662953 -371.690719) (xy 162.64692 -371.756206) (xy 162.623158 -371.819302)
			(xy 162.59201 -371.879096) (xy 162.553923 -371.934729) (xy 162.53206 -371.960394) (xy 162.526278 -371.96755)
			(xy 162.519756 -371.984732) (xy 162.51936 -371.993922) (xy 162.51936 -372.486174) (xy 162.519791 -372.495359)
			(xy 162.526291 -372.512543) (xy 162.53206 -372.519702) (xy 162.553959 -372.545339) (xy 162.592049 -372.600977)
			(xy 162.623201 -372.660776) (xy 162.646965 -372.723877) (xy 162.662999 -372.78937) (xy 162.671073 -372.856312)
			(xy 162.67107 -372.923739) (xy 162.66299 -372.99068) (xy 162.646949 -373.056172) (xy 162.62318 -373.11927)
			(xy 162.592023 -373.179067) (xy 162.553927 -373.234701) (xy 162.53206 -373.260366) (xy 162.526248 -373.2675)
			(xy 162.519743 -373.284699) (xy 162.51936 -373.293894) (xy 162.51936 -373.451374) (xy 162.518852 -373.461499)
			(xy 162.511133 -373.48022) (xy 162.496853 -373.494577) (xy 162.478174 -373.502397) (xy 162.468052 -373.502936)
			(xy 161.751772 -373.502936) (xy 161.741666 -373.502439) (xy 161.722994 -373.494699) (xy 161.708701 -373.480406)
			(xy 161.700961 -373.461734) (xy 161.700464 -373.451628) (xy 161.700464 -373.293894) (xy 161.700042 -373.284708)
			(xy 161.693535 -373.267525) (xy 161.687764 -373.260366) (xy 161.665935 -373.234673) (xy 161.627847 -373.179041)
			(xy 161.596697 -373.119249) (xy 161.572933 -373.056155) (xy 161.556896 -372.99067) (xy 161.548818 -372.923736)
			(xy 161.548815 -372.856315) (xy 161.556887 -372.78938) (xy 161.572918 -372.723893) (xy 161.596676 -372.660798)
			(xy 161.627821 -372.601003) (xy 161.665903 -372.545368) (xy 161.687764 -372.519702) (xy 161.69355 -372.51255)
			(xy 161.700069 -372.495364) (xy 161.700464 -372.486174) (xy 161.700464 -371.993922) (xy 161.700029 -371.984738)
			(xy 161.693531 -371.967554) (xy 161.687764 -371.960394) (xy 161.665864 -371.934759) (xy 161.627779 -371.879119)
			(xy 161.596632 -371.819319) (xy 161.572871 -371.756218) (xy 161.55684 -371.690725) (xy 161.548767 -371.623784)
			(xy 160.44667 -371.623784) (xy 160.446882 -371.624348) (xy 160.462856 -371.689733) (xy 160.470899 -371.756557)
			(xy 160.470898 -371.823864) (xy 160.462852 -371.890688) (xy 160.446876 -371.956072) (xy 160.4232 -372.019077)
			(xy 160.392163 -372.078801) (xy 160.35421 -372.134386) (xy 160.33242 -372.160038) (xy 160.326627 -372.167186)
			(xy 160.32011 -372.184374) (xy 160.31972 -372.193566) (xy 160.31972 -372.351554) (xy 160.319297 -372.361728)
			(xy 160.31152 -372.38053) (xy 160.297133 -372.394918) (xy 160.278332 -372.402697) (xy 160.268158 -372.403116)
			(xy 159.551878 -372.403116) (xy 159.541699 -372.402753) (xy 159.522895 -372.394952) (xy 159.50851 -372.380547)
			(xy 159.500734 -372.361733) (xy 159.500316 -372.351554) (xy 159.500316 -372.193566) (xy 159.499919 -372.184378)
			(xy 159.493396 -372.167193) (xy 159.487616 -372.160038) (xy 159.465843 -372.134374) (xy 159.427895 -372.078789)
			(xy 159.396862 -372.019067) (xy 159.37319 -371.956064) (xy 159.357216 -371.890683) (xy 159.349172 -371.823862)
			(xy 159.34917 -371.756559) (xy 159.357213 -371.689738) (xy 159.373184 -371.624356) (xy 159.396854 -371.561353)
			(xy 159.427884 -371.501629) (xy 159.46583 -371.446042) (xy 159.487616 -371.42039) (xy 159.493401 -371.413237)
			(xy 159.499922 -371.396052) (xy 159.500316 -371.386862) (xy 159.500316 -370.89334) (xy 159.499883 -370.884155)
			(xy 159.493385 -370.866971) (xy 159.487616 -370.859812) (xy 159.465817 -370.834169) (xy 159.42787 -370.778581)
			(xy 159.396839 -370.718856) (xy 159.373168 -370.65585) (xy 159.357196 -370.590467) (xy 159.349153 -370.523644)
			(xy 129.670828 -370.523644) (xy 129.662785 -370.590464) (xy 129.646814 -370.655846) (xy 129.623143 -370.71885)
			(xy 129.592113 -370.778573) (xy 129.554166 -370.83416) (xy 129.53238 -370.859812) (xy 129.526594 -370.866964)
			(xy 129.520073 -370.884149) (xy 129.51968 -370.89334) (xy 129.51968 -371.386862) (xy 129.520113 -371.396047)
			(xy 129.526611 -371.413231) (xy 129.53238 -371.42039) (xy 129.554181 -371.446031) (xy 129.592128 -371.50162)
			(xy 129.62316 -371.561345) (xy 129.646596 -371.623725) (xy 130.749241 -371.623725) (xy 130.749245 -371.556418)
			(xy 130.757292 -371.489593) (xy 130.773269 -371.424208) (xy 130.796945 -371.361202) (xy 130.827982 -371.301478)
			(xy 130.865934 -371.24589) (xy 130.887724 -371.220238) (xy 130.893532 -371.213101) (xy 130.900039 -371.195904)
			(xy 130.900424 -371.18671) (xy 130.900424 -371.028722) (xy 130.900882 -371.018554) (xy 130.908657 -370.999762)
			(xy 130.923032 -370.985377) (xy 130.941818 -370.977589) (xy 130.951986 -370.97716) (xy 131.668266 -370.97716)
			(xy 131.678438 -370.977592) (xy 131.697236 -370.98537) (xy 131.711623 -370.999754) (xy 131.719405 -371.01855)
			(xy 131.719828 -371.028722) (xy 131.719828 -371.18671) (xy 131.720227 -371.195898) (xy 131.726748 -371.213083)
			(xy 131.732528 -371.220238) (xy 131.754279 -371.24592) (xy 131.792231 -371.301502) (xy 131.823268 -371.361221)
			(xy 131.846945 -371.424221) (xy 131.862921 -371.4896) (xy 131.870969 -371.55642) (xy 131.870972 -371.623723)
			(xy 131.862931 -371.690543) (xy 131.846961 -371.755924) (xy 131.823291 -371.818927) (xy 131.792261 -371.878649)
			(xy 131.754314 -371.934234) (xy 131.732528 -371.959886) (xy 131.726704 -371.967011) (xy 131.720208 -371.984217)
			(xy 131.719828 -371.993414) (xy 131.719828 -372.486682) (xy 131.72024 -372.495869) (xy 131.726752 -372.513054)
			(xy 131.732528 -372.52021) (xy 131.75435 -372.545834) (xy 131.7923 -372.601424) (xy 131.823334 -372.661151)
			(xy 131.847006 -372.724159) (xy 131.862978 -372.789545) (xy 131.87102 -372.856371) (xy 131.871017 -372.92368)
			(xy 131.862969 -372.990505) (xy 131.846991 -373.05589) (xy 131.823313 -373.118896) (xy 131.792274 -373.17862)
			(xy 131.754319 -373.234206) (xy 131.732528 -373.259858) (xy 131.726716 -373.266992) (xy 131.720212 -373.284191)
			(xy 131.719828 -373.293386) (xy 131.719828 -373.451374) (xy 131.719414 -373.461548) (xy 131.711631 -373.480349)
			(xy 131.697242 -373.494736) (xy 131.67844 -373.502515) (xy 131.668266 -373.502936) (xy 130.951986 -373.502936)
			(xy 130.94181 -373.502547) (xy 130.92301 -373.494752) (xy 130.908625 -373.480356) (xy 130.900845 -373.46155)
			(xy 130.900424 -373.451374) (xy 130.900424 -373.293386) (xy 130.900015 -373.284199) (xy 130.8935 -373.267015)
			(xy 130.887724 -373.259858) (xy 130.86597 -373.234178) (xy 130.828022 -373.178595) (xy 130.796988 -373.118875)
			(xy 130.773314 -373.055874) (xy 130.757339 -372.990496) (xy 130.749292 -372.923677) (xy 130.749289 -372.856375)
			(xy 130.75733 -372.789555) (xy 130.773299 -372.724174) (xy 130.796967 -372.661171) (xy 130.827995 -372.601449)
			(xy 130.865939 -372.545863) (xy 130.887724 -372.52021) (xy 130.893544 -372.513082) (xy 130.900044 -372.495878)
			(xy 130.900424 -372.486682) (xy 130.900424 -371.993414) (xy 130.900002 -371.984228) (xy 130.893496 -371.967044)
			(xy 130.887724 -371.959886) (xy 130.865899 -371.934264) (xy 130.827953 -371.878673) (xy 130.796922 -371.818945)
			(xy 130.773252 -371.755937) (xy 130.757282 -371.690551) (xy 130.749241 -371.623725) (xy 129.646596 -371.623725)
			(xy 129.646831 -371.624351) (xy 129.662802 -371.689734) (xy 129.670845 -371.756558) (xy 129.670844 -371.823863)
			(xy 129.662799 -371.890687) (xy 129.646825 -371.956069) (xy 129.623151 -372.019074) (xy 129.592117 -372.078799)
			(xy 129.554168 -372.134386) (xy 129.53238 -372.160038) (xy 129.526582 -372.167182) (xy 129.520069 -372.184374)
			(xy 129.51968 -372.193566) (xy 129.51968 -372.351554) (xy 129.519199 -372.36172) (xy 129.511432 -372.380511)
			(xy 129.497064 -372.394896) (xy 129.478284 -372.402686) (xy 129.468118 -372.403116) (xy 128.751838 -372.403116)
			(xy 128.741663 -372.402704) (xy 128.722861 -372.394923) (xy 128.708473 -372.380533) (xy 128.700695 -372.361729)
			(xy 128.700276 -372.351554) (xy 128.700276 -372.193566) (xy 128.699887 -372.184376) (xy 128.693359 -372.167192)
			(xy 128.687576 -372.160038) (xy 128.665801 -372.134375) (xy 128.627849 -372.078791) (xy 128.596813 -372.019069)
			(xy 128.573138 -371.956066) (xy 128.557163 -371.890685) (xy 128.549117 -371.823863) (xy 128.549116 -371.756558)
			(xy 128.557159 -371.689736) (xy 128.573132 -371.624354) (xy 128.596805 -371.56135) (xy 128.627838 -371.501627)
			(xy 128.665788 -371.446042) (xy 128.687576 -371.42039) (xy 128.693357 -371.413233) (xy 128.699882 -371.396052)
			(xy 128.700276 -371.386862) (xy 128.700276 -370.89334) (xy 128.699852 -370.884154) (xy 128.693349 -370.866969)
			(xy 128.687576 -370.859812) (xy 128.665775 -370.83417) (xy 128.627825 -370.778583) (xy 128.59679 -370.718858)
			(xy 128.573116 -370.655852) (xy 128.557143 -370.590469) (xy 128.549099 -370.523644) (xy 125.271037 -370.523644)
			(xy 125.262994 -370.590464) (xy 125.247024 -370.655845) (xy 125.223354 -370.718849) (xy 125.192323 -370.778573)
			(xy 125.154378 -370.834159) (xy 125.132592 -370.859812) (xy 125.126807 -370.866965) (xy 125.120286 -370.88415)
			(xy 125.119892 -370.89334) (xy 125.119892 -371.386862) (xy 125.120322 -371.396047) (xy 125.126822 -371.413231)
			(xy 125.132592 -371.42039) (xy 125.154393 -371.446031) (xy 125.192339 -371.50162) (xy 125.22337 -371.561345)
			(xy 125.246828 -371.623785) (xy 126.348921 -371.623785) (xy 126.348925 -371.556358) (xy 126.357005 -371.489416)
			(xy 126.373046 -371.423925) (xy 126.396816 -371.360826) (xy 126.427973 -371.301029) (xy 126.466069 -371.245395)
			(xy 126.487936 -371.21973) (xy 126.493749 -371.212597) (xy 126.500253 -371.195397) (xy 126.500636 -371.186202)
			(xy 126.500636 -371.028722) (xy 126.501144 -371.018597) (xy 126.508864 -370.999877) (xy 126.523144 -370.98552)
			(xy 126.541822 -370.9777) (xy 126.551944 -370.97716) (xy 127.268224 -370.97716) (xy 127.278375 -370.977601)
			(xy 127.29712 -370.985397) (xy 127.311441 -370.999787) (xy 127.319147 -371.018569) (xy 127.319532 -371.028722)
			(xy 127.319532 -371.186202) (xy 127.319956 -371.195387) (xy 127.326462 -371.212571) (xy 127.332232 -371.21973)
			(xy 127.354058 -371.245427) (xy 127.392145 -371.301057) (xy 127.423296 -371.36085) (xy 127.447061 -371.423942)
			(xy 127.463098 -371.489427) (xy 127.471176 -371.556361) (xy 127.47118 -371.623781) (xy 127.463108 -371.690717)
			(xy 127.447078 -371.756203) (xy 127.423319 -371.819298) (xy 127.392175 -371.879094) (xy 127.354093 -371.934728)
			(xy 127.332232 -371.960394) (xy 127.326447 -371.967547) (xy 127.319927 -371.984732) (xy 127.319532 -371.993922)
			(xy 127.319532 -372.486174) (xy 127.31997 -372.495358) (xy 127.326466 -372.512542) (xy 127.332232 -372.519702)
			(xy 127.354128 -372.54534) (xy 127.392214 -372.600979) (xy 127.423361 -372.66078) (xy 127.447122 -372.72388)
			(xy 127.463154 -372.789372) (xy 127.471227 -372.856313) (xy 127.471224 -372.923738) (xy 127.463145 -372.990678)
			(xy 127.447107 -373.056169) (xy 127.42334 -373.119267) (xy 127.392188 -373.179064) (xy 127.354097 -373.2347)
			(xy 127.332232 -373.260366) (xy 127.326417 -373.267498) (xy 127.319915 -373.284699) (xy 127.319532 -373.293894)
			(xy 127.319532 -373.451374) (xy 127.319051 -373.461503) (xy 127.311327 -373.480228) (xy 127.297038 -373.494587)
			(xy 127.27835 -373.502402) (xy 127.268224 -373.502936) (xy 126.551944 -373.502936) (xy 126.541797 -373.502443)
			(xy 126.523053 -373.494669) (xy 126.508729 -373.480294) (xy 126.501021 -373.461522) (xy 126.500636 -373.451374)
			(xy 126.500636 -373.293894) (xy 126.500221 -373.284708) (xy 126.49371 -373.267524) (xy 126.487936 -373.260366)
			(xy 126.466104 -373.234674) (xy 126.428012 -373.179044) (xy 126.396858 -373.119252) (xy 126.37309 -373.056158)
			(xy 126.357051 -372.990672) (xy 126.348972 -372.923736) (xy 126.348969 -372.856315) (xy 126.357042 -372.789378)
			(xy 126.373075 -372.72389) (xy 126.396837 -372.660795) (xy 126.427986 -372.601) (xy 126.466073 -372.545367)
			(xy 126.487936 -372.519702) (xy 126.493719 -372.512547) (xy 126.500241 -372.495364) (xy 126.500636 -372.486174)
			(xy 126.500636 -371.993922) (xy 126.500207 -371.984737) (xy 126.493706 -371.967553) (xy 126.487936 -371.960394)
			(xy 126.466033 -371.93476) (xy 126.427943 -371.879122) (xy 126.396792 -371.819322) (xy 126.373029 -371.756221)
			(xy 126.356995 -371.690727) (xy 126.348921 -371.623785) (xy 125.246828 -371.623785) (xy 125.247041 -371.624351)
			(xy 125.263012 -371.689734) (xy 125.271054 -371.756558) (xy 125.271053 -371.823863) (xy 125.263008 -371.890686)
			(xy 125.247034 -371.956069) (xy 125.223361 -372.019074) (xy 125.192328 -372.078798) (xy 125.15438 -372.134385)
			(xy 125.132592 -372.160038) (xy 125.126796 -372.167183) (xy 125.120281 -372.184374) (xy 125.119892 -372.193566)
			(xy 125.119892 -372.351554) (xy 125.119399 -372.361719) (xy 125.111635 -372.380507) (xy 125.097271 -372.394892)
			(xy 125.078494 -372.402684) (xy 125.06833 -372.403116) (xy 124.35205 -372.403116) (xy 124.341876 -372.402694)
			(xy 124.323073 -372.394917) (xy 124.308685 -372.38053) (xy 124.300907 -372.361728) (xy 124.300488 -372.351554)
			(xy 124.300488 -372.193566) (xy 124.300097 -372.184377) (xy 124.29357 -372.167192) (xy 124.287788 -372.160038)
			(xy 124.266013 -372.134375) (xy 124.22806 -372.078791) (xy 124.197024 -372.01907) (xy 124.173348 -371.956067)
			(xy 124.157372 -371.890685) (xy 124.149326 -371.823863) (xy 124.149325 -371.756558) (xy 124.157369 -371.689736)
			(xy 124.173342 -371.624354) (xy 124.197015 -371.561349) (xy 124.228049 -371.501627) (xy 124.266 -371.446041)
			(xy 124.287788 -371.42039) (xy 124.29357 -371.413234) (xy 124.300094 -371.396052) (xy 124.300488 -371.386862)
			(xy 124.300488 -370.89334) (xy 124.300061 -370.884154) (xy 124.29356 -370.86697) (xy 124.287788 -370.859812)
			(xy 124.265987 -370.83417) (xy 124.228035 -370.778583) (xy 124.197 -370.718859) (xy 124.173326 -370.655853)
			(xy 124.157352 -370.590469) (xy 124.149308 -370.523644) (xy 120.871269 -370.523644) (xy 120.871269 -370.523702)
			(xy 120.863194 -370.59064) (xy 120.847159 -370.656128) (xy 120.823396 -370.719225) (xy 120.792247 -370.779021)
			(xy 120.754159 -370.834655) (xy 120.732296 -370.86032) (xy 120.726508 -370.867471) (xy 120.719988 -370.884657)
			(xy 120.719596 -370.893848) (xy 120.719596 -371.386354) (xy 120.720029 -371.395539) (xy 120.726527 -371.412723)
			(xy 120.732296 -371.419882) (xy 120.754174 -371.445536) (xy 120.792262 -371.501172) (xy 120.823413 -371.56097)
			(xy 120.847047 -371.623725) (xy 121.949153 -371.623725) (xy 121.949157 -371.556417) (xy 121.957205 -371.489592)
			(xy 121.973182 -371.424208) (xy 121.996859 -371.361202) (xy 122.027896 -371.301477) (xy 122.06585 -371.24589)
			(xy 122.08764 -371.220238) (xy 122.09345 -371.213103) (xy 122.099956 -371.195904) (xy 122.10034 -371.18671)
			(xy 122.10034 -371.028722) (xy 122.100782 -371.018552) (xy 122.10856 -370.999757) (xy 122.12294 -370.985371)
			(xy 122.141732 -370.977586) (xy 122.151902 -370.97716) (xy 122.868182 -370.97716) (xy 122.878355 -370.977579)
			(xy 122.897154 -370.985362) (xy 122.91154 -370.99975) (xy 122.919322 -371.018549) (xy 122.919744 -371.028722)
			(xy 122.919744 -371.18671) (xy 122.920162 -371.195896) (xy 122.926672 -371.21308) (xy 122.932444 -371.220238)
			(xy 122.954195 -371.245921) (xy 122.992146 -371.301502) (xy 123.023182 -371.361222) (xy 123.046857 -371.424222)
			(xy 123.062833 -371.489601) (xy 123.070881 -371.55642) (xy 123.070884 -371.623723) (xy 123.062844 -371.690543)
			(xy 123.046874 -371.755923) (xy 123.023205 -371.818926) (xy 122.992175 -371.878648) (xy 122.95423 -371.934234)
			(xy 122.932444 -371.959886) (xy 122.926622 -371.967013) (xy 122.920124 -371.984218) (xy 122.919744 -371.993414)
			(xy 122.919744 -372.486682) (xy 122.920175 -372.495867) (xy 122.926676 -372.513051) (xy 122.932444 -372.52021)
			(xy 122.954266 -372.545834) (xy 122.992215 -372.601424) (xy 123.023248 -372.661152) (xy 123.046919 -372.72416)
			(xy 123.06289 -372.789546) (xy 123.070932 -372.856372) (xy 123.070929 -372.92368) (xy 123.062881 -372.990505)
			(xy 123.046904 -373.055889) (xy 123.023227 -373.118895) (xy 122.992188 -373.17862) (xy 122.954234 -373.234206)
			(xy 122.932444 -373.259858) (xy 122.926633 -373.266993) (xy 122.920129 -373.284192) (xy 122.919744 -373.293386)
			(xy 122.919744 -373.451374) (xy 122.919314 -373.461546) (xy 122.911534 -373.480344) (xy 122.89715 -373.49473)
			(xy 122.878354 -373.502513) (xy 122.868182 -373.502936) (xy 122.151902 -373.502936) (xy 122.141727 -373.502534)
			(xy 122.122928 -373.494745) (xy 122.108542 -373.480352) (xy 122.100761 -373.461549) (xy 122.10034 -373.451374)
			(xy 122.10034 -373.293386) (xy 122.099928 -373.284199) (xy 122.093415 -373.267015) (xy 122.08764 -373.259858)
			(xy 122.065886 -373.234178) (xy 122.027936 -373.178596) (xy 121.996901 -373.118876) (xy 121.973226 -373.055875)
			(xy 121.957251 -372.990496) (xy 121.949204 -372.923677) (xy 121.949201 -372.856374) (xy 121.957242 -372.789554)
			(xy 121.973211 -372.724174) (xy 121.99688 -372.661171) (xy 122.02791 -372.601448) (xy 122.065855 -372.545862)
			(xy 122.08764 -372.52021) (xy 122.093462 -372.513083) (xy 122.099961 -372.495878) (xy 122.10034 -372.486682)
			(xy 122.10034 -371.993414) (xy 122.099914 -371.984229) (xy 122.093411 -371.967045) (xy 122.08764 -371.959886)
			(xy 122.065815 -371.934265) (xy 122.027867 -371.878674) (xy 121.996835 -371.818946) (xy 121.973165 -371.755937)
			(xy 121.957194 -371.690551) (xy 121.949153 -371.623725) (xy 120.847047 -371.623725) (xy 120.847176 -371.624068)
			(xy 120.863211 -371.689558) (xy 120.871286 -371.756498) (xy 120.871284 -371.823923) (xy 120.863207 -371.890862)
			(xy 120.84717 -371.956352) (xy 120.823404 -372.01945) (xy 120.792252 -372.079246) (xy 120.754161 -372.134881)
			(xy 120.732296 -372.160546) (xy 120.726497 -372.167689) (xy 120.719984 -372.184881) (xy 120.719596 -372.194074)
			(xy 120.719596 -372.351554) (xy 120.719037 -372.361673) (xy 120.711331 -372.380387) (xy 120.697067 -372.394743)
			(xy 120.678404 -372.40257) (xy 120.668288 -372.403116) (xy 119.952008 -372.403116) (xy 119.941856 -372.402672)
			(xy 119.923107 -372.394882) (xy 119.908784 -372.380493) (xy 119.901081 -372.361707) (xy 119.9007 -372.351554)
			(xy 119.9007 -372.194074) (xy 119.900303 -372.184885) (xy 119.89378 -372.167701) (xy 119.888 -372.160546)
			(xy 119.86615 -372.134869) (xy 119.828061 -372.079237) (xy 119.796909 -372.019442) (xy 119.773144 -371.956346)
			(xy 119.757108 -371.890859) (xy 119.749031 -371.823922) (xy 119.74903 -371.756499) (xy 119.757104 -371.689562)
			(xy 119.773138 -371.624074) (xy 119.796901 -371.560977) (xy 119.82805 -371.501182) (xy 119.866137 -371.445547)
			(xy 119.888 -371.419882) (xy 119.893787 -371.41273) (xy 119.900307 -371.395545) (xy 119.9007 -371.386354)
			(xy 119.9007 -370.893848) (xy 119.900267 -370.884663) (xy 119.893769 -370.867479) (xy 119.888 -370.86032)
			(xy 119.866124 -370.834664) (xy 119.828036 -370.779029) (xy 119.796886 -370.719231) (xy 119.773122 -370.656133)
			(xy 119.757088 -370.590643) (xy 119.749013 -370.523703) (xy 116.470966 -370.523703) (xy 116.462929 -370.590466)
			(xy 116.446956 -370.655848) (xy 116.423282 -370.718853) (xy 116.392247 -370.778575) (xy 116.354297 -370.834161)
			(xy 116.332508 -370.859812) (xy 116.326725 -370.866967) (xy 116.320202 -370.88415) (xy 116.319808 -370.89334)
			(xy 116.319808 -371.386862) (xy 116.320235 -371.396047) (xy 116.326737 -371.413232) (xy 116.332508 -371.42039)
			(xy 116.354311 -371.44603) (xy 116.392263 -371.501617) (xy 116.423299 -371.561342) (xy 116.446761 -371.623785)
			(xy 117.548834 -371.623785) (xy 117.548837 -371.556358) (xy 117.556917 -371.489416) (xy 117.572959 -371.423924)
			(xy 117.596729 -371.360825) (xy 117.627887 -371.301028) (xy 117.665984 -371.245394) (xy 117.687852 -371.21973)
			(xy 117.693667 -371.212598) (xy 117.700169 -371.195397) (xy 117.700552 -371.186202) (xy 117.700552 -371.028722)
			(xy 117.701045 -371.018595) (xy 117.708768 -370.999872) (xy 117.723052 -370.985515) (xy 117.741736 -370.977697)
			(xy 117.75186 -370.97716) (xy 118.46814 -370.97716) (xy 118.478292 -370.977588) (xy 118.497037 -370.985389)
			(xy 118.511358 -370.999783) (xy 118.519063 -371.018568) (xy 118.519448 -371.028722) (xy 118.519448 -371.186202)
			(xy 118.519869 -371.195388) (xy 118.526376 -371.212572) (xy 118.532148 -371.21973) (xy 118.553976 -371.245425)
			(xy 118.59207 -371.301054) (xy 118.623225 -371.360846) (xy 118.646994 -371.423939) (xy 118.663033 -371.489425)
			(xy 118.671113 -371.556361) (xy 118.671116 -371.623782) (xy 118.663044 -371.690719) (xy 118.647011 -371.756207)
			(xy 118.623248 -371.819302) (xy 118.592099 -371.879097) (xy 118.554012 -371.93473) (xy 118.532148 -371.960394)
			(xy 118.526365 -371.967549) (xy 118.519844 -371.984732) (xy 118.519448 -371.993922) (xy 118.519448 -372.486174)
			(xy 118.519882 -372.495358) (xy 118.52638 -372.512542) (xy 118.532148 -372.519702) (xy 118.554047 -372.545339)
			(xy 118.592138 -372.600976) (xy 118.62329 -372.660776) (xy 118.647055 -372.723877) (xy 118.66309 -372.78937)
			(xy 118.671164 -372.856312) (xy 118.671161 -372.923739) (xy 118.663081 -372.990681) (xy 118.64704 -373.056172)
			(xy 118.62327 -373.119271) (xy 118.592112 -373.179068) (xy 118.554016 -373.234702) (xy 118.532148 -373.260366)
			(xy 118.526334 -373.267499) (xy 118.519831 -373.284699) (xy 118.519448 -373.293894) (xy 118.519448 -373.451374)
			(xy 118.518952 -373.461501) (xy 118.51123 -373.480223) (xy 118.496947 -373.494581) (xy 118.478264 -373.502399)
			(xy 118.46814 -373.502936) (xy 117.75186 -373.502936) (xy 117.741708 -373.502512) (xy 117.722961 -373.49471)
			(xy 117.708641 -373.480315) (xy 117.700936 -373.461528) (xy 117.700552 -373.451374) (xy 117.700552 -373.293894)
			(xy 117.700133 -373.284708) (xy 117.693624 -373.267524) (xy 117.687852 -373.260366) (xy 117.66602 -373.234674)
			(xy 117.627926 -373.179045) (xy 117.596771 -373.119253) (xy 117.573003 -373.056159) (xy 117.556964 -372.990673)
			(xy 117.548884 -372.923737) (xy 117.548881 -372.856315) (xy 117.556954 -372.789378) (xy 117.572988 -372.72389)
			(xy 117.596751 -372.660794) (xy 117.6279 -372.600999) (xy 117.665988 -372.545366) (xy 117.687852 -372.519702)
			(xy 117.693637 -372.512549) (xy 117.700157 -372.495364) (xy 117.700552 -372.486174) (xy 117.700552 -371.993922)
			(xy 117.70012 -371.984737) (xy 117.69362 -371.967553) (xy 117.687852 -371.960394) (xy 117.665949 -371.93476)
			(xy 117.627858 -371.879123) (xy 117.596706 -371.819323) (xy 117.572942 -371.756221) (xy 117.556907 -371.690728)
			(xy 117.548834 -371.623785) (xy 116.446761 -371.623785) (xy 116.446973 -371.624348) (xy 116.462946 -371.689732)
			(xy 116.47099 -371.756557) (xy 116.470989 -371.823864) (xy 116.462943 -371.890689) (xy 116.446967 -371.956072)
			(xy 116.42329 -372.019077) (xy 116.392252 -372.078801) (xy 116.354298 -372.134387) (xy 116.332508 -372.160038)
			(xy 116.326714 -372.167185) (xy 116.320197 -372.184374) (xy 116.319808 -372.193566) (xy 116.319808 -372.351554)
			(xy 116.31923 -372.361703) (xy 116.311479 -372.380462) (xy 116.29714 -372.394828) (xy 116.278394 -372.402612)
			(xy 116.268246 -372.403116) (xy 115.551966 -372.403116) (xy 115.541786 -372.402763) (xy 115.522982 -372.394958)
			(xy 115.508597 -372.380551) (xy 115.500821 -372.361734) (xy 115.500404 -372.351554) (xy 115.500404 -372.193566)
			(xy 115.500009 -372.184377) (xy 115.493485 -372.167193) (xy 115.487704 -372.160038) (xy 115.465931 -372.134374)
			(xy 115.427984 -372.078788) (xy 115.396952 -372.019066) (xy 115.37328 -371.956063) (xy 115.357307 -371.890683)
			(xy 115.349263 -371.823862) (xy 115.349261 -371.756559) (xy 115.357303 -371.689738) (xy 115.373274 -371.624357)
			(xy 115.396944 -371.561353) (xy 115.427973 -371.50163) (xy 115.465918 -371.446043) (xy 115.487704 -371.42039)
			(xy 115.493488 -371.413236) (xy 115.50001 -371.396052) (xy 115.500404 -371.386862) (xy 115.500404 -370.89334)
			(xy 115.499974 -370.884155) (xy 115.493474 -370.86697) (xy 115.487704 -370.859812) (xy 115.465906 -370.834169)
			(xy 115.427959 -370.77858) (xy 115.396929 -370.718855) (xy 115.373258 -370.65585) (xy 115.357287 -370.590467)
			(xy 115.349244 -370.523644) (xy 85.670941 -370.523644) (xy 85.670941 -370.523703) (xy 85.662866 -370.590641)
			(xy 85.646831 -370.65613) (xy 85.623066 -370.719226) (xy 85.591915 -370.779022) (xy 85.553825 -370.834655)
			(xy 85.53196 -370.86032) (xy 85.526167 -370.867468) (xy 85.519651 -370.884656) (xy 85.51926 -370.893848)
			(xy 85.51926 -371.386354) (xy 85.519701 -371.395538) (xy 85.526194 -371.412722) (xy 85.53196 -371.419882)
			(xy 85.553839 -371.445535) (xy 85.59193 -371.501171) (xy 85.623082 -371.560968) (xy 85.646742 -371.623785)
			(xy 86.748803 -371.623785) (xy 86.748807 -371.556358) (xy 86.756887 -371.489417) (xy 86.772927 -371.423926)
			(xy 86.796696 -371.360827) (xy 86.827851 -371.30103) (xy 86.865945 -371.245395) (xy 86.887812 -371.21973)
			(xy 86.893622 -371.212594) (xy 86.900128 -371.195397) (xy 86.900512 -371.186202) (xy 86.900512 -371.028722)
			(xy 86.901044 -371.0186) (xy 86.908759 -370.999885) (xy 86.923031 -370.985529) (xy 86.941701 -370.977704)
			(xy 86.95182 -370.97716) (xy 87.6681 -370.97716) (xy 87.678204 -370.977684) (xy 87.696874 -370.985414)
			(xy 87.711168 -370.999699) (xy 87.718909 -371.018365) (xy 87.719408 -371.028468) (xy 87.719408 -371.186202)
			(xy 87.719815 -371.195389) (xy 87.726331 -371.212574) (xy 87.732108 -371.21973) (xy 87.753934 -371.245426)
			(xy 87.792024 -371.301056) (xy 87.823176 -371.360848) (xy 87.846942 -371.423941) (xy 87.862979 -371.489426)
			(xy 87.871058 -371.556361) (xy 87.871062 -371.623782) (xy 87.86299 -371.690717) (xy 87.846958 -371.756204)
			(xy 87.823199 -371.819299) (xy 87.792053 -371.879095) (xy 87.753969 -371.934729) (xy 87.732108 -371.960394)
			(xy 87.726332 -371.967554) (xy 87.719805 -371.984733) (xy 87.719408 -371.993922) (xy 87.719408 -372.486174)
			(xy 87.719829 -372.49536) (xy 87.726335 -372.512545) (xy 87.732108 -372.519702) (xy 87.754005 -372.54534)
			(xy 87.792092 -372.600978) (xy 87.823241 -372.660779) (xy 87.847003 -372.723879) (xy 87.863036 -372.789371)
			(xy 87.871109 -372.856312) (xy 87.871106 -372.923739) (xy 87.863027 -372.990679) (xy 87.846988 -373.05617)
			(xy 87.82322 -373.119268) (xy 87.792066 -373.179065) (xy 87.753974 -373.234701) (xy 87.732108 -373.260366)
			(xy 87.726302 -373.267504) (xy 87.719793 -373.2847) (xy 87.719408 -373.293894) (xy 87.719408 -373.451374)
			(xy 87.718854 -373.461493) (xy 87.711143 -373.480205) (xy 87.696878 -373.49456) (xy 87.678216 -373.502389)
			(xy 87.6681 -373.502936) (xy 86.95182 -373.502936) (xy 86.941717 -373.502399) (xy 86.923046 -373.494675)
			(xy 86.908752 -373.480394) (xy 86.90101 -373.461731) (xy 86.900512 -373.451628) (xy 86.900512 -373.293894)
			(xy 86.900102 -373.284707) (xy 86.893588 -373.267523) (xy 86.887812 -373.260366) (xy 86.865981 -373.234673)
			(xy 86.82789 -373.179043) (xy 86.796738 -373.119251) (xy 86.772971 -373.056157) (xy 86.756933 -372.990672)
			(xy 86.748854 -372.923736) (xy 86.748851 -372.856315) (xy 86.756924 -372.789379) (xy 86.772956 -372.723891)
			(xy 86.796717 -372.660796) (xy 86.827864 -372.601001) (xy 86.86595 -372.545367) (xy 86.887812 -372.519702)
			(xy 86.893592 -372.512545) (xy 86.900116 -372.495363) (xy 86.900512 -372.486174) (xy 86.900512 -371.993922)
			(xy 86.900088 -371.984736) (xy 86.893584 -371.967552) (xy 86.887812 -371.960394) (xy 86.86591 -371.93476)
			(xy 86.827822 -371.879121) (xy 86.796672 -371.819321) (xy 86.77291 -371.75622) (xy 86.756876 -371.690727)
			(xy 86.748803 -371.623785) (xy 85.646742 -371.623785) (xy 85.646848 -371.624067) (xy 85.662883 -371.689557)
			(xy 85.670959 -371.756498) (xy 85.670957 -371.823923) (xy 85.662879 -371.890863) (xy 85.646841 -371.956354)
			(xy 85.623074 -372.019451) (xy 85.591919 -372.079248) (xy 85.553826 -372.134881) (xy 85.53196 -372.160546)
			(xy 85.526156 -372.167686) (xy 85.519647 -372.184881) (xy 85.51926 -372.194074) (xy 85.51926 -372.351554)
			(xy 85.518736 -372.361678) (xy 85.511023 -372.380398) (xy 85.496748 -372.394756) (xy 85.478073 -372.402576)
			(xy 85.467952 -372.403116) (xy 84.751672 -372.403116) (xy 84.741563 -372.402638) (xy 84.722888 -372.394894)
			(xy 84.708594 -372.380596) (xy 84.700858 -372.361917) (xy 84.700364 -372.351808) (xy 84.700364 -372.194074)
			(xy 84.699952 -372.184887) (xy 84.693438 -372.167704) (xy 84.687664 -372.160546) (xy 84.665815 -372.134869)
			(xy 84.627728 -372.079235) (xy 84.596579 -372.01944) (xy 84.572816 -371.956345) (xy 84.55678 -371.890858)
			(xy 84.548704 -371.823921) (xy 84.548703 -371.7565) (xy 84.556776 -371.689563) (xy 84.572809 -371.624075)
			(xy 84.59657 -371.560979) (xy 84.627717 -371.501183) (xy 84.665802 -371.445548) (xy 84.687664 -371.419882)
			(xy 84.693459 -371.412736) (xy 84.699973 -371.395546) (xy 84.700364 -371.386354) (xy 84.700364 -370.893848)
			(xy 84.699917 -370.884665) (xy 84.693427 -370.867481) (xy 84.687664 -370.86032) (xy 84.66579 -370.834664)
			(xy 84.627704 -370.779027) (xy 84.596555 -370.719229) (xy 84.572793 -370.656131) (xy 84.55676 -370.590642)
			(xy 84.548686 -370.523703) (xy 81.27115 -370.523703) (xy 81.263075 -370.590641) (xy 81.24704 -370.656129)
			(xy 81.223276 -370.719226) (xy 81.192125 -370.779021) (xy 81.154036 -370.834655) (xy 81.132172 -370.86032)
			(xy 81.126381 -370.867469) (xy 81.119864 -370.884657) (xy 81.119472 -370.893848) (xy 81.119472 -371.386354)
			(xy 81.119911 -371.395538) (xy 81.126405 -371.412722) (xy 81.132172 -371.419882) (xy 81.154051 -371.445535)
			(xy 81.192141 -371.501171) (xy 81.223293 -371.560969) (xy 81.246928 -371.623725) (xy 82.349035 -371.623725)
			(xy 82.349038 -371.556418) (xy 82.357086 -371.489593) (xy 82.373062 -371.424209) (xy 82.396738 -371.361203)
			(xy 82.427775 -371.301478) (xy 82.465727 -371.24589) (xy 82.487516 -371.220238) (xy 82.493323 -371.2131)
			(xy 82.499831 -371.195904) (xy 82.500216 -371.18671) (xy 82.500216 -371.028722) (xy 82.500751 -371.018568)
			(xy 82.508514 -370.999804) (xy 82.522867 -370.985439) (xy 82.541625 -370.977659) (xy 82.551778 -370.97716)
			(xy 83.268058 -370.97716) (xy 83.27823 -370.977599) (xy 83.297028 -370.985374) (xy 83.311415 -370.999756)
			(xy 83.319197 -371.018551) (xy 83.31962 -371.028722) (xy 83.31962 -371.18671) (xy 83.320021 -371.195898)
			(xy 83.326541 -371.213083) (xy 83.33232 -371.220238) (xy 83.354072 -371.24592) (xy 83.392024 -371.301501)
			(xy 83.423061 -371.361221) (xy 83.446738 -371.424221) (xy 83.462715 -371.4896) (xy 83.470763 -371.55642)
			(xy 83.470766 -371.623723) (xy 83.462725 -371.690544) (xy 83.446755 -371.755924) (xy 83.423085 -371.818927)
			(xy 83.392054 -371.878649) (xy 83.354107 -371.934234) (xy 83.33232 -371.959886) (xy 83.326507 -371.96702)
			(xy 83.320001 -371.984219) (xy 83.31962 -371.993414) (xy 83.31962 -372.486682) (xy 83.320034 -372.495869)
			(xy 83.326545 -372.513054) (xy 83.33232 -372.52021) (xy 83.354142 -372.545834) (xy 83.392093 -372.601424)
			(xy 83.423127 -372.661151) (xy 83.446799 -372.724159) (xy 83.462771 -372.789545) (xy 83.470813 -372.856371)
			(xy 83.47081 -372.92368) (xy 83.462762 -372.990505) (xy 83.446784 -373.05589) (xy 83.423106 -373.118896)
			(xy 83.392066 -373.17862) (xy 83.354111 -373.234206) (xy 83.33232 -373.259858) (xy 83.326519 -373.267)
			(xy 83.320006 -373.284193) (xy 83.31962 -373.293386) (xy 83.31962 -373.451374) (xy 83.319214 -373.461549)
			(xy 83.311429 -373.480351) (xy 83.297038 -373.494738) (xy 83.278233 -373.502517) (xy 83.268058 -373.502936)
			(xy 82.551778 -373.502936) (xy 82.541602 -373.502553) (xy 82.522802 -373.494756) (xy 82.508417 -373.480358)
			(xy 82.500637 -373.461551) (xy 82.500216 -373.451374) (xy 82.500216 -373.293386) (xy 82.499809 -373.284199)
			(xy 82.493293 -373.267014) (xy 82.487516 -373.259858) (xy 82.465763 -373.234178) (xy 82.427814 -373.178595)
			(xy 82.396781 -373.118875) (xy 82.373107 -373.055874) (xy 82.357133 -372.990496) (xy 82.349086 -372.923677)
			(xy 82.349083 -372.856375) (xy 82.357123 -372.789555) (xy 82.373092 -372.724175) (xy 82.39676 -372.661172)
			(xy 82.427788 -372.601449) (xy 82.465731 -372.545863) (xy 82.487516 -372.52021) (xy 82.493335 -372.513081)
			(xy 82.499836 -372.495878) (xy 82.500216 -372.486682) (xy 82.500216 -371.993414) (xy 82.499795 -371.984228)
			(xy 82.493288 -371.967044) (xy 82.487516 -371.959886) (xy 82.465692 -371.934264) (xy 82.427745 -371.878673)
			(xy 82.396715 -371.818945) (xy 82.373045 -371.755936) (xy 82.357076 -371.690551) (xy 82.349035 -371.623725)
			(xy 81.246928 -371.623725) (xy 81.247057 -371.624067) (xy 81.263092 -371.689558) (xy 81.271168 -371.756498)
			(xy 81.271166 -371.823923) (xy 81.263089 -371.890863) (xy 81.247051 -371.956353) (xy 81.223284 -372.019451)
			(xy 81.19213 -372.079247) (xy 81.154038 -372.134881) (xy 81.132172 -372.160546) (xy 81.12637 -372.167687)
			(xy 81.119859 -372.184881) (xy 81.119472 -372.194074) (xy 81.119472 -372.351554) (xy 81.118936 -372.361676)
			(xy 81.111226 -372.380394) (xy 81.096954 -372.394752) (xy 81.078283 -372.402574) (xy 81.068164 -372.403116)
			(xy 80.351884 -372.403116) (xy 80.341776 -372.402628) (xy 80.323101 -372.394888) (xy 80.308807 -372.380592)
			(xy 80.30107 -372.361916) (xy 80.300576 -372.351808) (xy 80.300576 -372.194074) (xy 80.300184 -372.184885)
			(xy 80.293658 -372.1677) (xy 80.287876 -372.160546) (xy 80.266027 -372.134869) (xy 80.227939 -372.079236)
			(xy 80.196789 -372.019441) (xy 80.173025 -371.956346) (xy 80.156989 -371.890858) (xy 80.148913 -371.823922)
			(xy 80.148912 -371.756499) (xy 80.156986 -371.689563) (xy 80.173019 -371.624075) (xy 80.196781 -371.560978)
			(xy 80.227928 -371.501182) (xy 80.266014 -371.445548) (xy 80.287876 -371.419882) (xy 80.29366 -371.412728)
			(xy 80.300183 -371.395544) (xy 80.300576 -371.386354) (xy 80.300576 -370.893848) (xy 80.300148 -370.884663)
			(xy 80.293647 -370.867478) (xy 80.287876 -370.86032) (xy 80.266001 -370.834664) (xy 80.227914 -370.779028)
			(xy 80.196765 -370.71923) (xy 80.173003 -370.656132) (xy 80.156969 -370.590642) (xy 80.148895 -370.523703)
			(xy 76.870824 -370.523703) (xy 76.862788 -370.590464) (xy 76.846817 -370.655845) (xy 76.823147 -370.718849)
			(xy 76.792116 -370.778573) (xy 76.75417 -370.83416) (xy 76.732384 -370.859812) (xy 76.726598 -370.866965)
			(xy 76.720078 -370.88415) (xy 76.719684 -370.89334) (xy 76.719684 -371.386862) (xy 76.720116 -371.396047)
			(xy 76.726615 -371.413231) (xy 76.732384 -371.42039) (xy 76.754185 -371.446031) (xy 76.792132 -371.50162)
			(xy 76.823163 -371.561345) (xy 76.846621 -371.623785) (xy 77.948715 -371.623785) (xy 77.948719 -371.556358)
			(xy 77.956799 -371.489417) (xy 77.972839 -371.423925) (xy 77.996609 -371.360826) (xy 78.027766 -371.301029)
			(xy 78.065861 -371.245395) (xy 78.087728 -371.21973) (xy 78.09354 -371.212596) (xy 78.100045 -371.195397)
			(xy 78.100428 -371.186202) (xy 78.100428 -371.028722) (xy 78.100944 -371.018598) (xy 78.108662 -370.99988)
			(xy 78.12294 -370.985523) (xy 78.141615 -370.977701) (xy 78.151736 -370.97716) (xy 78.868016 -370.97716)
			(xy 78.878121 -370.977671) (xy 78.896792 -370.985407) (xy 78.911084 -370.999695) (xy 78.918826 -371.018363)
			(xy 78.919324 -371.028468) (xy 78.919324 -371.186202) (xy 78.919728 -371.19539) (xy 78.926245 -371.212575)
			(xy 78.932024 -371.21973) (xy 78.95385 -371.245426) (xy 78.991938 -371.301057) (xy 79.023089 -371.360849)
			(xy 79.046854 -371.423942) (xy 79.062892 -371.489427) (xy 79.07097 -371.556361) (xy 79.070974 -371.623782)
			(xy 79.062902 -371.690717) (xy 79.046871 -371.756203) (xy 79.023112 -371.819299) (xy 78.991967 -371.879094)
			(xy 78.953885 -371.934728) (xy 78.932024 -371.960394) (xy 78.92625 -371.967556) (xy 78.919721 -371.984733)
			(xy 78.919324 -371.993922) (xy 78.919324 -372.486174) (xy 78.919741 -372.495361) (xy 78.926249 -372.512545)
			(xy 78.932024 -372.519702) (xy 78.953921 -372.54534) (xy 78.992007 -372.600979) (xy 79.023155 -372.660779)
			(xy 79.046916 -372.72388) (xy 79.062948 -372.789372) (xy 79.071021 -372.856313) (xy 79.071018 -372.923738)
			(xy 79.062939 -372.990679) (xy 79.046901 -373.056169) (xy 79.023134 -373.119267) (xy 78.99198 -373.179065)
			(xy 78.953889 -373.2347) (xy 78.932024 -373.260366) (xy 78.92622 -373.267506) (xy 78.919709 -373.2847)
			(xy 78.919324 -373.293894) (xy 78.919324 -373.451374) (xy 78.918851 -373.461504) (xy 78.911125 -373.480231)
			(xy 78.896834 -373.49459) (xy 78.878143 -373.502403) (xy 78.868016 -373.502936) (xy 78.151736 -373.502936)
			(xy 78.14162 -373.502455) (xy 78.122924 -373.494726) (xy 78.10861 -373.480429) (xy 78.100857 -373.461743)
			(xy 78.100428 -373.451628) (xy 78.100428 -373.293894) (xy 78.100015 -373.284707) (xy 78.093503 -373.267523)
			(xy 78.087728 -373.260366) (xy 78.065896 -373.234674) (xy 78.027805 -373.179044) (xy 77.996651 -373.119251)
			(xy 77.972884 -373.056158) (xy 77.956845 -372.990672) (xy 77.948766 -372.923736) (xy 77.948763 -372.856315)
			(xy 77.956836 -372.789378) (xy 77.972869 -372.723891) (xy 77.99663 -372.660795) (xy 78.027779 -372.601)
			(xy 78.065865 -372.545367) (xy 78.087728 -372.519702) (xy 78.09351 -372.512547) (xy 78.100033 -372.495364)
			(xy 78.100428 -372.486174) (xy 78.100428 -371.993922) (xy 78.100001 -371.984737) (xy 78.093498 -371.967553)
			(xy 78.087728 -371.960394) (xy 78.065826 -371.93476) (xy 78.027736 -371.879122) (xy 77.996586 -371.819321)
			(xy 77.972822 -371.75622) (xy 77.956789 -371.690727) (xy 77.948715 -371.623785) (xy 76.846621 -371.623785)
			(xy 76.846834 -371.624351) (xy 76.862805 -371.689734) (xy 76.870848 -371.756558) (xy 76.870847 -371.823863)
			(xy 76.862802 -371.890687) (xy 76.846828 -371.956069) (xy 76.823155 -372.019074) (xy 76.792121 -372.078798)
			(xy 76.754172 -372.134386) (xy 76.732384 -372.160038) (xy 76.726587 -372.167183) (xy 76.720073 -372.184374)
			(xy 76.719684 -372.193566) (xy 76.719684 -372.351554) (xy 76.719199 -372.36172) (xy 76.711433 -372.380509)
			(xy 76.697067 -372.394895) (xy 76.678287 -372.402686) (xy 76.668122 -372.403116) (xy 75.951842 -372.403116)
			(xy 75.941667 -372.402701) (xy 75.922865 -372.394921) (xy 75.908477 -372.380532) (xy 75.900699 -372.361729)
			(xy 75.90028 -372.351554) (xy 75.90028 -372.193566) (xy 75.899891 -372.184377) (xy 75.893363 -372.167192)
			(xy 75.88758 -372.160038) (xy 75.865805 -372.134375) (xy 75.827853 -372.078791) (xy 75.796817 -372.019069)
			(xy 75.773141 -371.956066) (xy 75.757166 -371.890685) (xy 75.74912 -371.823863) (xy 75.749119 -371.756558)
			(xy 75.757162 -371.689736) (xy 75.773135 -371.624354) (xy 75.796808 -371.56135) (xy 75.827842 -371.501627)
			(xy 75.865792 -371.446042) (xy 75.88758 -371.42039) (xy 75.893361 -371.413234) (xy 75.899886 -371.396052)
			(xy 75.90028 -371.386862) (xy 75.90028 -370.89334) (xy 75.899855 -370.884154) (xy 75.893352 -370.866969)
			(xy 75.88758 -370.859812) (xy 75.865779 -370.83417) (xy 75.827828 -370.778583) (xy 75.796793 -370.718859)
			(xy 75.773119 -370.655853) (xy 75.757146 -370.590469) (xy 75.749102 -370.523644) (xy 72.471063 -370.523644)
			(xy 72.471063 -370.523702) (xy 72.462988 -370.59064) (xy 72.446953 -370.656129) (xy 72.42319 -370.719225)
			(xy 72.39204 -370.779021) (xy 72.353952 -370.834655) (xy 72.332088 -370.86032) (xy 72.326299 -370.867471)
			(xy 72.31978 -370.884657) (xy 72.319388 -370.893848) (xy 72.319388 -371.386354) (xy 72.319823 -371.395539)
			(xy 72.32632 -371.412723) (xy 72.332088 -371.419882) (xy 72.353966 -371.445536) (xy 72.392055 -371.501172)
			(xy 72.423206 -371.560969) (xy 72.446841 -371.623725) (xy 73.548947 -371.623725) (xy 73.548951 -371.556417)
			(xy 73.556998 -371.489592) (xy 73.572975 -371.424208) (xy 73.596652 -371.361202) (xy 73.627689 -371.301477)
			(xy 73.665642 -371.24589) (xy 73.687432 -371.220238) (xy 73.693242 -371.213102) (xy 73.699748 -371.195904)
			(xy 73.700132 -371.18671) (xy 73.700132 -371.028722) (xy 73.700582 -371.018553) (xy 73.708359 -370.99976)
			(xy 73.722736 -370.985374) (xy 73.741525 -370.977587) (xy 73.751694 -370.97716) (xy 74.467974 -370.97716)
			(xy 74.478147 -370.977586) (xy 74.496945 -370.985366) (xy 74.511331 -370.999752) (xy 74.519113 -371.018549)
			(xy 74.519536 -371.028722) (xy 74.519536 -371.18671) (xy 74.519956 -371.195896) (xy 74.526464 -371.21308)
			(xy 74.532236 -371.220238) (xy 74.553987 -371.245921) (xy 74.591939 -371.301502) (xy 74.622975 -371.361221)
			(xy 74.646651 -371.424222) (xy 74.662627 -371.489601) (xy 74.670675 -371.55642) (xy 74.670678 -371.623723)
			(xy 74.662638 -371.690543) (xy 74.646668 -371.755924) (xy 74.622998 -371.818926) (xy 74.591968 -371.878649)
			(xy 74.554022 -371.934234) (xy 74.532236 -371.959886) (xy 74.526413 -371.967012) (xy 74.519916 -371.984217)
			(xy 74.519536 -371.993414) (xy 74.519536 -372.486682) (xy 74.519969 -372.495866) (xy 74.526468 -372.51305)
			(xy 74.532236 -372.52021) (xy 74.554058 -372.545834) (xy 74.592008 -372.601424) (xy 74.623041 -372.661151)
			(xy 74.646713 -372.724159) (xy 74.662684 -372.789545) (xy 74.670726 -372.856371) (xy 74.670723 -372.92368)
			(xy 74.662675 -372.990505) (xy 74.646698 -373.055889) (xy 74.62302 -373.118896) (xy 74.591981 -373.17862)
			(xy 74.554027 -373.234206) (xy 74.532236 -373.259858) (xy 74.526425 -373.266992) (xy 74.519921 -373.284191)
			(xy 74.519536 -373.293386) (xy 74.519536 -373.451374) (xy 74.519114 -373.461547) (xy 74.511333 -373.480346)
			(xy 74.496946 -373.494733) (xy 74.478147 -373.502514) (xy 74.467974 -373.502936) (xy 73.751694 -373.502936)
			(xy 73.741519 -373.50254) (xy 73.722719 -373.494749) (xy 73.708333 -373.480354) (xy 73.700553 -373.461549)
			(xy 73.700132 -373.451374) (xy 73.700132 -373.293386) (xy 73.699722 -373.284199) (xy 73.693207 -373.267015)
			(xy 73.687432 -373.259858) (xy 73.665678 -373.234178) (xy 73.627729 -373.178595) (xy 73.596694 -373.118876)
			(xy 73.57302 -373.055875) (xy 73.557045 -372.990496) (xy 73.548998 -372.923677) (xy 73.548995 -372.856374)
			(xy 73.557036 -372.789554) (xy 73.573005 -372.724174) (xy 73.596674 -372.661171) (xy 73.627702 -372.601448)
			(xy 73.665647 -372.545862) (xy 73.687432 -372.52021) (xy 73.693253 -372.513083) (xy 73.699753 -372.495878)
			(xy 73.700132 -372.486682) (xy 73.700132 -371.993414) (xy 73.699708 -371.984228) (xy 73.693203 -371.967044)
			(xy 73.687432 -371.959886) (xy 73.665607 -371.934265) (xy 73.62766 -371.878674) (xy 73.596629 -371.818946)
			(xy 73.572958 -371.755937) (xy 73.556988 -371.690551) (xy 73.548947 -371.623725) (xy 72.446841 -371.623725)
			(xy 72.44697 -371.624068) (xy 72.463005 -371.689558) (xy 72.47108 -371.756498) (xy 72.471078 -371.823923)
			(xy 72.463001 -371.890862) (xy 72.446964 -371.956352) (xy 72.423197 -372.01945) (xy 72.392044 -372.079246)
			(xy 72.353953 -372.134881) (xy 72.332088 -372.160546) (xy 72.326288 -372.167689) (xy 72.319776 -372.184881)
			(xy 72.319388 -372.194074) (xy 72.319388 -372.351554) (xy 72.318836 -372.361674) (xy 72.311129 -372.380389)
			(xy 72.296863 -372.394746) (xy 72.278197 -372.402572) (xy 72.26808 -372.403116) (xy 71.5518 -372.403116)
			(xy 71.541648 -372.402679) (xy 71.522899 -372.394886) (xy 71.508576 -372.380494) (xy 71.500873 -372.361708)
			(xy 71.500492 -372.351554) (xy 71.500492 -372.194074) (xy 71.500096 -372.184885) (xy 71.493573 -372.167701)
			(xy 71.487792 -372.160546) (xy 71.465942 -372.134869) (xy 71.427853 -372.079236) (xy 71.396703 -372.019442)
			(xy 71.372938 -371.956346) (xy 71.356902 -371.890859) (xy 71.348825 -371.823922) (xy 71.348824 -371.756499)
			(xy 71.356898 -371.689562) (xy 71.372932 -371.624074) (xy 71.396694 -371.560978) (xy 71.427843 -371.501182)
			(xy 71.465929 -371.445547) (xy 71.487792 -371.419882) (xy 71.493578 -371.412729) (xy 71.500099 -371.395545)
			(xy 71.500492 -371.386354) (xy 71.500492 -370.893848) (xy 71.500061 -370.884663) (xy 71.493562 -370.867478)
			(xy 71.487792 -370.86032) (xy 71.465917 -370.834664) (xy 71.427829 -370.779028) (xy 71.396679 -370.719231)
			(xy 71.372916 -370.656133) (xy 71.356881 -370.590642) (xy 71.348807 -370.523703) (xy 58.103008 -370.523703)
			(xy 58.103008 -371.310662) (xy 58.102522 -371.337931) (xy 58.09476 -371.391915) (xy 58.079395 -371.444245)
			(xy 58.056738 -371.493855) (xy 58.027252 -371.539736) (xy 57.991537 -371.580953) (xy 57.95032 -371.616668)
			(xy 57.904439 -371.646154) (xy 57.854829 -371.668811) (xy 57.802499 -371.684176) (xy 57.748515 -371.691938)
			(xy 57.693977 -371.691938) (xy 57.639993 -371.684176) (xy 57.587663 -371.668811) (xy 57.538053 -371.646154)
			(xy 57.492172 -371.616668) (xy 57.450955 -371.580953) (xy 57.41524 -371.539736) (xy 57.385754 -371.493855)
			(xy 57.363097 -371.444245) (xy 57.347732 -371.391915) (xy 57.33997 -371.337931) (xy 57.339484 -371.310662)
			(xy 54.729888 -371.310662) (xy 54.729402 -371.337931) (xy 54.72164 -371.391915) (xy 54.706275 -371.444245)
			(xy 54.683618 -371.493855) (xy 54.654132 -371.539736) (xy 54.618417 -371.580953) (xy 54.5772 -371.616668)
			(xy 54.531319 -371.646154) (xy 54.481709 -371.668811) (xy 54.429379 -371.684176) (xy 54.375395 -371.691938)
			(xy 54.320857 -371.691938) (xy 54.266873 -371.684176) (xy 54.214543 -371.668811) (xy 54.164933 -371.646154)
			(xy 54.119052 -371.616668) (xy 54.077835 -371.580953) (xy 54.04212 -371.539736) (xy 54.012634 -371.493855)
			(xy 53.989977 -371.444245) (xy 53.974612 -371.391915) (xy 53.96685 -371.337931) (xy 53.966364 -371.310662)
			(xy 48.196948 -371.310662) (xy 48.223223 -371.361224) (xy 48.246896 -371.424224) (xy 48.262871 -371.489602)
			(xy 48.270918 -371.556421) (xy 48.270921 -371.623722) (xy 48.262881 -371.690542) (xy 48.246913 -371.755921)
			(xy 48.223246 -371.818924) (xy 48.192219 -371.878647) (xy 48.154277 -371.934234) (xy 48.132492 -371.959886)
			(xy 48.126675 -371.967017) (xy 48.120173 -371.984218) (xy 48.119792 -371.993414) (xy 48.119792 -372.486682)
			(xy 48.120213 -372.495868) (xy 48.126719 -372.513052) (xy 48.132492 -372.52021) (xy 48.154312 -372.545835)
			(xy 48.192258 -372.601426) (xy 48.223288 -372.661154) (xy 48.246958 -372.724162) (xy 48.262927 -372.789547)
			(xy 48.270968 -372.856372) (xy 48.270965 -372.923679) (xy 48.262918 -372.990504) (xy 48.246942 -373.055887)
			(xy 48.223267 -373.118893) (xy 48.192232 -373.178618) (xy 48.154281 -373.234205) (xy 48.132492 -373.259858)
			(xy 48.126687 -373.266997) (xy 48.120178 -373.284192) (xy 48.119792 -373.293386) (xy 48.119792 -373.451374)
			(xy 48.119246 -373.461526) (xy 48.111486 -373.480289) (xy 48.097136 -373.494655) (xy 48.078382 -373.502435)
			(xy 48.06823 -373.502936) (xy 47.35195 -373.502936) (xy 47.341778 -373.502495) (xy 47.32298 -373.494721)
			(xy 47.308592 -373.48034) (xy 47.30081 -373.461545) (xy 47.300388 -373.451374) (xy 47.300388 -373.293386)
			(xy 47.299987 -373.284198) (xy 47.293467 -373.267013) (xy 47.287688 -373.259858) (xy 47.265932 -373.234179)
			(xy 47.227979 -373.178598) (xy 47.196942 -373.118878) (xy 47.173265 -373.055877) (xy 47.157288 -372.990498)
			(xy 47.14924 -372.923677) (xy 47.149237 -372.856374) (xy 47.157279 -372.789553) (xy 47.17325 -372.724172)
			(xy 47.196921 -372.661169) (xy 47.227953 -372.601446) (xy 47.265901 -372.545861) (xy 47.287688 -372.52021)
			(xy 47.293504 -372.513078) (xy 47.300007 -372.495878) (xy 47.300388 -372.486682) (xy 47.300388 -371.993414)
			(xy 47.299974 -371.984227) (xy 47.293463 -371.967043) (xy 47.287688 -371.959886) (xy 47.265861 -371.934265)
			(xy 47.227911 -371.878675) (xy 47.196876 -371.818948) (xy 47.173204 -371.755939) (xy 47.157232 -371.690553)
			(xy 47.14919 -371.623726) (xy 46.046568 -371.623726) (xy 46.046802 -371.624349) (xy 46.062775 -371.689733)
			(xy 46.070818 -371.756557) (xy 46.070817 -371.823864) (xy 46.062771 -371.890688) (xy 46.046796 -371.956071)
			(xy 46.023121 -372.019076) (xy 45.992085 -372.0788) (xy 45.954133 -372.134386) (xy 45.932344 -372.160038)
			(xy 45.926542 -372.167179) (xy 45.920032 -372.184373) (xy 45.919644 -372.193566) (xy 45.919644 -372.351554)
			(xy 45.919198 -372.361725) (xy 45.911425 -372.380522) (xy 45.897046 -372.394909) (xy 45.878253 -372.402693)
			(xy 45.868082 -372.403116) (xy 45.151802 -372.403116) (xy 45.141625 -372.402733) (xy 45.122821 -372.394941)
			(xy 45.108435 -372.380542) (xy 45.100658 -372.361732) (xy 45.10024 -372.351554) (xy 45.10024 -372.193566)
			(xy 45.099837 -372.184378) (xy 45.093317 -372.167194) (xy 45.08754 -372.160038) (xy 45.065766 -372.134374)
			(xy 45.027817 -372.07879) (xy 44.996783 -372.019068) (xy 44.973109 -371.956065) (xy 44.957135 -371.890684)
			(xy 44.94909 -371.823862) (xy 44.949089 -371.756559) (xy 44.957132 -371.689737) (xy 44.973103 -371.624356)
			(xy 44.996774 -371.561352) (xy 45.027806 -371.501628) (xy 45.065753 -371.446042) (xy 45.08754 -371.42039)
			(xy 45.093328 -371.413239) (xy 45.099847 -371.396053) (xy 45.10024 -371.386862) (xy 45.10024 -370.89334)
			(xy 45.099801 -370.884156) (xy 45.093306 -370.866972) (xy 45.08754 -370.859812) (xy 45.06574 -370.83417)
			(xy 45.027792 -370.778582) (xy 44.996759 -370.718857) (xy 44.973087 -370.655851) (xy 44.957115 -370.590468)
			(xy 44.949071 -370.523644) (xy 41.671032 -370.523644) (xy 41.671032 -370.523703) (xy 41.662957 -370.590641)
			(xy 41.646921 -370.65613) (xy 41.623156 -370.719227) (xy 41.592004 -370.779022) (xy 41.553913 -370.834656)
			(xy 41.532048 -370.86032) (xy 41.526254 -370.867467) (xy 41.519739 -370.884656) (xy 41.519348 -370.893848)
			(xy 41.519348 -371.386354) (xy 41.519792 -371.395537) (xy 41.526284 -371.412721) (xy 41.532048 -371.419882)
			(xy 41.553928 -371.445535) (xy 41.592019 -371.50117) (xy 41.623172 -371.560967) (xy 41.646832 -371.623785)
			(xy 42.748894 -371.623785) (xy 42.748898 -371.556358) (xy 42.756977 -371.489417) (xy 42.773017 -371.423926)
			(xy 42.796785 -371.360828) (xy 42.827941 -371.30103) (xy 42.866034 -371.245395) (xy 42.8879 -371.21973)
			(xy 42.893709 -371.212593) (xy 42.900216 -371.195396) (xy 42.9006 -371.186202) (xy 42.9006 -371.028722)
			(xy 42.901143 -371.018602) (xy 42.908856 -370.999888) (xy 42.923125 -370.985533) (xy 42.941791 -370.977706)
			(xy 42.951908 -370.97716) (xy 43.668188 -370.97716) (xy 43.678336 -370.977631) (xy 43.697081 -370.985415)
			(xy 43.711403 -370.999796) (xy 43.71911 -371.018572) (xy 43.719496 -371.028722) (xy 43.719496 -371.186202)
			(xy 43.719906 -371.195389) (xy 43.72642 -371.212573) (xy 43.732196 -371.21973) (xy 43.754023 -371.245426)
			(xy 43.792113 -371.301056) (xy 43.823265 -371.360848) (xy 43.847032 -371.423941) (xy 43.86307 -371.489426)
			(xy 43.871149 -371.556361) (xy 43.871153 -371.623782) (xy 43.86308 -371.690718) (xy 43.847049 -371.756205)
			(xy 43.823289 -371.8193) (xy 43.792142 -371.879095) (xy 43.754058 -371.934729) (xy 43.732196 -371.960394)
			(xy 43.726419 -371.967553) (xy 43.719893 -371.984733) (xy 43.719496 -371.993922) (xy 43.719496 -372.486174)
			(xy 43.71992 -372.49536) (xy 43.726424 -372.512544) (xy 43.732196 -372.519702) (xy 43.754094 -372.54534)
			(xy 43.792181 -372.600978) (xy 43.823331 -372.660778) (xy 43.847093 -372.723878) (xy 43.863127 -372.789371)
			(xy 43.8712 -372.856312) (xy 43.871197 -372.923739) (xy 43.863117 -372.990679) (xy 43.847078 -373.05617)
			(xy 43.82331 -373.119269) (xy 43.792155 -373.179066) (xy 43.754062 -373.234701) (xy 43.732196 -373.260366)
			(xy 43.726388 -373.267503) (xy 43.71988 -373.2847) (xy 43.719496 -373.293894) (xy 43.719496 -373.451374)
			(xy 43.718953 -373.461495) (xy 43.711241 -373.480208) (xy 43.696972 -373.494564) (xy 43.678306 -373.502391)
			(xy 43.668188 -373.502936) (xy 42.951908 -373.502936) (xy 42.941759 -373.502473) (xy 42.923014 -373.494686)
			(xy 42.908691 -373.480303) (xy 42.900985 -373.461525) (xy 42.9006 -373.451374) (xy 42.9006 -373.293894)
			(xy 42.900193 -373.284707) (xy 42.893677 -373.267522) (xy 42.8879 -373.260366) (xy 42.866069 -373.234673)
			(xy 42.82798 -373.179043) (xy 42.796828 -373.11925) (xy 42.773061 -373.056157) (xy 42.757024 -372.990671)
			(xy 42.748945 -372.923736) (xy 42.748942 -372.856315) (xy 42.757014 -372.789379) (xy 42.773046 -372.723892)
			(xy 42.796807 -372.660796) (xy 42.827953 -372.601001) (xy 42.866038 -372.545367) (xy 42.8879 -372.519702)
			(xy 42.893678 -372.512544) (xy 42.900204 -372.495363) (xy 42.9006 -372.486174) (xy 42.9006 -371.993922)
			(xy 42.900179 -371.984736) (xy 42.893673 -371.967551) (xy 42.8879 -371.960394) (xy 42.865999 -371.93476)
			(xy 42.827911 -371.879121) (xy 42.796762 -371.81932) (xy 42.773 -371.756219) (xy 42.756967 -371.690726)
			(xy 42.748894 -371.623785) (xy 41.646832 -371.623785) (xy 41.646938 -371.624066) (xy 41.662974 -371.689557)
			(xy 41.67105 -371.756498) (xy 41.671048 -371.823923) (xy 41.66297 -371.890864) (xy 41.646932 -371.956354)
			(xy 41.623164 -372.019452) (xy 41.592008 -372.079248) (xy 41.553915 -372.134882) (xy 41.532048 -372.160546)
			(xy 41.526243 -372.167685) (xy 41.519735 -372.18488) (xy 41.519348 -372.194074) (xy 41.519348 -372.351554)
			(xy 41.518835 -372.361679) (xy 41.51112 -372.380402) (xy 41.496842 -372.39476) (xy 41.478162 -372.402579)
			(xy 41.46804 -372.403116) (xy 40.75176 -372.403116) (xy 40.741605 -372.402711) (xy 40.722855 -372.394906)
			(xy 40.708534 -372.380504) (xy 40.700833 -372.361711) (xy 40.700452 -372.351554) (xy 40.700452 -372.194074)
			(xy 40.700043 -372.184887) (xy 40.693527 -372.167703) (xy 40.687752 -372.160546) (xy 40.6659 -372.13487)
			(xy 40.627807 -372.079238) (xy 40.596653 -372.019444) (xy 40.572886 -371.956349) (xy 40.556848 -371.89086)
			(xy 40.54877 -371.823922) (xy 40.548769 -371.756499) (xy 40.556844 -371.68956) (xy 40.57288 -371.624072)
			(xy 40.596645 -371.560975) (xy 40.627797 -371.50118) (xy 40.665887 -371.445546) (xy 40.687752 -371.419882)
			(xy 40.693545 -371.412735) (xy 40.70006 -371.395546) (xy 40.700452 -371.386354) (xy 40.700452 -370.893848)
			(xy 40.700007 -370.884665) (xy 40.693516 -370.867481) (xy 40.687752 -370.86032) (xy 40.665874 -370.834665)
			(xy 40.627783 -370.779031) (xy 40.59663 -370.719233) (xy 40.572864 -370.656135) (xy 40.556828 -370.590644)
			(xy 40.548752 -370.523704) (xy 37.271241 -370.523704) (xy 37.263166 -370.590641) (xy 37.247131 -370.65613)
			(xy 37.223366 -370.719226) (xy 37.192215 -370.779022) (xy 37.154125 -370.834655) (xy 37.13226 -370.86032)
			(xy 37.126467 -370.867468) (xy 37.119951 -370.884656) (xy 37.11956 -370.893848) (xy 37.11956 -371.386354)
			(xy 37.120001 -371.395538) (xy 37.126494 -371.412722) (xy 37.13226 -371.419882) (xy 37.154139 -371.445535)
			(xy 37.19223 -371.501171) (xy 37.223382 -371.560968) (xy 37.247019 -371.623725) (xy 38.349126 -371.623725)
			(xy 38.349129 -371.556418) (xy 38.357177 -371.489593) (xy 38.373153 -371.424209) (xy 38.396828 -371.361203)
			(xy 38.427864 -371.301478) (xy 38.465815 -371.245891) (xy 38.487604 -371.220238) (xy 38.49341 -371.213099)
			(xy 38.499919 -371.195904) (xy 38.500304 -371.18671) (xy 38.500304 -371.028722) (xy 38.50085 -371.01857)
			(xy 38.508611 -370.999808) (xy 38.522961 -370.985443) (xy 38.541714 -370.977661) (xy 38.551866 -370.97716)
			(xy 39.268146 -370.97716) (xy 39.278309 -370.977596) (xy 39.297084 -370.98539) (xy 39.311448 -370.999773)
			(xy 39.319217 -371.018558) (xy 39.319708 -371.028722) (xy 39.319708 -371.18671) (xy 39.320112 -371.195898)
			(xy 39.32663 -371.213082) (xy 39.332408 -371.220238) (xy 39.35416 -371.24592) (xy 39.392113 -371.301501)
			(xy 39.423151 -371.36122) (xy 39.446829 -371.424221) (xy 39.462806 -371.4896) (xy 39.470854 -371.55642)
			(xy 39.470857 -371.623723) (xy 39.462816 -371.690544) (xy 39.446845 -371.755925) (xy 39.423175 -371.818928)
			(xy 39.392143 -371.87865) (xy 39.354195 -371.934235) (xy 39.332408 -371.959886) (xy 39.326593 -371.967018)
			(xy 39.320089 -371.984219) (xy 39.319708 -371.993414) (xy 39.319708 -372.486682) (xy 39.320125 -372.495868)
			(xy 39.326634 -372.513053) (xy 39.332408 -372.52021) (xy 39.354231 -372.545834) (xy 39.392182 -372.601423)
			(xy 39.423217 -372.66115) (xy 39.44689 -372.724158) (xy 39.462862 -372.789545) (xy 39.470904 -372.856371)
			(xy 39.470901 -372.92368) (xy 39.462853 -372.990506) (xy 39.446875 -373.05589) (xy 39.423196 -373.118897)
			(xy 39.392156 -373.178621) (xy 39.354199 -373.234207) (xy 39.332408 -373.259858) (xy 39.326605 -373.266999)
			(xy 39.320094 -373.284193) (xy 39.319708 -373.293386) (xy 39.319708 -373.451374) (xy 39.319147 -373.461525)
			(xy 39.311389 -373.480284) (xy 39.297045 -373.494649) (xy 39.278296 -373.502432) (xy 39.268146 -373.502936)
			(xy 38.551866 -373.502936) (xy 38.541703 -373.502494) (xy 38.522928 -373.494703) (xy 38.508563 -373.480322)
			(xy 38.500794 -373.461538) (xy 38.500304 -373.451374) (xy 38.500304 -373.293386) (xy 38.4999 -373.284198)
			(xy 38.493382 -373.267014) (xy 38.487604 -373.259858) (xy 38.465851 -373.234178) (xy 38.427903 -373.178595)
			(xy 38.39687 -373.118875) (xy 38.373197 -373.055874) (xy 38.357223 -372.990495) (xy 38.349177 -372.923676)
			(xy 38.349174 -372.856375) (xy 38.357214 -372.789555) (xy 38.373182 -372.724175) (xy 38.396849 -372.661172)
			(xy 38.427877 -372.601449) (xy 38.465819 -372.545863) (xy 38.487604 -372.52021) (xy 38.493422 -372.51308)
			(xy 38.499924 -372.495878) (xy 38.500304 -372.486682) (xy 38.500304 -371.993414) (xy 38.499886 -371.984228)
			(xy 38.493378 -371.967043) (xy 38.487604 -371.959886) (xy 38.46578 -371.934264) (xy 38.427835 -371.878672)
			(xy 38.396805 -371.818944) (xy 38.373136 -371.755936) (xy 38.357167 -371.69055) (xy 38.349126 -371.623725)
			(xy 37.247019 -371.623725) (xy 37.247148 -371.624067) (xy 37.263183 -371.689557) (xy 37.271259 -371.756498)
			(xy 37.271257 -371.823923) (xy 37.263179 -371.890863) (xy 37.247141 -371.956354) (xy 37.223374 -372.019451)
			(xy 37.192219 -372.079248) (xy 37.154126 -372.134881) (xy 37.13226 -372.160546) (xy 37.126456 -372.167686)
			(xy 37.119947 -372.184881) (xy 37.11956 -372.194074) (xy 37.11956 -372.351554) (xy 37.119036 -372.361678)
			(xy 37.111323 -372.380398) (xy 37.097048 -372.394756) (xy 37.078373 -372.402576) (xy 37.068252 -372.403116)
			(xy 36.351972 -372.403116) (xy 36.341818 -372.402702) (xy 36.323068 -372.3949) (xy 36.308746 -372.380501)
			(xy 36.301045 -372.36171) (xy 36.300664 -372.351554) (xy 36.300664 -372.194074) (xy 36.300252 -372.184887)
			(xy 36.293738 -372.167704) (xy 36.287964 -372.160546) (xy 36.266115 -372.134869) (xy 36.228028 -372.079235)
			(xy 36.196879 -372.01944) (xy 36.173116 -371.956345) (xy 36.15708 -371.890858) (xy 36.149004 -371.823921)
			(xy 36.149003 -371.7565) (xy 36.157076 -371.689563) (xy 36.173109 -371.624075) (xy 36.19687 -371.560979)
			(xy 36.228017 -371.501183) (xy 36.266102 -371.445548) (xy 36.287964 -371.419882) (xy 36.293759 -371.412736)
			(xy 36.300273 -371.395546) (xy 36.300664 -371.386354) (xy 36.300664 -370.893848) (xy 36.300217 -370.884665)
			(xy 36.293727 -370.867481) (xy 36.287964 -370.86032) (xy 36.26609 -370.834664) (xy 36.228004 -370.779027)
			(xy 36.196855 -370.719229) (xy 36.173093 -370.656131) (xy 36.15706 -370.590642) (xy 36.148986 -370.523703)
			(xy 32.870915 -370.523703) (xy 32.862879 -370.590465) (xy 32.846908 -370.655846) (xy 32.823237 -370.71885)
			(xy 32.792205 -370.778573) (xy 32.754259 -370.83416) (xy 32.732472 -370.859812) (xy 32.726684 -370.866963)
			(xy 32.720165 -370.884149) (xy 32.719772 -370.89334) (xy 32.719772 -371.386862) (xy 32.720207 -371.396046)
			(xy 32.726704 -371.413231) (xy 32.732472 -371.42039) (xy 32.754273 -371.446031) (xy 32.792221 -371.501619)
			(xy 32.823253 -371.561344) (xy 32.846713 -371.623785) (xy 33.948806 -371.623785) (xy 33.94881 -371.556358)
			(xy 33.95689 -371.489417) (xy 33.97293 -371.423925) (xy 33.996699 -371.360827) (xy 34.027855 -371.30103)
			(xy 34.065949 -371.245395) (xy 34.087816 -371.21973) (xy 34.093627 -371.212595) (xy 34.100132 -371.195397)
			(xy 34.100516 -371.186202) (xy 34.100516 -371.028722) (xy 34.101044 -371.0186) (xy 34.10876 -370.999883)
			(xy 34.123033 -370.985527) (xy 34.141705 -370.977703) (xy 34.151824 -370.97716) (xy 34.868104 -370.97716)
			(xy 34.878253 -370.977618) (xy 34.896998 -370.985407) (xy 34.91132 -370.999792) (xy 34.919027 -371.018571)
			(xy 34.919412 -371.028722) (xy 34.919412 -371.186202) (xy 34.919819 -371.19539) (xy 34.926334 -371.212574)
			(xy 34.932112 -371.21973) (xy 34.953938 -371.245426) (xy 34.992027 -371.301057) (xy 35.023179 -371.360849)
			(xy 35.046945 -371.423941) (xy 35.062982 -371.489427) (xy 35.071061 -371.556361) (xy 35.071065 -371.623782)
			(xy 35.062993 -371.690717) (xy 35.046962 -371.756204) (xy 35.023202 -371.819299) (xy 34.992057 -371.879094)
			(xy 34.953973 -371.934729) (xy 34.932112 -371.960394) (xy 34.926337 -371.967555) (xy 34.919809 -371.984733)
			(xy 34.919412 -371.993922) (xy 34.919412 -372.486174) (xy 34.919832 -372.49536) (xy 34.926338 -372.512545)
			(xy 34.932112 -372.519702) (xy 34.954009 -372.54534) (xy 34.992096 -372.600979) (xy 35.023244 -372.660779)
			(xy 35.047006 -372.723879) (xy 35.063039 -372.789371) (xy 35.071112 -372.856312) (xy 35.071109 -372.923739)
			(xy 35.06303 -372.990679) (xy 35.046991 -373.05617) (xy 35.023224 -373.119268) (xy 34.99207 -373.179065)
			(xy 34.953978 -373.234701) (xy 34.932112 -373.260366) (xy 34.926306 -373.267505) (xy 34.919797 -373.2847)
			(xy 34.919412 -373.293894) (xy 34.919412 -373.451374) (xy 34.918854 -373.461493) (xy 34.911144 -373.480203)
			(xy 34.89688 -373.494559) (xy 34.878219 -373.502388) (xy 34.868104 -373.502936) (xy 34.151824 -373.502936)
			(xy 34.141676 -373.50246) (xy 34.122931 -373.494679) (xy 34.108608 -373.480299) (xy 34.100901 -373.461524)
			(xy 34.100516 -373.451374) (xy 34.100516 -373.293894) (xy 34.100105 -373.284707) (xy 34.093592 -373.267523)
			(xy 34.087816 -373.260366) (xy 34.065985 -373.234673) (xy 34.027894 -373.179043) (xy 33.996741 -373.119251)
			(xy 33.972974 -373.056158) (xy 33.956936 -372.990672) (xy 33.948857 -372.923736) (xy 33.948854 -372.856315)
			(xy 33.956927 -372.789379) (xy 33.972959 -372.723891) (xy 33.99672 -372.660796) (xy 34.027868 -372.601001)
			(xy 34.065953 -372.545367) (xy 34.087816 -372.519702) (xy 34.093596 -372.512545) (xy 34.10012 -372.495364)
			(xy 34.100516 -372.486174) (xy 34.100516 -371.993922) (xy 34.100092 -371.984736) (xy 34.093587 -371.967552)
			(xy 34.087816 -371.960394) (xy 34.065914 -371.93476) (xy 34.027826 -371.879121) (xy 33.996676 -371.819321)
			(xy 33.972913 -371.75622) (xy 33.956879 -371.690727) (xy 33.948806 -371.623785) (xy 32.846713 -371.623785)
			(xy 32.846925 -371.62435) (xy 32.862896 -371.689734) (xy 32.870939 -371.756558) (xy 32.870938 -371.823864)
			(xy 32.862892 -371.890687) (xy 32.846918 -371.95607) (xy 32.823244 -372.019075) (xy 32.79221 -372.078799)
			(xy 32.75426 -372.134386) (xy 32.732472 -372.160038) (xy 32.726673 -372.167181) (xy 32.72016 -372.184373)
			(xy 32.719772 -372.193566) (xy 32.719772 -372.351554) (xy 32.719299 -372.361721) (xy 32.711531 -372.380513)
			(xy 32.69716 -372.394899) (xy 32.678377 -372.402688) (xy 32.66821 -372.403116) (xy 31.95193 -372.403116)
			(xy 31.941755 -372.40271) (xy 31.922952 -372.394927) (xy 31.908564 -372.380535) (xy 31.900787 -372.361729)
			(xy 31.900368 -372.351554) (xy 31.900368 -372.193566) (xy 31.899959 -372.184379) (xy 31.893443 -372.167195)
			(xy 31.887668 -372.160038) (xy 31.865893 -372.134375) (xy 31.827942 -372.078791) (xy 31.796907 -372.019069)
			(xy 31.773232 -371.956066) (xy 31.757257 -371.890685) (xy 31.749211 -371.823863) (xy 31.74921 -371.756558)
			(xy 31.757253 -371.689736) (xy 31.773226 -371.624354) (xy 31.796898 -371.56135) (xy 31.827931 -371.501627)
			(xy 31.86588 -371.446042) (xy 31.887668 -371.42039) (xy 31.89346 -371.413242) (xy 31.899975 -371.396053)
			(xy 31.900368 -371.386862) (xy 31.900368 -370.89334) (xy 31.899923 -370.884157) (xy 31.893432 -370.866973)
			(xy 31.887668 -370.859812) (xy 31.865868 -370.83417) (xy 31.827917 -370.778583) (xy 31.796883 -370.718858)
			(xy 31.77321 -370.655852) (xy 31.757237 -370.590468) (xy 31.749193 -370.523644) (xy 28.471153 -370.523644)
			(xy 28.471153 -370.523703) (xy 28.463078 -370.59064) (xy 28.447043 -370.656129) (xy 28.42328 -370.719226)
			(xy 28.392129 -370.779021) (xy 28.35404 -370.834655) (xy 28.332176 -370.86032) (xy 28.326386 -370.867469)
			(xy 28.319868 -370.884657) (xy 28.319476 -370.893848) (xy 28.319476 -371.386354) (xy 28.319914 -371.395538)
			(xy 28.326409 -371.412722) (xy 28.332176 -371.419882) (xy 28.354055 -371.445535) (xy 28.392144 -371.501171)
			(xy 28.423296 -371.560969) (xy 28.446931 -371.623725) (xy 29.549038 -371.623725) (xy 29.549042 -371.556418)
			(xy 29.557089 -371.489593) (xy 29.573066 -371.424209) (xy 29.596742 -371.361203) (xy 29.627778 -371.301478)
			(xy 29.665731 -371.24589) (xy 29.68752 -371.220238) (xy 29.693328 -371.213101) (xy 29.699835 -371.195904)
			(xy 29.70022 -371.18671) (xy 29.70022 -371.028722) (xy 29.700682 -371.018554) (xy 29.708456 -370.999763)
			(xy 29.72283 -370.985378) (xy 29.741614 -370.97759) (xy 29.751782 -370.97716) (xy 30.468062 -370.97716)
			(xy 30.478234 -370.977596) (xy 30.497032 -370.985372) (xy 30.511419 -370.999755) (xy 30.519201 -371.01855)
			(xy 30.519624 -371.028722) (xy 30.519624 -371.18671) (xy 30.520024 -371.195898) (xy 30.526544 -371.213083)
			(xy 30.532324 -371.220238) (xy 30.554075 -371.24592) (xy 30.592028 -371.301502) (xy 30.623065 -371.361221)
			(xy 30.646741 -371.424221) (xy 30.662718 -371.4896) (xy 30.670766 -371.55642) (xy 30.670769 -371.623723)
			(xy 30.662728 -371.690543) (xy 30.646758 -371.755924) (xy 30.623088 -371.818927) (xy 30.592057 -371.878649)
			(xy 30.554111 -371.934234) (xy 30.532324 -371.959886) (xy 30.526511 -371.96702) (xy 30.520005 -371.984219)
			(xy 30.519624 -371.993414) (xy 30.519624 -372.486682) (xy 30.520037 -372.495869) (xy 30.526548 -372.513054)
			(xy 30.532324 -372.52021) (xy 30.554146 -372.545834) (xy 30.592096 -372.601424) (xy 30.62313 -372.661151)
			(xy 30.646803 -372.724159) (xy 30.662774 -372.789545) (xy 30.670816 -372.856371) (xy 30.670813 -372.92368)
			(xy 30.662765 -372.990505) (xy 30.646788 -373.05589) (xy 30.623109 -373.118896) (xy 30.59207 -373.17862)
			(xy 30.554115 -373.234206) (xy 30.532324 -373.259858) (xy 30.526523 -373.267) (xy 30.52001 -373.284193)
			(xy 30.519624 -373.293386) (xy 30.519624 -373.451374) (xy 30.519214 -373.461549) (xy 30.51143 -373.48035)
			(xy 30.49704 -373.494737) (xy 30.478237 -373.502516) (xy 30.468062 -373.502936) (xy 29.751782 -373.502936)
			(xy 29.741606 -373.50255) (xy 29.722806 -373.494754) (xy 29.708421 -373.480357) (xy 29.700641 -373.46155)
			(xy 29.70022 -373.451374) (xy 29.70022 -373.293386) (xy 29.699812 -373.284199) (xy 29.693297 -373.267015)
			(xy 29.68752 -373.259858) (xy 29.665767 -373.234178) (xy 29.627818 -373.178595) (xy 29.596784 -373.118875)
			(xy 29.57311 -373.055874) (xy 29.557136 -372.990496) (xy 29.549089 -372.923677) (xy 29.549086 -372.856375)
			(xy 29.557127 -372.789555) (xy 29.573095 -372.724175) (xy 29.596763 -372.661172) (xy 29.627792 -372.601449)
			(xy 29.665735 -372.545863) (xy 29.68752 -372.52021) (xy 29.69334 -372.513081) (xy 29.69984 -372.495878)
			(xy 29.70022 -372.486682) (xy 29.70022 -371.993414) (xy 29.699798 -371.984228) (xy 29.693292 -371.967044)
			(xy 29.68752 -371.959886) (xy 29.665695 -371.934264) (xy 29.627749 -371.878673) (xy 29.596718 -371.818945)
			(xy 29.573049 -371.755937) (xy 29.557079 -371.690551) (xy 29.549038 -371.623725) (xy 28.446931 -371.623725)
			(xy 28.44706 -371.624067) (xy 28.463096 -371.689558) (xy 28.471171 -371.756498) (xy 28.471169 -371.823923)
			(xy 28.463092 -371.890863) (xy 28.447054 -371.956353) (xy 28.423287 -372.01945) (xy 28.392134 -372.079247)
			(xy 28.354042 -372.134881) (xy 28.332176 -372.160546) (xy 28.326375 -372.167688) (xy 28.319864 -372.184881)
			(xy 28.319476 -372.194074) (xy 28.319476 -372.351554) (xy 28.318936 -372.361676) (xy 28.311226 -372.380393)
			(xy 28.296956 -372.39475) (xy 28.278287 -372.402574) (xy 28.268168 -372.403116) (xy 27.551888 -372.403116)
			(xy 27.541781 -372.402625) (xy 27.523105 -372.394886) (xy 27.508811 -372.380591) (xy 27.501074 -372.361916)
			(xy 27.50058 -372.351808) (xy 27.50058 -372.194074) (xy 27.500187 -372.184885) (xy 27.493662 -372.167701)
			(xy 27.48788 -372.160546) (xy 27.46603 -372.134869) (xy 27.427943 -372.079236) (xy 27.396792 -372.019441)
			(xy 27.373028 -371.956346) (xy 27.356993 -371.890858) (xy 27.348916 -371.823922) (xy 27.348915 -371.756499)
			(xy 27.356989 -371.689562) (xy 27.373022 -371.624074) (xy 27.396784 -371.560978) (xy 27.427932 -371.501182)
			(xy 27.466018 -371.445548) (xy 27.48788 -371.419882) (xy 27.493664 -371.412728) (xy 27.500187 -371.395544)
			(xy 27.50058 -371.386354) (xy 27.50058 -370.893848) (xy 27.500151 -370.884663) (xy 27.493651 -370.867478)
			(xy 27.48788 -370.86032) (xy 27.466005 -370.834664) (xy 27.427918 -370.779028) (xy 27.396769 -370.71923)
			(xy 27.373006 -370.656132) (xy 27.356972 -370.590642) (xy 27.348898 -370.523703) (xy 0.508 -370.523703)
			(xy 0.508 -372.100847) (xy 8.642336 -372.100847) (xy 8.642336 -372.040913) (xy 8.650159 -371.981491)
			(xy 8.665671 -371.923598) (xy 8.688607 -371.868226) (xy 8.718575 -371.81632) (xy 8.755061 -371.768771)
			(xy 8.797441 -371.726391) (xy 8.84499 -371.689905) (xy 8.896896 -371.659937) (xy 8.952268 -371.637001)
			(xy 9.010161 -371.621489) (xy 9.069583 -371.613666) (xy 9.09955 -371.613176) (xy 9.96315 -371.613176)
			(xy 9.993118 -371.613658) (xy 10.052541 -371.621481) (xy 10.110435 -371.636994) (xy 10.165808 -371.65993)
			(xy 10.217714 -371.689898) (xy 10.265264 -371.726385) (xy 10.307645 -371.768766) (xy 10.344132 -371.816316)
			(xy 10.3741 -371.868222) (xy 10.397036 -371.923595) (xy 10.412549 -371.981489) (xy 10.420372 -372.040912)
			(xy 10.420372 -372.100848) (xy 10.412549 -372.160271) (xy 10.397036 -372.218165) (xy 10.3741 -372.273538)
			(xy 10.344132 -372.325444) (xy 10.307645 -372.372994) (xy 10.265264 -372.415375) (xy 10.217714 -372.451862)
			(xy 10.165808 -372.48183) (xy 10.110435 -372.504766) (xy 10.052541 -372.520279) (xy 9.993118 -372.528102)
			(xy 9.96315 -372.528592) (xy 9.09955 -372.528592) (xy 9.069583 -372.528094) (xy 9.010161 -372.520271)
			(xy 8.952268 -372.504759) (xy 8.896896 -372.481823) (xy 8.84499 -372.451855) (xy 8.797441 -372.415369)
			(xy 8.755061 -372.372989) (xy 8.718575 -372.32544) (xy 8.688607 -372.273534) (xy 8.665671 -372.218162)
			(xy 8.650159 -372.160269) (xy 8.642336 -372.100847) (xy 0.508 -372.100847) (xy 0.508 -374.423871)
			(xy 27.348897 -374.423871) (xy 27.348897 -374.356446) (xy 27.356974 -374.289508) (xy 27.37301 -374.224019)
			(xy 27.396774 -374.160922) (xy 27.427926 -374.101125) (xy 27.466016 -374.045491) (xy 27.48788 -374.019826)
			(xy 27.493688 -374.012689) (xy 27.500197 -373.995492) (xy 27.50058 -373.986298) (xy 27.50058 -373.828818)
			(xy 27.501042 -373.818688) (xy 27.508772 -373.799959) (xy 27.523066 -373.785601) (xy 27.54176 -373.777788)
			(xy 27.551888 -373.777256) (xy 28.268168 -373.777256) (xy 28.278269 -373.77781) (xy 28.296938 -373.785529)
			(xy 28.311233 -373.799804) (xy 28.318977 -373.818463) (xy 28.319476 -373.828564) (xy 28.319476 -373.986298)
			(xy 28.319892 -373.995484) (xy 28.326402 -374.012669) (xy 28.332176 -374.019826) (xy 28.354038 -374.045493)
			(xy 28.392127 -374.101127) (xy 28.423278 -374.160923) (xy 28.447043 -374.22402) (xy 28.463078 -374.289509)
			(xy 28.471154 -374.356447) (xy 28.471155 -374.423823) (xy 31.749171 -374.423823) (xy 31.749175 -374.356514)
			(xy 31.757224 -374.289688) (xy 31.773202 -374.224303) (xy 31.796881 -374.161297) (xy 31.827921 -374.101572)
			(xy 31.865877 -374.045986) (xy 31.887668 -374.020334) (xy 31.893483 -374.013202) (xy 31.899985 -373.996001)
			(xy 31.900368 -373.986806) (xy 31.900368 -373.828818) (xy 31.900779 -373.818644) (xy 31.908564 -373.799844)
			(xy 31.922954 -373.785457) (xy 31.941756 -373.777677) (xy 31.95193 -373.777256) (xy 32.66821 -373.777256)
			(xy 32.678384 -373.777656) (xy 32.697183 -373.785448) (xy 32.711568 -373.799841) (xy 32.719349 -373.818643)
			(xy 32.719772 -373.828818) (xy 32.719772 -373.986806) (xy 32.720185 -373.995993) (xy 32.726697 -374.013177)
			(xy 32.732472 -374.020334) (xy 32.754218 -374.04602) (xy 32.792167 -374.101602) (xy 32.823202 -374.161321)
			(xy 32.846876 -374.224321) (xy 32.862852 -374.289699) (xy 32.870899 -374.356518) (xy 32.870903 -374.423819)
			(xy 32.870895 -374.423882) (xy 36.148964 -374.423882) (xy 36.148968 -374.356455) (xy 36.157048 -374.289515)
			(xy 36.173087 -374.224024) (xy 36.196854 -374.160925) (xy 36.228007 -374.101128) (xy 36.266099 -374.045492)
			(xy 36.287964 -374.019826) (xy 36.293782 -374.012697) (xy 36.300282 -373.995494) (xy 36.300664 -373.986298)
			(xy 36.300664 -373.828818) (xy 36.301142 -373.818689) (xy 36.308868 -373.799964) (xy 36.323158 -373.785606)
			(xy 36.341846 -373.777791) (xy 36.351972 -373.777256) (xy 37.068252 -373.777256) (xy 37.078398 -373.77776)
			(xy 37.09714 -373.785532) (xy 37.111464 -373.799903) (xy 37.119173 -373.818671) (xy 37.11956 -373.828818)
			(xy 37.11956 -373.986298) (xy 37.11998 -373.995484) (xy 37.126488 -374.012668) (xy 37.13226 -374.019826)
			(xy 37.154084 -374.045525) (xy 37.192177 -374.101153) (xy 37.223331 -374.160945) (xy 37.2471 -374.224037)
			(xy 37.263139 -374.289523) (xy 37.271219 -374.356458) (xy 37.271223 -374.423879) (xy 37.271223 -374.423882)
			(xy 40.548731 -374.423882) (xy 40.548735 -374.356454) (xy 40.556815 -374.289512) (xy 40.572857 -374.22402)
			(xy 40.596628 -374.160921) (xy 40.627787 -374.101124) (xy 40.665884 -374.04549) (xy 40.687752 -374.019826)
			(xy 40.693569 -374.012695) (xy 40.70007 -373.995494) (xy 40.700452 -373.986298) (xy 40.700452 -373.828818)
			(xy 40.700942 -373.818691) (xy 40.708666 -373.799968) (xy 40.722951 -373.785611) (xy 40.741636 -373.777793)
			(xy 40.75176 -373.777256) (xy 41.46804 -373.777256) (xy 41.478191 -373.777688) (xy 41.496936 -373.785489)
			(xy 41.511256 -373.799881) (xy 41.518963 -373.818665) (xy 41.519348 -373.828818) (xy 41.519348 -373.986298)
			(xy 41.519771 -373.995484) (xy 41.526277 -374.012667) (xy 41.532048 -374.019826) (xy 41.553873 -374.045524)
			(xy 41.591966 -374.101153) (xy 41.623121 -374.160944) (xy 41.64689 -374.224037) (xy 41.66293 -374.289522)
			(xy 41.67101 -374.356458) (xy 41.671014 -374.423823) (xy 44.94905 -374.423823) (xy 44.949054 -374.356514)
			(xy 44.957102 -374.289689) (xy 44.97308 -374.224304) (xy 44.996757 -374.161298) (xy 45.027796 -374.101573)
			(xy 45.06575 -374.045986) (xy 45.08754 -374.020334) (xy 45.093352 -374.0132) (xy 45.099857 -373.996001)
			(xy 45.10024 -373.986806) (xy 45.10024 -373.828818) (xy 45.100678 -373.818647) (xy 45.108458 -373.799853)
			(xy 45.122839 -373.785467) (xy 45.141631 -373.777682) (xy 45.151802 -373.777256) (xy 45.868082 -373.777256)
			(xy 45.878255 -373.777679) (xy 45.897053 -373.785461) (xy 45.911439 -373.799847) (xy 45.919221 -373.818645)
			(xy 45.919644 -373.828818) (xy 45.919644 -373.986806) (xy 45.920064 -373.995992) (xy 45.926572 -374.013176)
			(xy 45.932344 -374.020334) (xy 45.954091 -374.04602) (xy 45.992042 -374.101601) (xy 46.023078 -374.16132)
			(xy 46.046754 -374.22432) (xy 46.06273 -374.289698) (xy 46.070778 -374.356517) (xy 46.070782 -374.423819)
			(xy 46.070774 -374.423882) (xy 71.348786 -374.423882) (xy 71.348789 -374.356455) (xy 71.356869 -374.289514)
			(xy 71.372909 -374.224023) (xy 71.396677 -374.160924) (xy 71.427833 -374.101127) (xy 71.465926 -374.045491)
			(xy 71.487792 -374.019826) (xy 71.493602 -374.01269) (xy 71.500109 -373.995492) (xy 71.500492 -373.986298)
			(xy 71.500492 -373.828818) (xy 71.50104 -373.818698) (xy 71.508753 -373.799987) (xy 71.52302 -373.785631)
			(xy 71.541684 -373.777803) (xy 71.5518 -373.777256) (xy 72.26808 -373.777256) (xy 72.278227 -373.777737)
			(xy 72.296971 -373.785518) (xy 72.311293 -373.799896) (xy 72.319002 -373.818669) (xy 72.319388 -373.828818)
			(xy 72.319388 -373.986298) (xy 72.319802 -373.995485) (xy 72.326313 -374.012669) (xy 72.332088 -374.019826)
			(xy 72.353911 -374.045525) (xy 72.392002 -374.101154) (xy 72.423155 -374.160946) (xy 72.446922 -374.224038)
			(xy 72.462961 -374.289523) (xy 72.47104 -374.356458) (xy 72.471044 -374.423823) (xy 75.749081 -374.423823)
			(xy 75.749084 -374.356514) (xy 75.757133 -374.289688) (xy 75.773112 -374.224303) (xy 75.796791 -374.161296)
			(xy 75.827832 -374.101572) (xy 75.865788 -374.045985) (xy 75.88758 -374.020334) (xy 75.893385 -374.013194)
			(xy 75.899895 -373.996) (xy 75.90028 -373.986806) (xy 75.90028 -373.828818) (xy 75.900679 -373.818642)
			(xy 75.908466 -373.79984) (xy 75.92286 -373.785453) (xy 75.941666 -373.777675) (xy 75.951842 -373.777256)
			(xy 76.668122 -373.777256) (xy 76.678283 -373.777716) (xy 76.697057 -373.785501) (xy 76.711422 -373.799877)
			(xy 76.719192 -373.818656) (xy 76.719684 -373.828818) (xy 76.719684 -373.986806) (xy 76.720095 -373.995993)
			(xy 76.726608 -374.013177) (xy 76.732384 -374.020334) (xy 76.754129 -374.046021) (xy 76.792078 -374.101603)
			(xy 76.823112 -374.161322) (xy 76.846786 -374.224322) (xy 76.862761 -374.289699) (xy 76.870808 -374.356518)
			(xy 76.870812 -374.423819) (xy 76.870804 -374.423882) (xy 80.148873 -374.423882) (xy 80.148877 -374.356455)
			(xy 80.156957 -374.289515) (xy 80.172996 -374.224023) (xy 80.196764 -374.160925) (xy 80.227918 -374.101127)
			(xy 80.26601 -374.045492) (xy 80.287876 -374.019826) (xy 80.293684 -374.012689) (xy 80.300193 -373.995492)
			(xy 80.300576 -373.986298) (xy 80.300576 -373.828818) (xy 80.301042 -373.818688) (xy 80.308771 -373.79996)
			(xy 80.323064 -373.785602) (xy 80.341756 -373.777789) (xy 80.351884 -373.777256) (xy 81.068164 -373.777256)
			(xy 81.078265 -373.777814) (xy 81.096934 -373.785531) (xy 81.111228 -373.799806) (xy 81.118972 -373.818464)
			(xy 81.119472 -373.828564) (xy 81.119472 -373.986298) (xy 81.119889 -373.995484) (xy 81.126399 -374.012668)
			(xy 81.132172 -374.019826) (xy 81.153996 -374.045525) (xy 81.192087 -374.101154) (xy 81.223242 -374.160945)
			(xy 81.247009 -374.224038) (xy 81.263049 -374.289523) (xy 81.271128 -374.356458) (xy 81.271132 -374.423879)
			(xy 81.271132 -374.423882) (xy 84.548664 -374.423882) (xy 84.548668 -374.356455) (xy 84.556748 -374.289515)
			(xy 84.572787 -374.224024) (xy 84.596554 -374.160925) (xy 84.627707 -374.101128) (xy 84.665799 -374.045492)
			(xy 84.687664 -374.019826) (xy 84.693482 -374.012697) (xy 84.699982 -373.995494) (xy 84.700364 -373.986298)
			(xy 84.700364 -373.828818) (xy 84.700842 -373.818689) (xy 84.708568 -373.799964) (xy 84.722858 -373.785606)
			(xy 84.741546 -373.777791) (xy 84.751672 -373.777256) (xy 85.467952 -373.777256) (xy 85.478066 -373.777754)
			(xy 85.49676 -373.785478) (xy 85.511074 -373.799769) (xy 85.518829 -373.818451) (xy 85.51926 -373.828564)
			(xy 85.51926 -373.986298) (xy 85.51968 -373.995484) (xy 85.526188 -374.012668) (xy 85.53196 -374.019826)
			(xy 85.553784 -374.045525) (xy 85.591877 -374.101153) (xy 85.623031 -374.160945) (xy 85.6468 -374.224037)
			(xy 85.662839 -374.289523) (xy 85.670919 -374.356458) (xy 85.670923 -374.423822) (xy 115.349223 -374.423822)
			(xy 115.349227 -374.356515) (xy 115.357275 -374.28969) (xy 115.373251 -374.224306) (xy 115.396927 -374.1613)
			(xy 115.427963 -374.101574) (xy 115.465915 -374.045987) (xy 115.487704 -374.020334) (xy 115.493512 -374.013197)
			(xy 115.50002 -373.996) (xy 115.500404 -373.986806) (xy 115.500404 -373.828818) (xy 115.500947 -373.818666)
			(xy 115.508709 -373.799903) (xy 115.52306 -373.785539) (xy 115.541814 -373.777757) (xy 115.551966 -373.777256)
			(xy 116.268246 -373.777256) (xy 116.278409 -373.777696) (xy 116.297183 -373.785489) (xy 116.311547 -373.799871)
			(xy 116.319316 -373.818654) (xy 116.319808 -373.828818) (xy 116.319808 -373.986806) (xy 116.320214 -373.995994)
			(xy 116.32673 -374.013178) (xy 116.332508 -374.020334) (xy 116.354256 -374.046019) (xy 116.39221 -374.1016)
			(xy 116.423248 -374.161318) (xy 116.446925 -374.224319) (xy 116.462903 -374.289697) (xy 116.470951 -374.356517)
			(xy 116.470955 -374.42382) (xy 116.470948 -374.423882) (xy 119.748992 -374.423882) (xy 119.748995 -374.356455)
			(xy 119.757075 -374.289514) (xy 119.773115 -374.224022) (xy 119.796884 -374.160924) (xy 119.82804 -374.101126)
			(xy 119.866134 -374.045491) (xy 119.888 -374.019826) (xy 119.89381 -374.012691) (xy 119.900317 -373.995493)
			(xy 119.9007 -373.986298) (xy 119.9007 -373.828818) (xy 119.90124 -373.818697) (xy 119.908955 -373.799984)
			(xy 119.923224 -373.785629) (xy 119.94189 -373.777802) (xy 119.952008 -373.777256) (xy 120.668288 -373.777256)
			(xy 120.678436 -373.777731) (xy 120.69718 -373.785514) (xy 120.711502 -373.799894) (xy 120.71921 -373.818669)
			(xy 120.719596 -373.828818) (xy 120.719596 -373.986298) (xy 120.720008 -373.995485) (xy 120.726521 -374.012669)
			(xy 120.732296 -374.019826) (xy 120.754119 -374.045525) (xy 120.792209 -374.101155) (xy 120.823362 -374.160946)
			(xy 120.847129 -374.224039) (xy 120.863167 -374.289524) (xy 120.871246 -374.356458) (xy 120.87125 -374.423823)
			(xy 124.149287 -374.423823) (xy 124.149291 -374.356514) (xy 124.15734 -374.289688) (xy 124.173319 -374.224302)
			(xy 124.196998 -374.161296) (xy 124.228039 -374.101572) (xy 124.265996 -374.045986) (xy 124.287788 -374.020334)
			(xy 124.293594 -374.013195) (xy 124.300103 -373.996) (xy 124.300488 -373.986806) (xy 124.300488 -373.828818)
			(xy 124.30088 -373.818641) (xy 124.308668 -373.799837) (xy 124.323064 -373.78545) (xy 124.341873 -373.777673)
			(xy 124.35205 -373.777256) (xy 125.06833 -373.777256) (xy 125.078492 -373.777709) (xy 125.097265 -373.785497)
			(xy 125.11163 -373.799875) (xy 125.1194 -373.818656) (xy 125.119892 -373.828818) (xy 125.119892 -373.986806)
			(xy 125.120301 -373.995993) (xy 125.126816 -374.013177) (xy 125.132592 -374.020334) (xy 125.154338 -374.04602)
			(xy 125.192286 -374.101603) (xy 125.223319 -374.161322) (xy 125.246993 -374.224322) (xy 125.262968 -374.2897)
			(xy 125.271015 -374.356518) (xy 125.271019 -374.423819) (xy 125.271019 -374.423823) (xy 128.549078 -374.423823)
			(xy 128.549081 -374.356514) (xy 128.55713 -374.289688) (xy 128.573109 -374.224303) (xy 128.596788 -374.161296)
			(xy 128.627828 -374.101572) (xy 128.665784 -374.045985) (xy 128.687576 -374.020334) (xy 128.69338 -374.013194)
			(xy 128.699891 -373.996) (xy 128.700276 -373.986806) (xy 128.700276 -373.828818) (xy 128.700679 -373.818643)
			(xy 128.708465 -373.799841) (xy 128.722858 -373.785454) (xy 128.741663 -373.777675) (xy 128.751838 -373.777256)
			(xy 129.468118 -373.777256) (xy 129.478279 -373.777719) (xy 129.497052 -373.785503) (xy 129.511418 -373.799878)
			(xy 129.519188 -373.818656) (xy 129.51968 -373.828818) (xy 129.51968 -373.986806) (xy 129.520092 -373.995993)
			(xy 129.526605 -374.013177) (xy 129.53238 -374.020334) (xy 129.554126 -374.046021) (xy 129.592074 -374.101603)
			(xy 129.623108 -374.161322) (xy 129.646783 -374.224321) (xy 129.662758 -374.289699) (xy 129.670805 -374.356518)
			(xy 129.670809 -374.423819) (xy 129.670809 -374.423822) (xy 159.349132 -374.423822) (xy 159.349136 -374.356514)
			(xy 159.357184 -374.289689) (xy 159.373161 -374.224305) (xy 159.396837 -374.161299) (xy 159.427874 -374.101574)
			(xy 159.465826 -374.045986) (xy 159.487616 -374.020334) (xy 159.493425 -374.013198) (xy 159.499932 -373.996)
			(xy 159.500316 -373.986806) (xy 159.500316 -373.828818) (xy 159.500847 -373.818664) (xy 159.508612 -373.799899)
			(xy 159.522966 -373.785534) (xy 159.541724 -373.777755) (xy 159.551878 -373.777256) (xy 160.268158 -373.777256)
			(xy 160.278329 -373.777699) (xy 160.297126 -373.785473) (xy 160.311513 -373.799854) (xy 160.319297 -373.818647)
			(xy 160.31972 -373.828818) (xy 160.31972 -373.986806) (xy 160.320123 -373.995994) (xy 160.326641 -374.013179)
			(xy 160.33242 -374.020334) (xy 160.354168 -374.04602) (xy 160.39212 -374.1016) (xy 160.423158 -374.161319)
			(xy 160.446835 -374.224319) (xy 160.462812 -374.289698) (xy 160.47086 -374.356517) (xy 160.470864 -374.42382)
			(xy 160.470857 -374.423882) (xy 163.748901 -374.423882) (xy 163.748904 -374.356455) (xy 163.756985 -374.289514)
			(xy 163.773025 -374.224022) (xy 163.796794 -374.160923) (xy 163.827951 -374.101126) (xy 163.866045 -374.045491)
			(xy 163.887912 -374.019826) (xy 163.893724 -374.012692) (xy 163.900229 -373.995493) (xy 163.900612 -373.986298)
			(xy 163.900612 -373.828818) (xy 163.90114 -373.818696) (xy 163.908857 -373.79998) (xy 163.92313 -373.785624)
			(xy 163.941801 -373.7778) (xy 163.95192 -373.777256) (xy 164.6682 -373.777256) (xy 164.678349 -373.777721)
			(xy 164.697092 -373.785508) (xy 164.711414 -373.799891) (xy 164.719122 -373.818668) (xy 164.719508 -373.828818)
			(xy 164.719508 -373.986298) (xy 164.719917 -373.995485) (xy 164.726431 -374.01267) (xy 164.732208 -374.019826)
			(xy 164.75403 -374.045525) (xy 164.79212 -374.101155) (xy 164.823272 -374.160947) (xy 164.847038 -374.224039)
			(xy 164.863076 -374.289524) (xy 164.871155 -374.356458) (xy 164.871159 -374.423822) (xy 168.14922 -374.423822)
			(xy 168.149224 -374.356515) (xy 168.157272 -374.28969) (xy 168.173248 -374.224306) (xy 168.196924 -374.1613)
			(xy 168.22796 -374.101575) (xy 168.265911 -374.045987) (xy 168.2877 -374.020334) (xy 168.293507 -374.013196)
			(xy 168.300015 -373.996) (xy 168.3004 -373.986806) (xy 168.3004 -373.828818) (xy 168.300947 -373.818666)
			(xy 168.308709 -373.799905) (xy 168.323058 -373.78554) (xy 168.341811 -373.777758) (xy 168.351962 -373.777256)
			(xy 169.068242 -373.777256) (xy 169.078405 -373.777699) (xy 169.097178 -373.785491) (xy 169.111543 -373.799872)
			(xy 169.119312 -373.818655) (xy 169.119804 -373.828818) (xy 169.119804 -373.986806) (xy 169.120211 -373.995994)
			(xy 169.126727 -374.013178) (xy 169.132504 -374.020334) (xy 169.154249 -374.046021) (xy 169.192196 -374.101603)
			(xy 169.223229 -374.161322) (xy 169.246902 -374.224322) (xy 169.262877 -374.2897) (xy 169.270924 -374.356518)
			(xy 169.270928 -374.423819) (xy 169.270928 -374.423823) (xy 172.548987 -374.423823) (xy 172.548991 -374.356514)
			(xy 172.55704 -374.289688) (xy 172.573019 -374.224302) (xy 172.596698 -374.161296) (xy 172.627739 -374.101572)
			(xy 172.665696 -374.045986) (xy 172.687488 -374.020334) (xy 172.693294 -374.013195) (xy 172.699803 -373.996)
			(xy 172.700188 -373.986806) (xy 172.700188 -373.828818) (xy 172.70058 -373.818641) (xy 172.708368 -373.799837)
			(xy 172.722764 -373.78545) (xy 172.741573 -373.777673) (xy 172.75175 -373.777256) (xy 173.46803 -373.777256)
			(xy 173.478192 -373.777709) (xy 173.496965 -373.785497) (xy 173.51133 -373.799875) (xy 173.5191 -373.818656)
			(xy 173.519592 -373.828818) (xy 173.519592 -373.986806) (xy 173.520001 -373.995993) (xy 173.526516 -374.013177)
			(xy 173.532292 -374.020334) (xy 173.554038 -374.04602) (xy 173.591986 -374.101603) (xy 173.623019 -374.161322)
			(xy 173.646693 -374.224322) (xy 173.662668 -374.2897) (xy 173.670715 -374.356518) (xy 173.670719 -374.423819)
			(xy 173.662679 -374.490638) (xy 173.646712 -374.556018) (xy 173.623045 -374.61902) (xy 173.592018 -374.678743)
			(xy 173.554076 -374.73433) (xy 173.532292 -374.759982) (xy 173.526477 -374.767114) (xy 173.519974 -374.784315)
			(xy 173.519592 -374.79351) (xy 173.519592 -375.286778) (xy 173.520015 -375.295964) (xy 173.52652 -375.313148)
			(xy 173.532292 -375.320306) (xy 173.554108 -375.345934) (xy 173.592054 -375.401525) (xy 173.623084 -375.461252)
			(xy 173.646754 -375.52426) (xy 173.662724 -375.589644) (xy 173.670765 -375.656469) (xy 173.670763 -375.723776)
			(xy 173.662716 -375.7906) (xy 173.646741 -375.855984) (xy 173.623066 -375.918989) (xy 173.592031 -375.978714)
			(xy 173.554081 -376.034301) (xy 173.532292 -376.059954) (xy 173.526489 -376.067095) (xy 173.519978 -376.084289)
			(xy 173.519592 -376.093482) (xy 173.519592 -376.25147) (xy 173.519043 -376.261622) (xy 173.511284 -376.280385)
			(xy 173.496935 -376.29475) (xy 173.478182 -376.302531) (xy 173.46803 -376.303032) (xy 172.75175 -376.303032)
			(xy 172.741578 -376.302595) (xy 172.722779 -376.29482) (xy 172.708391 -376.280438) (xy 172.700609 -376.261642)
			(xy 172.700188 -376.25147) (xy 172.700188 -376.093482) (xy 172.699789 -376.084294) (xy 172.693268 -376.067109)
			(xy 172.687488 -376.059954) (xy 172.665728 -376.034278) (xy 172.627775 -375.978696) (xy 172.596738 -375.918976)
			(xy 172.573061 -375.855975) (xy 172.557085 -375.790595) (xy 172.549038 -375.723774) (xy 172.549035 -375.656471)
			(xy 172.557077 -375.589649) (xy 172.573048 -375.524268) (xy 172.59672 -375.461265) (xy 172.627752 -375.401542)
			(xy 172.665701 -375.345957) (xy 172.687488 -375.320306) (xy 172.693263 -375.313145) (xy 172.699791 -375.295967)
			(xy 172.700188 -375.286778) (xy 172.700188 -374.79351) (xy 172.699776 -374.784323) (xy 172.693264 -374.767138)
			(xy 172.687488 -374.759982) (xy 172.665658 -374.734364) (xy 172.627707 -374.678774) (xy 172.596673 -374.619046)
			(xy 172.573 -374.556037) (xy 172.557029 -374.49065) (xy 172.548987 -374.423823) (xy 169.270928 -374.423823)
			(xy 169.262888 -374.490638) (xy 169.246921 -374.556017) (xy 169.223255 -374.61902) (xy 169.192229 -374.678743)
			(xy 169.154288 -374.734329) (xy 169.132504 -374.759982) (xy 169.126691 -374.767115) (xy 169.120186 -374.784315)
			(xy 169.119804 -374.79351) (xy 169.119804 -375.286778) (xy 169.120224 -375.295964) (xy 169.126731 -375.313149)
			(xy 169.132504 -375.320306) (xy 169.15432 -375.345935) (xy 169.192265 -375.401525) (xy 169.223295 -375.461253)
			(xy 169.246964 -375.52426) (xy 169.262933 -375.589645) (xy 169.270974 -375.656469) (xy 169.270972 -375.723776)
			(xy 169.262925 -375.7906) (xy 169.24695 -375.855983) (xy 169.223276 -375.918989) (xy 169.192242 -375.978713)
			(xy 169.154292 -376.034301) (xy 169.132504 -376.059954) (xy 169.126702 -376.067096) (xy 169.120191 -376.084289)
			(xy 169.119804 -376.093482) (xy 169.119804 -376.25147) (xy 169.119243 -376.261621) (xy 169.111487 -376.280381)
			(xy 169.097142 -376.294746) (xy 169.078392 -376.302529) (xy 169.068242 -376.303032) (xy 168.351962 -376.303032)
			(xy 168.341798 -376.302597) (xy 168.323022 -376.294804) (xy 168.308657 -376.280421) (xy 168.30089 -376.261635)
			(xy 168.3004 -376.25147) (xy 168.3004 -376.093482) (xy 168.299998 -376.084294) (xy 168.293479 -376.06711)
			(xy 168.2877 -376.059954) (xy 168.265943 -376.034277) (xy 168.227996 -375.978693) (xy 168.196963 -375.918973)
			(xy 168.173291 -375.855972) (xy 168.157317 -375.790593) (xy 168.149271 -375.723774) (xy 168.149268 -375.656472)
			(xy 168.157309 -375.589652) (xy 168.173277 -375.524272) (xy 168.196945 -375.461269) (xy 168.227973 -375.401546)
			(xy 168.265915 -375.345959) (xy 168.2877 -375.320306) (xy 168.293477 -375.313147) (xy 168.300003 -375.295967)
			(xy 168.3004 -375.286778) (xy 168.3004 -374.79351) (xy 168.299985 -374.784323) (xy 168.293475 -374.767139)
			(xy 168.2877 -374.759982) (xy 168.265872 -374.734363) (xy 168.227927 -374.678771) (xy 168.196898 -374.619043)
			(xy 168.173229 -374.556034) (xy 168.15726 -374.490648) (xy 168.14922 -374.423822) (xy 164.871159 -374.423822)
			(xy 164.871159 -374.423879) (xy 164.863088 -374.490814) (xy 164.847057 -374.5563) (xy 164.823298 -374.619396)
			(xy 164.792152 -374.679191) (xy 164.754069 -374.734825) (xy 164.732208 -374.76049) (xy 164.726392 -374.767621)
			(xy 164.719889 -374.784822) (xy 164.719508 -374.794018) (xy 164.719508 -375.28627) (xy 164.719931 -375.295456)
			(xy 164.726435 -375.31264) (xy 164.732208 -375.319798) (xy 164.754101 -375.345439) (xy 164.792188 -375.401077)
			(xy 164.823337 -375.460877) (xy 164.8471 -375.523977) (xy 164.863133 -375.589469) (xy 164.871206 -375.65641)
			(xy 164.871203 -375.723835) (xy 164.863125 -375.790776) (xy 164.847086 -375.856266) (xy 164.823319 -375.919364)
			(xy 164.792165 -375.979161) (xy 164.754073 -376.034797) (xy 164.732208 -376.060462) (xy 164.726404 -376.067602)
			(xy 164.719893 -376.084796) (xy 164.719508 -376.09399) (xy 164.719508 -376.25147) (xy 164.71895 -376.261589)
			(xy 164.711241 -376.2803) (xy 164.696977 -376.294656) (xy 164.678316 -376.302485) (xy 164.6682 -376.303032)
			(xy 163.95192 -376.303032) (xy 163.941771 -376.302563) (xy 163.923025 -376.29478) (xy 163.908702 -376.280398)
			(xy 163.900996 -376.26162) (xy 163.900612 -376.25147) (xy 163.900612 -376.09399) (xy 163.900204 -376.084803)
			(xy 163.893689 -376.067618) (xy 163.887912 -376.060462) (xy 163.866077 -376.034773) (xy 163.827987 -375.979142)
			(xy 163.796834 -375.919349) (xy 163.773068 -375.856255) (xy 163.75703 -375.790769) (xy 163.748951 -375.723833)
			(xy 163.748949 -375.656412) (xy 163.757022 -375.589475) (xy 163.773054 -375.523988) (xy 163.796816 -375.460892)
			(xy 163.827963 -375.401097) (xy 163.866049 -375.345463) (xy 163.887912 -375.319798) (xy 163.893693 -375.312642)
			(xy 163.900217 -375.29546) (xy 163.900612 -375.28627) (xy 163.900612 -374.794018) (xy 163.90019 -374.784832)
			(xy 163.893684 -374.767648) (xy 163.887912 -374.76049) (xy 163.866006 -374.734859) (xy 163.827918 -374.67922)
			(xy 163.796769 -374.619419) (xy 163.773006 -374.556318) (xy 163.756973 -374.490824) (xy 163.748901 -374.423882)
			(xy 160.470857 -374.423882) (xy 160.462823 -374.49064) (xy 160.446853 -374.556021) (xy 160.423184 -374.619023)
			(xy 160.392153 -374.678745) (xy 160.354206 -374.73433) (xy 160.33242 -374.759982) (xy 160.326608 -374.767117)
			(xy 160.320102 -374.784315) (xy 160.31972 -374.79351) (xy 160.31972 -375.286778) (xy 160.320136 -375.295965)
			(xy 160.326645 -375.313149) (xy 160.33242 -375.320306) (xy 160.354238 -375.345933) (xy 160.392189 -375.401522)
			(xy 160.423223 -375.461249) (xy 160.446896 -375.524257) (xy 160.462868 -375.589643) (xy 160.470911 -375.656468)
			(xy 160.470908 -375.723777) (xy 160.46286 -375.790602) (xy 160.446883 -375.855986) (xy 160.423205 -375.918992)
			(xy 160.392166 -375.978716) (xy 160.354211 -376.034302) (xy 160.33242 -376.059954) (xy 160.32662 -376.067097)
			(xy 160.320107 -376.084289) (xy 160.31972 -376.093482) (xy 160.31972 -376.25147) (xy 160.31931 -376.261645)
			(xy 160.311528 -376.280447) (xy 160.297137 -376.294834) (xy 160.278333 -376.302613) (xy 160.268158 -376.303032)
			(xy 159.551878 -376.303032) (xy 159.541701 -376.302653) (xy 159.5229 -376.294855) (xy 159.508515 -376.280456)
			(xy 159.500737 -376.261647) (xy 159.500316 -376.25147) (xy 159.500316 -376.093482) (xy 159.499911 -376.084294)
			(xy 159.493393 -376.06711) (xy 159.487616 -376.059954) (xy 159.465858 -376.034277) (xy 159.42791 -375.978694)
			(xy 159.396877 -375.918973) (xy 159.373203 -375.855972) (xy 159.357229 -375.790593) (xy 159.349183 -375.723774)
			(xy 159.34918 -375.656471) (xy 159.357221 -375.589651) (xy 159.37319 -375.524271) (xy 159.396858 -375.461268)
			(xy 159.427887 -375.401545) (xy 159.465831 -375.345958) (xy 159.487616 -375.320306) (xy 159.493394 -375.313148)
			(xy 159.499919 -375.295967) (xy 159.500316 -375.286778) (xy 159.500316 -374.79351) (xy 159.499897 -374.784324)
			(xy 159.493389 -374.76714) (xy 159.487616 -374.759982) (xy 159.465788 -374.734364) (xy 159.427842 -374.678772)
			(xy 159.396811 -374.619043) (xy 159.373142 -374.556034) (xy 159.357173 -374.490648) (xy 159.349132 -374.423822)
			(xy 129.670809 -374.423822) (xy 129.662769 -374.490638) (xy 129.646801 -374.556018) (xy 129.623134 -374.619021)
			(xy 129.592107 -374.678743) (xy 129.554164 -374.734329) (xy 129.53238 -374.759982) (xy 129.526564 -374.767113)
			(xy 129.520062 -374.784315) (xy 129.51968 -374.79351) (xy 129.51968 -375.286778) (xy 129.520105 -375.295963)
			(xy 129.526609 -375.313148) (xy 129.53238 -375.320306) (xy 129.554197 -375.345934) (xy 129.592143 -375.401524)
			(xy 129.623174 -375.461252) (xy 129.646845 -375.524259) (xy 129.662815 -375.589644) (xy 129.670856 -375.656469)
			(xy 129.670854 -375.723776) (xy 129.662807 -375.7906) (xy 129.646831 -375.855984) (xy 129.623156 -375.91899)
			(xy 129.59212 -375.978714) (xy 129.554169 -376.034302) (xy 129.53238 -376.059954) (xy 129.526576 -376.067094)
			(xy 129.520066 -376.084288) (xy 129.51968 -376.093482) (xy 129.51968 -376.25147) (xy 129.519212 -376.261637)
			(xy 129.51144 -376.280428) (xy 129.497068 -376.294813) (xy 129.478285 -376.302602) (xy 129.468118 -376.303032)
			(xy 128.751838 -376.303032) (xy 128.741665 -376.302604) (xy 128.722866 -376.294826) (xy 128.708478 -376.280441)
			(xy 128.700697 -376.261643) (xy 128.700276 -376.25147) (xy 128.700276 -376.093482) (xy 128.69988 -376.084293)
			(xy 128.693357 -376.067109) (xy 128.687576 -376.059954) (xy 128.665817 -376.034278) (xy 128.627865 -375.978696)
			(xy 128.596828 -375.918976) (xy 128.573152 -375.855974) (xy 128.557176 -375.790595) (xy 128.549129 -375.723774)
			(xy 128.549126 -375.656471) (xy 128.557168 -375.58965) (xy 128.573138 -375.524269) (xy 128.59681 -375.461265)
			(xy 128.627841 -375.401543) (xy 128.665789 -375.345958) (xy 128.687576 -375.320306) (xy 128.69335 -375.313144)
			(xy 128.699879 -375.295967) (xy 128.700276 -375.286778) (xy 128.700276 -374.79351) (xy 128.699866 -374.784323)
			(xy 128.693353 -374.767138) (xy 128.687576 -374.759982) (xy 128.665746 -374.734365) (xy 128.627796 -374.678774)
			(xy 128.596762 -374.619046) (xy 128.57309 -374.556037) (xy 128.557119 -374.49065) (xy 128.549078 -374.423823)
			(xy 125.271019 -374.423823) (xy 125.262979 -374.490638) (xy 125.247012 -374.556018) (xy 125.223345 -374.61902)
			(xy 125.192318 -374.678743) (xy 125.154376 -374.73433) (xy 125.132592 -374.759982) (xy 125.126777 -374.767114)
			(xy 125.120274 -374.784315) (xy 125.119892 -374.79351) (xy 125.119892 -375.286778) (xy 125.120315 -375.295964)
			(xy 125.12682 -375.313148) (xy 125.132592 -375.320306) (xy 125.154408 -375.345934) (xy 125.192354 -375.401525)
			(xy 125.223384 -375.461252) (xy 125.247054 -375.52426) (xy 125.263024 -375.589644) (xy 125.271065 -375.656469)
			(xy 125.271063 -375.723776) (xy 125.263016 -375.7906) (xy 125.247041 -375.855984) (xy 125.223366 -375.918989)
			(xy 125.192331 -375.978714) (xy 125.154381 -376.034301) (xy 125.132592 -376.059954) (xy 125.126789 -376.067095)
			(xy 125.120278 -376.084289) (xy 125.119892 -376.093482) (xy 125.119892 -376.25147) (xy 125.119343 -376.261622)
			(xy 125.111584 -376.280385) (xy 125.097235 -376.29475) (xy 125.078482 -376.302531) (xy 125.06833 -376.303032)
			(xy 124.35205 -376.303032) (xy 124.341878 -376.302595) (xy 124.323079 -376.29482) (xy 124.308691 -376.280438)
			(xy 124.300909 -376.261642) (xy 124.300488 -376.25147) (xy 124.300488 -376.093482) (xy 124.300089 -376.084294)
			(xy 124.293568 -376.067109) (xy 124.287788 -376.059954) (xy 124.266028 -376.034278) (xy 124.228075 -375.978696)
			(xy 124.197038 -375.918976) (xy 124.173361 -375.855975) (xy 124.157385 -375.790595) (xy 124.149338 -375.723774)
			(xy 124.149335 -375.656471) (xy 124.157377 -375.589649) (xy 124.173348 -375.524268) (xy 124.19702 -375.461265)
			(xy 124.228052 -375.401542) (xy 124.266001 -375.345957) (xy 124.287788 -375.320306) (xy 124.293563 -375.313145)
			(xy 124.300091 -375.295967) (xy 124.300488 -375.286778) (xy 124.300488 -374.79351) (xy 124.300076 -374.784323)
			(xy 124.293564 -374.767138) (xy 124.287788 -374.759982) (xy 124.265958 -374.734364) (xy 124.228007 -374.678774)
			(xy 124.196973 -374.619046) (xy 124.1733 -374.556037) (xy 124.157329 -374.49065) (xy 124.149287 -374.423823)
			(xy 120.87125 -374.423823) (xy 120.87125 -374.423879) (xy 120.863178 -374.490814) (xy 120.847147 -374.556301)
			(xy 120.823388 -374.619396) (xy 120.792242 -374.679191) (xy 120.754158 -374.734825) (xy 120.732296 -374.76049)
			(xy 120.726478 -374.76762) (xy 120.719976 -374.784822) (xy 120.719596 -374.794018) (xy 120.719596 -375.28627)
			(xy 120.720022 -375.295456) (xy 120.726525 -375.31264) (xy 120.732296 -375.319798) (xy 120.75419 -375.345439)
			(xy 120.792278 -375.401077) (xy 120.823427 -375.460876) (xy 120.84719 -375.523976) (xy 120.863223 -375.589468)
			(xy 120.871297 -375.656409) (xy 120.871294 -375.723836) (xy 120.863215 -375.790776) (xy 120.847177 -375.856267)
			(xy 120.823409 -375.919365) (xy 120.792254 -375.979162) (xy 120.754162 -376.034797) (xy 120.732296 -376.060462)
			(xy 120.72649 -376.067601) (xy 120.719981 -376.084796) (xy 120.719596 -376.09399) (xy 120.719596 -376.25147)
			(xy 120.71905 -376.26159) (xy 120.711339 -376.280304) (xy 120.697071 -376.29466) (xy 120.678405 -376.302487)
			(xy 120.668288 -376.303032) (xy 119.952008 -376.303032) (xy 119.941858 -376.302572) (xy 119.923112 -376.294786)
			(xy 119.90879 -376.280401) (xy 119.901084 -376.261621) (xy 119.9007 -376.25147) (xy 119.9007 -376.09399)
			(xy 119.900294 -376.084802) (xy 119.893777 -376.067618) (xy 119.888 -376.060462) (xy 119.866166 -376.034772)
			(xy 119.828076 -375.979141) (xy 119.796924 -375.919349) (xy 119.773158 -375.856255) (xy 119.75712 -375.790769)
			(xy 119.749042 -375.723833) (xy 119.749039 -375.656412) (xy 119.757112 -375.589476) (xy 119.773145 -375.523988)
			(xy 119.796905 -375.460893) (xy 119.828053 -375.401097) (xy 119.866138 -375.345463) (xy 119.888 -375.319798)
			(xy 119.89378 -375.312641) (xy 119.900305 -375.29546) (xy 119.9007 -375.28627) (xy 119.9007 -374.794018)
			(xy 119.900281 -374.784832) (xy 119.893773 -374.767647) (xy 119.888 -374.76049) (xy 119.866095 -374.734859)
			(xy 119.828007 -374.679219) (xy 119.796858 -374.619418) (xy 119.773097 -374.556317) (xy 119.757064 -374.490824)
			(xy 119.748992 -374.423882) (xy 116.470948 -374.423882) (xy 116.462914 -374.49064) (xy 116.446944 -374.556021)
			(xy 116.423273 -374.619024) (xy 116.392242 -374.678746) (xy 116.354295 -374.734331) (xy 116.332508 -374.759982)
			(xy 116.326695 -374.767116) (xy 116.32019 -374.784315) (xy 116.319808 -374.79351) (xy 116.319808 -375.286778)
			(xy 116.320227 -375.295964) (xy 116.326734 -375.313149) (xy 116.332508 -375.320306) (xy 116.354327 -375.345933)
			(xy 116.392278 -375.401522) (xy 116.423313 -375.461249) (xy 116.446986 -375.524256) (xy 116.462959 -375.589642)
			(xy 116.471001 -375.656468) (xy 116.470999 -375.723777) (xy 116.462951 -375.790602) (xy 116.446973 -375.855987)
			(xy 116.423295 -375.918993) (xy 116.392255 -375.978717) (xy 116.354299 -376.034303) (xy 116.332508 -376.059954)
			(xy 116.326707 -376.067096) (xy 116.320195 -376.084289) (xy 116.319808 -376.093482) (xy 116.319808 -376.25147)
			(xy 116.319243 -376.26162) (xy 116.311487 -376.28038) (xy 116.297144 -376.294745) (xy 116.278395 -376.302528)
			(xy 116.268246 -376.303032) (xy 115.551966 -376.303032) (xy 115.541802 -376.302594) (xy 115.523027 -376.294803)
			(xy 115.508662 -376.28042) (xy 115.500894 -376.261634) (xy 115.500404 -376.25147) (xy 115.500404 -376.093482)
			(xy 115.500002 -376.084294) (xy 115.493483 -376.06711) (xy 115.487704 -376.059954) (xy 115.465947 -376.034277)
			(xy 115.427999 -375.978693) (xy 115.396967 -375.918973) (xy 115.373294 -375.855972) (xy 115.35732 -375.790593)
			(xy 115.349274 -375.723774) (xy 115.349271 -375.656472) (xy 115.357312 -375.589652) (xy 115.37328 -375.524271)
			(xy 115.396948 -375.461268) (xy 115.427976 -375.401545) (xy 115.465919 -375.345959) (xy 115.487704 -375.320306)
			(xy 115.493481 -375.313147) (xy 115.500007 -375.295967) (xy 115.500404 -375.286778) (xy 115.500404 -374.79351)
			(xy 115.499988 -374.784323) (xy 115.493478 -374.767139) (xy 115.487704 -374.759982) (xy 115.465876 -374.734363)
			(xy 115.427931 -374.678771) (xy 115.396901 -374.619043) (xy 115.373232 -374.556034) (xy 115.357263 -374.490648)
			(xy 115.349223 -374.423822) (xy 85.670923 -374.423822) (xy 85.670923 -374.423879) (xy 85.662851 -374.490815)
			(xy 85.646818 -374.556302) (xy 85.623057 -374.619398) (xy 85.591909 -374.679192) (xy 85.553823 -374.734826)
			(xy 85.53196 -374.76049) (xy 85.526138 -374.767617) (xy 85.519639 -374.784822) (xy 85.51926 -374.794018)
			(xy 85.51926 -375.28627) (xy 85.519694 -375.295454) (xy 85.526192 -375.312639) (xy 85.53196 -375.319798)
			(xy 85.553855 -375.345438) (xy 85.591945 -375.401075) (xy 85.623097 -375.460875) (xy 85.646861 -375.523975)
			(xy 85.662896 -375.589467) (xy 85.67097 -375.656409) (xy 85.670967 -375.723836) (xy 85.662888 -375.790777)
			(xy 85.646848 -375.856268) (xy 85.623079 -375.919367) (xy 85.591922 -375.979163) (xy 85.553827 -376.034797)
			(xy 85.53196 -376.060462) (xy 85.52615 -376.067597) (xy 85.519644 -376.084796) (xy 85.51926 -376.09399)
			(xy 85.51926 -376.25147) (xy 85.518749 -376.261595) (xy 85.511031 -376.280315) (xy 85.496752 -376.294673)
			(xy 85.478074 -376.302493) (xy 85.467952 -376.303032) (xy 84.751672 -376.303032) (xy 84.741565 -376.302539)
			(xy 84.722893 -376.294798) (xy 84.7086 -376.280504) (xy 84.700861 -376.261831) (xy 84.700364 -376.251724)
			(xy 84.700364 -376.09399) (xy 84.699944 -376.084804) (xy 84.693436 -376.06762) (xy 84.687664 -376.060462)
			(xy 84.665831 -376.034772) (xy 84.627744 -375.97914) (xy 84.596594 -375.919347) (xy 84.572829 -375.856253)
			(xy 84.556793 -375.790768) (xy 84.548715 -375.723833) (xy 84.548712 -375.656412) (xy 84.556785 -375.589477)
			(xy 84.572816 -375.52399) (xy 84.596575 -375.460894) (xy 84.62772 -375.401099) (xy 84.665803 -375.345464)
			(xy 84.687664 -375.319798) (xy 84.693452 -375.312647) (xy 84.69997 -375.295461) (xy 84.700364 -375.28627)
			(xy 84.700364 -374.794018) (xy 84.699931 -374.784834) (xy 84.693432 -374.76765) (xy 84.687664 -374.76049)
			(xy 84.66576 -374.734858) (xy 84.627675 -374.679218) (xy 84.596528 -374.619417) (xy 84.572768 -374.556316)
			(xy 84.556736 -374.490823) (xy 84.548664 -374.423882) (xy 81.271132 -374.423882) (xy 81.26306 -374.490815)
			(xy 81.247028 -374.556302) (xy 81.223267 -374.619397) (xy 81.19212 -374.679192) (xy 81.154034 -374.734825)
			(xy 81.132172 -374.76049) (xy 81.126351 -374.767618) (xy 81.119852 -374.784822) (xy 81.119472 -374.794018)
			(xy 81.119472 -375.28627) (xy 81.119903 -375.295455) (xy 81.126403 -375.312639) (xy 81.132172 -375.319798)
			(xy 81.154066 -375.345438) (xy 81.192156 -375.401076) (xy 81.223307 -375.460875) (xy 81.247071 -375.523975)
			(xy 81.263105 -375.589468) (xy 81.271179 -375.656409) (xy 81.271176 -375.723836) (xy 81.263097 -375.790777)
			(xy 81.247057 -375.856268) (xy 81.223289 -375.919366) (xy 81.192133 -375.979163) (xy 81.154039 -376.034797)
			(xy 81.132172 -376.060462) (xy 81.126363 -376.067598) (xy 81.119856 -376.084796) (xy 81.119472 -376.09399)
			(xy 81.119472 -376.25147) (xy 81.118949 -376.261593) (xy 81.111234 -376.280312) (xy 81.096958 -376.294669)
			(xy 81.078284 -376.302491) (xy 81.068164 -376.303032) (xy 80.351884 -376.303032) (xy 80.341778 -376.302529)
			(xy 80.323106 -376.294792) (xy 80.308813 -376.280501) (xy 80.301073 -376.26183) (xy 80.300576 -376.251724)
			(xy 80.300576 -376.09399) (xy 80.300176 -376.084802) (xy 80.293656 -376.067617) (xy 80.287876 -376.060462)
			(xy 80.266042 -376.034772) (xy 80.227954 -375.97914) (xy 80.196804 -375.919347) (xy 80.173039 -375.856254)
			(xy 80.157002 -375.790768) (xy 80.148924 -375.723833) (xy 80.148921 -375.656412) (xy 80.156994 -375.589476)
			(xy 80.173025 -375.523989) (xy 80.196785 -375.460894) (xy 80.227931 -375.401098) (xy 80.266015 -375.345464)
			(xy 80.287876 -375.319798) (xy 80.293653 -375.312639) (xy 80.30018 -375.295459) (xy 80.300576 -375.28627)
			(xy 80.300576 -374.794018) (xy 80.300163 -374.784831) (xy 80.293652 -374.767646) (xy 80.287876 -374.76049)
			(xy 80.265972 -374.734858) (xy 80.227886 -374.679218) (xy 80.196738 -374.619417) (xy 80.172977 -374.556316)
			(xy 80.156946 -374.490823) (xy 80.148873 -374.423882) (xy 76.870804 -374.423882) (xy 76.862772 -374.490638)
			(xy 76.846805 -374.556018) (xy 76.823138 -374.619021) (xy 76.79211 -374.678743) (xy 76.754168 -374.734329)
			(xy 76.732384 -374.759982) (xy 76.726568 -374.767114) (xy 76.720066 -374.784315) (xy 76.719684 -374.79351)
			(xy 76.719684 -375.286778) (xy 76.720108 -375.295964) (xy 76.726613 -375.313148) (xy 76.732384 -375.320306)
			(xy 76.754201 -375.345934) (xy 76.792147 -375.401525) (xy 76.823178 -375.461252) (xy 76.846848 -375.524259)
			(xy 76.862818 -375.589644) (xy 76.870859 -375.656469) (xy 76.870857 -375.723776) (xy 76.86281 -375.7906)
			(xy 76.846834 -375.855984) (xy 76.823159 -375.91899) (xy 76.792124 -375.978714) (xy 76.754173 -376.034302)
			(xy 76.732384 -376.059954) (xy 76.72658 -376.067094) (xy 76.72007 -376.084289) (xy 76.719684 -376.093482)
			(xy 76.719684 -376.25147) (xy 76.719212 -376.261637) (xy 76.711441 -376.280427) (xy 76.69707 -376.294812)
			(xy 76.678288 -376.302602) (xy 76.668122 -376.303032) (xy 75.951842 -376.303032) (xy 75.941669 -376.302601)
			(xy 75.92287 -376.294824) (xy 75.908482 -376.28044) (xy 75.900701 -376.261643) (xy 75.90028 -376.25147)
			(xy 75.90028 -376.093482) (xy 75.899883 -376.084293) (xy 75.893361 -376.067109) (xy 75.88758 -376.059954)
			(xy 75.865821 -376.034278) (xy 75.827868 -375.978696) (xy 75.796831 -375.918976) (xy 75.773155 -375.855975)
			(xy 75.757179 -375.790595) (xy 75.749132 -375.723774) (xy 75.749129 -375.656471) (xy 75.757171 -375.58965)
			(xy 75.773142 -375.524269) (xy 75.796813 -375.461265) (xy 75.827845 -375.401543) (xy 75.865793 -375.345958)
			(xy 75.88758 -375.320306) (xy 75.893354 -375.313145) (xy 75.899883 -375.295967) (xy 75.90028 -375.286778)
			(xy 75.90028 -374.79351) (xy 75.89987 -374.784323) (xy 75.893357 -374.767138) (xy 75.88758 -374.759982)
			(xy 75.865749 -374.734365) (xy 75.827799 -374.678774) (xy 75.796765 -374.619046) (xy 75.773093 -374.556037)
			(xy 75.757122 -374.49065) (xy 75.749081 -374.423823) (xy 72.471044 -374.423823) (xy 72.471044 -374.423879)
			(xy 72.462972 -374.490814) (xy 72.446941 -374.556301) (xy 72.423181 -374.619396) (xy 72.392034 -374.679191)
			(xy 72.35395 -374.734825) (xy 72.332088 -374.76049) (xy 72.326269 -374.76762) (xy 72.319768 -374.784822)
			(xy 72.319388 -374.794018) (xy 72.319388 -375.28627) (xy 72.319815 -375.295455) (xy 72.326317 -375.31264)
			(xy 72.332088 -375.319798) (xy 72.353982 -375.345439) (xy 72.39207 -375.401076) (xy 72.423221 -375.460876)
			(xy 72.446984 -375.523976) (xy 72.463017 -375.589468) (xy 72.471091 -375.656409) (xy 72.471088 -375.723836)
			(xy 72.463009 -375.790776) (xy 72.44697 -375.856267) (xy 72.423202 -375.919365) (xy 72.392047 -375.979162)
			(xy 72.353954 -376.034797) (xy 72.332088 -376.060462) (xy 72.326281 -376.0676) (xy 72.319773 -376.084796)
			(xy 72.319388 -376.09399) (xy 72.319388 -376.25147) (xy 72.31885 -376.261591) (xy 72.311137 -376.280307)
			(xy 72.296867 -376.294663) (xy 72.278198 -376.302488) (xy 72.26808 -376.303032) (xy 71.5518 -376.303032)
			(xy 71.54165 -376.302579) (xy 71.522904 -376.294789) (xy 71.508582 -376.280403) (xy 71.500876 -376.261622)
			(xy 71.500492 -376.25147) (xy 71.500492 -376.09399) (xy 71.500088 -376.084802) (xy 71.49357 -376.067618)
			(xy 71.487792 -376.060462) (xy 71.465958 -376.034772) (xy 71.427869 -375.979141) (xy 71.396717 -375.919348)
			(xy 71.372952 -375.856255) (xy 71.356914 -375.790769) (xy 71.348836 -375.723833) (xy 71.348833 -375.656412)
			(xy 71.356906 -375.589476) (xy 71.372938 -375.523989) (xy 71.396699 -375.460893) (xy 71.427845 -375.401098)
			(xy 71.46593 -375.345463) (xy 71.487792 -375.319798) (xy 71.493571 -375.31264) (xy 71.500096 -375.295459)
			(xy 71.500492 -375.28627) (xy 71.500492 -374.794018) (xy 71.500075 -374.784832) (xy 71.493566 -374.767647)
			(xy 71.487792 -374.76049) (xy 71.465887 -374.734859) (xy 71.4278 -374.679219) (xy 71.396652 -374.619418)
			(xy 71.37289 -374.556317) (xy 71.356858 -374.490824) (xy 71.348786 -374.423882) (xy 46.070774 -374.423882)
			(xy 46.062742 -374.490639) (xy 46.046773 -374.55602) (xy 46.023104 -374.619022) (xy 45.992075 -374.678745)
			(xy 45.95413 -374.73433) (xy 45.932344 -374.759982) (xy 45.926523 -374.76711) (xy 45.920025 -374.784314)
			(xy 45.919644 -374.79351) (xy 45.919644 -375.286778) (xy 45.920077 -375.295962) (xy 45.926576 -375.313146)
			(xy 45.932344 -375.320306) (xy 45.954162 -375.345934) (xy 45.992111 -375.401523) (xy 46.023144 -375.46125)
			(xy 46.046816 -375.524258) (xy 46.062787 -375.589643) (xy 46.070829 -375.656469) (xy 46.070826 -375.723776)
			(xy 46.062779 -375.790601) (xy 46.046802 -375.855985) (xy 46.023125 -375.918991) (xy 45.992088 -375.978716)
			(xy 45.954134 -376.034302) (xy 45.932344 -376.059954) (xy 45.926535 -376.06709) (xy 45.920029 -376.084288)
			(xy 45.919644 -376.093482) (xy 45.919644 -376.25147) (xy 45.919211 -376.261642) (xy 45.911433 -376.280439)
			(xy 45.897049 -376.294826) (xy 45.878254 -376.302609) (xy 45.868082 -376.303032) (xy 45.151802 -376.303032)
			(xy 45.141627 -376.302634) (xy 45.122826 -376.294844) (xy 45.10844 -376.28045) (xy 45.100661 -376.261645)
			(xy 45.10024 -376.25147) (xy 45.10024 -376.093482) (xy 45.09983 -376.084295) (xy 45.093315 -376.067111)
			(xy 45.08754 -376.059954) (xy 45.065782 -376.034277) (xy 45.027832 -375.978695) (xy 44.996798 -375.918974)
			(xy 44.973123 -375.855973) (xy 44.957148 -375.790594) (xy 44.949101 -375.723774) (xy 44.949099 -375.656471)
			(xy 44.95714 -375.589651) (xy 44.97311 -375.52427) (xy 44.996779 -375.461267) (xy 45.027809 -375.401544)
			(xy 45.065754 -375.345958) (xy 45.08754 -375.320306) (xy 45.093322 -375.31315) (xy 45.099844 -375.295968)
			(xy 45.10024 -375.286778) (xy 45.10024 -374.79351) (xy 45.099816 -374.784324) (xy 45.093311 -374.76714)
			(xy 45.08754 -374.759982) (xy 45.065711 -374.734364) (xy 45.027763 -374.678773) (xy 44.996732 -374.619044)
			(xy 44.973061 -374.556035) (xy 44.957091 -374.490649) (xy 44.94905 -374.423823) (xy 41.671014 -374.423823)
			(xy 41.671014 -374.423879) (xy 41.662941 -374.490816) (xy 41.646909 -374.556303) (xy 41.623147 -374.619398)
			(xy 41.591998 -374.679193) (xy 41.553911 -374.734826) (xy 41.532048 -374.76049) (xy 41.526224 -374.767616)
			(xy 41.519727 -374.784821) (xy 41.519348 -374.794018) (xy 41.519348 -375.28627) (xy 41.519784 -375.295454)
			(xy 41.526281 -375.312638) (xy 41.532048 -375.319798) (xy 41.553943 -375.345438) (xy 41.592035 -375.401075)
			(xy 41.623187 -375.460874) (xy 41.646952 -375.523974) (xy 41.662987 -375.589467) (xy 41.671061 -375.656409)
			(xy 41.671058 -375.723836) (xy 41.662978 -375.790777) (xy 41.646938 -375.856269) (xy 41.623168 -375.919367)
			(xy 41.592011 -375.979164) (xy 41.553916 -376.034798) (xy 41.532048 -376.060462) (xy 41.526236 -376.067596)
			(xy 41.519732 -376.084795) (xy 41.519348 -376.09399) (xy 41.519348 -376.25147) (xy 41.518849 -376.261596)
			(xy 41.511129 -376.280319) (xy 41.496846 -376.294677) (xy 41.478164 -376.302495) (xy 41.46804 -376.303032)
			(xy 40.75176 -376.303032) (xy 40.741607 -376.302612) (xy 40.72286 -376.294809) (xy 40.708539 -376.280413)
			(xy 40.700835 -376.261625) (xy 40.700452 -376.25147) (xy 40.700452 -376.09399) (xy 40.700035 -376.084804)
			(xy 40.693525 -376.06762) (xy 40.687752 -376.060462) (xy 40.665916 -376.034773) (xy 40.627823 -375.979143)
			(xy 40.596668 -375.919351) (xy 40.5729 -375.856257) (xy 40.55686 -375.79077) (xy 40.548781 -375.723834)
			(xy 40.548779 -375.656411) (xy 40.556852 -375.589474) (xy 40.572886 -375.523986) (xy 40.596649 -375.46089)
			(xy 40.627799 -375.401095) (xy 40.665888 -375.345462) (xy 40.687752 -375.319798) (xy 40.693538 -375.312646)
			(xy 40.700058 -375.29546) (xy 40.700452 -375.28627) (xy 40.700452 -374.794018) (xy 40.700022 -374.784833)
			(xy 40.693521 -374.767649) (xy 40.687752 -374.76049) (xy 40.665845 -374.73486) (xy 40.627754 -374.679221)
			(xy 40.596602 -374.619421) (xy 40.572838 -374.556319) (xy 40.556804 -374.490825) (xy 40.548731 -374.423882)
			(xy 37.271223 -374.423882) (xy 37.263151 -374.490815) (xy 37.247118 -374.556302) (xy 37.223357 -374.619398)
			(xy 37.192209 -374.679192) (xy 37.154123 -374.734826) (xy 37.13226 -374.76049) (xy 37.126438 -374.767617)
			(xy 37.119939 -374.784822) (xy 37.11956 -374.794018) (xy 37.11956 -375.28627) (xy 37.119994 -375.295454)
			(xy 37.126492 -375.312639) (xy 37.13226 -375.319798) (xy 37.154155 -375.345438) (xy 37.192245 -375.401075)
			(xy 37.223397 -375.460875) (xy 37.247161 -375.523975) (xy 37.263196 -375.589467) (xy 37.27127 -375.656409)
			(xy 37.271267 -375.723836) (xy 37.263188 -375.790777) (xy 37.247148 -375.856268) (xy 37.223379 -375.919367)
			(xy 37.192222 -375.979163) (xy 37.154127 -376.034797) (xy 37.13226 -376.060462) (xy 37.12645 -376.067597)
			(xy 37.119944 -376.084796) (xy 37.11956 -376.09399) (xy 37.11956 -376.25147) (xy 37.119049 -376.261595)
			(xy 37.111331 -376.280315) (xy 37.097052 -376.294673) (xy 37.078374 -376.302493) (xy 37.068252 -376.303032)
			(xy 36.351972 -376.303032) (xy 36.34182 -376.302602) (xy 36.323073 -376.294803) (xy 36.308752 -376.28041)
			(xy 36.301047 -376.261624) (xy 36.300664 -376.25147) (xy 36.300664 -376.09399) (xy 36.300244 -376.084804)
			(xy 36.293736 -376.06762) (xy 36.287964 -376.060462) (xy 36.266131 -376.034772) (xy 36.228044 -375.97914)
			(xy 36.196894 -375.919347) (xy 36.173129 -375.856253) (xy 36.157093 -375.790768) (xy 36.149015 -375.723833)
			(xy 36.149012 -375.656412) (xy 36.157085 -375.589477) (xy 36.173116 -375.52399) (xy 36.196875 -375.460894)
			(xy 36.22802 -375.401099) (xy 36.266103 -375.345464) (xy 36.287964 -375.319798) (xy 36.293752 -375.312647)
			(xy 36.30027 -375.295461) (xy 36.300664 -375.28627) (xy 36.300664 -374.794018) (xy 36.300231 -374.784834)
			(xy 36.293732 -374.76765) (xy 36.287964 -374.76049) (xy 36.26606 -374.734858) (xy 36.227975 -374.679218)
			(xy 36.196828 -374.619417) (xy 36.173068 -374.556316) (xy 36.157036 -374.490823) (xy 36.148964 -374.423882)
			(xy 32.870895 -374.423882) (xy 32.862863 -374.490639) (xy 32.846895 -374.556018) (xy 32.823227 -374.619021)
			(xy 32.7922 -374.678743) (xy 32.754257 -374.73433) (xy 32.732472 -374.759982) (xy 32.726654 -374.767112)
			(xy 32.720153 -374.784314) (xy 32.719772 -374.79351) (xy 32.719772 -375.286778) (xy 32.720199 -375.295963)
			(xy 32.726702 -375.313147) (xy 32.732472 -375.320306) (xy 32.754289 -375.345934) (xy 32.792236 -375.401524)
			(xy 32.823268 -375.461251) (xy 32.846938 -375.524259) (xy 32.862909 -375.589644) (xy 32.87095 -375.656469)
			(xy 32.870948 -375.723776) (xy 32.862901 -375.790601) (xy 32.846925 -375.855984) (xy 32.823249 -375.91899)
			(xy 32.792213 -375.978715) (xy 32.754261 -376.034302) (xy 32.732472 -376.059954) (xy 32.726666 -376.067093)
			(xy 32.720158 -376.084288) (xy 32.719772 -376.093482) (xy 32.719772 -376.25147) (xy 32.719312 -376.261638)
			(xy 32.711538 -376.28043) (xy 32.697164 -376.294816) (xy 32.678378 -376.302604) (xy 32.66821 -376.303032)
			(xy 31.95193 -376.303032) (xy 31.941757 -376.302611) (xy 31.922957 -376.29483) (xy 31.90857 -376.280443)
			(xy 31.900789 -376.261643) (xy 31.900368 -376.25147) (xy 31.900368 -376.093482) (xy 31.899951 -376.084296)
			(xy 31.89344 -376.067112) (xy 31.887668 -376.059954) (xy 31.865909 -376.034278) (xy 31.827957 -375.978696)
			(xy 31.796921 -375.918976) (xy 31.773245 -375.855974) (xy 31.75727 -375.790595) (xy 31.749223 -375.723774)
			(xy 31.74922 -375.656471) (xy 31.757261 -375.58965) (xy 31.773232 -375.524269) (xy 31.796903 -375.461266)
			(xy 31.827934 -375.401543) (xy 31.865881 -375.345958) (xy 31.887668 -375.320306) (xy 31.893453 -375.313153)
			(xy 31.899973 -375.295968) (xy 31.900368 -375.286778) (xy 31.900368 -374.79351) (xy 31.899938 -374.784325)
			(xy 31.893436 -374.767142) (xy 31.887668 -374.759982) (xy 31.865838 -374.734364) (xy 31.827888 -374.678774)
			(xy 31.796855 -374.619046) (xy 31.773184 -374.556036) (xy 31.757213 -374.49065) (xy 31.749171 -374.423823)
			(xy 28.471155 -374.423823) (xy 28.471155 -374.42387) (xy 28.463079 -374.490809) (xy 28.447044 -374.556297)
			(xy 28.423279 -374.619394) (xy 28.392129 -374.67919) (xy 28.35404 -374.734825) (xy 28.332176 -374.76049)
			(xy 28.326356 -374.767618) (xy 28.319856 -374.784822) (xy 28.319476 -374.794018) (xy 28.319476 -375.28627)
			(xy 28.319906 -375.295455) (xy 28.326407 -375.312639) (xy 28.332176 -375.319798) (xy 28.35407 -375.345439)
			(xy 28.39216 -375.401076) (xy 28.42331 -375.460875) (xy 28.447074 -375.523976) (xy 28.463108 -375.589468)
			(xy 28.471182 -375.656409) (xy 28.471179 -375.723836) (xy 28.4631 -375.790777) (xy 28.447061 -375.856268)
			(xy 28.423292 -375.919366) (xy 28.392136 -375.979163) (xy 28.354043 -376.034797) (xy 28.332176 -376.060462)
			(xy 28.326368 -376.067599) (xy 28.319861 -376.084796) (xy 28.319476 -376.09399) (xy 28.319476 -376.25147)
			(xy 28.31895 -376.261593) (xy 28.311235 -376.28031) (xy 28.29696 -376.294667) (xy 28.278288 -376.30249)
			(xy 28.268168 -376.303032) (xy 27.551888 -376.303032) (xy 27.541783 -376.302525) (xy 27.52311 -376.29479)
			(xy 27.508817 -376.2805) (xy 27.501077 -376.261829) (xy 27.50058 -376.251724) (xy 27.50058 -376.09399)
			(xy 27.500179 -376.084802) (xy 27.493659 -376.067617) (xy 27.48788 -376.060462) (xy 27.466046 -376.034772)
			(xy 27.427958 -375.979141) (xy 27.396807 -375.919348) (xy 27.373042 -375.856254) (xy 27.357005 -375.790768)
			(xy 27.348927 -375.723833) (xy 27.348924 -375.656412) (xy 27.356997 -375.589476) (xy 27.373029 -375.523989)
			(xy 27.396789 -375.460894) (xy 27.427935 -375.401098) (xy 27.466019 -375.345464) (xy 27.48788 -375.319798)
			(xy 27.493658 -375.312639) (xy 27.500184 -375.295459) (xy 27.50058 -375.28627) (xy 27.50058 -374.794018)
			(xy 27.500166 -374.784831) (xy 27.493655 -374.767646) (xy 27.48788 -374.76049) (xy 27.466014 -374.734827)
			(xy 27.427924 -374.679192) (xy 27.396773 -374.619396) (xy 27.373009 -374.556299) (xy 27.356973 -374.490809)
			(xy 27.348897 -374.423871) (xy 0.508 -374.423871) (xy 0.508 -376.756551) (xy 29.549067 -376.756551)
			(xy 29.557111 -376.689729) (xy 29.573083 -376.624347) (xy 29.596754 -376.561343) (xy 29.627786 -376.501619)
			(xy 29.665733 -376.446032) (xy 29.68752 -376.42038) (xy 29.69331 -376.41323) (xy 29.699828 -376.396043)
			(xy 29.70022 -376.386852) (xy 29.70022 -375.893584) (xy 29.699813 -375.884397) (xy 29.693297 -375.867212)
			(xy 29.68752 -375.860056) (xy 29.665765 -375.834378) (xy 29.627816 -375.778794) (xy 29.596782 -375.719074)
			(xy 29.573109 -375.656073) (xy 29.557134 -375.590694) (xy 29.549088 -375.523875) (xy 29.549085 -375.456573)
			(xy 29.557126 -375.389753) (xy 29.573095 -375.324373) (xy 29.596763 -375.26137) (xy 29.627791 -375.201647)
			(xy 29.665735 -375.146061) (xy 29.68752 -375.120408) (xy 29.693298 -375.11325) (xy 29.699823 -375.096069)
			(xy 29.70022 -375.08688) (xy 29.70022 -374.928638) (xy 29.700695 -374.918471) (xy 29.708464 -374.899681)
			(xy 29.722834 -374.885295) (xy 29.741616 -374.877506) (xy 29.751782 -374.877076) (xy 30.468062 -374.877076)
			(xy 30.478236 -374.877496) (xy 30.497037 -374.885276) (xy 30.511424 -374.899663) (xy 30.519204 -374.918464)
			(xy 30.519624 -374.928638) (xy 30.519624 -375.08688) (xy 30.520038 -375.096067) (xy 30.526548 -375.113252)
			(xy 30.532324 -375.120408) (xy 30.554144 -375.146034) (xy 30.592094 -375.201623) (xy 30.623128 -375.26135)
			(xy 30.646801 -375.324358) (xy 30.662773 -375.389744) (xy 30.670815 -375.45657) (xy 30.670812 -375.523878)
			(xy 30.662764 -375.590704) (xy 30.646787 -375.656088) (xy 30.623109 -375.719094) (xy 30.59207 -375.778818)
			(xy 30.554115 -375.834404) (xy 30.532324 -375.860056) (xy 30.526524 -375.867199) (xy 30.520011 -375.884391)
			(xy 30.519624 -375.893584) (xy 30.519624 -376.386852) (xy 30.520052 -376.396037) (xy 30.526553 -376.413222)
			(xy 30.532324 -376.42038) (xy 30.554117 -376.446028) (xy 30.592068 -376.501615) (xy 30.623103 -376.561338)
			(xy 30.646777 -376.624343) (xy 30.662751 -376.689726) (xy 30.670795 -376.75655) (xy 30.670795 -376.823856)
			(xy 30.670788 -376.823915) (xy 33.948836 -376.823915) (xy 33.948836 -376.756491) (xy 33.956911 -376.689553)
			(xy 33.972947 -376.624064) (xy 33.996711 -376.560967) (xy 34.027862 -376.501171) (xy 34.065952 -376.445537)
			(xy 34.087816 -376.419872) (xy 34.093609 -376.412724) (xy 34.100125 -376.395536) (xy 34.100516 -376.386344)
			(xy 34.100516 -375.894092) (xy 34.100106 -375.884905) (xy 34.093592 -375.867721) (xy 34.087816 -375.860564)
			(xy 34.065983 -375.834873) (xy 34.027892 -375.779243) (xy 33.996739 -375.71945) (xy 33.972973 -375.656357)
			(xy 33.956934 -375.59087) (xy 33.948856 -375.523935) (xy 33.948853 -375.456513) (xy 33.956926 -375.389577)
			(xy 33.972958 -375.324089) (xy 33.99672 -375.260994) (xy 34.027867 -375.201199) (xy 34.065953 -375.145565)
			(xy 34.087816 -375.1199) (xy 34.093597 -375.112744) (xy 34.10012 -375.095562) (xy 34.100516 -375.086372)
			(xy 34.100516 -374.928638) (xy 34.101057 -374.918517) (xy 34.108768 -374.899801) (xy 34.123038 -374.885444)
			(xy 34.141706 -374.87762) (xy 34.151824 -374.877076) (xy 34.868104 -374.877076) (xy 34.878255 -374.877518)
			(xy 34.897003 -374.88531) (xy 34.911325 -374.8997) (xy 34.919029 -374.918485) (xy 34.919412 -374.928638)
			(xy 34.919412 -375.086372) (xy 34.919833 -375.095558) (xy 34.926339 -375.112743) (xy 34.932112 -375.1199)
			(xy 34.954007 -375.14554) (xy 34.992094 -375.201178) (xy 35.023243 -375.260978) (xy 35.047004 -375.324078)
			(xy 35.063037 -375.38957) (xy 35.07111 -375.456511) (xy 35.071108 -375.523937) (xy 35.063029 -375.590877)
			(xy 35.04699 -375.656368) (xy 35.023223 -375.719466) (xy 34.992069 -375.779263) (xy 34.953977 -375.834899)
			(xy 34.932112 -375.860564) (xy 34.926307 -375.867703) (xy 34.919797 -375.884898) (xy 34.919412 -375.894092)
			(xy 34.919412 -376.386344) (xy 34.919798 -376.395534) (xy 34.926328 -376.412718) (xy 34.932112 -376.419872)
			(xy 34.953979 -376.445534) (xy 34.992067 -376.501169) (xy 35.023217 -376.560966) (xy 35.046981 -376.624063)
			(xy 35.063015 -376.689553) (xy 35.071091 -376.756491) (xy 35.071091 -376.756551) (xy 38.349155 -376.756551)
			(xy 38.357198 -376.689729) (xy 38.37317 -376.624348) (xy 38.396841 -376.561343) (xy 38.427872 -376.50162)
			(xy 38.465818 -376.446033) (xy 38.487604 -376.42038) (xy 38.493392 -376.413229) (xy 38.499912 -376.396043)
			(xy 38.500304 -376.386852) (xy 38.500304 -375.893584) (xy 38.499901 -375.884396) (xy 38.493382 -375.867212)
			(xy 38.487604 -375.860056) (xy 38.465849 -375.834378) (xy 38.427901 -375.778794) (xy 38.396869 -375.719074)
			(xy 38.373195 -375.656073) (xy 38.357221 -375.590694) (xy 38.349175 -375.523875) (xy 38.349172 -375.456573)
			(xy 38.357213 -375.389753) (xy 38.373181 -375.324373) (xy 38.396849 -375.26137) (xy 38.427876 -375.201647)
			(xy 38.465819 -375.146061) (xy 38.487604 -375.120408) (xy 38.49338 -375.113248) (xy 38.499907 -375.096069)
			(xy 38.500304 -375.08688) (xy 38.500304 -374.928638) (xy 38.500794 -374.918473) (xy 38.50856 -374.899686)
			(xy 38.522925 -374.885301) (xy 38.541702 -374.877508) (xy 38.551866 -374.877076) (xy 39.268146 -374.877076)
			(xy 39.278311 -374.877497) (xy 39.297089 -374.885293) (xy 39.311454 -374.899682) (xy 39.31922 -374.918472)
			(xy 39.319708 -374.928638) (xy 39.319708 -375.08688) (xy 39.320126 -375.096066) (xy 39.326634 -375.113251)
			(xy 39.332408 -375.120408) (xy 39.354229 -375.146034) (xy 39.39218 -375.201623) (xy 39.423215 -375.261349)
			(xy 39.446888 -375.324357) (xy 39.462861 -375.389743) (xy 39.470903 -375.45657) (xy 39.4709 -375.523878)
			(xy 39.462852 -375.590704) (xy 39.446874 -375.656089) (xy 39.423195 -375.719095) (xy 39.392155 -375.778819)
			(xy 39.354199 -375.834405) (xy 39.332408 -375.860056) (xy 39.326606 -375.867197) (xy 39.320094 -375.884391)
			(xy 39.319708 -375.893584) (xy 39.319708 -376.386852) (xy 39.320139 -376.396037) (xy 39.326638 -376.413222)
			(xy 39.332408 -376.42038) (xy 39.354201 -376.446028) (xy 39.392153 -376.501614) (xy 39.423189 -376.561338)
			(xy 39.446864 -376.624343) (xy 39.462839 -376.689726) (xy 39.470883 -376.75655) (xy 39.470883 -376.823856)
			(xy 39.470876 -376.823915) (xy 42.748924 -376.823915) (xy 42.748924 -376.756491) (xy 42.756999 -376.689553)
			(xy 42.773034 -376.624064) (xy 42.796798 -376.560968) (xy 42.827948 -376.501172) (xy 42.866036 -376.445537)
			(xy 42.8879 -376.419872) (xy 42.893691 -376.412723) (xy 42.900209 -376.395535) (xy 42.9006 -376.386344)
			(xy 42.9006 -375.894092) (xy 42.900194 -375.884904) (xy 42.893677 -375.86772) (xy 42.8879 -375.860564)
			(xy 42.866067 -375.834873) (xy 42.827978 -375.779242) (xy 42.796826 -375.719449) (xy 42.77306 -375.656356)
			(xy 42.757022 -375.59087) (xy 42.748944 -375.523935) (xy 42.748941 -375.456513) (xy 42.757013 -375.389577)
			(xy 42.773045 -375.32409) (xy 42.796806 -375.260995) (xy 42.827953 -375.201199) (xy 42.866038 -375.145565)
			(xy 42.8879 -375.1199) (xy 42.893679 -375.112742) (xy 42.900204 -375.095561) (xy 42.9006 -375.086372)
			(xy 42.9006 -374.928638) (xy 42.901157 -374.918519) (xy 42.908865 -374.899806) (xy 42.923129 -374.88545)
			(xy 42.941792 -374.877622) (xy 42.951908 -374.877076) (xy 43.668188 -374.877076) (xy 43.678338 -374.877531)
			(xy 43.697086 -374.885318) (xy 43.711409 -374.899704) (xy 43.719113 -374.918486) (xy 43.719496 -374.928638)
			(xy 43.719496 -375.086372) (xy 43.719921 -375.095558) (xy 43.726424 -375.112742) (xy 43.732196 -375.1199)
			(xy 43.754092 -375.145539) (xy 43.79218 -375.201177) (xy 43.823329 -375.260977) (xy 43.847092 -375.324077)
			(xy 43.863125 -375.38957) (xy 43.871198 -375.456511) (xy 43.871196 -375.523937) (xy 43.863116 -375.590878)
			(xy 43.847077 -375.656369) (xy 43.823309 -375.719467) (xy 43.792155 -375.779264) (xy 43.754062 -375.834899)
			(xy 43.732196 -375.860564) (xy 43.726389 -375.867702) (xy 43.719881 -375.884898) (xy 43.719496 -375.894092)
			(xy 43.719496 -376.386344) (xy 43.719886 -376.395533) (xy 43.726414 -376.412717) (xy 43.732196 -376.419872)
			(xy 43.754064 -376.445534) (xy 43.792153 -376.501169) (xy 43.823304 -376.560965) (xy 43.847068 -376.624063)
			(xy 43.863103 -376.689552) (xy 43.871179 -376.756491) (xy 43.871178 -376.823856) (xy 47.149219 -376.823856)
			(xy 47.149219 -376.75655) (xy 47.157264 -376.689727) (xy 47.173238 -376.624344) (xy 47.196912 -376.56134)
			(xy 47.227948 -376.501617) (xy 47.265899 -376.446031) (xy 47.287688 -376.42038) (xy 47.293474 -376.413227)
			(xy 47.299995 -376.396043) (xy 47.300388 -376.386852) (xy 47.300388 -375.893584) (xy 47.299988 -375.884396)
			(xy 47.293468 -375.867211) (xy 47.287688 -375.860056) (xy 47.26593 -375.834379) (xy 47.227977 -375.778797)
			(xy 47.19694 -375.719077) (xy 47.173263 -375.656076) (xy 47.157287 -375.590696) (xy 47.149239 -375.523876)
			(xy 47.149236 -375.456572) (xy 47.157278 -375.389751) (xy 47.173249 -375.32437) (xy 47.19692 -375.261367)
			(xy 47.227952 -375.201644) (xy 47.265901 -375.146059) (xy 47.287688 -375.120408) (xy 47.293462 -375.113247)
			(xy 47.299991 -375.096069) (xy 47.300388 -375.08688) (xy 47.300388 -374.928892) (xy 47.300815 -374.918739)
			(xy 47.308611 -374.899989) (xy 47.323006 -374.885666) (xy 47.341795 -374.877965) (xy 47.35195 -374.877584)
			(xy 48.06823 -374.877584) (xy 48.078364 -374.878003) (xy 48.097094 -374.885749) (xy 48.111451 -374.900056)
			(xy 48.119261 -374.91876) (xy 48.119792 -374.928892) (xy 48.119792 -375.08688) (xy 48.120214 -375.096066)
			(xy 48.12672 -375.11325) (xy 48.132492 -375.120408) (xy 48.15431 -375.146035) (xy 48.192256 -375.201626)
			(xy 48.223286 -375.261353) (xy 48.246956 -375.324361) (xy 48.262926 -375.389746) (xy 48.270967 -375.456571)
			(xy 48.270964 -375.523878) (xy 48.262917 -375.590702) (xy 48.246942 -375.656085) (xy 48.223267 -375.719091)
			(xy 48.192231 -375.778816) (xy 48.154281 -375.834403) (xy 48.132492 -375.860056) (xy 48.126688 -375.867196)
			(xy 48.120178 -375.884391) (xy 48.119792 -375.893584) (xy 48.119792 -376.386852) (xy 48.120227 -376.396037)
			(xy 48.126724 -376.413221) (xy 48.132492 -376.42038) (xy 48.154283 -376.446029) (xy 48.192229 -376.501617)
			(xy 48.223261 -376.561341) (xy 48.246932 -376.624346) (xy 48.262904 -376.689728) (xy 48.270947 -376.756551)
			(xy 73.548976 -376.756551) (xy 73.55702 -376.689728) (xy 73.572992 -376.624347) (xy 73.596664 -376.561342)
			(xy 73.627697 -376.501619) (xy 73.665645 -376.446032) (xy 73.687432 -376.42038) (xy 73.693224 -376.413231)
			(xy 73.699741 -376.396043) (xy 73.700132 -376.386852) (xy 73.700132 -375.893584) (xy 73.699722 -375.884397)
			(xy 73.693208 -375.867213) (xy 73.687432 -375.860056) (xy 73.665676 -375.834378) (xy 73.627727 -375.778795)
			(xy 73.596693 -375.719075) (xy 73.573018 -375.656074) (xy 73.557043 -375.590695) (xy 73.548997 -375.523875)
			(xy 73.548994 -375.456573) (xy 73.557035 -375.389753) (xy 73.573004 -375.324372) (xy 73.596673 -375.261369)
			(xy 73.627702 -375.201647) (xy 73.665647 -375.14606) (xy 73.687432 -375.120408) (xy 73.693212 -375.113251)
			(xy 73.699736 -375.096069) (xy 73.700132 -375.08688) (xy 73.700132 -374.928638) (xy 73.700595 -374.91847)
			(xy 73.708366 -374.899677) (xy 73.72274 -374.885291) (xy 73.741526 -374.877504) (xy 73.751694 -374.877076)
			(xy 74.467974 -374.877076) (xy 74.478149 -374.877486) (xy 74.49695 -374.88527) (xy 74.511337 -374.89966)
			(xy 74.519116 -374.918463) (xy 74.519536 -374.928638) (xy 74.519536 -375.08688) (xy 74.51997 -375.096064)
			(xy 74.526469 -375.113248) (xy 74.532236 -375.120408) (xy 74.554056 -375.146034) (xy 74.592006 -375.201623)
			(xy 74.623039 -375.26135) (xy 74.646711 -375.324358) (xy 74.662683 -375.389744) (xy 74.670725 -375.45657)
			(xy 74.670722 -375.523878) (xy 74.662674 -375.590703) (xy 74.646697 -375.656088) (xy 74.623019 -375.719094)
			(xy 74.591981 -375.778818) (xy 74.554027 -375.834404) (xy 74.532236 -375.860056) (xy 74.526425 -375.867191)
			(xy 74.519921 -375.88439) (xy 74.519536 -375.893584) (xy 74.519536 -376.386852) (xy 74.519983 -376.396035)
			(xy 74.526473 -376.413219) (xy 74.532236 -376.42038) (xy 74.554028 -376.446029) (xy 74.591979 -376.501615)
			(xy 74.623013 -376.561339) (xy 74.646687 -376.624344) (xy 74.66266 -376.689727) (xy 74.670704 -376.75655)
			(xy 74.670704 -376.823856) (xy 74.670697 -376.823915) (xy 77.948745 -376.823915) (xy 77.948745 -376.756491)
			(xy 77.956821 -376.689553) (xy 77.972856 -376.624063) (xy 77.996621 -376.560967) (xy 78.027773 -376.501171)
			(xy 78.065863 -376.445537) (xy 78.087728 -376.419872) (xy 78.093523 -376.412726) (xy 78.100038 -376.395536)
			(xy 78.100428 -376.386344) (xy 78.100428 -375.894092) (xy 78.100016 -375.884905) (xy 78.093503 -375.867721)
			(xy 78.087728 -375.860564) (xy 78.065894 -375.834873) (xy 78.027803 -375.779243) (xy 77.996649 -375.719451)
			(xy 77.972882 -375.656357) (xy 77.956844 -375.590871) (xy 77.948765 -375.523935) (xy 77.948762 -375.456513)
			(xy 77.956835 -375.389577) (xy 77.972868 -375.324089) (xy 77.99663 -375.260993) (xy 78.027778 -375.201198)
			(xy 78.065865 -375.145565) (xy 78.087728 -375.1199) (xy 78.093511 -375.112745) (xy 78.100033 -375.095562)
			(xy 78.100428 -375.086372) (xy 78.100428 -374.928638) (xy 78.100958 -374.918515) (xy 78.108671 -374.899797)
			(xy 78.122944 -374.88544) (xy 78.141616 -374.877618) (xy 78.151736 -374.877076) (xy 78.868016 -374.877076)
			(xy 78.878123 -374.877572) (xy 78.896797 -374.88531) (xy 78.91109 -374.899603) (xy 78.918828 -374.918277)
			(xy 78.919324 -374.928384) (xy 78.919324 -375.086372) (xy 78.919742 -375.095558) (xy 78.92625 -375.112743)
			(xy 78.932024 -375.1199) (xy 78.953919 -375.14554) (xy 78.992005 -375.201178) (xy 79.023153 -375.260978)
			(xy 79.046914 -375.324079) (xy 79.062947 -375.38957) (xy 79.07102 -375.456511) (xy 79.071017 -375.523937)
			(xy 79.062938 -375.590877) (xy 79.0469 -375.656367) (xy 79.023133 -375.719466) (xy 78.99198 -375.779263)
			(xy 78.953889 -375.834898) (xy 78.932024 -375.860564) (xy 78.926221 -375.867704) (xy 78.919709 -375.884898)
			(xy 78.919324 -375.894092) (xy 78.919324 -376.386344) (xy 78.919708 -376.395534) (xy 78.926239 -376.412718)
			(xy 78.932024 -376.419872) (xy 78.953891 -376.445534) (xy 78.991978 -376.50117) (xy 79.023127 -376.560967)
			(xy 79.04689 -376.624064) (xy 79.062925 -376.689553) (xy 79.071 -376.756491) (xy 79.071 -376.756551)
			(xy 82.349064 -376.756551) (xy 82.357108 -376.689729) (xy 82.373079 -376.624347) (xy 82.396751 -376.561343)
			(xy 82.427782 -376.501619) (xy 82.465729 -376.446032) (xy 82.487516 -376.42038) (xy 82.493305 -376.41323)
			(xy 82.499824 -376.396043) (xy 82.500216 -376.386852) (xy 82.500216 -375.893584) (xy 82.49981 -375.884396)
			(xy 82.493293 -375.867212) (xy 82.487516 -375.860056) (xy 82.46576 -375.834378) (xy 82.427812 -375.778795)
			(xy 82.396779 -375.719074) (xy 82.373105 -375.656073) (xy 82.357131 -375.590694) (xy 82.349084 -375.523875)
			(xy 82.349081 -375.456573) (xy 82.357122 -375.389753) (xy 82.373091 -375.324373) (xy 82.396759 -375.26137)
			(xy 82.427787 -375.201647) (xy 82.465731 -375.14606) (xy 82.487516 -375.120408) (xy 82.493294 -375.113249)
			(xy 82.499819 -375.096069) (xy 82.500216 -375.08688) (xy 82.500216 -374.928638) (xy 82.500694 -374.918472)
			(xy 82.508463 -374.899682) (xy 82.522832 -374.885297) (xy 82.541612 -374.877506) (xy 82.551778 -374.877076)
			(xy 83.268058 -374.877076) (xy 83.278232 -374.877499) (xy 83.297033 -374.885277) (xy 83.31142 -374.899664)
			(xy 83.3192 -374.918464) (xy 83.31962 -374.928638) (xy 83.31962 -375.08688) (xy 83.320035 -375.096067)
			(xy 83.326545 -375.113251) (xy 83.33232 -375.120408) (xy 83.35414 -375.146034) (xy 83.392091 -375.201623)
			(xy 83.423125 -375.26135) (xy 83.446798 -375.324358) (xy 83.46277 -375.389744) (xy 83.470812 -375.45657)
			(xy 83.470809 -375.523878) (xy 83.462761 -375.590704) (xy 83.446784 -375.656088) (xy 83.423105 -375.719094)
			(xy 83.392066 -375.778818) (xy 83.354111 -375.834404) (xy 83.33232 -375.860056) (xy 83.326519 -375.867199)
			(xy 83.320007 -375.884391) (xy 83.31962 -375.893584) (xy 83.31962 -376.386852) (xy 83.320049 -376.396037)
			(xy 83.326549 -376.413222) (xy 83.33232 -376.42038) (xy 83.354113 -376.446028) (xy 83.392064 -376.501614)
			(xy 83.4231 -376.561338) (xy 83.446774 -376.624343) (xy 83.462748 -376.689726) (xy 83.470792 -376.75655)
			(xy 83.470792 -376.823856) (xy 83.470785 -376.823915) (xy 86.748833 -376.823915) (xy 86.748833 -376.756491)
			(xy 86.756908 -376.689553) (xy 86.772944 -376.624064) (xy 86.796708 -376.560967) (xy 86.827859 -376.501171)
			(xy 86.865948 -376.445537) (xy 86.887812 -376.419872) (xy 86.893604 -376.412724) (xy 86.900121 -376.395536)
			(xy 86.900512 -376.386344) (xy 86.900512 -375.894092) (xy 86.900103 -375.884905) (xy 86.893588 -375.86772)
			(xy 86.887812 -375.860564) (xy 86.865979 -375.834873) (xy 86.827889 -375.779242) (xy 86.796736 -375.71945)
			(xy 86.772969 -375.656356) (xy 86.756931 -375.59087) (xy 86.748853 -375.523935) (xy 86.74885 -375.456513)
			(xy 86.756923 -375.389577) (xy 86.772955 -375.32409) (xy 86.796716 -375.260994) (xy 86.827864 -375.201199)
			(xy 86.86595 -375.145565) (xy 86.887812 -375.1199) (xy 86.893592 -375.112743) (xy 86.900116 -375.095562)
			(xy 86.900512 -375.086372) (xy 86.900512 -374.928638) (xy 86.901057 -374.918517) (xy 86.908767 -374.899802)
			(xy 86.923035 -374.885446) (xy 86.941702 -374.87762) (xy 86.95182 -374.877076) (xy 87.6681 -374.877076)
			(xy 87.678206 -374.877585) (xy 87.696879 -374.885318) (xy 87.711173 -374.899607) (xy 87.718912 -374.918278)
			(xy 87.719408 -374.928384) (xy 87.719408 -375.086372) (xy 87.71983 -375.095558) (xy 87.726335 -375.112743)
			(xy 87.732108 -375.1199) (xy 87.754003 -375.145539) (xy 87.79209 -375.201178) (xy 87.798441 -375.213371)
			(xy 104.681961 -375.213371) (xy 104.681961 -375.153429) (xy 104.689785 -375.094001) (xy 104.7053 -375.036103)
			(xy 104.72824 -374.980725) (xy 104.758212 -374.928815) (xy 104.794703 -374.881262) (xy 104.837089 -374.838879)
			(xy 104.884645 -374.802391) (xy 104.936557 -374.772424) (xy 104.991937 -374.749489) (xy 105.049837 -374.733978)
			(xy 105.109265 -374.726159) (xy 105.139236 -374.725692) (xy 106.002836 -374.725692) (xy 106.032802 -374.726184)
			(xy 106.092221 -374.734011) (xy 106.15011 -374.749527) (xy 106.205479 -374.772465) (xy 106.25738 -374.802434)
			(xy 106.304926 -374.838921) (xy 106.347303 -374.881301) (xy 106.383786 -374.92885) (xy 106.413751 -374.980753)
			(xy 106.436685 -375.036124) (xy 106.452196 -375.094014) (xy 106.460018 -375.153434) (xy 106.460018 -375.213366)
			(xy 106.452196 -375.272786) (xy 106.436685 -375.330676) (xy 106.413751 -375.386047) (xy 106.383786 -375.43795)
			(xy 106.347303 -375.485499) (xy 106.304926 -375.527879) (xy 106.25738 -375.564366) (xy 106.205479 -375.594335)
			(xy 106.15011 -375.617273) (xy 106.092221 -375.632789) (xy 106.032802 -375.640616) (xy 106.002836 -375.641108)
			(xy 105.139236 -375.641108) (xy 105.109265 -375.640641) (xy 105.049837 -375.632822) (xy 104.991937 -375.617311)
			(xy 104.936557 -375.594376) (xy 104.884645 -375.564409) (xy 104.837089 -375.527921) (xy 104.794703 -375.485538)
			(xy 104.758212 -375.437985) (xy 104.72824 -375.386075) (xy 104.7053 -375.330697) (xy 104.689785 -375.272799)
			(xy 104.681961 -375.213371) (xy 87.798441 -375.213371) (xy 87.823239 -375.260978) (xy 87.847001 -375.324078)
			(xy 87.863034 -375.38957) (xy 87.871107 -375.456511) (xy 87.871105 -375.523937) (xy 87.863026 -375.590877)
			(xy 87.846987 -375.656368) (xy 87.82322 -375.719466) (xy 87.792066 -375.779263) (xy 87.753974 -375.834899)
			(xy 87.732108 -375.860564) (xy 87.726303 -375.867703) (xy 87.719793 -375.884898) (xy 87.719408 -375.894092)
			(xy 87.719408 -376.386344) (xy 87.719795 -376.395534) (xy 87.726324 -376.412718) (xy 87.732108 -376.419872)
			(xy 87.753976 -376.445534) (xy 87.792064 -376.501169) (xy 87.823214 -376.560966) (xy 87.846977 -376.624063)
			(xy 87.863012 -376.689553) (xy 87.871088 -376.756491) (xy 87.871087 -376.823915) (xy 117.548863 -376.823915)
			(xy 117.548863 -376.756491) (xy 117.556939 -376.689552) (xy 117.572976 -376.624062) (xy 117.596742 -376.560965)
			(xy 117.627895 -376.50117) (xy 117.665986 -376.445536) (xy 117.687852 -376.419872) (xy 117.693649 -376.412728)
			(xy 117.700162 -376.395536) (xy 117.700552 -376.386344) (xy 117.700552 -375.894092) (xy 117.700134 -375.884906)
			(xy 117.693625 -375.867722) (xy 117.687852 -375.860564) (xy 117.666018 -375.834874) (xy 117.627925 -375.779244)
			(xy 117.59677 -375.719452) (xy 117.573001 -375.656358) (xy 117.556962 -375.590871) (xy 117.548883 -375.523935)
			(xy 117.54888 -375.456513) (xy 117.556953 -375.389576) (xy 117.572987 -375.324088) (xy 117.59675 -375.260992)
			(xy 117.6279 -375.201197) (xy 117.665988 -375.145564) (xy 117.687852 -375.1199) (xy 117.693638 -375.112747)
			(xy 117.700157 -375.095562) (xy 117.700552 -375.086372) (xy 117.700552 -374.928638) (xy 117.701058 -374.918512)
			(xy 117.708776 -374.89979) (xy 117.723056 -374.885432) (xy 117.741737 -374.877613) (xy 117.75186 -374.877076)
			(xy 118.46814 -374.877076) (xy 118.478294 -374.877488) (xy 118.497042 -374.885293) (xy 118.511363 -374.899691)
			(xy 118.519066 -374.918482) (xy 118.519448 -374.928638) (xy 118.519448 -375.086372) (xy 118.519883 -375.095556)
			(xy 118.526381 -375.11274) (xy 118.532148 -375.1199) (xy 118.554045 -375.145538) (xy 118.592136 -375.201176)
			(xy 118.623289 -375.260975) (xy 118.647053 -375.324075) (xy 118.663088 -375.389568) (xy 118.671162 -375.45651)
			(xy 118.671159 -375.523938) (xy 118.66308 -375.590879) (xy 118.647039 -375.656371) (xy 118.623269 -375.719469)
			(xy 118.592112 -375.779266) (xy 118.554016 -375.8349) (xy 118.532148 -375.860564) (xy 118.526335 -375.867698)
			(xy 118.519832 -375.884897) (xy 118.519448 -375.894092) (xy 118.519448 -376.386344) (xy 118.519849 -376.395532)
			(xy 118.52637 -376.412715) (xy 118.532148 -376.419872) (xy 118.554018 -376.445533) (xy 118.59211 -376.501167)
			(xy 118.623263 -376.560963) (xy 118.647029 -376.624061) (xy 118.663066 -376.689551) (xy 118.671143 -376.75649)
			(xy 118.671143 -376.756551) (xy 121.949182 -376.756551) (xy 121.957226 -376.689728) (xy 121.973199 -376.624346)
			(xy 121.996871 -376.561342) (xy 122.027904 -376.501618) (xy 122.065852 -376.446032) (xy 122.08764 -376.42038)
			(xy 122.093433 -376.413232) (xy 122.099949 -376.396044) (xy 122.10034 -376.386852) (xy 122.10034 -375.893584)
			(xy 122.099929 -375.884397) (xy 122.093415 -375.867213) (xy 122.08764 -375.860056) (xy 122.065884 -375.834378)
			(xy 122.027934 -375.778795) (xy 121.996899 -375.719075) (xy 121.973225 -375.656074) (xy 121.95725 -375.590695)
			(xy 121.949203 -375.523875) (xy 121.9492 -375.456573) (xy 121.957241 -375.389752) (xy 121.973211 -375.324372)
			(xy 121.99688 -375.261369) (xy 122.027909 -375.201646) (xy 122.065854 -375.14606) (xy 122.08764 -375.120408)
			(xy 122.093421 -375.113252) (xy 122.099944 -375.09607) (xy 122.10034 -375.08688) (xy 122.10034 -374.928638)
			(xy 122.100795 -374.918469) (xy 122.108568 -374.899674) (xy 122.122944 -374.885288) (xy 122.141733 -374.877502)
			(xy 122.151902 -374.877076) (xy 122.868182 -374.877076) (xy 122.878357 -374.877479) (xy 122.897159 -374.885265)
			(xy 122.911546 -374.899658) (xy 122.919325 -374.918463) (xy 122.919744 -374.928638) (xy 122.919744 -375.08688)
			(xy 122.920176 -375.096065) (xy 122.926676 -375.113249) (xy 122.932444 -375.120408) (xy 122.954264 -375.146034)
			(xy 122.992213 -375.201624) (xy 123.023246 -375.261351) (xy 123.046917 -375.324359) (xy 123.062889 -375.389744)
			(xy 123.070931 -375.45657) (xy 123.070928 -375.523878) (xy 123.06288 -375.590703) (xy 123.046903 -375.656087)
			(xy 123.023226 -375.719093) (xy 122.992188 -375.778818) (xy 122.954234 -375.834404) (xy 122.932444 -375.860056)
			(xy 122.926634 -375.867192) (xy 122.920129 -375.88439) (xy 122.919744 -375.893584) (xy 122.919744 -376.386852)
			(xy 122.92019 -376.396035) (xy 122.92668 -376.413219) (xy 122.932444 -376.42038) (xy 122.954236 -376.446029)
			(xy 122.992186 -376.501615) (xy 123.02322 -376.561339) (xy 123.046893 -376.624344) (xy 123.062866 -376.689727)
			(xy 123.07091 -376.75655) (xy 123.07091 -376.823856) (xy 123.070903 -376.823915) (xy 126.348951 -376.823915)
			(xy 126.348951 -376.756491) (xy 126.357027 -376.689552) (xy 126.373063 -376.624063) (xy 126.396828 -376.560966)
			(xy 126.42798 -376.50117) (xy 126.466071 -376.445537) (xy 126.487936 -376.419872) (xy 126.493732 -376.412726)
			(xy 126.500246 -376.395536) (xy 126.500636 -376.386344) (xy 126.500636 -375.894092) (xy 126.500222 -375.884905)
			(xy 126.49371 -375.867721) (xy 126.487936 -375.860564) (xy 126.466102 -375.834873) (xy 126.42801 -375.779243)
			(xy 126.396856 -375.719451) (xy 126.373088 -375.656357) (xy 126.35705 -375.590871) (xy 126.348971 -375.523935)
			(xy 126.348968 -375.456513) (xy 126.357041 -375.389576) (xy 126.373074 -375.324089) (xy 126.396836 -375.260993)
			(xy 126.427985 -375.201198) (xy 126.466073 -375.145565) (xy 126.487936 -375.1199) (xy 126.49372 -375.112746)
			(xy 126.500241 -375.095562) (xy 126.500636 -375.086372) (xy 126.500636 -374.928638) (xy 126.501158 -374.918514)
			(xy 126.508872 -374.899795) (xy 126.523148 -374.885437) (xy 126.541823 -374.877616) (xy 126.551944 -374.877076)
			(xy 127.268224 -374.877076) (xy 127.278377 -374.877501) (xy 127.297125 -374.8853) (xy 127.311447 -374.899695)
			(xy 127.31915 -374.918483) (xy 127.319532 -374.928638) (xy 127.319532 -375.086372) (xy 127.319971 -375.095556)
			(xy 127.326466 -375.11274) (xy 127.332232 -375.1199) (xy 127.354126 -375.14554) (xy 127.392212 -375.201179)
			(xy 127.423359 -375.260979) (xy 127.44712 -375.324079) (xy 127.463153 -375.389571) (xy 127.471226 -375.456511)
			(xy 127.471223 -375.523937) (xy 127.463144 -375.590877) (xy 127.447106 -375.656367) (xy 127.42334 -375.719465)
			(xy 127.392187 -375.779263) (xy 127.354097 -375.834898) (xy 127.332232 -375.860564) (xy 127.326417 -375.867696)
			(xy 127.319915 -375.884897) (xy 127.319532 -375.894092) (xy 127.319532 -376.386344) (xy 127.319936 -376.395532)
			(xy 127.326456 -376.412715) (xy 127.332232 -376.419872) (xy 127.354099 -376.445535) (xy 127.392185 -376.50117)
			(xy 127.423334 -376.560967) (xy 127.447097 -376.624064) (xy 127.463131 -376.689553) (xy 127.471206 -376.756491)
			(xy 127.471206 -376.756551) (xy 130.74927 -376.756551) (xy 130.757314 -376.689729) (xy 130.773286 -376.624347)
			(xy 130.796958 -376.561343) (xy 130.827989 -376.501619) (xy 130.865937 -376.446032) (xy 130.887724 -376.42038)
			(xy 130.893514 -376.413231) (xy 130.900032 -376.396043) (xy 130.900424 -376.386852) (xy 130.900424 -375.893584)
			(xy 130.900016 -375.884397) (xy 130.8935 -375.867213) (xy 130.887724 -375.860056) (xy 130.865968 -375.834378)
			(xy 130.82802 -375.778795) (xy 130.796986 -375.719074) (xy 130.773312 -375.656073) (xy 130.757337 -375.590695)
			(xy 130.749291 -375.523875) (xy 130.749288 -375.456573) (xy 130.757329 -375.389753) (xy 130.773298 -375.324373)
			(xy 130.796966 -375.26137) (xy 130.827995 -375.201647) (xy 130.865939 -375.146061) (xy 130.887724 -375.120408)
			(xy 130.893502 -375.11325) (xy 130.900027 -375.096069) (xy 130.900424 -375.08688) (xy 130.900424 -374.928638)
			(xy 130.900895 -374.918471) (xy 130.908665 -374.899679) (xy 130.923036 -374.885294) (xy 130.941819 -374.877505)
			(xy 130.951986 -374.877076) (xy 131.668266 -374.877076) (xy 131.67844 -374.877493) (xy 131.697241 -374.885274)
			(xy 131.711629 -374.899662) (xy 131.719408 -374.918464) (xy 131.719828 -374.928638) (xy 131.719828 -375.08688)
			(xy 131.720241 -375.096067) (xy 131.726752 -375.113252) (xy 131.732528 -375.120408) (xy 131.754348 -375.146034)
			(xy 131.792298 -375.201623) (xy 131.823332 -375.26135) (xy 131.847005 -375.324358) (xy 131.862976 -375.389744)
			(xy 131.871018 -375.45657) (xy 131.871016 -375.523878) (xy 131.862968 -375.590704) (xy 131.84699 -375.656088)
			(xy 131.823313 -375.719094) (xy 131.792274 -375.778818) (xy 131.754319 -375.834404) (xy 131.732528 -375.860056)
			(xy 131.726716 -375.86719) (xy 131.720213 -375.884389) (xy 131.719828 -375.893584) (xy 131.719828 -376.386852)
			(xy 131.720255 -376.396037) (xy 131.726756 -376.413222) (xy 131.732528 -376.42038) (xy 131.754321 -376.446029)
			(xy 131.792271 -376.501615) (xy 131.823306 -376.561338) (xy 131.84698 -376.624344) (xy 131.862954 -376.689727)
			(xy 131.870991 -376.756492) (xy 161.548796 -376.756492) (xy 161.556871 -376.689554) (xy 161.572905 -376.624066)
			(xy 161.596667 -376.560969) (xy 161.627816 -376.501173) (xy 161.665902 -376.445538) (xy 161.687764 -376.419872)
			(xy 161.693563 -376.412729) (xy 161.700074 -376.395536) (xy 161.700464 -376.386344) (xy 161.700464 -375.894092)
			(xy 161.700043 -375.884906) (xy 161.693535 -375.867723) (xy 161.687764 -375.860564) (xy 161.665933 -375.834872)
			(xy 161.627845 -375.779241) (xy 161.596695 -375.719448) (xy 161.572931 -375.656354) (xy 161.556894 -375.590869)
			(xy 161.548816 -375.523934) (xy 161.548814 -375.456514) (xy 161.556886 -375.389578) (xy 161.572917 -375.324092)
			(xy 161.596676 -375.260996) (xy 161.627821 -375.201201) (xy 161.665903 -375.145566) (xy 161.687764 -375.1199)
			(xy 161.693551 -375.112748) (xy 161.70007 -375.095562) (xy 161.700464 -375.086372) (xy 161.700464 -374.928638)
			(xy 161.700959 -374.918511) (xy 161.708678 -374.899786) (xy 161.722963 -374.885428) (xy 161.741647 -374.877611)
			(xy 161.751772 -374.877076) (xy 162.468052 -374.877076) (xy 162.478168 -374.877555) (xy 162.496866 -374.885283)
			(xy 162.511181 -374.89958) (xy 162.518933 -374.918268) (xy 162.51936 -374.928384) (xy 162.51936 -375.086372)
			(xy 162.519793 -375.095557) (xy 162.526292 -375.112741) (xy 162.53206 -375.1199) (xy 162.553957 -375.145539)
			(xy 162.592047 -375.201176) (xy 162.623199 -375.260976) (xy 162.646963 -375.324076) (xy 162.662997 -375.389569)
			(xy 162.671071 -375.456511) (xy 162.671068 -375.523938) (xy 162.662989 -375.590879) (xy 162.646949 -375.65637)
			(xy 162.623179 -375.719468) (xy 162.592022 -375.779265) (xy 162.553927 -375.834899) (xy 162.53206 -375.860564)
			(xy 162.526249 -375.867699) (xy 162.519744 -375.884897) (xy 162.51936 -375.894092) (xy 162.51936 -376.386344)
			(xy 162.519758 -376.395532) (xy 162.526281 -376.412716) (xy 162.53206 -376.419872) (xy 162.553929 -376.445533)
			(xy 162.592021 -376.501167) (xy 162.623173 -376.560964) (xy 162.646939 -376.624061) (xy 162.662975 -376.689551)
			(xy 162.671052 -376.756491) (xy 162.671051 -376.823855) (xy 165.949092 -376.823855) (xy 165.949092 -376.756551)
			(xy 165.957136 -376.689728) (xy 165.973109 -376.624346) (xy 165.996782 -376.561342) (xy 166.027815 -376.501618)
			(xy 166.065764 -376.446032) (xy 166.087552 -376.42038) (xy 166.093346 -376.413233) (xy 166.099861 -376.396044)
			(xy 166.100252 -376.386852) (xy 166.100252 -375.893584) (xy 166.099838 -375.884397) (xy 166.093326 -375.867214)
			(xy 166.087552 -375.860056) (xy 166.065795 -375.834378) (xy 166.027845 -375.778796) (xy 165.996809 -375.719076)
			(xy 165.973134 -375.656075) (xy 165.957159 -375.590695) (xy 165.949112 -375.523875) (xy 165.949109 -375.456573)
			(xy 165.95715 -375.389752) (xy 165.97312 -375.324371) (xy 165.99679 -375.261368) (xy 166.02782 -375.201646)
			(xy 166.065766 -375.14606) (xy 166.087552 -375.120408) (xy 166.093334 -375.113253) (xy 166.099856 -375.09607)
			(xy 166.100252 -375.08688) (xy 166.100252 -374.928638) (xy 166.100695 -374.918467) (xy 166.10847 -374.899671)
			(xy 166.12285 -374.885284) (xy 166.141643 -374.8775) (xy 166.151814 -374.877076) (xy 166.868094 -374.877076)
			(xy 166.87827 -374.87747) (xy 166.897072 -374.88526) (xy 166.911458 -374.899655) (xy 166.919237 -374.918462)
			(xy 166.919656 -374.928638) (xy 166.919656 -375.08688) (xy 166.920085 -375.096065) (xy 166.926587 -375.113249)
			(xy 166.932356 -375.120408) (xy 166.954175 -375.146034) (xy 166.992124 -375.201624) (xy 167.023156 -375.261351)
			(xy 167.046827 -375.324359) (xy 167.062798 -375.389745) (xy 167.07084 -375.45657) (xy 167.070837 -375.523878)
			(xy 167.062789 -375.590703) (xy 167.046813 -375.656087) (xy 167.023136 -375.719093) (xy 166.992099 -375.778817)
			(xy 166.954146 -375.834404) (xy 166.932356 -375.860056) (xy 166.926548 -375.867193) (xy 166.920041 -375.88439)
			(xy 166.919656 -375.893584) (xy 166.919656 -376.386852) (xy 166.920099 -376.396035) (xy 166.926591 -376.41322)
			(xy 166.932356 -376.42038) (xy 166.954148 -376.446029) (xy 166.992097 -376.501616) (xy 167.02313 -376.56134)
			(xy 167.046803 -376.624345) (xy 167.062776 -376.689727) (xy 167.07082 -376.75655) (xy 167.07082 -376.823856)
			(xy 167.070813 -376.823915) (xy 170.34886 -376.823915) (xy 170.34886 -376.756491) (xy 170.356936 -376.689552)
			(xy 170.372972 -376.624063) (xy 170.396738 -376.560966) (xy 170.427891 -376.50117) (xy 170.465983 -376.445536)
			(xy 170.487848 -376.419872) (xy 170.493645 -376.412727) (xy 170.500158 -376.395536) (xy 170.500548 -376.386344)
			(xy 170.500548 -375.894092) (xy 170.500131 -375.884906) (xy 170.493621 -375.867722) (xy 170.487848 -375.860564)
			(xy 170.466014 -375.834874) (xy 170.427921 -375.779244) (xy 170.396766 -375.719452) (xy 170.372998 -375.656358)
			(xy 170.356959 -375.590871) (xy 170.34888 -375.523935) (xy 170.348877 -375.456513) (xy 170.35695 -375.389576)
			(xy 170.372984 -375.324088) (xy 170.396747 -375.260992) (xy 170.427896 -375.201197) (xy 170.465984 -375.145564)
			(xy 170.487848 -375.1199) (xy 170.493633 -375.112747) (xy 170.500153 -375.095562) (xy 170.500548 -375.086372)
			(xy 170.500548 -374.928638) (xy 170.501058 -374.918513) (xy 170.508775 -374.899791) (xy 170.523054 -374.885433)
			(xy 170.541734 -374.877614) (xy 170.551856 -374.877076) (xy 171.268136 -374.877076) (xy 171.278289 -374.877492)
			(xy 171.297038 -374.885295) (xy 171.311359 -374.899692) (xy 171.319062 -374.918482) (xy 171.319444 -374.928638)
			(xy 171.319444 -375.086372) (xy 171.31988 -375.095556) (xy 171.326377 -375.11274) (xy 171.332144 -375.1199)
			(xy 171.354041 -375.145538) (xy 171.392133 -375.201175) (xy 171.423285 -375.260975) (xy 171.44705 -375.324075)
			(xy 171.463085 -375.389568) (xy 171.471159 -375.45651) (xy 171.471156 -375.523938) (xy 171.463076 -375.590879)
			(xy 171.447036 -375.656371) (xy 171.423266 -375.719469) (xy 171.392108 -375.779266) (xy 171.354012 -375.8349)
			(xy 171.332144 -375.860564) (xy 171.326331 -375.867697) (xy 171.319828 -375.884897) (xy 171.319444 -375.894092)
			(xy 171.319444 -376.386344) (xy 171.319845 -376.395532) (xy 171.326366 -376.412716) (xy 171.332144 -376.419872)
			(xy 171.354014 -376.445533) (xy 171.392106 -376.501167) (xy 171.42326 -376.560963) (xy 171.447026 -376.624061)
			(xy 171.463063 -376.689551) (xy 171.47114 -376.75649) (xy 171.47114 -376.756551) (xy 174.749179 -376.756551)
			(xy 174.757223 -376.689728) (xy 174.773195 -376.624346) (xy 174.796868 -376.561342) (xy 174.8279 -376.501619)
			(xy 174.865848 -376.446032) (xy 174.887636 -376.42038) (xy 174.893428 -376.413232) (xy 174.899945 -376.396043)
			(xy 174.900336 -376.386852) (xy 174.900336 -375.893584) (xy 174.899926 -375.884397) (xy 174.893411 -375.867213)
			(xy 174.887636 -375.860056) (xy 174.86588 -375.834378) (xy 174.82793 -375.778795) (xy 174.796896 -375.719075)
			(xy 174.773222 -375.656074) (xy 174.757246 -375.590695) (xy 174.7492 -375.523875) (xy 174.749197 -375.456573)
			(xy 174.757238 -375.389752) (xy 174.773207 -375.324372) (xy 174.796876 -375.261369) (xy 174.827906 -375.201646)
			(xy 174.865851 -375.14606) (xy 174.887636 -375.120408) (xy 174.893416 -375.113251) (xy 174.89994 -375.096069)
			(xy 174.900336 -375.08688) (xy 174.900336 -374.928638) (xy 174.900795 -374.918469) (xy 174.908567 -374.899676)
			(xy 174.922942 -374.88529) (xy 174.941729 -374.877503) (xy 174.951898 -374.877076) (xy 175.668178 -374.877076)
			(xy 175.678353 -374.877483) (xy 175.697154 -374.885268) (xy 175.711541 -374.899659) (xy 175.71932 -374.918463)
			(xy 175.71974 -374.928638) (xy 175.71974 -375.08688) (xy 175.720173 -375.096064) (xy 175.726672 -375.113248)
			(xy 175.73244 -375.120408) (xy 175.75426 -375.146034) (xy 175.792209 -375.201624) (xy 175.823242 -375.261351)
			(xy 175.846914 -375.324359) (xy 175.862886 -375.389744) (xy 175.870928 -375.45657) (xy 175.870925 -375.523878)
			(xy 175.862877 -375.590703) (xy 175.8469 -375.656087) (xy 175.823223 -375.719093) (xy 175.792185 -375.778818)
			(xy 175.754231 -375.834404) (xy 175.73244 -375.860056) (xy 175.72663 -375.867191) (xy 175.720125 -375.88439)
			(xy 175.71974 -375.893584) (xy 175.71974 -376.386852) (xy 175.720186 -376.396035) (xy 175.726676 -376.413219)
			(xy 175.73244 -376.42038) (xy 175.754232 -376.446029) (xy 175.792182 -376.501615) (xy 175.823216 -376.561339)
			(xy 175.84689 -376.624344) (xy 175.862863 -376.689727) (xy 175.870907 -376.75655) (xy 175.870907 -376.823856)
			(xy 175.862862 -376.890679) (xy 175.846888 -376.956062) (xy 175.823214 -377.019066) (xy 175.792179 -377.07879)
			(xy 175.754228 -377.134376) (xy 175.73244 -377.160028) (xy 175.726642 -377.167172) (xy 175.72013 -377.184364)
			(xy 175.71974 -377.193556) (xy 175.71974 -377.35129) (xy 175.719328 -377.361464) (xy 175.711542 -377.380262)
			(xy 175.697152 -377.394648) (xy 175.678352 -377.40243) (xy 175.668178 -377.402852) (xy 174.951898 -377.402852)
			(xy 174.941725 -377.402438) (xy 174.922928 -377.39465) (xy 174.908543 -377.380262) (xy 174.90076 -377.361463)
			(xy 174.900336 -377.35129) (xy 174.900336 -377.193556) (xy 174.899939 -377.184368) (xy 174.893415 -377.167184)
			(xy 174.887636 -377.160028) (xy 174.865852 -377.134373) (xy 174.827903 -377.078787) (xy 174.79687 -377.019063)
			(xy 174.773197 -376.956059) (xy 174.757224 -376.890678) (xy 174.74918 -376.823855) (xy 174.749179 -376.756551)
			(xy 171.47114 -376.756551) (xy 171.471139 -376.823916) (xy 171.463062 -376.890855) (xy 171.447024 -376.956345)
			(xy 171.423257 -377.019442) (xy 171.392103 -377.079238) (xy 171.35401 -377.134872) (xy 171.332144 -377.160536)
			(xy 171.326343 -377.167678) (xy 171.319832 -377.184871) (xy 171.319444 -377.194064) (xy 171.319444 -377.35129)
			(xy 171.318965 -377.361418) (xy 171.311237 -377.380142) (xy 171.296948 -377.394499) (xy 171.278262 -377.402316)
			(xy 171.268136 -377.402852) (xy 170.551856 -377.402852) (xy 170.541706 -377.402415) (xy 170.522962 -377.394615)
			(xy 170.508642 -377.380224) (xy 170.500935 -377.361442) (xy 170.500548 -377.35129) (xy 170.500548 -377.194064)
			(xy 170.500144 -377.184876) (xy 170.493625 -377.167693) (xy 170.487848 -377.160536) (xy 170.465986 -377.134868)
			(xy 170.427894 -377.079235) (xy 170.396741 -377.01944) (xy 170.372974 -376.956343) (xy 170.356937 -376.890854)
			(xy 170.34886 -376.823915) (xy 167.070813 -376.823915) (xy 167.062775 -376.890679) (xy 167.046801 -376.956061)
			(xy 167.023128 -377.019066) (xy 166.992094 -377.07879) (xy 166.954144 -377.134376) (xy 166.932356 -377.160028)
			(xy 166.92656 -377.167173) (xy 166.920046 -377.184364) (xy 166.919656 -377.193556) (xy 166.919656 -377.35129)
			(xy 166.919228 -377.361462) (xy 166.911445 -377.380257) (xy 166.897061 -377.394643) (xy 166.878266 -377.402427)
			(xy 166.868094 -377.402852) (xy 166.151814 -377.402852) (xy 166.141642 -377.402425) (xy 166.122846 -377.394642)
			(xy 166.10846 -377.380258) (xy 166.100676 -377.361462) (xy 166.100252 -377.35129) (xy 166.100252 -377.193556)
			(xy 166.099851 -377.184368) (xy 166.09333 -377.167185) (xy 166.087552 -377.160028) (xy 166.065768 -377.134373)
			(xy 166.027818 -377.078787) (xy 165.996784 -377.019064) (xy 165.97311 -376.95606) (xy 165.957137 -376.890678)
			(xy 165.949092 -376.823855) (xy 162.671051 -376.823855) (xy 162.671051 -376.823915) (xy 162.662974 -376.890855)
			(xy 162.646937 -376.956344) (xy 162.623171 -377.019442) (xy 162.592017 -377.079238) (xy 162.553926 -377.134871)
			(xy 162.53206 -377.160536) (xy 162.526261 -377.167679) (xy 162.519749 -377.184871) (xy 162.51936 -377.194064)
			(xy 162.51936 -377.35129) (xy 162.518865 -377.361416) (xy 162.511141 -377.380137) (xy 162.496857 -377.394494)
			(xy 162.478175 -377.402313) (xy 162.468052 -377.402852) (xy 161.751772 -377.402852) (xy 161.741668 -377.402339)
			(xy 161.722999 -377.394602) (xy 161.708707 -377.380314) (xy 161.700964 -377.361648) (xy 161.700464 -377.351544)
			(xy 161.700464 -377.194064) (xy 161.700057 -377.184877) (xy 161.69354 -377.167693) (xy 161.687764 -377.160536)
			(xy 161.665905 -377.134867) (xy 161.627819 -377.079232) (xy 161.59667 -377.019436) (xy 161.572907 -376.95634)
			(xy 161.556872 -376.890852) (xy 161.548797 -376.823914) (xy 161.548796 -376.756492) (xy 131.870991 -376.756492)
			(xy 131.870998 -376.75655) (xy 131.870998 -376.823856) (xy 131.862953 -376.890679) (xy 131.846979 -376.956062)
			(xy 131.823304 -377.019067) (xy 131.792268 -377.07879) (xy 131.754317 -377.134376) (xy 131.732528 -377.160028)
			(xy 131.726728 -377.167171) (xy 131.720218 -377.184363) (xy 131.719828 -377.193556) (xy 131.719828 -377.35129)
			(xy 131.719427 -377.361465) (xy 131.711639 -377.380266) (xy 131.697246 -377.394653) (xy 131.678441 -377.402432)
			(xy 131.668266 -377.402852) (xy 130.951986 -377.402852) (xy 130.941826 -377.402378) (xy 130.923055 -377.394597)
			(xy 130.90869 -377.380225) (xy 130.900918 -377.36145) (xy 130.900424 -377.35129) (xy 130.900424 -377.193556)
			(xy 130.90003 -377.184367) (xy 130.893504 -377.167183) (xy 130.887724 -377.160028) (xy 130.865941 -377.134372)
			(xy 130.827993 -377.078786) (xy 130.79696 -377.019063) (xy 130.773288 -376.956059) (xy 130.757315 -376.890677)
			(xy 130.749271 -376.823855) (xy 130.74927 -376.756551) (xy 127.471206 -376.756551) (xy 127.471205 -376.823915)
			(xy 127.46313 -376.890853) (xy 127.447095 -376.956342) (xy 127.423332 -377.019438) (xy 127.392182 -377.079235)
			(xy 127.354095 -377.13487) (xy 127.332232 -377.160536) (xy 127.326429 -377.167677) (xy 127.31992 -377.184871)
			(xy 127.319532 -377.194064) (xy 127.319532 -377.35129) (xy 127.319064 -377.36142) (xy 127.311335 -377.380146)
			(xy 127.297042 -377.394503) (xy 127.278351 -377.402318) (xy 127.268224 -377.402852) (xy 126.551944 -377.402852)
			(xy 126.541799 -377.402343) (xy 126.523058 -377.394572) (xy 126.508735 -377.380202) (xy 126.501024 -377.361436)
			(xy 126.500636 -377.35129) (xy 126.500636 -377.194064) (xy 126.500235 -377.184876) (xy 126.493714 -377.167692)
			(xy 126.487936 -377.160536) (xy 126.466075 -377.134868) (xy 126.427984 -377.079235) (xy 126.396831 -377.019439)
			(xy 126.373065 -376.956343) (xy 126.357028 -376.890854) (xy 126.348951 -376.823915) (xy 123.070903 -376.823915)
			(xy 123.062865 -376.890679) (xy 123.046891 -376.956062) (xy 123.023217 -377.019066) (xy 122.992183 -377.07879)
			(xy 122.954232 -377.134376) (xy 122.932444 -377.160028) (xy 122.926646 -377.167172) (xy 122.920134 -377.184364)
			(xy 122.919744 -377.193556) (xy 122.919744 -377.35129) (xy 122.919328 -377.361463) (xy 122.911543 -377.380261)
			(xy 122.897154 -377.394647) (xy 122.878355 -377.402429) (xy 122.868182 -377.402852) (xy 122.151902 -377.402852)
			(xy 122.141729 -377.402434) (xy 122.122933 -377.394648) (xy 122.108547 -377.380261) (xy 122.100764 -377.361463)
			(xy 122.10034 -377.35129) (xy 122.10034 -377.193556) (xy 122.099942 -377.184368) (xy 122.093419 -377.167184)
			(xy 122.08764 -377.160028) (xy 122.065856 -377.134373) (xy 122.027907 -377.078787) (xy 121.996873 -377.019064)
			(xy 121.9732 -376.95606) (xy 121.957227 -376.890678) (xy 121.949183 -376.823855) (xy 121.949182 -376.756551)
			(xy 118.671143 -376.756551) (xy 118.671142 -376.823916) (xy 118.663065 -376.890855) (xy 118.647028 -376.956345)
			(xy 118.623261 -377.019442) (xy 118.592107 -377.079238) (xy 118.554014 -377.134872) (xy 118.532148 -377.160536)
			(xy 118.526347 -377.167678) (xy 118.519836 -377.184871) (xy 118.519448 -377.194064) (xy 118.519448 -377.35129)
			(xy 118.518965 -377.361418) (xy 118.511238 -377.380141) (xy 118.496951 -377.394498) (xy 118.478265 -377.402315)
			(xy 118.46814 -377.402852) (xy 117.75186 -377.402852) (xy 117.74171 -377.402412) (xy 117.722967 -377.394613)
			(xy 117.708647 -377.380223) (xy 117.700939 -377.361442) (xy 117.700552 -377.35129) (xy 117.700552 -377.194064)
			(xy 117.700147 -377.184876) (xy 117.693628 -377.167693) (xy 117.687852 -377.160536) (xy 117.66599 -377.134868)
			(xy 117.627898 -377.079235) (xy 117.596744 -377.01944) (xy 117.572977 -376.956343) (xy 117.55694 -376.890854)
			(xy 117.548863 -376.823915) (xy 87.871087 -376.823915) (xy 87.863011 -376.890853) (xy 87.846976 -376.956342)
			(xy 87.823211 -377.019439) (xy 87.792061 -377.079236) (xy 87.753972 -377.134871) (xy 87.732108 -377.160536)
			(xy 87.726315 -377.167684) (xy 87.719798 -377.184872) (xy 87.719408 -377.194064) (xy 87.719408 -377.35129)
			(xy 87.718867 -377.36141) (xy 87.711151 -377.380122) (xy 87.696882 -377.394477) (xy 87.678217 -377.402305)
			(xy 87.6681 -377.402852) (xy 86.95182 -377.402852) (xy 86.941719 -377.4023) (xy 86.923051 -377.394578)
			(xy 86.908757 -377.380303) (xy 86.901013 -377.361644) (xy 86.900512 -377.351544) (xy 86.900512 -377.194064)
			(xy 86.900117 -377.184875) (xy 86.893592 -377.167691) (xy 86.887812 -377.160536) (xy 86.865952 -377.134868)
			(xy 86.827862 -377.079234) (xy 86.79671 -377.019438) (xy 86.772945 -376.956342) (xy 86.756909 -376.890853)
			(xy 86.748833 -376.823915) (xy 83.470785 -376.823915) (xy 83.462747 -376.89068) (xy 83.446772 -376.956063)
			(xy 83.423097 -377.019067) (xy 83.392061 -377.078791) (xy 83.354109 -377.134376) (xy 83.33232 -377.160028)
			(xy 83.326531 -377.167179) (xy 83.320011 -377.184365) (xy 83.31962 -377.193556) (xy 83.31962 -377.35129)
			(xy 83.319227 -377.361466) (xy 83.311438 -377.380269) (xy 83.297042 -377.394655) (xy 83.278234 -377.402433)
			(xy 83.268058 -377.402852) (xy 82.551778 -377.402852) (xy 82.541618 -377.402385) (xy 82.522846 -377.394601)
			(xy 82.508481 -377.380227) (xy 82.500709 -377.361451) (xy 82.500216 -377.35129) (xy 82.500216 -377.193556)
			(xy 82.499823 -377.184367) (xy 82.493297 -377.167183) (xy 82.487516 -377.160028) (xy 82.465733 -377.134372)
			(xy 82.427785 -377.078786) (xy 82.396753 -377.019063) (xy 82.373081 -376.956059) (xy 82.357109 -376.890677)
			(xy 82.349065 -376.823855) (xy 82.349064 -376.756551) (xy 79.071 -376.756551) (xy 79.070999 -376.823915)
			(xy 79.062924 -376.890853) (xy 79.046888 -376.956342) (xy 79.023125 -377.019439) (xy 78.991975 -377.079235)
			(xy 78.953887 -377.13487) (xy 78.932024 -377.160536) (xy 78.926232 -377.167685) (xy 78.919714 -377.184872)
			(xy 78.919324 -377.194064) (xy 78.919324 -377.35129) (xy 78.918864 -377.36142) (xy 78.911133 -377.380148)
			(xy 78.896838 -377.394506) (xy 78.878144 -377.402319) (xy 78.868016 -377.402852) (xy 78.151736 -377.402852)
			(xy 78.141636 -377.402286) (xy 78.122969 -377.39457) (xy 78.108674 -377.380299) (xy 78.100929 -377.361643)
			(xy 78.100428 -377.351544) (xy 78.100428 -377.194064) (xy 78.100029 -377.184876) (xy 78.093507 -377.167692)
			(xy 78.087728 -377.160536) (xy 78.065867 -377.134868) (xy 78.027776 -377.079235) (xy 77.996624 -377.019439)
			(xy 77.972858 -376.956342) (xy 77.956822 -376.890853) (xy 77.948745 -376.823915) (xy 74.670697 -376.823915)
			(xy 74.662659 -376.890679) (xy 74.646685 -376.956062) (xy 74.623011 -377.019067) (xy 74.591976 -377.07879)
			(xy 74.554025 -377.134376) (xy 74.532236 -377.160028) (xy 74.526437 -377.167171) (xy 74.519926 -377.184364)
			(xy 74.519536 -377.193556) (xy 74.519536 -377.35129) (xy 74.519127 -377.361464) (xy 74.511341 -377.380264)
			(xy 74.49695 -377.39465) (xy 74.478148 -377.402431) (xy 74.467974 -377.402852) (xy 73.751694 -377.402852)
			(xy 73.741521 -377.402441) (xy 73.722724 -377.394652) (xy 73.708339 -377.380263) (xy 73.700556 -377.361463)
			(xy 73.700132 -377.35129) (xy 73.700132 -377.193556) (xy 73.699736 -377.184367) (xy 73.693212 -377.167184)
			(xy 73.687432 -377.160028) (xy 73.665648 -377.134373) (xy 73.6277 -377.078786) (xy 73.596667 -377.019063)
			(xy 73.572994 -376.956059) (xy 73.557021 -376.890677) (xy 73.548977 -376.823855) (xy 73.548976 -376.756551)
			(xy 48.270947 -376.756551) (xy 48.270947 -376.823855) (xy 48.262903 -376.890678) (xy 48.24693 -376.95606)
			(xy 48.223258 -377.019064) (xy 48.192226 -377.078788) (xy 48.154279 -377.134375) (xy 48.132492 -377.160028)
			(xy 48.1267 -377.167176) (xy 48.120183 -377.184365) (xy 48.119792 -377.193556) (xy 48.119792 -377.351544)
			(xy 48.119414 -377.361702) (xy 48.111603 -377.380457) (xy 48.097193 -377.394779) (xy 48.07839 -377.402476)
			(xy 48.06823 -377.402852) (xy 47.35195 -377.402852) (xy 47.341825 -377.402332) (xy 47.323104 -377.394619)
			(xy 47.308746 -377.380343) (xy 47.300926 -377.361666) (xy 47.300388 -377.351544) (xy 47.300388 -377.193556)
			(xy 47.300002 -377.184366) (xy 47.293472 -377.167182) (xy 47.287688 -377.160028) (xy 47.265903 -377.134373)
			(xy 47.227951 -377.078788) (xy 47.196914 -377.019066) (xy 47.173239 -376.956061) (xy 47.157265 -376.890679)
			(xy 47.149219 -376.823856) (xy 43.871178 -376.823856) (xy 43.871178 -376.823915) (xy 43.863102 -376.890854)
			(xy 43.847066 -376.956343) (xy 43.823301 -377.01944) (xy 43.79215 -377.079236) (xy 43.75406 -377.134871)
			(xy 43.732196 -377.160536) (xy 43.726401 -377.167682) (xy 43.719886 -377.184872) (xy 43.719496 -377.194064)
			(xy 43.719496 -377.35129) (xy 43.718966 -377.361412) (xy 43.711248 -377.380126) (xy 43.696976 -377.394481)
			(xy 43.678307 -377.402307) (xy 43.668188 -377.402852) (xy 42.951908 -377.402852) (xy 42.941761 -377.402373)
			(xy 42.923019 -377.39459) (xy 42.908697 -377.380211) (xy 42.900988 -377.361439) (xy 42.9006 -377.35129)
			(xy 42.9006 -377.194064) (xy 42.900207 -377.184875) (xy 42.893682 -377.167691) (xy 42.8879 -377.160536)
			(xy 42.86604 -377.134868) (xy 42.827951 -377.079233) (xy 42.7968 -377.019438) (xy 42.773036 -376.956341)
			(xy 42.757 -376.890853) (xy 42.748924 -376.823915) (xy 39.470876 -376.823915) (xy 39.462838 -376.89068)
			(xy 39.446863 -376.956063) (xy 39.423187 -377.019068) (xy 39.39215 -377.078791) (xy 39.354198 -377.134377)
			(xy 39.332408 -377.160028) (xy 39.326618 -377.167178) (xy 39.320099 -377.184365) (xy 39.319708 -377.193556)
			(xy 39.319708 -377.35129) (xy 39.31916 -377.361441) (xy 39.311397 -377.380202) (xy 39.297049 -377.394566)
			(xy 39.278297 -377.402349) (xy 39.268146 -377.402852) (xy 38.551866 -377.402852) (xy 38.541705 -377.402394)
			(xy 38.522933 -377.394607) (xy 38.508569 -377.38023) (xy 38.500797 -377.361452) (xy 38.500304 -377.35129)
			(xy 38.500304 -377.193556) (xy 38.499914 -377.184367) (xy 38.493386 -377.167183) (xy 38.487604 -377.160028)
			(xy 38.465821 -377.134372) (xy 38.427875 -377.078785) (xy 38.396843 -377.019062) (xy 38.373172 -376.956058)
			(xy 38.357199 -376.890677) (xy 38.349156 -376.823855) (xy 38.349155 -376.756551) (xy 35.071091 -376.756551)
			(xy 35.07109 -376.823915) (xy 35.063014 -376.890853) (xy 35.046979 -376.956342) (xy 35.023215 -377.019439)
			(xy 34.992064 -377.079236) (xy 34.953976 -377.134871) (xy 34.932112 -377.160536) (xy 34.926319 -377.167684)
			(xy 34.919802 -377.184872) (xy 34.919412 -377.194064) (xy 34.919412 -377.35129) (xy 34.918867 -377.36141)
			(xy 34.911152 -377.380121) (xy 34.896884 -377.394476) (xy 34.878221 -377.402304) (xy 34.868104 -377.402852)
			(xy 34.151824 -377.402852) (xy 34.141678 -377.40236) (xy 34.122936 -377.394582) (xy 34.108614 -377.380208)
			(xy 34.100904 -377.361438) (xy 34.100516 -377.35129) (xy 34.100516 -377.194064) (xy 34.10012 -377.184875)
			(xy 34.093596 -377.167691) (xy 34.087816 -377.160536) (xy 34.065955 -377.134868) (xy 34.027866 -377.079234)
			(xy 33.996714 -377.019438) (xy 33.972949 -376.956342) (xy 33.956912 -376.890853) (xy 33.948836 -376.823915)
			(xy 30.670788 -376.823915) (xy 30.66275 -376.89068) (xy 30.646775 -376.956062) (xy 30.6231 -377.019067)
			(xy 30.592065 -377.078791) (xy 30.554113 -377.134376) (xy 30.532324 -377.160028) (xy 30.526536 -377.167179)
			(xy 30.520015 -377.184365) (xy 30.519624 -377.193556) (xy 30.519624 -377.35129) (xy 30.519227 -377.361466)
			(xy 30.511438 -377.380267) (xy 30.497044 -377.394654) (xy 30.478238 -377.402433) (xy 30.468062 -377.402852)
			(xy 29.751782 -377.402852) (xy 29.741622 -377.402381) (xy 29.72285 -377.394599) (xy 29.708485 -377.380226)
			(xy 29.700713 -377.36145) (xy 29.70022 -377.35129) (xy 29.70022 -377.193556) (xy 29.699827 -377.184367)
			(xy 29.693301 -377.167183) (xy 29.68752 -377.160028) (xy 29.665737 -377.134372) (xy 29.627789 -377.078786)
			(xy 29.596757 -377.019063) (xy 29.573084 -376.956059) (xy 29.557112 -376.890677) (xy 29.549068 -376.823855)
			(xy 29.549067 -376.756551) (xy 0.508 -376.756551) (xy 0.508 -378.323793) (xy 27.348888 -378.323793)
			(xy 27.34889 -378.256368) (xy 27.356968 -378.189428) (xy 27.373006 -378.123938) (xy 27.396772 -378.06084)
			(xy 27.427925 -378.001043) (xy 27.466015 -377.945408) (xy 27.48788 -377.919742) (xy 27.493681 -377.9126)
			(xy 27.500194 -377.895407) (xy 27.50058 -377.886214) (xy 27.50058 -377.728734) (xy 27.501056 -377.718605)
			(xy 27.50878 -377.699877) (xy 27.52307 -377.685518) (xy 27.541761 -377.677705) (xy 27.551888 -377.677172)
			(xy 28.268168 -377.677172) (xy 28.278285 -377.677641) (xy 28.296983 -377.685374) (xy 28.311297 -377.699674)
			(xy 28.319048 -377.718363) (xy 28.319476 -377.72848) (xy 28.319476 -377.886214) (xy 28.319885 -377.895401)
			(xy 28.3264 -377.912585) (xy 28.332176 -377.919742) (xy 28.354015 -377.945428) (xy 28.392106 -378.001059)
			(xy 28.42326 -378.060852) (xy 28.447026 -378.123946) (xy 28.463064 -378.189433) (xy 28.471143 -378.256369)
			(xy 28.471145 -378.323734) (xy 31.749183 -378.323734) (xy 31.749186 -378.256427) (xy 31.757233 -378.189602)
			(xy 31.773209 -378.124218) (xy 31.796886 -378.061212) (xy 31.827924 -378.001488) (xy 31.865878 -377.945902)
			(xy 31.887668 -377.92025) (xy 31.893477 -377.913114) (xy 31.899982 -377.895916) (xy 31.900368 -377.886722)
			(xy 31.900368 -377.728734) (xy 31.900793 -377.718561) (xy 31.908572 -377.699761) (xy 31.922958 -377.685374)
			(xy 31.941757 -377.677593) (xy 31.95193 -377.677172) (xy 32.66821 -377.677172) (xy 32.678386 -377.677557)
			(xy 32.697188 -377.685351) (xy 32.711574 -377.699749) (xy 32.719352 -377.718557) (xy 32.719772 -377.728734)
			(xy 32.719772 -377.886722) (xy 32.720178 -377.89591) (xy 32.726695 -377.913094) (xy 32.732472 -377.92025)
			(xy 32.754234 -377.945924) (xy 32.792182 -378.001507) (xy 32.823216 -378.061228) (xy 32.84689 -378.12423)
			(xy 32.862864 -378.189609) (xy 32.87091 -378.256429) (xy 32.870913 -378.323732) (xy 32.870906 -378.323793)
			(xy 36.148976 -378.323793) (xy 36.148978 -378.256368) (xy 36.157056 -378.189429) (xy 36.173093 -378.123939)
			(xy 36.196859 -378.060841) (xy 36.22801 -378.001044) (xy 36.2661 -377.945408) (xy 36.287964 -377.919742)
			(xy 36.293775 -377.912608) (xy 36.300279 -377.895409) (xy 36.300664 -377.886214) (xy 36.300664 -377.728734)
			(xy 36.301155 -377.718607) (xy 36.308876 -377.699882) (xy 36.323162 -377.685523) (xy 36.341847 -377.677707)
			(xy 36.351972 -377.677172) (xy 37.068252 -377.677172) (xy 37.0784 -377.67766) (xy 37.097145 -377.685435)
			(xy 37.11147 -377.699811) (xy 37.119176 -377.718585) (xy 37.11956 -377.728734) (xy 37.11956 -377.886214)
			(xy 37.119972 -377.895401) (xy 37.126485 -377.912585) (xy 37.13226 -377.919742) (xy 37.1541 -377.945428)
			(xy 37.192192 -378.001058) (xy 37.223346 -378.060851) (xy 37.247113 -378.123946) (xy 37.263152 -378.189433)
			(xy 37.27123 -378.256369) (xy 37.271233 -378.323792) (xy 37.271233 -378.323794) (xy 40.548742 -378.323794)
			(xy 40.548744 -378.256367) (xy 40.556824 -378.189426) (xy 40.572863 -378.123935) (xy 40.596633 -378.060837)
			(xy 40.627789 -378.00104) (xy 40.665885 -377.945406) (xy 40.687752 -377.919742) (xy 40.693562 -377.912607)
			(xy 40.700067 -377.895408) (xy 40.700452 -377.886214) (xy 40.700452 -377.728734) (xy 40.700955 -377.718608)
			(xy 40.708674 -377.699885) (xy 40.722955 -377.685528) (xy 40.741637 -377.677709) (xy 40.75176 -377.677172)
			(xy 41.46804 -377.677172) (xy 41.478193 -377.677588) (xy 41.496941 -377.685392) (xy 41.511262 -377.699789)
			(xy 41.518965 -377.718579) (xy 41.519348 -377.728734) (xy 41.519348 -377.886214) (xy 41.519763 -377.8954)
			(xy 41.526275 -377.912584) (xy 41.532048 -377.919742) (xy 41.553888 -377.945427) (xy 41.591981 -378.001058)
			(xy 41.623136 -378.060851) (xy 41.646904 -378.123945) (xy 41.662943 -378.189432) (xy 41.671021 -378.256369)
			(xy 41.671024 -378.323792) (xy 41.671024 -378.323793) (xy 71.348797 -378.323793) (xy 71.348799 -378.256368)
			(xy 71.356877 -378.189428) (xy 71.372915 -378.123937) (xy 71.396682 -378.060839) (xy 71.427835 -378.001042)
			(xy 71.465927 -377.945407) (xy 71.487792 -377.919742) (xy 71.493595 -377.912601) (xy 71.500106 -377.895407)
			(xy 71.500492 -377.886214) (xy 71.500492 -377.728734) (xy 71.501053 -377.718615) (xy 71.508761 -377.699904)
			(xy 71.523024 -377.685548) (xy 71.541685 -377.67772) (xy 71.5518 -377.677172) (xy 72.26808 -377.677172)
			(xy 72.278229 -377.677637) (xy 72.296976 -377.685421) (xy 72.311299 -377.699804) (xy 72.319005 -377.718583)
			(xy 72.319388 -377.728734) (xy 72.319388 -377.886214) (xy 72.319794 -377.895402) (xy 72.326311 -377.912586)
			(xy 72.332088 -377.919742) (xy 72.353927 -377.945428) (xy 72.392017 -378.001059) (xy 72.42317 -378.060853)
			(xy 72.446936 -378.123947) (xy 72.462973 -378.189433) (xy 72.471052 -378.25637) (xy 72.471054 -378.323734)
			(xy 75.749092 -378.323734) (xy 75.749095 -378.256427) (xy 75.757142 -378.189601) (xy 75.773119 -378.124217)
			(xy 75.796796 -378.061212) (xy 75.827835 -378.001488) (xy 75.86579 -377.945902) (xy 75.88758 -377.92025)
			(xy 75.893378 -377.913106) (xy 75.899892 -377.895915) (xy 75.90028 -377.886722) (xy 75.90028 -377.728734)
			(xy 75.900693 -377.718559) (xy 75.908474 -377.699757) (xy 75.922864 -377.68537) (xy 75.941667 -377.677591)
			(xy 75.951842 -377.677172) (xy 76.668122 -377.677172) (xy 76.678299 -377.677547) (xy 76.697101 -377.685345)
			(xy 76.711486 -377.699746) (xy 76.719264 -377.718556) (xy 76.719684 -377.728734) (xy 76.719684 -377.886722)
			(xy 76.720087 -377.89591) (xy 76.726606 -377.913094) (xy 76.732384 -377.92025) (xy 76.754146 -377.945923)
			(xy 76.792094 -378.001507) (xy 76.823127 -378.061228) (xy 76.8468 -378.12423) (xy 76.862774 -378.189609)
			(xy 76.87082 -378.256429) (xy 76.870822 -378.323732) (xy 76.870815 -378.323793) (xy 80.148885 -378.323793)
			(xy 80.148887 -378.256368) (xy 80.156965 -378.189428) (xy 80.173003 -378.123938) (xy 80.196769 -378.06084)
			(xy 80.227921 -378.001043) (xy 80.266011 -377.945408) (xy 80.287876 -377.919742) (xy 80.293677 -377.9126)
			(xy 80.30019 -377.895407) (xy 80.300576 -377.886214) (xy 80.300576 -377.728734) (xy 80.301056 -377.718605)
			(xy 80.308779 -377.699878) (xy 80.323068 -377.685519) (xy 80.341758 -377.677705) (xy 80.351884 -377.677172)
			(xy 81.068164 -377.677172) (xy 81.078281 -377.677645) (xy 81.096978 -377.685376) (xy 81.111293 -377.699675)
			(xy 81.119044 -377.718364) (xy 81.119472 -377.72848) (xy 81.119472 -377.886214) (xy 81.119882 -377.895401)
			(xy 81.126396 -377.912585) (xy 81.132172 -377.919742) (xy 81.154011 -377.945428) (xy 81.192103 -378.001059)
			(xy 81.223256 -378.060852) (xy 81.247023 -378.123946) (xy 81.263061 -378.189433) (xy 81.27114 -378.256369)
			(xy 81.271142 -378.323792) (xy 81.271142 -378.323793) (xy 84.548676 -378.323793) (xy 84.548678 -378.256368)
			(xy 84.556756 -378.189429) (xy 84.572793 -378.123939) (xy 84.596559 -378.060841) (xy 84.62771 -378.001044)
			(xy 84.6658 -377.945408) (xy 84.687664 -377.919742) (xy 84.693475 -377.912608) (xy 84.699979 -377.895409)
			(xy 84.700364 -377.886214) (xy 84.700364 -377.728734) (xy 84.700855 -377.718607) (xy 84.708576 -377.699882)
			(xy 84.722862 -377.685523) (xy 84.741547 -377.677707) (xy 84.751672 -377.677172) (xy 85.467952 -377.677172)
			(xy 85.478068 -377.677655) (xy 85.496765 -377.685382) (xy 85.51108 -377.699678) (xy 85.518832 -377.718365)
			(xy 85.51926 -377.72848) (xy 85.51926 -377.886214) (xy 85.519672 -377.895401) (xy 85.526185 -377.912585)
			(xy 85.53196 -377.919742) (xy 85.5538 -377.945428) (xy 85.591892 -378.001058) (xy 85.623046 -378.060851)
			(xy 85.646813 -378.123946) (xy 85.662852 -378.189433) (xy 85.67093 -378.256369) (xy 85.670933 -378.323734)
			(xy 115.349234 -378.323734) (xy 115.349237 -378.256427) (xy 115.357283 -378.189603) (xy 115.373258 -378.12422)
			(xy 115.396932 -378.061215) (xy 115.427966 -378.00149) (xy 115.465916 -377.945903) (xy 115.487704 -377.92025)
			(xy 115.493505 -377.913108) (xy 115.500017 -377.895915) (xy 115.500404 -377.886722) (xy 115.500404 -377.728734)
			(xy 115.500961 -377.718583) (xy 115.508717 -377.699821) (xy 115.523064 -377.685456) (xy 115.541815 -377.677674)
			(xy 115.551966 -377.677172) (xy 116.268246 -377.677172) (xy 116.278411 -377.677597) (xy 116.297188 -377.685393)
			(xy 116.311552 -377.69978) (xy 116.319319 -377.718568) (xy 116.319808 -377.728734) (xy 116.319808 -377.886722)
			(xy 116.320206 -377.895911) (xy 116.326728 -377.913095) (xy 116.332508 -377.92025) (xy 116.354272 -377.945922)
			(xy 116.392225 -378.001505) (xy 116.423262 -378.061225) (xy 116.446939 -378.124227) (xy 116.462915 -378.189607)
			(xy 116.470962 -378.256428) (xy 116.470964 -378.323732) (xy 116.470957 -378.323793) (xy 119.749003 -378.323793)
			(xy 119.749005 -378.256368) (xy 119.757084 -378.189428) (xy 119.773122 -378.123937) (xy 119.796889 -378.060839)
			(xy 119.828043 -378.001042) (xy 119.866134 -377.945407) (xy 119.888 -377.919742) (xy 119.893804 -377.912602)
			(xy 119.900314 -377.895407) (xy 119.9007 -377.886214) (xy 119.9007 -377.728734) (xy 119.901253 -377.718614)
			(xy 119.908963 -377.699902) (xy 119.923228 -377.685546) (xy 119.941892 -377.677718) (xy 119.952008 -377.677172)
			(xy 120.668288 -377.677172) (xy 120.678438 -377.677631) (xy 120.697185 -377.685417) (xy 120.711507 -377.699802)
			(xy 120.719213 -377.718582) (xy 120.719596 -377.728734) (xy 120.719596 -377.886214) (xy 120.72 -377.895402)
			(xy 120.726518 -377.912586) (xy 120.732296 -377.919742) (xy 120.754135 -377.945428) (xy 120.792224 -378.00106)
			(xy 120.823376 -378.060853) (xy 120.847142 -378.123947) (xy 120.86318 -378.189434) (xy 120.871258 -378.25637)
			(xy 120.87126 -378.323734) (xy 124.149298 -378.323734) (xy 124.149301 -378.256426) (xy 124.157348 -378.189601)
			(xy 124.173325 -378.124217) (xy 124.197003 -378.061211) (xy 124.228042 -378.001487) (xy 124.265997 -377.945902)
			(xy 124.287788 -377.92025) (xy 124.293587 -377.913106) (xy 124.300101 -377.895915) (xy 124.300488 -377.886722)
			(xy 124.300488 -377.728734) (xy 124.300893 -377.718558) (xy 124.308676 -377.699755) (xy 124.323068 -377.685367)
			(xy 124.341874 -377.67759) (xy 124.35205 -377.677172) (xy 125.06833 -377.677172) (xy 125.078508 -377.67754)
			(xy 125.09731 -377.685341) (xy 125.111695 -377.699744) (xy 125.119473 -377.718556) (xy 125.119892 -377.728734)
			(xy 125.119892 -377.886722) (xy 125.120293 -377.89591) (xy 125.126813 -377.913094) (xy 125.132592 -377.92025)
			(xy 125.154353 -377.945924) (xy 125.192301 -378.001508) (xy 125.223334 -378.061229) (xy 125.247006 -378.12423)
			(xy 125.26298 -378.189609) (xy 125.271026 -378.256429) (xy 125.271028 -378.323732) (xy 125.271028 -378.323734)
			(xy 128.549089 -378.323734) (xy 128.549092 -378.256427) (xy 128.557139 -378.189602) (xy 128.573116 -378.124218)
			(xy 128.596793 -378.061212) (xy 128.627831 -378.001488) (xy 128.665786 -377.945902) (xy 128.687576 -377.92025)
			(xy 128.693374 -377.913105) (xy 128.699888 -377.895915) (xy 128.700276 -377.886722) (xy 128.700276 -377.728734)
			(xy 128.700693 -377.71856) (xy 128.708474 -377.699759) (xy 128.722862 -377.685371) (xy 128.741664 -377.677592)
			(xy 128.751838 -377.677172) (xy 129.468118 -377.677172) (xy 129.478295 -377.67755) (xy 129.497097 -377.685347)
			(xy 129.511482 -377.699747) (xy 129.51926 -377.718557) (xy 129.51968 -377.728734) (xy 129.51968 -377.886722)
			(xy 129.520084 -377.89591) (xy 129.526602 -377.913094) (xy 129.53238 -377.92025) (xy 129.554142 -377.945923)
			(xy 129.59209 -378.001507) (xy 129.623123 -378.061228) (xy 129.646797 -378.12423) (xy 129.662771 -378.189609)
			(xy 129.670817 -378.256429) (xy 129.670819 -378.323732) (xy 129.670819 -378.323734) (xy 159.349143 -378.323734)
			(xy 159.349146 -378.256427) (xy 159.357192 -378.189603) (xy 159.373167 -378.12422) (xy 159.396842 -378.061214)
			(xy 159.427877 -378.00149) (xy 159.465827 -377.945902) (xy 159.487616 -377.92025) (xy 159.493418 -377.913109)
			(xy 159.499929 -377.895915) (xy 159.500316 -377.886722) (xy 159.500316 -377.728734) (xy 159.500791 -377.718567)
			(xy 159.508561 -377.699778) (xy 159.522931 -377.685392) (xy 159.541712 -377.677602) (xy 159.551878 -377.677172)
			(xy 160.268158 -377.677172) (xy 160.278331 -377.677599) (xy 160.297131 -377.685377) (xy 160.311519 -377.699762)
			(xy 160.319299 -377.718561) (xy 160.31972 -377.728734) (xy 160.31972 -377.886722) (xy 160.320115 -377.895911)
			(xy 160.326639 -377.913095) (xy 160.33242 -377.92025) (xy 160.354183 -377.945923) (xy 160.392136 -378.001505)
			(xy 160.423172 -378.061226) (xy 160.446848 -378.124227) (xy 160.462824 -378.189608) (xy 160.470871 -378.256429)
			(xy 160.470874 -378.323732) (xy 160.470867 -378.323793) (xy 163.748912 -378.323793) (xy 163.748914 -378.256367)
			(xy 163.756993 -378.189427) (xy 163.773031 -378.123937) (xy 163.796799 -378.060839) (xy 163.827953 -378.001042)
			(xy 163.866046 -377.945407) (xy 163.887912 -377.919742) (xy 163.893717 -377.912603) (xy 163.900226 -377.895408)
			(xy 163.900612 -377.886214) (xy 163.900612 -377.728734) (xy 163.901154 -377.718613) (xy 163.908865 -377.699898)
			(xy 163.923134 -377.685542) (xy 163.941802 -377.677716) (xy 163.95192 -377.677172) (xy 164.6682 -377.677172)
			(xy 164.678351 -377.677621) (xy 164.697098 -377.685411) (xy 164.71142 -377.699799) (xy 164.719125 -377.718582)
			(xy 164.719508 -377.728734) (xy 164.719508 -377.886214) (xy 164.71991 -377.895402) (xy 164.726429 -377.912586)
			(xy 164.732208 -377.919742) (xy 164.754046 -377.945428) (xy 164.792135 -378.00106) (xy 164.823286 -378.060853)
			(xy 164.847052 -378.123948) (xy 164.863089 -378.189434) (xy 164.871167 -378.25637) (xy 164.871169 -378.323734)
			(xy 168.149231 -378.323734) (xy 168.149234 -378.256427) (xy 168.15728 -378.189604) (xy 168.173254 -378.12422)
			(xy 168.196928 -378.061215) (xy 168.227963 -378.00149) (xy 168.265912 -377.945903) (xy 168.2877 -377.92025)
			(xy 168.2935 -377.913107) (xy 168.300013 -377.895915) (xy 168.3004 -377.886722) (xy 168.3004 -377.728734)
			(xy 168.30096 -377.718583) (xy 168.308717 -377.699822) (xy 168.323062 -377.685457) (xy 168.341812 -377.677675)
			(xy 168.351962 -377.677172) (xy 169.068242 -377.677172) (xy 169.078407 -377.6776) (xy 169.097183 -377.685394)
			(xy 169.111548 -377.699781) (xy 169.119315 -377.718569) (xy 169.119804 -377.728734) (xy 169.119804 -377.886722)
			(xy 169.120203 -377.89591) (xy 169.126724 -377.913095) (xy 169.132504 -377.92025) (xy 169.154265 -377.945924)
			(xy 169.192212 -378.001508) (xy 169.223244 -378.061229) (xy 169.246916 -378.124231) (xy 169.26289 -378.18961)
			(xy 169.270935 -378.256429) (xy 169.270937 -378.323732) (xy 169.270937 -378.323734) (xy 172.548998 -378.323734)
			(xy 172.549001 -378.256426) (xy 172.557048 -378.189601) (xy 172.573025 -378.124217) (xy 172.596703 -378.061211)
			(xy 172.627742 -378.001487) (xy 172.665697 -377.945902) (xy 172.687488 -377.92025) (xy 172.693287 -377.913106)
			(xy 172.699801 -377.895915) (xy 172.700188 -377.886722) (xy 172.700188 -377.728734) (xy 172.700593 -377.718558)
			(xy 172.708376 -377.699755) (xy 172.722768 -377.685367) (xy 172.741574 -377.67759) (xy 172.75175 -377.677172)
			(xy 173.46803 -377.677172) (xy 173.478208 -377.67754) (xy 173.49701 -377.685341) (xy 173.511395 -377.699744)
			(xy 173.519173 -377.718556) (xy 173.519592 -377.728734) (xy 173.519592 -377.886722) (xy 173.519993 -377.89591)
			(xy 173.526513 -377.913094) (xy 173.532292 -377.92025) (xy 173.554053 -377.945924) (xy 173.592001 -378.001508)
			(xy 173.623034 -378.061229) (xy 173.646706 -378.12423) (xy 173.66268 -378.189609) (xy 173.670726 -378.256429)
			(xy 173.670728 -378.323732) (xy 173.662687 -378.390552) (xy 173.646718 -378.455932) (xy 173.623049 -378.518936)
			(xy 173.592021 -378.578659) (xy 173.554077 -378.634245) (xy 173.532292 -378.659898) (xy 173.526513 -378.667056)
			(xy 173.519988 -378.684237) (xy 173.519592 -378.693426) (xy 173.519592 -378.766811) (xy 193.48983 -378.766811)
			(xy 193.48983 -378.633249) (xy 193.497894 -378.499931) (xy 193.513994 -378.367343) (xy 193.538069 -378.235969)
			(xy 193.570032 -378.106288) (xy 193.609767 -377.978774) (xy 193.657129 -377.853891) (xy 193.711944 -377.732096)
			(xy 193.774014 -377.613833) (xy 193.84311 -377.499534) (xy 193.918982 -377.389614) (xy 194.001352 -377.284477)
			(xy 194.08992 -377.184504) (xy 194.184362 -377.090062) (xy 194.284335 -377.001494) (xy 194.389472 -376.919124)
			(xy 194.499392 -376.843252) (xy 194.613691 -376.774156) (xy 194.731954 -376.712086) (xy 194.853749 -376.657271)
			(xy 194.978632 -376.609909) (xy 195.106146 -376.570174) (xy 195.235827 -376.538211) (xy 195.367201 -376.514136)
			(xy 195.499789 -376.498036) (xy 195.633107 -376.489972) (xy 195.766669 -376.489972) (xy 195.899987 -376.498036)
			(xy 196.032575 -376.514136) (xy 196.163949 -376.538211) (xy 196.29363 -376.570174) (xy 196.421144 -376.609909)
			(xy 196.546027 -376.657271) (xy 196.667822 -376.712086) (xy 196.786085 -376.774156) (xy 196.900384 -376.843252)
			(xy 197.010304 -376.919124) (xy 197.115441 -377.001494) (xy 197.215414 -377.090062) (xy 197.309856 -377.184504)
			(xy 197.398424 -377.284477) (xy 197.480794 -377.389614) (xy 197.556666 -377.499534) (xy 197.625762 -377.613833)
			(xy 197.687832 -377.732096) (xy 197.742647 -377.853891) (xy 197.790009 -377.978774) (xy 197.829744 -378.106288)
			(xy 197.861707 -378.235969) (xy 197.885782 -378.367343) (xy 197.901882 -378.499931) (xy 197.909946 -378.633249)
			(xy 197.91045 -378.70003) (xy 197.909946 -378.766811) (xy 197.901882 -378.900129) (xy 197.885782 -379.032717)
			(xy 197.861707 -379.164091) (xy 197.829744 -379.293772) (xy 197.790009 -379.421286) (xy 197.742647 -379.546169)
			(xy 197.687832 -379.667964) (xy 197.625762 -379.786227) (xy 197.556666 -379.900526) (xy 197.480794 -380.010446)
			(xy 197.398424 -380.115583) (xy 197.309856 -380.215556) (xy 197.215414 -380.309998) (xy 197.115441 -380.398566)
			(xy 197.010304 -380.480936) (xy 196.900384 -380.556808) (xy 196.786085 -380.625904) (xy 196.667822 -380.687974)
			(xy 196.546027 -380.742789) (xy 196.421144 -380.790151) (xy 196.29363 -380.829886) (xy 196.163949 -380.861849)
			(xy 196.032575 -380.885924) (xy 195.899987 -380.902024) (xy 195.766669 -380.910088) (xy 195.633107 -380.910088)
			(xy 195.499789 -380.902024) (xy 195.367201 -380.885924) (xy 195.235827 -380.861849) (xy 195.106146 -380.829886)
			(xy 194.978632 -380.790151) (xy 194.853749 -380.742789) (xy 194.731954 -380.687974) (xy 194.613691 -380.625904)
			(xy 194.499392 -380.556808) (xy 194.389472 -380.480936) (xy 194.284335 -380.398566) (xy 194.184362 -380.309998)
			(xy 194.08992 -380.215556) (xy 194.001352 -380.115583) (xy 193.918982 -380.010446) (xy 193.84311 -379.900526)
			(xy 193.774014 -379.786227) (xy 193.711944 -379.667964) (xy 193.657129 -379.546169) (xy 193.609767 -379.421286)
			(xy 193.570032 -379.293772) (xy 193.538069 -379.164091) (xy 193.513994 -379.032717) (xy 193.497894 -378.900129)
			(xy 193.48983 -378.766811) (xy 173.519592 -378.766811) (xy 173.519592 -379.186694) (xy 173.520007 -379.195881)
			(xy 173.526518 -379.213065) (xy 173.532292 -379.220222) (xy 173.554124 -379.245837) (xy 173.592069 -379.30143)
			(xy 173.623099 -379.361159) (xy 173.646768 -379.424168) (xy 173.662737 -379.489554) (xy 173.670777 -379.556381)
			(xy 173.670772 -379.623689) (xy 173.662724 -379.690514) (xy 173.646747 -379.755898) (xy 173.623071 -379.818905)
			(xy 173.592034 -379.87863) (xy 173.554082 -379.934217) (xy 173.532292 -379.95987) (xy 173.526482 -379.967006)
			(xy 173.519976 -379.984204) (xy 173.519592 -379.993398) (xy 173.519592 -380.151386) (xy 173.519056 -380.161539)
			(xy 173.511292 -380.180302) (xy 173.496939 -380.194667) (xy 173.478183 -380.202447) (xy 173.46803 -380.202948)
			(xy 172.75175 -380.202948) (xy 172.74158 -380.202495) (xy 172.722784 -380.194724) (xy 172.708396 -380.180347)
			(xy 172.700612 -380.161556) (xy 172.700188 -380.151386) (xy 172.700188 -379.993398) (xy 172.699781 -379.98421)
			(xy 172.693266 -379.967026) (xy 172.687488 -379.95987) (xy 172.665744 -379.934181) (xy 172.627791 -379.878601)
			(xy 172.596753 -379.818883) (xy 172.573075 -379.755883) (xy 172.557097 -379.690505) (xy 172.549049 -379.623686)
			(xy 172.549045 -379.556383) (xy 172.557085 -379.489563) (xy 172.573055 -379.424183) (xy 172.596724 -379.36118)
			(xy 172.627755 -379.301458) (xy 172.665702 -379.245873) (xy 172.687488 -379.220222) (xy 172.693299 -379.213087)
			(xy 172.699805 -379.195889) (xy 172.700188 -379.186694) (xy 172.700188 -378.693426) (xy 172.699768 -378.68424)
			(xy 172.693262 -378.667055) (xy 172.687488 -378.659898) (xy 172.665673 -378.634268) (xy 172.627722 -378.578679)
			(xy 172.596687 -378.518953) (xy 172.573014 -378.455946) (xy 172.557041 -378.39056) (xy 172.548998 -378.323734)
			(xy 169.270937 -378.323734) (xy 169.262897 -378.390552) (xy 169.246928 -378.455932) (xy 169.22326 -378.518935)
			(xy 169.192232 -378.578658) (xy 169.154289 -378.634245) (xy 169.132504 -378.659898) (xy 169.126726 -378.667057)
			(xy 169.1202 -378.684237) (xy 169.119804 -378.693426) (xy 169.119804 -379.186694) (xy 169.120216 -379.195881)
			(xy 169.126728 -379.213065) (xy 169.132504 -379.220222) (xy 169.154336 -379.245838) (xy 169.19228 -379.30143)
			(xy 169.223309 -379.361159) (xy 169.246977 -379.424169) (xy 169.262946 -379.489555) (xy 169.270986 -379.556381)
			(xy 169.270982 -379.623689) (xy 169.262933 -379.690513) (xy 169.246957 -379.755898) (xy 169.223281 -379.818904)
			(xy 169.192245 -379.878629) (xy 169.154293 -379.934217) (xy 169.132504 -379.95987) (xy 169.126696 -379.967007)
			(xy 169.120188 -379.984204) (xy 169.119804 -379.993398) (xy 169.119804 -380.151386) (xy 169.119256 -380.161538)
			(xy 169.111494 -380.180299) (xy 169.097146 -380.194663) (xy 169.078393 -380.202445) (xy 169.068242 -380.202948)
			(xy 168.351962 -380.202948) (xy 168.3418 -380.202497) (xy 168.323027 -380.194708) (xy 168.308663 -380.180329)
			(xy 168.300892 -380.161548) (xy 168.3004 -380.151386) (xy 168.3004 -379.993398) (xy 168.299991 -379.984211)
			(xy 168.293476 -379.967026) (xy 168.2877 -379.95987) (xy 168.265959 -379.93418) (xy 168.228011 -379.878598)
			(xy 168.196978 -379.818879) (xy 168.173304 -379.75588) (xy 168.157329 -379.690503) (xy 168.149282 -379.623685)
			(xy 168.149278 -379.556384) (xy 168.157317 -379.489565) (xy 168.173284 -379.424186) (xy 168.19695 -379.361184)
			(xy 168.227975 -379.301461) (xy 168.265916 -379.245875) (xy 168.2877 -379.220222) (xy 168.293512 -379.213088)
			(xy 168.300018 -379.195889) (xy 168.3004 -379.186694) (xy 168.3004 -378.693426) (xy 168.299977 -378.68424)
			(xy 168.293472 -378.667056) (xy 168.2877 -378.659898) (xy 168.265888 -378.634266) (xy 168.227942 -378.578676)
			(xy 168.196912 -378.518949) (xy 168.173243 -378.455942) (xy 168.157273 -378.390558) (xy 168.149231 -378.323734)
			(xy 164.871169 -378.323734) (xy 164.871169 -378.323791) (xy 164.863096 -378.390728) (xy 164.847063 -378.456215)
			(xy 164.823302 -378.519311) (xy 164.792155 -378.579106) (xy 164.75407 -378.634741) (xy 164.732208 -378.660406)
			(xy 164.726427 -378.667563) (xy 164.719903 -378.684744) (xy 164.719508 -378.693934) (xy 164.719508 -379.186186)
			(xy 164.719923 -379.195373) (xy 164.726433 -379.212557) (xy 164.732208 -379.219714) (xy 164.754117 -379.245342)
			(xy 164.792204 -379.300982) (xy 164.823352 -379.360784) (xy 164.847113 -379.423885) (xy 164.863145 -379.489379)
			(xy 164.871217 -379.556321) (xy 164.871213 -379.623748) (xy 164.863133 -379.690689) (xy 164.847093 -379.756181)
			(xy 164.823324 -379.81928) (xy 164.792168 -379.879077) (xy 164.754074 -379.934713) (xy 164.732208 -379.960378)
			(xy 164.726397 -379.967513) (xy 164.719891 -379.984711) (xy 164.719508 -379.993906) (xy 164.719508 -380.151386)
			(xy 164.718963 -380.161506) (xy 164.711249 -380.180218) (xy 164.696981 -380.194573) (xy 164.678317 -380.202401)
			(xy 164.6682 -380.202948) (xy 163.95192 -380.202948) (xy 163.941773 -380.202463) (xy 163.92303 -380.194683)
			(xy 163.908708 -380.180306) (xy 163.900999 -380.161534) (xy 163.900612 -380.151386) (xy 163.900612 -379.993906)
			(xy 163.900196 -379.98472) (xy 163.893686 -379.967535) (xy 163.887912 -379.960378) (xy 163.866093 -379.934676)
			(xy 163.828002 -379.879047) (xy 163.796849 -379.819256) (xy 163.773081 -379.756164) (xy 163.757042 -379.690679)
			(xy 163.748963 -379.623745) (xy 163.748958 -379.556324) (xy 163.75703 -379.489389) (xy 163.773061 -379.423902)
			(xy 163.79682 -379.360807) (xy 163.827966 -379.301013) (xy 163.86605 -379.245379) (xy 163.887912 -379.219714)
			(xy 163.893729 -379.212583) (xy 163.900231 -379.195382) (xy 163.900612 -379.186186) (xy 163.900612 -378.693934)
			(xy 163.900183 -378.684749) (xy 163.893682 -378.667565) (xy 163.887912 -378.660406) (xy 163.866022 -378.634762)
			(xy 163.827933 -378.579125) (xy 163.796783 -378.519326) (xy 163.77302 -378.456226) (xy 163.756986 -378.390734)
			(xy 163.748912 -378.323793) (xy 160.470867 -378.323793) (xy 160.462831 -378.390554) (xy 160.44686 -378.455935)
			(xy 160.423188 -378.518939) (xy 160.392156 -378.578661) (xy 160.354207 -378.634246) (xy 160.33242 -378.659898)
			(xy 160.326644 -378.667058) (xy 160.320116 -378.684237) (xy 160.31972 -378.693426) (xy 160.31972 -379.186694)
			(xy 160.320129 -379.195881) (xy 160.326643 -379.213066) (xy 160.33242 -379.220222) (xy 160.354254 -379.245836)
			(xy 160.392205 -379.301427) (xy 160.423238 -379.361156) (xy 160.44691 -379.424165) (xy 160.462881 -379.489552)
			(xy 160.470922 -379.55638) (xy 160.470918 -379.623689) (xy 160.462869 -379.690516) (xy 160.44689 -379.755901)
			(xy 160.42321 -379.818908) (xy 160.392169 -379.878632) (xy 160.354212 -379.934219) (xy 160.33242 -379.95987)
			(xy 160.326614 -379.967008) (xy 160.320104 -379.984204) (xy 160.31972 -379.993398) (xy 160.31972 -380.151386)
			(xy 160.319324 -380.161562) (xy 160.311536 -380.180364) (xy 160.297141 -380.194751) (xy 160.278334 -380.202529)
			(xy 160.268158 -380.202948) (xy 159.551878 -380.202948) (xy 159.541717 -380.202484) (xy 159.522945 -380.1947)
			(xy 159.50858 -380.180325) (xy 159.500808 -380.161547) (xy 159.500316 -380.151386) (xy 159.500316 -379.993398)
			(xy 159.499903 -379.984211) (xy 159.493391 -379.967027) (xy 159.487616 -379.95987) (xy 159.465874 -379.93418)
			(xy 159.427926 -379.878599) (xy 159.396892 -379.81888) (xy 159.373217 -379.75588) (xy 159.357242 -379.690503)
			(xy 159.349195 -379.623685) (xy 159.34919 -379.556384) (xy 159.35723 -379.489565) (xy 159.373197 -379.424186)
			(xy 159.396864 -379.361183) (xy 159.42789 -379.301461) (xy 159.465832 -379.245875) (xy 159.487616 -379.220222)
			(xy 159.49343 -379.213089) (xy 159.499934 -379.195889) (xy 159.500316 -379.186694) (xy 159.500316 -378.693426)
			(xy 159.49989 -378.684241) (xy 159.493387 -378.667056) (xy 159.487616 -378.659898) (xy 159.465803 -378.634267)
			(xy 159.427857 -378.578677) (xy 159.396826 -378.51895) (xy 159.373156 -378.455943) (xy 159.357185 -378.390558)
			(xy 159.349143 -378.323734) (xy 129.670819 -378.323734) (xy 129.662778 -378.390552) (xy 129.646808 -378.455933)
			(xy 129.623139 -378.518936) (xy 129.59211 -378.578659) (xy 129.554166 -378.634246) (xy 129.53238 -378.659898)
			(xy 129.526599 -378.667054) (xy 129.520076 -378.684236) (xy 129.51968 -378.693426) (xy 129.51968 -379.186694)
			(xy 129.520098 -379.19588) (xy 129.526607 -379.213064) (xy 129.53238 -379.220222) (xy 129.554212 -379.245837)
			(xy 129.592159 -379.301429) (xy 129.623189 -379.361158) (xy 129.646858 -379.424168) (xy 129.662827 -379.489554)
			(xy 129.670868 -379.55638) (xy 129.670863 -379.623689) (xy 129.662815 -379.690514) (xy 129.646838 -379.755899)
			(xy 129.623161 -379.818905) (xy 129.592123 -379.87863) (xy 129.55417 -379.934218) (xy 129.53238 -379.95987)
			(xy 129.526569 -379.967005) (xy 129.520064 -379.984203) (xy 129.51968 -379.993398) (xy 129.51968 -380.151386)
			(xy 129.519156 -380.161541) (xy 129.511389 -380.180306) (xy 129.497033 -380.194671) (xy 129.478272 -380.202449)
			(xy 129.468118 -380.202948) (xy 128.751838 -380.202948) (xy 128.741667 -380.202505) (xy 128.722871 -380.19473)
			(xy 128.708484 -380.18035) (xy 128.7007 -380.161557) (xy 128.700276 -380.151386) (xy 128.700276 -379.993398)
			(xy 128.699872 -379.98421) (xy 128.693355 -379.967025) (xy 128.687576 -379.95987) (xy 128.665832 -379.934181)
			(xy 128.62788 -379.878601) (xy 128.596842 -379.818883) (xy 128.573165 -379.755883) (xy 128.557188 -379.690505)
			(xy 128.54914 -379.623686) (xy 128.549136 -379.556384) (xy 128.557176 -379.489563) (xy 128.573145 -379.424183)
			(xy 128.596814 -379.361181) (xy 128.627844 -379.301459) (xy 128.66579 -379.245874) (xy 128.687576 -379.220222)
			(xy 128.693385 -379.213086) (xy 128.699893 -379.195889) (xy 128.700276 -379.186694) (xy 128.700276 -378.693426)
			(xy 128.699859 -378.684239) (xy 128.693351 -378.667055) (xy 128.687576 -378.659898) (xy 128.665762 -378.634267)
			(xy 128.627811 -378.578679) (xy 128.596777 -378.518952) (xy 128.573104 -378.455945) (xy 128.557132 -378.39056)
			(xy 128.549089 -378.323734) (xy 125.271028 -378.323734) (xy 125.262987 -378.390552) (xy 125.247018 -378.455932)
			(xy 125.223349 -378.518936) (xy 125.192321 -378.578659) (xy 125.154377 -378.634245) (xy 125.132592 -378.659898)
			(xy 125.126813 -378.667056) (xy 125.120288 -378.684237) (xy 125.119892 -378.693426) (xy 125.119892 -379.186694)
			(xy 125.120307 -379.195881) (xy 125.126818 -379.213065) (xy 125.132592 -379.220222) (xy 125.154424 -379.245837)
			(xy 125.192369 -379.30143) (xy 125.223399 -379.361159) (xy 125.247068 -379.424168) (xy 125.263037 -379.489554)
			(xy 125.271077 -379.556381) (xy 125.271072 -379.623689) (xy 125.263024 -379.690514) (xy 125.247047 -379.755898)
			(xy 125.223371 -379.818905) (xy 125.192334 -379.87863) (xy 125.154382 -379.934217) (xy 125.132592 -379.95987)
			(xy 125.126782 -379.967006) (xy 125.120276 -379.984204) (xy 125.119892 -379.993398) (xy 125.119892 -380.151386)
			(xy 125.119356 -380.161539) (xy 125.111592 -380.180302) (xy 125.097239 -380.194667) (xy 125.078483 -380.202447)
			(xy 125.06833 -380.202948) (xy 124.35205 -380.202948) (xy 124.34188 -380.202495) (xy 124.323084 -380.194724)
			(xy 124.308696 -380.180347) (xy 124.300912 -380.161556) (xy 124.300488 -380.151386) (xy 124.300488 -379.993398)
			(xy 124.300081 -379.98421) (xy 124.293566 -379.967026) (xy 124.287788 -379.95987) (xy 124.266044 -379.934181)
			(xy 124.228091 -379.878601) (xy 124.197053 -379.818883) (xy 124.173375 -379.755883) (xy 124.157397 -379.690505)
			(xy 124.149349 -379.623686) (xy 124.149345 -379.556383) (xy 124.157385 -379.489563) (xy 124.173355 -379.424183)
			(xy 124.197024 -379.36118) (xy 124.228055 -379.301458) (xy 124.266002 -379.245873) (xy 124.287788 -379.220222)
			(xy 124.293599 -379.213087) (xy 124.300105 -379.195889) (xy 124.300488 -379.186694) (xy 124.300488 -378.693426)
			(xy 124.300068 -378.68424) (xy 124.293562 -378.667055) (xy 124.287788 -378.659898) (xy 124.265973 -378.634268)
			(xy 124.228022 -378.578679) (xy 124.196987 -378.518953) (xy 124.173314 -378.455946) (xy 124.157341 -378.39056)
			(xy 124.149298 -378.323734) (xy 120.87126 -378.323734) (xy 120.87126 -378.323791) (xy 120.863187 -378.390728)
			(xy 120.847154 -378.456216) (xy 120.823392 -378.519311) (xy 120.792244 -378.579107) (xy 120.754159 -378.634741)
			(xy 120.732296 -378.660406) (xy 120.726514 -378.667561) (xy 120.719991 -378.684744) (xy 120.719596 -378.693934)
			(xy 120.719596 -379.186186) (xy 120.720014 -379.195372) (xy 120.726522 -379.212557) (xy 120.732296 -379.219714)
			(xy 120.754205 -379.245342) (xy 120.792293 -379.300982) (xy 120.823442 -379.360783) (xy 120.847204 -379.423885)
			(xy 120.863236 -379.489378) (xy 120.871308 -379.556321) (xy 120.871304 -379.623748) (xy 120.863224 -379.69069)
			(xy 120.847183 -379.756181) (xy 120.823414 -379.81928) (xy 120.792257 -379.879078) (xy 120.754163 -379.934713)
			(xy 120.732296 -379.960378) (xy 120.726483 -379.967512) (xy 120.719978 -379.984711) (xy 120.719596 -379.993906)
			(xy 120.719596 -380.151386) (xy 120.719063 -380.161507) (xy 120.711347 -380.180221) (xy 120.697075 -380.194577)
			(xy 120.678406 -380.202403) (xy 120.668288 -380.202948) (xy 119.952008 -380.202948) (xy 119.94186 -380.202473)
			(xy 119.923117 -380.194689) (xy 119.908795 -380.180309) (xy 119.901087 -380.161535) (xy 119.9007 -380.151386)
			(xy 119.9007 -379.993906) (xy 119.900287 -379.984719) (xy 119.893775 -379.967535) (xy 119.888 -379.960378)
			(xy 119.866181 -379.934675) (xy 119.828091 -379.879046) (xy 119.796938 -379.819255) (xy 119.773172 -379.756163)
			(xy 119.757133 -379.690679) (xy 119.749053 -379.623745) (xy 119.749049 -379.556325) (xy 119.757121 -379.489389)
			(xy 119.773151 -379.423903) (xy 119.79691 -379.360808) (xy 119.828056 -379.301013) (xy 119.866139 -379.245379)
			(xy 119.888 -379.219714) (xy 119.893816 -379.212582) (xy 119.900319 -379.195381) (xy 119.9007 -379.186186)
			(xy 119.9007 -378.693934) (xy 119.900273 -378.684749) (xy 119.893771 -378.667564) (xy 119.888 -378.660406)
			(xy 119.86611 -378.634762) (xy 119.828023 -378.579124) (xy 119.796873 -378.519325) (xy 119.77311 -378.456226)
			(xy 119.757077 -378.390734) (xy 119.749003 -378.323793) (xy 116.470957 -378.323793) (xy 116.462922 -378.390554)
			(xy 116.44695 -378.455936) (xy 116.423278 -378.518939) (xy 116.392245 -378.578662) (xy 116.354296 -378.634247)
			(xy 116.332508 -378.659898) (xy 116.326731 -378.667057) (xy 116.320204 -378.684237) (xy 116.319808 -378.693426)
			(xy 116.319808 -379.186694) (xy 116.320219 -379.195881) (xy 116.326732 -379.213066) (xy 116.332508 -379.220222)
			(xy 116.354343 -379.245836) (xy 116.392293 -379.301427) (xy 116.423328 -379.361155) (xy 116.447 -379.424165)
			(xy 116.462971 -379.489552) (xy 116.471013 -379.55638) (xy 116.471009 -379.623689) (xy 116.462959 -379.690516)
			(xy 116.44698 -379.755901) (xy 116.423299 -379.818908) (xy 116.392258 -379.878633) (xy 116.3543 -379.934219)
			(xy 116.332508 -379.95987) (xy 116.3267 -379.967007) (xy 116.320192 -379.984204) (xy 116.319808 -379.993398)
			(xy 116.319808 -380.151386) (xy 116.319256 -380.161537) (xy 116.311495 -380.180297) (xy 116.297148 -380.194661)
			(xy 116.278397 -380.202445) (xy 116.268246 -380.202948) (xy 115.551966 -380.202948) (xy 115.541804 -380.202494)
			(xy 115.523032 -380.194706) (xy 115.508667 -380.180328) (xy 115.500896 -380.161548) (xy 115.500404 -380.151386)
			(xy 115.500404 -379.993398) (xy 115.499994 -379.984211) (xy 115.49348 -379.967027) (xy 115.487704 -379.95987)
			(xy 115.465963 -379.93418) (xy 115.428015 -379.878598) (xy 115.396981 -379.81888) (xy 115.373307 -379.75588)
			(xy 115.357332 -379.690503) (xy 115.349285 -379.623685) (xy 115.349281 -379.556384) (xy 115.35732 -379.489565)
			(xy 115.373287 -379.424186) (xy 115.396953 -379.361184) (xy 115.427979 -379.301461) (xy 115.46592 -379.245875)
			(xy 115.487704 -379.220222) (xy 115.493517 -379.213088) (xy 115.500022 -379.195889) (xy 115.500404 -379.186694)
			(xy 115.500404 -378.693426) (xy 115.49998 -378.68424) (xy 115.493476 -378.667056) (xy 115.487704 -378.659898)
			(xy 115.465892 -378.634266) (xy 115.427946 -378.578676) (xy 115.396916 -378.518949) (xy 115.373246 -378.455942)
			(xy 115.357276 -378.390558) (xy 115.349234 -378.323734) (xy 85.670933 -378.323734) (xy 85.670933 -378.323792)
			(xy 85.662859 -378.390729) (xy 85.646825 -378.456217) (xy 85.623062 -378.519313) (xy 85.591912 -378.579108)
			(xy 85.553824 -378.634741) (xy 85.53196 -378.660406) (xy 85.526173 -378.667558) (xy 85.519654 -378.684743)
			(xy 85.51926 -378.693934) (xy 85.51926 -379.186186) (xy 85.519686 -379.195371) (xy 85.526189 -379.212555)
			(xy 85.53196 -379.219714) (xy 85.553871 -379.245341) (xy 85.591961 -379.30098) (xy 85.623111 -379.360781)
			(xy 85.646875 -379.423883) (xy 85.662908 -379.489377) (xy 85.670981 -379.55632) (xy 85.670977 -379.623749)
			(xy 85.662896 -379.690691) (xy 85.646854 -379.756183) (xy 85.623083 -379.819282) (xy 85.591925 -379.879079)
			(xy 85.553828 -379.934713) (xy 85.53196 -379.960378) (xy 85.526143 -379.967508) (xy 85.519641 -379.98471)
			(xy 85.51926 -379.993906) (xy 85.51926 -380.151386) (xy 85.518762 -380.161512) (xy 85.511039 -380.180233)
			(xy 85.496756 -380.194589) (xy 85.478075 -380.202409) (xy 85.467952 -380.202948) (xy 84.751672 -380.202948)
			(xy 84.741567 -380.202439) (xy 84.722898 -380.194701) (xy 84.708606 -380.180412) (xy 84.700863 -380.161744)
			(xy 84.700364 -380.15164) (xy 84.700364 -379.993906) (xy 84.699937 -379.984721) (xy 84.693433 -379.967537)
			(xy 84.687664 -379.960378) (xy 84.665846 -379.934675) (xy 84.627759 -379.879045) (xy 84.596608 -379.819254)
			(xy 84.572843 -379.756162) (xy 84.556805 -379.690678) (xy 84.548726 -379.623744) (xy 84.548722 -379.556325)
			(xy 84.556793 -379.48939) (xy 84.572822 -379.423904) (xy 84.59658 -379.36081) (xy 84.627723 -379.301014)
			(xy 84.665804 -379.24538) (xy 84.687664 -379.219714) (xy 84.693487 -379.212588) (xy 84.699984 -379.195383)
			(xy 84.700364 -379.186186) (xy 84.700364 -378.693934) (xy 84.699923 -378.68475) (xy 84.693429 -378.667566)
			(xy 84.687664 -378.660406) (xy 84.665776 -378.634761) (xy 84.62769 -378.579123) (xy 84.596543 -378.519324)
			(xy 84.572781 -378.456224) (xy 84.556749 -378.390733) (xy 84.548676 -378.323793) (xy 81.271142 -378.323793)
			(xy 81.263068 -378.390729) (xy 81.247035 -378.456217) (xy 81.223272 -378.519312) (xy 81.192123 -378.579108)
			(xy 81.154035 -378.634741) (xy 81.132172 -378.660406) (xy 81.126387 -378.667559) (xy 81.119866 -378.684744)
			(xy 81.119472 -378.693934) (xy 81.119472 -379.186186) (xy 81.119895 -379.195372) (xy 81.126401 -379.212556)
			(xy 81.132172 -379.219714) (xy 81.154082 -379.245341) (xy 81.192171 -379.300981) (xy 81.223322 -379.360782)
			(xy 81.247084 -379.423884) (xy 81.263118 -379.489378) (xy 81.27119 -379.556321) (xy 81.271186 -379.623748)
			(xy 81.263105 -379.69069) (xy 81.247064 -379.756182) (xy 81.223293 -379.819281) (xy 81.192136 -379.879079)
			(xy 81.15404 -379.934713) (xy 81.132172 -379.960378) (xy 81.126356 -379.967509) (xy 81.119854 -379.984711)
			(xy 81.119472 -379.993906) (xy 81.119472 -380.151386) (xy 81.118962 -380.16151) (xy 81.111241 -380.180229)
			(xy 81.096962 -380.194585) (xy 81.078286 -380.202407) (xy 81.068164 -380.202948) (xy 80.351884 -380.202948)
			(xy 80.34178 -380.202429) (xy 80.323111 -380.194695) (xy 80.308818 -380.180409) (xy 80.301076 -380.161744)
			(xy 80.300576 -380.15164) (xy 80.300576 -379.993906) (xy 80.300168 -379.984718) (xy 80.293654 -379.967534)
			(xy 80.287876 -379.960378) (xy 80.266058 -379.934675) (xy 80.22797 -379.879045) (xy 80.196818 -379.819254)
			(xy 80.173052 -379.756162) (xy 80.157015 -379.690678) (xy 80.148935 -379.623744) (xy 80.148931 -379.556325)
			(xy 80.157002 -379.48939) (xy 80.173032 -379.423904) (xy 80.19679 -379.360809) (xy 80.227934 -379.301014)
			(xy 80.266016 -379.24538) (xy 80.287876 -379.219714) (xy 80.293689 -379.21258) (xy 80.300195 -379.195381)
			(xy 80.300576 -379.186186) (xy 80.300576 -378.693934) (xy 80.300155 -378.684748) (xy 80.29365 -378.667563)
			(xy 80.287876 -378.660406) (xy 80.265987 -378.634761) (xy 80.227901 -378.579123) (xy 80.196753 -378.519324)
			(xy 80.172991 -378.456225) (xy 80.156958 -378.390733) (xy 80.148885 -378.323793) (xy 76.870815 -378.323793)
			(xy 76.862781 -378.390552) (xy 76.846812 -378.455933) (xy 76.823143 -378.518936) (xy 76.792114 -378.578659)
			(xy 76.75417 -378.634246) (xy 76.732384 -378.659898) (xy 76.726604 -378.667055) (xy 76.72008 -378.684236)
			(xy 76.719684 -378.693426) (xy 76.719684 -379.186694) (xy 76.720101 -379.19588) (xy 76.72661 -379.213065)
			(xy 76.732384 -379.220222) (xy 76.754216 -379.245837) (xy 76.792162 -379.30143) (xy 76.823192 -379.361158)
			(xy 76.846861 -379.424168) (xy 76.86283 -379.489554) (xy 76.870871 -379.55638) (xy 76.870866 -379.623689)
			(xy 76.862818 -379.690514) (xy 76.846841 -379.755899) (xy 76.823164 -379.818905) (xy 76.792127 -379.87863)
			(xy 76.754174 -379.934218) (xy 76.732384 -379.95987) (xy 76.726573 -379.967005) (xy 76.720068 -379.984203)
			(xy 76.719684 -379.993398) (xy 76.719684 -380.151386) (xy 76.719156 -380.16154) (xy 76.71139 -380.180305)
			(xy 76.697035 -380.19467) (xy 76.678276 -380.202449) (xy 76.668122 -380.202948) (xy 75.951842 -380.202948)
			(xy 75.941671 -380.202501) (xy 75.922875 -380.194728) (xy 75.908488 -380.180349) (xy 75.900704 -380.161556)
			(xy 75.90028 -380.151386) (xy 75.90028 -379.993398) (xy 75.899875 -379.98421) (xy 75.893358 -379.967026)
			(xy 75.88758 -379.95987) (xy 75.865836 -379.934181) (xy 75.827883 -379.878601) (xy 75.796846 -379.818883)
			(xy 75.773169 -379.755883) (xy 75.757191 -379.690505) (xy 75.749143 -379.623686) (xy 75.749139 -379.556383)
			(xy 75.757179 -379.489563) (xy 75.773148 -379.424183) (xy 75.796818 -379.36118) (xy 75.827848 -379.301458)
			(xy 75.865794 -379.245874) (xy 75.88758 -379.220222) (xy 75.89339 -379.213086) (xy 75.899897 -379.195889)
			(xy 75.90028 -379.186694) (xy 75.90028 -378.693426) (xy 75.899862 -378.68424) (xy 75.893354 -378.667055)
			(xy 75.88758 -378.659898) (xy 75.865766 -378.634267) (xy 75.827815 -378.578679) (xy 75.79678 -378.518953)
			(xy 75.773107 -378.455945) (xy 75.757135 -378.39056) (xy 75.749092 -378.323734) (xy 72.471054 -378.323734)
			(xy 72.471054 -378.323791) (xy 72.46298 -378.390728) (xy 72.446947 -378.456216) (xy 72.423186 -378.519312)
			(xy 72.392037 -378.579107) (xy 72.353951 -378.634741) (xy 72.332088 -378.660406) (xy 72.326305 -378.667561)
			(xy 72.319783 -378.684744) (xy 72.319388 -378.693934) (xy 72.319388 -379.186186) (xy 72.319808 -379.195372)
			(xy 72.326315 -379.212556) (xy 72.332088 -379.219714) (xy 72.353998 -379.245342) (xy 72.392086 -379.300981)
			(xy 72.423235 -379.360783) (xy 72.446997 -379.423884) (xy 72.46303 -379.489378) (xy 72.471102 -379.556321)
			(xy 72.471098 -379.623748) (xy 72.463017 -379.69069) (xy 72.446977 -379.756182) (xy 72.423207 -379.819281)
			(xy 72.39205 -379.879078) (xy 72.353955 -379.934713) (xy 72.332088 -379.960378) (xy 72.326274 -379.967511)
			(xy 72.31977 -379.984711) (xy 72.319388 -379.993906) (xy 72.319388 -380.151386) (xy 72.318863 -380.161508)
			(xy 72.311145 -380.180224) (xy 72.296871 -380.19458) (xy 72.278199 -380.202404) (xy 72.26808 -380.202948)
			(xy 71.5518 -380.202948) (xy 71.541652 -380.202479) (xy 71.522909 -380.194693) (xy 71.508587 -380.180311)
			(xy 71.500879 -380.161536) (xy 71.500492 -380.151386) (xy 71.500492 -379.993906) (xy 71.500081 -379.984719)
			(xy 71.493568 -379.967534) (xy 71.487792 -379.960378) (xy 71.465974 -379.934675) (xy 71.427884 -379.879046)
			(xy 71.396732 -379.819255) (xy 71.372965 -379.756163) (xy 71.356927 -379.690678) (xy 71.348847 -379.623744)
			(xy 71.348843 -379.556325) (xy 71.356914 -379.48939) (xy 71.372945 -379.423903) (xy 71.396703 -379.360808)
			(xy 71.427848 -379.301013) (xy 71.465931 -379.245379) (xy 71.487792 -379.219714) (xy 71.493607 -379.212582)
			(xy 71.500111 -379.195381) (xy 71.500492 -379.186186) (xy 71.500492 -378.693934) (xy 71.500067 -378.684748)
			(xy 71.493564 -378.667564) (xy 71.487792 -378.660406) (xy 71.465903 -378.634762) (xy 71.427815 -378.579124)
			(xy 71.396666 -378.519325) (xy 71.372904 -378.456225) (xy 71.35687 -378.390734) (xy 71.348797 -378.323793)
			(xy 41.671024 -378.323793) (xy 41.66295 -378.390729) (xy 41.646915 -378.456218) (xy 41.623152 -378.519314)
			(xy 41.592001 -378.579109) (xy 41.553912 -378.634742) (xy 41.532048 -378.660406) (xy 41.52626 -378.667557)
			(xy 41.519742 -378.684743) (xy 41.519348 -378.693934) (xy 41.519348 -379.186186) (xy 41.519776 -379.195371)
			(xy 41.526279 -379.212555) (xy 41.532048 -379.219714) (xy 41.553959 -379.245341) (xy 41.59205 -379.30098)
			(xy 41.623201 -379.360781) (xy 41.646965 -379.423883) (xy 41.662999 -379.489377) (xy 41.671072 -379.55632)
			(xy 41.671068 -379.623749) (xy 41.662987 -379.690691) (xy 41.646945 -379.756183) (xy 41.623173 -379.819282)
			(xy 41.592014 -379.879079) (xy 41.553917 -379.934714) (xy 41.532048 -379.960378) (xy 41.526229 -379.967507)
			(xy 41.519729 -379.98471) (xy 41.519348 -379.993906) (xy 41.519348 -380.151386) (xy 41.518862 -380.161513)
			(xy 41.511136 -380.180236) (xy 41.49685 -380.194594) (xy 41.478165 -380.202411) (xy 41.46804 -380.202948)
			(xy 40.75176 -380.202948) (xy 40.741609 -380.202512) (xy 40.722865 -380.194712) (xy 40.708545 -380.180321)
			(xy 40.700838 -380.161539) (xy 40.700452 -380.151386) (xy 40.700452 -379.993906) (xy 40.700027 -379.984721)
			(xy 40.693523 -379.967537) (xy 40.687752 -379.960378) (xy 40.665931 -379.934676) (xy 40.627838 -379.879048)
			(xy 40.596682 -379.819258) (xy 40.572913 -379.756165) (xy 40.556873 -379.69068) (xy 40.548793 -379.623745)
			(xy 40.548788 -379.556324) (xy 40.556861 -379.489388) (xy 40.572893 -379.423901) (xy 40.596654 -379.360806)
			(xy 40.627802 -379.301011) (xy 40.665889 -379.245378) (xy 40.687752 -379.219714) (xy 40.693574 -379.212587)
			(xy 40.700072 -379.195382) (xy 40.700452 -379.186186) (xy 40.700452 -378.693934) (xy 40.700014 -378.68475)
			(xy 40.693519 -378.667566) (xy 40.687752 -378.660406) (xy 40.665861 -378.634763) (xy 40.627769 -378.579126)
			(xy 40.596617 -378.519328) (xy 40.572852 -378.456228) (xy 40.556817 -378.390735) (xy 40.548742 -378.323794)
			(xy 37.271233 -378.323794) (xy 37.263159 -378.390729) (xy 37.247125 -378.456217) (xy 37.223362 -378.519313)
			(xy 37.192212 -378.579108) (xy 37.154124 -378.634741) (xy 37.13226 -378.660406) (xy 37.126473 -378.667558)
			(xy 37.119954 -378.684743) (xy 37.11956 -378.693934) (xy 37.11956 -379.186186) (xy 37.119986 -379.195371)
			(xy 37.126489 -379.212555) (xy 37.13226 -379.219714) (xy 37.154171 -379.245341) (xy 37.192261 -379.30098)
			(xy 37.223411 -379.360781) (xy 37.247175 -379.423883) (xy 37.263208 -379.489377) (xy 37.271281 -379.55632)
			(xy 37.271277 -379.623749) (xy 37.263196 -379.690691) (xy 37.247154 -379.756183) (xy 37.223383 -379.819282)
			(xy 37.192225 -379.879079) (xy 37.154128 -379.934713) (xy 37.13226 -379.960378) (xy 37.126443 -379.967508)
			(xy 37.119941 -379.98471) (xy 37.11956 -379.993906) (xy 37.11956 -380.151386) (xy 37.119062 -380.161512)
			(xy 37.111339 -380.180233) (xy 37.097056 -380.194589) (xy 37.078375 -380.202409) (xy 37.068252 -380.202948)
			(xy 36.351972 -380.202948) (xy 36.341822 -380.202502) (xy 36.323078 -380.194707) (xy 36.308758 -380.180318)
			(xy 36.30105 -380.161538) (xy 36.300664 -380.151386) (xy 36.300664 -379.993906) (xy 36.300237 -379.984721)
			(xy 36.293733 -379.967537) (xy 36.287964 -379.960378) (xy 36.266146 -379.934675) (xy 36.228059 -379.879045)
			(xy 36.196908 -379.819254) (xy 36.173143 -379.756162) (xy 36.157105 -379.690678) (xy 36.149026 -379.623744)
			(xy 36.149022 -379.556325) (xy 36.157093 -379.48939) (xy 36.173122 -379.423904) (xy 36.19688 -379.36081)
			(xy 36.228023 -379.301014) (xy 36.266104 -379.24538) (xy 36.287964 -379.219714) (xy 36.293787 -379.212588)
			(xy 36.300284 -379.195383) (xy 36.300664 -379.186186) (xy 36.300664 -378.693934) (xy 36.300223 -378.68475)
			(xy 36.293729 -378.667566) (xy 36.287964 -378.660406) (xy 36.266076 -378.634761) (xy 36.22799 -378.579123)
			(xy 36.196843 -378.519324) (xy 36.173081 -378.456224) (xy 36.157049 -378.390733) (xy 36.148976 -378.323793)
			(xy 32.870906 -378.323793) (xy 32.862871 -378.390552) (xy 32.846902 -378.455933) (xy 32.823232 -378.518936)
			(xy 32.792203 -378.578659) (xy 32.754258 -378.634246) (xy 32.732472 -378.659898) (xy 32.72669 -378.667053)
			(xy 32.720167 -378.684236) (xy 32.719772 -378.693426) (xy 32.719772 -379.186694) (xy 32.720191 -379.19588)
			(xy 32.726699 -379.213064) (xy 32.732472 -379.220222) (xy 32.754305 -379.245837) (xy 32.792251 -379.301429)
			(xy 32.823282 -379.361158) (xy 32.846952 -379.424167) (xy 32.862921 -379.489554) (xy 32.870962 -379.55638)
			(xy 32.870957 -379.623689) (xy 32.862909 -379.690514) (xy 32.846931 -379.755899) (xy 32.823254 -379.818905)
			(xy 32.792216 -379.87863) (xy 32.754262 -379.934218) (xy 32.732472 -379.95987) (xy 32.72666 -379.967004)
			(xy 32.720155 -379.984203) (xy 32.719772 -379.993398) (xy 32.719772 -380.151386) (xy 32.719325 -380.161556)
			(xy 32.711547 -380.180348) (xy 32.697168 -380.194733) (xy 32.678379 -380.20252) (xy 32.66821 -380.202948)
			(xy 31.95193 -380.202948) (xy 31.941759 -380.202511) (xy 31.922962 -380.194733) (xy 31.908576 -380.180351)
			(xy 31.900792 -380.161557) (xy 31.900368 -380.151386) (xy 31.900368 -379.993398) (xy 31.899944 -379.984213)
			(xy 31.893438 -379.967029) (xy 31.887668 -379.95987) (xy 31.865925 -379.934181) (xy 31.827973 -379.878601)
			(xy 31.796936 -379.818882) (xy 31.773259 -379.755883) (xy 31.757282 -379.690505) (xy 31.749234 -379.623686)
			(xy 31.74923 -379.556384) (xy 31.75727 -379.489564) (xy 31.773239 -379.424184) (xy 31.796908 -379.361181)
			(xy 31.827937 -379.301459) (xy 31.865882 -379.245874) (xy 31.887668 -379.220222) (xy 31.893488 -379.213094)
			(xy 31.899987 -379.19589) (xy 31.900368 -379.186694) (xy 31.900368 -378.693426) (xy 31.89993 -378.684242)
			(xy 31.893434 -378.667058) (xy 31.887668 -378.659898) (xy 31.865854 -378.634267) (xy 31.827904 -378.578678)
			(xy 31.79687 -378.518952) (xy 31.773198 -378.455945) (xy 31.757226 -378.39056) (xy 31.749183 -378.323734)
			(xy 28.471145 -378.323734) (xy 28.471145 -378.323792) (xy 28.463071 -378.390728) (xy 28.447038 -378.456216)
			(xy 28.423275 -378.519312) (xy 28.392126 -378.579108) (xy 28.354039 -378.634741) (xy 28.332176 -378.660406)
			(xy 28.326392 -378.66756) (xy 28.31987 -378.684744) (xy 28.319476 -378.693934) (xy 28.319476 -379.186186)
			(xy 28.319898 -379.195372) (xy 28.326404 -379.212556) (xy 28.332176 -379.219714) (xy 28.354036 -379.245382)
			(xy 28.392125 -379.301016) (xy 28.423276 -379.360812) (xy 28.447 -379.423801) (xy 29.549058 -379.423801)
			(xy 29.549059 -379.356496) (xy 29.557103 -379.289673) (xy 29.573076 -379.224291) (xy 29.596749 -379.161286)
			(xy 29.627783 -379.101562) (xy 29.665732 -379.045976) (xy 29.68752 -379.020324) (xy 29.693334 -379.013191)
			(xy 29.699837 -378.995991) (xy 29.70022 -378.986796) (xy 29.70022 -378.828554) (xy 29.700695 -378.818396)
			(xy 29.708482 -378.799629) (xy 29.722852 -378.785266) (xy 29.741623 -378.77749) (xy 29.751782 -378.776992)
			(xy 30.468062 -378.776992) (xy 30.478212 -378.777564) (xy 30.496971 -378.785317) (xy 30.511336 -378.799658)
			(xy 30.51912 -378.818405) (xy 30.519624 -378.828554) (xy 30.519624 -378.986796) (xy 30.520031 -378.995984)
			(xy 30.526546 -379.013168) (xy 30.532324 -379.020324) (xy 30.55411 -379.045978) (xy 30.592059 -379.101564)
			(xy 30.623093 -379.161287) (xy 30.646766 -379.224291) (xy 30.662739 -379.289673) (xy 30.670784 -379.356496)
			(xy 30.670784 -379.423801) (xy 30.66274 -379.490624) (xy 30.646767 -379.556006) (xy 30.623094 -379.61901)
			(xy 30.592061 -379.678734) (xy 30.554112 -379.73432) (xy 30.532324 -379.759972) (xy 30.526517 -379.76711)
			(xy 30.520008 -379.784306) (xy 30.519624 -379.7935) (xy 30.519624 -380.286768) (xy 30.520044 -380.295954)
			(xy 30.52655 -380.313139) (xy 30.532324 -380.320296) (xy 30.554132 -380.345932) (xy 30.592083 -380.40152)
			(xy 30.623117 -380.461245) (xy 30.646791 -380.524252) (xy 30.662763 -380.589636) (xy 30.6708 -380.656404)
			(xy 33.948845 -380.656404) (xy 33.95692 -380.589467) (xy 33.972953 -380.523978) (xy 33.996716 -380.460882)
			(xy 34.027865 -380.401087) (xy 34.065953 -380.345453) (xy 34.087816 -380.319788) (xy 34.093602 -380.312635)
			(xy 34.100122 -380.29545) (xy 34.100516 -380.28626) (xy 34.100516 -379.794008) (xy 34.100098 -379.784822)
			(xy 34.093589 -379.767638) (xy 34.087816 -379.76048) (xy 34.065999 -379.734776) (xy 34.027907 -379.679148)
			(xy 33.996754 -379.619357) (xy 33.972986 -379.556265) (xy 33.956947 -379.49078) (xy 33.948867 -379.423846)
			(xy 33.948863 -379.356426) (xy 33.956934 -379.289491) (xy 33.972965 -379.224004) (xy 33.996724 -379.160909)
			(xy 34.02787 -379.101114) (xy 34.065954 -379.045481) (xy 34.087816 -379.019816) (xy 34.093633 -379.012685)
			(xy 34.100135 -378.995484) (xy 34.100516 -378.986288) (xy 34.100516 -378.828554) (xy 34.100988 -378.818427)
			(xy 34.108727 -378.79971) (xy 34.123017 -378.785356) (xy 34.1417 -378.777534) (xy 34.151824 -378.776992)
			(xy 34.868104 -378.776992) (xy 34.878257 -378.777418) (xy 34.897008 -378.785214) (xy 34.911331 -378.799609)
			(xy 34.919032 -378.818399) (xy 34.919412 -378.828554) (xy 34.919412 -378.986288) (xy 34.919825 -378.995475)
			(xy 34.926336 -379.012659) (xy 34.932112 -379.019816) (xy 34.954023 -379.045443) (xy 34.992109 -379.101083)
			(xy 35.023257 -379.160885) (xy 35.047018 -379.223986) (xy 35.06305 -379.28948) (xy 35.071122 -379.356422)
			(xy 35.071117 -379.42385) (xy 35.063037 -379.490791) (xy 35.046997 -379.556283) (xy 35.023228 -379.619381)
			(xy 34.992072 -379.679179) (xy 34.953978 -379.734815) (xy 34.932112 -379.76048) (xy 34.9263 -379.767615)
			(xy 34.919794 -379.784813) (xy 34.919412 -379.794008) (xy 34.919412 -380.28626) (xy 34.919839 -380.295446)
			(xy 34.92634 -380.31263) (xy 34.932112 -380.319788) (xy 34.953995 -380.345437) (xy 34.992083 -380.401074)
			(xy 35.023232 -380.460873) (xy 35.046994 -380.523972) (xy 35.063028 -380.589463) (xy 35.071102 -380.656403)
			(xy 35.071102 -380.656464) (xy 38.349165 -380.656464) (xy 38.357207 -380.589643) (xy 38.373176 -380.524262)
			(xy 38.396845 -380.461259) (xy 38.427874 -380.401536) (xy 38.465819 -380.345949) (xy 38.487604 -380.320296)
			(xy 38.493385 -380.31314) (xy 38.499909 -380.295958) (xy 38.500304 -380.286768) (xy 38.500304 -379.7935)
			(xy 38.499893 -379.784313) (xy 38.49338 -379.767129) (xy 38.487604 -379.759972) (xy 38.465865 -379.73428)
			(xy 38.427917 -379.678699) (xy 38.396884 -379.61898) (xy 38.37321 -379.555981) (xy 38.357234 -379.490604)
			(xy 38.349187 -379.423786) (xy 38.349183 -379.356486) (xy 38.357221 -379.289667) (xy 38.373188 -379.224288)
			(xy 38.396854 -379.161286) (xy 38.42788 -379.101563) (xy 38.465821 -379.045977) (xy 38.487604 -379.020324)
			(xy 38.493416 -379.01319) (xy 38.499921 -378.995991) (xy 38.500304 -378.986796) (xy 38.500304 -378.828554)
			(xy 38.500795 -378.818397) (xy 38.508578 -378.799634) (xy 38.522944 -378.785271) (xy 38.541709 -378.777493)
			(xy 38.551866 -378.776992) (xy 39.268146 -378.776992) (xy 39.278301 -378.777495) (xy 39.297062 -378.785276)
			(xy 39.311424 -378.799638) (xy 39.319205 -378.818399) (xy 39.319708 -378.828554) (xy 39.319708 -378.986796)
			(xy 39.320118 -378.995983) (xy 39.326632 -379.013168) (xy 39.332408 -379.020324) (xy 39.354244 -379.045937)
			(xy 39.392195 -379.101528) (xy 39.423229 -379.161256) (xy 39.446902 -379.224266) (xy 39.462873 -379.289653)
			(xy 39.470914 -379.356481) (xy 39.47091 -379.423791) (xy 39.46286 -379.490618) (xy 39.44688 -379.556003)
			(xy 39.4232 -379.61901) (xy 39.392158 -379.678735) (xy 39.3542 -379.734321) (xy 39.332408 -379.759972)
			(xy 39.326599 -379.767109) (xy 39.320092 -379.784306) (xy 39.319708 -379.7935) (xy 39.319708 -380.286768)
			(xy 39.320132 -380.295954) (xy 39.326636 -380.313138) (xy 39.332408 -380.320296) (xy 39.354217 -380.345931)
			(xy 39.392169 -380.401519) (xy 39.423204 -380.461244) (xy 39.446878 -380.524251) (xy 39.462851 -380.589636)
			(xy 39.470887 -380.656404) (xy 42.748933 -380.656404) (xy 42.757007 -380.589467) (xy 42.773041 -380.523979)
			(xy 42.796803 -380.460883) (xy 42.827951 -380.401087) (xy 42.866037 -380.345453) (xy 42.8879 -380.319788)
			(xy 42.893684 -380.312634) (xy 42.900206 -380.29545) (xy 42.9006 -380.28626) (xy 42.9006 -379.794008)
			(xy 42.900186 -379.784821) (xy 42.893675 -379.767637) (xy 42.8879 -379.76048) (xy 42.866083 -379.734776)
			(xy 42.827993 -379.679147) (xy 42.79684 -379.619356) (xy 42.773073 -379.556264) (xy 42.757035 -379.49078)
			(xy 42.748955 -379.423846) (xy 42.748951 -379.356426) (xy 42.757022 -379.289491) (xy 42.773052 -379.224005)
			(xy 42.796811 -379.16091) (xy 42.827956 -379.101115) (xy 42.866039 -379.045481) (xy 42.8879 -379.019816)
			(xy 42.893715 -379.012684) (xy 42.900219 -378.995483) (xy 42.9006 -378.986288) (xy 42.9006 -378.828554)
			(xy 42.901088 -378.818429) (xy 42.908823 -378.799715) (xy 42.923108 -378.785361) (xy 42.941786 -378.777537)
			(xy 42.951908 -378.776992) (xy 43.668188 -378.776992) (xy 43.67834 -378.777431) (xy 43.697091 -378.785221)
			(xy 43.711414 -378.799613) (xy 43.719116 -378.8184) (xy 43.719496 -378.828554) (xy 43.719496 -378.986288)
			(xy 43.719913 -378.995474) (xy 43.726422 -379.012659) (xy 43.732196 -379.019816) (xy 43.754107 -379.045442)
			(xy 43.792195 -379.101082) (xy 43.823344 -379.160884) (xy 43.847105 -379.223986) (xy 43.863138 -379.28948)
			(xy 43.87121 -379.356422) (xy 43.871205 -379.42385) (xy 43.863125 -379.490791) (xy 43.847084 -379.556283)
			(xy 43.823314 -379.619382) (xy 43.792158 -379.67918) (xy 43.754063 -379.734815) (xy 43.732196 -379.76048)
			(xy 43.726382 -379.767613) (xy 43.719878 -379.784813) (xy 43.719496 -379.794008) (xy 43.719496 -380.28626)
			(xy 43.719926 -380.295445) (xy 43.726426 -380.31263) (xy 43.732196 -380.319788) (xy 43.75408 -380.345437)
			(xy 43.792168 -380.401074) (xy 43.823318 -380.460872) (xy 43.847081 -380.523971) (xy 43.863116 -380.589462)
			(xy 43.87119 -380.656402) (xy 43.87119 -380.656463) (xy 73.548987 -380.656463) (xy 73.557029 -380.589642)
			(xy 73.572999 -380.524261) (xy 73.596669 -380.461258) (xy 73.6277 -380.401535) (xy 73.665646 -380.345948)
			(xy 73.687432 -380.320296) (xy 73.693217 -380.313143) (xy 73.699738 -380.295958) (xy 73.700132 -380.286768)
			(xy 73.700132 -379.7935) (xy 73.699715 -379.784314) (xy 73.693205 -379.76713) (xy 73.687432 -379.759972)
			(xy 73.665692 -379.734281) (xy 73.627742 -379.6787) (xy 73.596707 -379.618982) (xy 73.573032 -379.555982)
			(xy 73.557056 -379.490605) (xy 73.549008 -379.423787) (xy 73.549004 -379.356486) (xy 73.557043 -379.289666)
			(xy 73.573011 -379.224287) (xy 73.596678 -379.161285) (xy 73.627705 -379.101562) (xy 73.665648 -379.045976)
			(xy 73.687432 -379.020324) (xy 73.693247 -379.013192) (xy 73.69975 -378.995991) (xy 73.700132 -378.986796)
			(xy 73.700132 -378.828554) (xy 73.700596 -378.818394) (xy 73.708384 -378.799625) (xy 73.722759 -378.785262)
			(xy 73.741534 -378.777488) (xy 73.751694 -378.776992) (xy 74.467974 -378.776992) (xy 74.478125 -378.777553)
			(xy 74.496884 -378.785311) (xy 74.511249 -378.799655) (xy 74.519032 -378.818404) (xy 74.519536 -378.828554)
			(xy 74.519536 -378.986796) (xy 74.519962 -378.995981) (xy 74.526466 -379.013165) (xy 74.532236 -379.020324)
			(xy 74.554072 -379.045937) (xy 74.592021 -379.101528) (xy 74.623053 -379.161257) (xy 74.646725 -379.224267)
			(xy 74.662695 -379.289654) (xy 74.670736 -379.356481) (xy 74.670731 -379.423791) (xy 74.662682 -379.490617)
			(xy 74.646703 -379.556002) (xy 74.623024 -379.619009) (xy 74.591984 -379.678734) (xy 74.554028 -379.73432)
			(xy 74.532236 -379.759972) (xy 74.526419 -379.767102) (xy 74.519918 -379.784304) (xy 74.519536 -379.7935)
			(xy 74.519536 -380.286768) (xy 74.519976 -380.295952) (xy 74.52647 -380.313136) (xy 74.532236 -380.320296)
			(xy 74.554044 -380.345932) (xy 74.591994 -380.40152) (xy 74.623028 -380.461246) (xy 74.6467 -380.524252)
			(xy 74.662673 -380.589637) (xy 74.670709 -380.656404) (xy 77.948754 -380.656404) (xy 77.956829 -380.589466)
			(xy 77.972863 -380.523978) (xy 77.996626 -380.460882) (xy 78.027776 -380.401086) (xy 78.065864 -380.345453)
			(xy 78.087728 -380.319788) (xy 78.093516 -380.312637) (xy 78.100035 -380.295451) (xy 78.100428 -380.28626)
			(xy 78.100428 -379.794008) (xy 78.100008 -379.784822) (xy 78.093501 -379.767638) (xy 78.087728 -379.76048)
			(xy 78.06591 -379.734776) (xy 78.027818 -379.679148) (xy 77.996664 -379.619357) (xy 77.972896 -379.556265)
			(xy 77.956856 -379.490781) (xy 77.948776 -379.423846) (xy 77.948772 -379.356426) (xy 77.956843 -379.28949)
			(xy 77.972874 -379.224004) (xy 77.996634 -379.160909) (xy 78.027781 -379.101114) (xy 78.065866 -379.045481)
			(xy 78.087728 -379.019816) (xy 78.093546 -379.012686) (xy 78.100047 -378.995484) (xy 78.100428 -378.986288)
			(xy 78.100428 -378.828554) (xy 78.100889 -378.818426) (xy 78.108629 -378.799706) (xy 78.122923 -378.785352)
			(xy 78.14161 -378.777532) (xy 78.151736 -378.776992) (xy 78.868016 -378.776992) (xy 78.878125 -378.777472)
			(xy 78.896802 -378.785213) (xy 78.911096 -378.799512) (xy 78.918831 -378.818191) (xy 78.919324 -378.8283)
			(xy 78.919324 -378.986288) (xy 78.919734 -378.995475) (xy 78.926247 -379.01266) (xy 78.932024 -379.019816)
			(xy 78.953934 -379.045443) (xy 78.99202 -379.101083) (xy 79.023167 -379.160885) (xy 79.046928 -379.223987)
			(xy 79.062959 -379.28948) (xy 79.071031 -379.356423) (xy 79.071026 -379.42385) (xy 79.062946 -379.490791)
			(xy 79.046906 -379.556282) (xy 79.023138 -379.619381) (xy 78.991983 -379.679179) (xy 78.95389 -379.734814)
			(xy 78.932024 -379.76048) (xy 78.926214 -379.767616) (xy 78.919706 -379.784813) (xy 78.919324 -379.794008)
			(xy 78.919324 -380.28626) (xy 78.919748 -380.295446) (xy 78.926251 -380.312631) (xy 78.932024 -380.319788)
			(xy 78.953907 -380.345437) (xy 78.991993 -380.401075) (xy 79.023142 -380.460873) (xy 79.046904 -380.523972)
			(xy 79.062937 -380.589463) (xy 79.071011 -380.656403) (xy 79.071011 -380.656464) (xy 82.349074 -380.656464)
			(xy 82.357116 -380.589643) (xy 82.373086 -380.524262) (xy 82.396755 -380.461258) (xy 82.427785 -380.401535)
			(xy 82.46573 -380.345948) (xy 82.487516 -380.320296) (xy 82.493299 -380.313141) (xy 82.499821 -380.295958)
			(xy 82.500216 -380.286768) (xy 82.500216 -379.7935) (xy 82.499803 -379.784313) (xy 82.493291 -379.767129)
			(xy 82.487516 -379.759972) (xy 82.465776 -379.734281) (xy 82.427828 -379.678699) (xy 82.396794 -379.618981)
			(xy 82.373119 -379.555982) (xy 82.357144 -379.490604) (xy 82.349096 -379.423786) (xy 82.349092 -379.356486)
			(xy 82.357131 -379.289667) (xy 82.373098 -379.224288) (xy 82.396764 -379.161285) (xy 82.427791 -379.101563)
			(xy 82.465732 -379.045977) (xy 82.487516 -379.020324) (xy 82.493329 -379.013191) (xy 82.499833 -378.995991)
			(xy 82.500216 -378.986796) (xy 82.500216 -378.828554) (xy 82.500695 -378.818396) (xy 82.508481 -378.79963)
			(xy 82.52285 -378.785267) (xy 82.54162 -378.777491) (xy 82.551778 -378.776992) (xy 83.268058 -378.776992)
			(xy 83.278207 -378.777567) (xy 83.296967 -378.785319) (xy 83.311332 -378.799659) (xy 83.319116 -378.818405)
			(xy 83.31962 -378.828554) (xy 83.31962 -378.986796) (xy 83.320028 -378.995984) (xy 83.326543 -379.013168)
			(xy 83.33232 -379.020324) (xy 83.354156 -379.045937) (xy 83.392107 -379.101528) (xy 83.42314 -379.161256)
			(xy 83.446812 -379.224266) (xy 83.462783 -379.289654) (xy 83.470824 -379.356481) (xy 83.470819 -379.423791)
			(xy 83.46277 -379.490618) (xy 83.446791 -379.556003) (xy 83.423111 -379.61901) (xy 83.392069 -379.678734)
			(xy 83.354112 -379.734321) (xy 83.33232 -379.759972) (xy 83.326513 -379.76711) (xy 83.320004 -379.784306)
			(xy 83.31962 -379.7935) (xy 83.31962 -380.286768) (xy 83.320041 -380.295954) (xy 83.326547 -380.313139)
			(xy 83.33232 -380.320296) (xy 83.354129 -380.345931) (xy 83.392079 -380.401519) (xy 83.423114 -380.461245)
			(xy 83.446788 -380.524252) (xy 83.46276 -380.589636) (xy 83.470797 -380.656404) (xy 86.748842 -380.656404)
			(xy 86.756916 -380.589467) (xy 86.77295 -380.523979) (xy 86.796713 -380.460883) (xy 86.827862 -380.401087)
			(xy 86.865949 -380.345453) (xy 86.887812 -380.319788) (xy 86.893598 -380.312635) (xy 86.900118 -380.29545)
			(xy 86.900512 -380.28626) (xy 86.900512 -379.794008) (xy 86.900095 -379.784822) (xy 86.893586 -379.767637)
			(xy 86.887812 -379.76048) (xy 86.865995 -379.734776) (xy 86.827904 -379.679147) (xy 86.79675 -379.619357)
			(xy 86.772983 -379.556265) (xy 86.756944 -379.49078) (xy 86.748864 -379.423846) (xy 86.74886 -379.356426)
			(xy 86.756931 -379.289491) (xy 86.772962 -379.224004) (xy 86.796721 -379.160909) (xy 86.827867 -379.101115)
			(xy 86.86595 -379.045481) (xy 86.887812 -379.019816) (xy 86.893628 -379.012685) (xy 86.900131 -378.995483)
			(xy 86.900512 -378.986288) (xy 86.900512 -378.828554) (xy 86.900988 -378.818428) (xy 86.908726 -378.799711)
			(xy 86.923015 -378.785357) (xy 86.941696 -378.777535) (xy 86.95182 -378.776992) (xy 87.6681 -378.776992)
			(xy 87.678208 -378.777485) (xy 87.696884 -378.785221) (xy 87.711179 -378.799516) (xy 87.718915 -378.818192)
			(xy 87.719408 -378.8283) (xy 87.719408 -378.986288) (xy 87.719822 -378.995475) (xy 87.726333 -379.012659)
			(xy 87.732108 -379.019816) (xy 87.754019 -379.045442) (xy 87.792106 -379.101083) (xy 87.823254 -379.160884)
			(xy 87.847015 -379.223986) (xy 87.863047 -379.28948) (xy 87.871119 -379.356422) (xy 87.871114 -379.42385)
			(xy 87.863034 -379.490791) (xy 87.846994 -379.556283) (xy 87.823224 -379.619382) (xy 87.792068 -379.679179)
			(xy 87.753975 -379.734815) (xy 87.732108 -379.76048) (xy 87.726296 -379.767614) (xy 87.71979 -379.784813)
			(xy 87.719408 -379.794008) (xy 87.719408 -380.28626) (xy 87.719836 -380.295445) (xy 87.726337 -380.31263)
			(xy 87.732108 -380.319788) (xy 87.753991 -380.345437) (xy 87.792079 -380.401074) (xy 87.823228 -380.460873)
			(xy 87.846991 -380.523972) (xy 87.863025 -380.589463) (xy 87.871099 -380.656402) (xy 87.871097 -380.723828)
			(xy 87.863019 -380.790767) (xy 87.846982 -380.856257) (xy 87.838954 -380.877572) (xy 105.0036 -380.877572)
			(xy 105.0036 -380.013972) (xy 105.00409 -379.983988) (xy 105.011918 -379.924532) (xy 105.027439 -379.866607)
			(xy 105.050388 -379.811203) (xy 105.080372 -379.759269) (xy 105.116878 -379.711693) (xy 105.159283 -379.669288)
			(xy 105.206859 -379.632782) (xy 105.258793 -379.602798) (xy 105.314197 -379.579849) (xy 105.372122 -379.564328)
			(xy 105.431578 -379.5565) (xy 105.491546 -379.5565) (xy 105.551002 -379.564328) (xy 105.608927 -379.579849)
			(xy 105.664331 -379.602798) (xy 105.716265 -379.632782) (xy 105.763841 -379.669288) (xy 105.806246 -379.711693)
			(xy 105.842752 -379.759269) (xy 105.872736 -379.811203) (xy 105.895685 -379.866607) (xy 105.911206 -379.924532)
			(xy 105.919034 -379.983988) (xy 105.919524 -380.013972) (xy 105.919524 -380.656403) (xy 117.548873 -380.656403)
			(xy 117.556947 -380.589466) (xy 117.572982 -380.523977) (xy 117.596746 -380.460881) (xy 117.627898 -380.401085)
			(xy 117.665987 -380.345452) (xy 117.687852 -380.319788) (xy 117.693643 -380.312639) (xy 117.700159 -380.295451)
			(xy 117.700552 -380.28626) (xy 117.700552 -379.794008) (xy 117.700126 -379.784823) (xy 117.693622 -379.767639)
			(xy 117.687852 -379.76048) (xy 117.666033 -379.734777) (xy 117.62794 -379.679149) (xy 117.596784 -379.619358)
			(xy 117.573015 -379.556266) (xy 117.556975 -379.490781) (xy 117.548894 -379.423846) (xy 117.54889 -379.356426)
			(xy 117.556962 -379.28949) (xy 117.572994 -379.224003) (xy 117.596755 -379.160908) (xy 117.627903 -379.101113)
			(xy 117.665989 -379.04548) (xy 117.687852 -379.019816) (xy 117.693673 -379.012688) (xy 117.700172 -378.995484)
			(xy 117.700552 -378.986288) (xy 117.700552 -378.828554) (xy 117.700989 -378.818423) (xy 117.708734 -378.799698)
			(xy 117.723036 -378.785343) (xy 117.741731 -378.777528) (xy 117.75186 -378.776992) (xy 118.46814 -378.776992)
			(xy 118.478296 -378.777389) (xy 118.497047 -378.785196) (xy 118.511369 -378.7996) (xy 118.519069 -378.818396)
			(xy 118.519448 -378.828554) (xy 118.519448 -378.986288) (xy 118.519875 -378.995473) (xy 118.526378 -379.012657)
			(xy 118.532148 -379.019816) (xy 118.554061 -379.045441) (xy 118.592152 -379.10108) (xy 118.623303 -379.160882)
			(xy 118.647067 -379.223984) (xy 118.663101 -379.289478) (xy 118.671174 -379.356422) (xy 118.671169 -379.42385)
			(xy 118.663088 -379.490793) (xy 118.647046 -379.556285) (xy 118.623274 -379.619384) (xy 118.592115 -379.679181)
			(xy 118.554017 -379.734816) (xy 118.532148 -379.76048) (xy 118.526329 -379.767609) (xy 118.519829 -379.784812)
			(xy 118.519448 -379.794008) (xy 118.519448 -380.28626) (xy 118.519889 -380.295444) (xy 118.526382 -380.312628)
			(xy 118.532148 -380.319788) (xy 118.554033 -380.345436) (xy 118.592125 -380.401072) (xy 118.623278 -380.46087)
			(xy 118.647043 -380.523969) (xy 118.663079 -380.589461) (xy 118.671154 -380.656402) (xy 118.671154 -380.656463)
			(xy 121.949193 -380.656463) (xy 121.957235 -380.589642) (xy 121.973206 -380.524261) (xy 121.996876 -380.461257)
			(xy 122.027907 -380.401534) (xy 122.065854 -380.345948) (xy 122.08764 -380.320296) (xy 122.093426 -380.313143)
			(xy 122.099946 -380.295958) (xy 122.10034 -380.286768) (xy 122.10034 -379.7935) (xy 122.099921 -379.784314)
			(xy 122.093413 -379.76713) (xy 122.08764 -379.759972) (xy 122.0659 -379.734281) (xy 122.027949 -379.6787)
			(xy 121.996914 -379.618982) (xy 121.973238 -379.555982) (xy 121.957262 -379.490605) (xy 121.949214 -379.423787)
			(xy 121.94921 -379.356485) (xy 121.957249 -379.289666) (xy 121.973217 -379.224287) (xy 121.996884 -379.161284)
			(xy 122.027912 -379.101562) (xy 122.065855 -379.045976) (xy 122.08764 -379.020324) (xy 122.093456 -379.013193)
			(xy 122.099958 -378.995991) (xy 122.10034 -378.986796) (xy 122.10034 -378.828554) (xy 122.100796 -378.818393)
			(xy 122.108586 -378.799623) (xy 122.122963 -378.785259) (xy 122.141741 -378.777486) (xy 122.151902 -378.776992)
			(xy 122.868182 -378.776992) (xy 122.878333 -378.777547) (xy 122.897093 -378.785307) (xy 122.911457 -378.799653)
			(xy 122.919241 -378.818404) (xy 122.919744 -378.828554) (xy 122.919744 -378.986796) (xy 122.920169 -378.995981)
			(xy 122.926674 -379.013165) (xy 122.932444 -379.020324) (xy 122.95428 -379.045937) (xy 122.992228 -379.101529)
			(xy 123.02326 -379.161257) (xy 123.046931 -379.224267) (xy 123.062901 -379.289654) (xy 123.070942 -379.356482)
			(xy 123.070937 -379.423791) (xy 123.062888 -379.490617) (xy 123.04691 -379.556002) (xy 123.023231 -379.619009)
			(xy 122.992191 -379.678733) (xy 122.954235 -379.73432) (xy 122.932444 -379.759972) (xy 122.926627 -379.767103)
			(xy 122.920126 -379.784305) (xy 122.919744 -379.7935) (xy 122.919744 -380.286768) (xy 122.920182 -380.295952)
			(xy 122.926678 -380.313136) (xy 122.932444 -380.320296) (xy 122.954252 -380.345932) (xy 122.992201 -380.40152)
			(xy 123.023235 -380.461246) (xy 123.046907 -380.524252) (xy 123.062879 -380.589637) (xy 123.070915 -380.656404)
			(xy 126.34896 -380.656404) (xy 126.357035 -380.589466) (xy 126.373069 -380.523978) (xy 126.396833 -380.460881)
			(xy 126.427983 -380.401086) (xy 126.466072 -380.345453) (xy 126.487936 -380.319788) (xy 126.493725 -380.312637)
			(xy 126.500243 -380.295451) (xy 126.500636 -380.28626) (xy 126.500636 -379.794008) (xy 126.500214 -379.784822)
			(xy 126.493708 -379.767638) (xy 126.487936 -379.76048) (xy 126.466118 -379.734776) (xy 126.428025 -379.679148)
			(xy 126.396871 -379.619358) (xy 126.373102 -379.556266) (xy 126.357062 -379.490781) (xy 126.348982 -379.423846)
			(xy 126.348978 -379.356426) (xy 126.357049 -379.28949) (xy 126.373081 -379.224003) (xy 126.396841 -379.160908)
			(xy 126.427988 -379.101114) (xy 126.466074 -379.045481) (xy 126.487936 -379.019816) (xy 126.493755 -379.012687)
			(xy 126.500256 -378.995484) (xy 126.500636 -378.986288) (xy 126.500636 -378.828554) (xy 126.501089 -378.818425)
			(xy 126.508831 -378.799703) (xy 126.523127 -378.785349) (xy 126.541817 -378.777531) (xy 126.551944 -378.776992)
			(xy 127.268224 -378.776992) (xy 127.278379 -378.777402) (xy 127.29713 -378.785204) (xy 127.311452 -378.799604)
			(xy 127.319153 -378.818397) (xy 127.319532 -378.828554) (xy 127.319532 -378.986288) (xy 127.319963 -378.995473)
			(xy 127.326464 -379.012656) (xy 127.332232 -379.019816) (xy 127.354142 -379.045443) (xy 127.392227 -379.101084)
			(xy 127.423374 -379.160885) (xy 127.447134 -379.223987) (xy 127.463165 -379.289481) (xy 127.471237 -379.356423)
			(xy 127.471232 -379.423849) (xy 127.463152 -379.49079) (xy 127.447113 -379.556282) (xy 127.423345 -379.61938)
			(xy 127.39219 -379.679178) (xy 127.354098 -379.734814) (xy 127.332232 -379.76048) (xy 127.326411 -379.767607)
			(xy 127.319913 -379.784812) (xy 127.319532 -379.794008) (xy 127.319532 -380.28626) (xy 127.319977 -380.295443)
			(xy 127.326468 -380.312627) (xy 127.332232 -380.319788) (xy 127.354114 -380.345438) (xy 127.392201 -380.401075)
			(xy 127.423349 -380.460874) (xy 127.44711 -380.523973) (xy 127.463143 -380.589463) (xy 127.471217 -380.656403)
			(xy 127.471217 -380.656463) (xy 130.74928 -380.656463) (xy 130.757322 -380.589642) (xy 130.773292 -380.524262)
			(xy 130.796962 -380.461258) (xy 130.827992 -380.401535) (xy 130.865938 -380.345948) (xy 130.887724 -380.320296)
			(xy 130.893508 -380.313142) (xy 130.900029 -380.295958) (xy 130.900424 -380.286768) (xy 130.900424 -379.7935)
			(xy 130.900009 -379.784313) (xy 130.893498 -379.767129) (xy 130.887724 -379.759972) (xy 130.865984 -379.734281)
			(xy 130.828035 -379.678699) (xy 130.797 -379.618981) (xy 130.773326 -379.555982) (xy 130.75735 -379.490605)
			(xy 130.749302 -379.423787) (xy 130.749298 -379.356486) (xy 130.757337 -379.289667) (xy 130.773304 -379.224287)
			(xy 130.796971 -379.161285) (xy 130.827998 -379.101563) (xy 130.86594 -379.045977) (xy 130.887724 -379.020324)
			(xy 130.893538 -379.013191) (xy 130.900042 -378.995991) (xy 130.900424 -378.986796) (xy 130.900424 -378.828554)
			(xy 130.900895 -378.818395) (xy 130.908682 -378.799628) (xy 130.923054 -378.785264) (xy 130.941827 -378.777489)
			(xy 130.951986 -378.776992) (xy 131.668266 -378.776992) (xy 131.678416 -378.77756) (xy 131.697175 -378.785315)
			(xy 131.71154 -378.799657) (xy 131.719324 -378.818405) (xy 131.719828 -378.828554) (xy 131.719828 -378.986796)
			(xy 131.720234 -378.995984) (xy 131.72675 -379.013168) (xy 131.732528 -379.020324) (xy 131.754364 -379.045937)
			(xy 131.792314 -379.101528) (xy 131.823347 -379.161257) (xy 131.847018 -379.224267) (xy 131.862989 -379.289654)
			(xy 131.87103 -379.356481) (xy 131.871025 -379.423791) (xy 131.862976 -379.490617) (xy 131.846997 -379.556003)
			(xy 131.823317 -379.619009) (xy 131.792277 -379.678734) (xy 131.75432 -379.73432) (xy 131.732528 -379.759972)
			(xy 131.72671 -379.767101) (xy 131.72021 -379.784304) (xy 131.719828 -379.7935) (xy 131.719828 -380.286768)
			(xy 131.720247 -380.295954) (xy 131.726754 -380.313139) (xy 131.732528 -380.320296) (xy 131.754336 -380.345932)
			(xy 131.792287 -380.40152) (xy 131.823321 -380.461245) (xy 131.846994 -380.524252) (xy 131.862967 -380.589636)
			(xy 131.871003 -380.656404) (xy 161.548806 -380.656404) (xy 161.55688 -380.589468) (xy 161.572912 -380.523981)
			(xy 161.596672 -380.460885) (xy 161.627819 -380.401089) (xy 161.665902 -380.345454) (xy 161.687764 -380.319788)
			(xy 161.693556 -380.31264) (xy 161.700072 -380.295451) (xy 161.700464 -380.28626) (xy 161.700464 -379.794008)
			(xy 161.700036 -379.784823) (xy 161.693533 -379.767639) (xy 161.687764 -379.76048) (xy 161.665948 -379.734775)
			(xy 161.627861 -379.679146) (xy 161.59671 -379.619354) (xy 161.572945 -379.556263) (xy 161.556907 -379.490779)
			(xy 161.548828 -379.423846) (xy 161.548823 -379.356426) (xy 161.556894 -379.289492) (xy 161.572923 -379.224006)
			(xy 161.59668 -379.160911) (xy 161.627824 -379.101116) (xy 161.665904 -379.045482) (xy 161.687764 -379.019816)
			(xy 161.693587 -379.01269) (xy 161.700084 -378.995484) (xy 161.700464 -378.986288) (xy 161.700464 -378.828554)
			(xy 161.70089 -378.818421) (xy 161.708637 -378.799695) (xy 161.722942 -378.785339) (xy 161.741641 -378.777526)
			(xy 161.751772 -378.776992) (xy 162.468052 -378.776992) (xy 162.47817 -378.777455) (xy 162.496871 -378.785186)
			(xy 162.511187 -378.799488) (xy 162.518935 -378.818182) (xy 162.51936 -378.8283) (xy 162.51936 -378.986288)
			(xy 162.519785 -378.995473) (xy 162.526289 -379.012658) (xy 162.53206 -379.019816) (xy 162.553973 -379.045442)
			(xy 162.592062 -379.101081) (xy 162.623213 -379.160882) (xy 162.646977 -379.223984) (xy 162.66301 -379.289479)
			(xy 162.671083 -379.356422) (xy 162.671078 -379.42385) (xy 162.662997 -379.490792) (xy 162.646955 -379.556285)
			(xy 162.623184 -379.619384) (xy 162.592025 -379.679181) (xy 162.553928 -379.734815) (xy 162.53206 -379.76048)
			(xy 162.526242 -379.76761) (xy 162.519741 -379.784812) (xy 162.51936 -379.794008) (xy 162.51936 -380.28626)
			(xy 162.519799 -380.295444) (xy 162.526294 -380.312628) (xy 162.53206 -380.319788) (xy 162.553945 -380.345436)
			(xy 162.592036 -380.401072) (xy 162.623188 -380.460871) (xy 162.646953 -380.52397) (xy 162.662988 -380.589461)
			(xy 162.671063 -380.656402) (xy 162.671063 -380.656463) (xy 165.949102 -380.656463) (xy 165.957144 -380.589642)
			(xy 165.973115 -380.524261) (xy 165.996786 -380.461257) (xy 166.027818 -380.401534) (xy 166.065765 -380.345948)
			(xy 166.087552 -380.320296) (xy 166.093339 -380.313144) (xy 166.099858 -380.295959) (xy 166.100252 -380.286768)
			(xy 166.100252 -379.7935) (xy 166.09983 -379.784314) (xy 166.093323 -379.76713) (xy 166.087552 -379.759972)
			(xy 166.065811 -379.734281) (xy 166.02786 -379.678701) (xy 165.996824 -379.618982) (xy 165.973148 -379.555983)
			(xy 165.957171 -379.490605) (xy 165.949123 -379.423787) (xy 165.949119 -379.356485) (xy 165.957158 -379.289666)
			(xy 165.973127 -379.224286) (xy 165.996795 -379.161284) (xy 166.027823 -379.101562) (xy 166.065767 -379.045976)
			(xy 166.087552 -379.020324) (xy 166.09337 -379.013194) (xy 166.09987 -378.995992) (xy 166.100252 -378.986796)
			(xy 166.100252 -378.828554) (xy 166.100696 -378.818392) (xy 166.108488 -378.799619) (xy 166.122869 -378.785255)
			(xy 166.141651 -378.777484) (xy 166.151814 -378.776992) (xy 166.868094 -378.776992) (xy 166.878246 -378.777537)
			(xy 166.897006 -378.785301) (xy 166.91137 -378.79965) (xy 166.919153 -378.818403) (xy 166.919656 -378.828554)
			(xy 166.919656 -378.986796) (xy 166.920078 -378.995982) (xy 166.926584 -379.013166) (xy 166.932356 -379.020324)
			(xy 166.954191 -379.045937) (xy 166.992139 -379.101529) (xy 167.02317 -379.161258) (xy 167.046841 -379.224268)
			(xy 167.06281 -379.289655) (xy 167.070851 -379.356482) (xy 167.070847 -379.423791) (xy 167.062798 -379.490617)
			(xy 167.046819 -379.556001) (xy 167.023141 -379.619008) (xy 166.992102 -379.678733) (xy 166.954147 -379.73432)
			(xy 166.932356 -379.759972) (xy 166.926541 -379.767104) (xy 166.920038 -379.784305) (xy 166.919656 -379.7935)
			(xy 166.919656 -380.286768) (xy 166.920091 -380.295952) (xy 166.926588 -380.313137) (xy 166.932356 -380.320296)
			(xy 166.954164 -380.345932) (xy 166.992112 -380.40152) (xy 167.023145 -380.461246) (xy 167.046817 -380.524253)
			(xy 167.062789 -380.589637) (xy 167.070824 -380.656403) (xy 170.34887 -380.656403) (xy 170.356944 -380.589466)
			(xy 170.372979 -380.523977) (xy 170.396743 -380.460881) (xy 170.427894 -380.401086) (xy 170.465984 -380.345452)
			(xy 170.487848 -380.319788) (xy 170.493638 -380.312638) (xy 170.500155 -380.295451) (xy 170.500548 -380.28626)
			(xy 170.500548 -379.794008) (xy 170.500123 -379.784823) (xy 170.493619 -379.767639) (xy 170.487848 -379.76048)
			(xy 170.46603 -379.734777) (xy 170.427936 -379.679149) (xy 170.396781 -379.619358) (xy 170.373012 -379.556266)
			(xy 170.356971 -379.490781) (xy 170.348891 -379.423846) (xy 170.348887 -379.356426) (xy 170.356959 -379.28949)
			(xy 170.37299 -379.224003) (xy 170.396751 -379.160908) (xy 170.427899 -379.101113) (xy 170.465985 -379.04548)
			(xy 170.487848 -379.019816) (xy 170.493669 -379.012688) (xy 170.500168 -378.995484) (xy 170.500548 -378.986288)
			(xy 170.500548 -378.828554) (xy 170.500989 -378.818423) (xy 170.508734 -378.7997) (xy 170.523034 -378.785345)
			(xy 170.541727 -378.777529) (xy 170.551856 -378.776992) (xy 171.268136 -378.776992) (xy 171.278291 -378.777392)
			(xy 171.297043 -378.785198) (xy 171.311365 -378.799601) (xy 171.319065 -378.818396) (xy 171.319444 -378.828554)
			(xy 171.319444 -378.986288) (xy 171.319872 -378.995473) (xy 171.326375 -379.012657) (xy 171.332144 -379.019816)
			(xy 171.354057 -379.045441) (xy 171.392148 -379.10108) (xy 171.4233 -379.160881) (xy 171.447064 -379.223984)
			(xy 171.463098 -379.289478) (xy 171.47117 -379.356422) (xy 171.471166 -379.42385) (xy 171.463085 -379.490793)
			(xy 171.447042 -379.556285) (xy 171.42327 -379.619384) (xy 171.392111 -379.679182) (xy 171.354013 -379.734816)
			(xy 171.332144 -379.76048) (xy 171.326324 -379.767608) (xy 171.319825 -379.784812) (xy 171.319444 -379.794008)
			(xy 171.319444 -380.28626) (xy 171.319886 -380.295444) (xy 171.326379 -380.312628) (xy 171.332144 -380.319788)
			(xy 171.35403 -380.345436) (xy 171.392121 -380.401072) (xy 171.423274 -380.46087) (xy 171.44704 -380.523969)
			(xy 171.463076 -380.589461) (xy 171.471151 -380.656402) (xy 171.471151 -380.656463) (xy 174.74919 -380.656463)
			(xy 174.757232 -380.589642) (xy 174.773202 -380.524261) (xy 174.796873 -380.461258) (xy 174.827904 -380.401535)
			(xy 174.86585 -380.345948) (xy 174.887636 -380.320296) (xy 174.893421 -380.313143) (xy 174.899942 -380.295958)
			(xy 174.900336 -380.286768) (xy 174.900336 -379.7935) (xy 174.899918 -379.784314) (xy 174.893409 -379.76713)
			(xy 174.887636 -379.759972) (xy 174.865896 -379.734281) (xy 174.827946 -379.6787) (xy 174.796911 -379.618982)
			(xy 174.773235 -379.555982) (xy 174.757259 -379.490605) (xy 174.749211 -379.423787) (xy 174.749207 -379.356486)
			(xy 174.757246 -379.289666) (xy 174.773214 -379.224287) (xy 174.796881 -379.161284) (xy 174.827909 -379.101562)
			(xy 174.865851 -379.045976) (xy 174.887636 -379.020324) (xy 174.893452 -379.013193) (xy 174.899954 -378.995991)
			(xy 174.900336 -378.986796) (xy 174.900336 -378.828554) (xy 174.900796 -378.818394) (xy 174.908585 -378.799624)
			(xy 174.922961 -378.78526) (xy 174.941737 -378.777487) (xy 174.951898 -378.776992) (xy 175.668178 -378.776992)
			(xy 175.678329 -378.77755) (xy 175.697089 -378.785309) (xy 175.711453 -378.799654) (xy 175.719237 -378.818404)
			(xy 175.71974 -378.828554) (xy 175.71974 -378.986796) (xy 175.720166 -378.995981) (xy 175.72667 -379.013165)
			(xy 175.73244 -379.020324) (xy 175.754276 -379.045937) (xy 175.792225 -379.101529) (xy 175.823257 -379.161257)
			(xy 175.846928 -379.224267) (xy 175.862898 -379.289654) (xy 175.870939 -379.356481) (xy 175.870934 -379.423791)
			(xy 175.862885 -379.490617) (xy 175.846907 -379.556002) (xy 175.823227 -379.619009) (xy 175.792187 -379.678734)
			(xy 175.754231 -379.73432) (xy 175.73244 -379.759972) (xy 175.726623 -379.767102) (xy 175.720122 -379.784305)
			(xy 175.71974 -379.7935) (xy 175.71974 -380.286768) (xy 175.720179 -380.295952) (xy 175.726674 -380.313136)
			(xy 175.73244 -380.320296) (xy 175.754248 -380.345932) (xy 175.792198 -380.40152) (xy 175.823231 -380.461246)
			(xy 175.846904 -380.524252) (xy 175.862876 -380.589637) (xy 175.870919 -380.656462) (xy 175.870917 -380.723769)
			(xy 175.862871 -380.790593) (xy 175.846895 -380.855977) (xy 175.823219 -380.918982) (xy 175.792182 -380.978706)
			(xy 175.75423 -381.034292) (xy 175.73244 -381.059944) (xy 175.726635 -381.067083) (xy 175.720127 -381.084278)
			(xy 175.71974 -381.093472) (xy 175.71974 -381.251206) (xy 175.71934 -381.261381) (xy 175.711549 -381.28018)
			(xy 175.697156 -381.294565) (xy 175.678353 -381.302346) (xy 175.668178 -381.302768) (xy 174.951898 -381.302768)
			(xy 174.941741 -381.302268) (xy 174.922973 -381.294494) (xy 174.908608 -381.280131) (xy 174.900832 -381.261363)
			(xy 174.900336 -381.251206) (xy 174.900336 -381.093472) (xy 174.899931 -381.084284) (xy 174.893413 -381.067101)
			(xy 174.887636 -381.059944) (xy 174.865868 -381.034275) (xy 174.827919 -380.978691) (xy 174.796885 -380.91897)
			(xy 174.773211 -380.855968) (xy 174.757237 -380.790587) (xy 174.749191 -380.723767) (xy 174.74919 -380.656463)
			(xy 171.471151 -380.656463) (xy 171.471149 -380.723828) (xy 171.46307 -380.790769) (xy 171.447031 -380.85626)
			(xy 171.423262 -380.919358) (xy 171.392106 -380.979154) (xy 171.354011 -381.034788) (xy 171.332144 -381.060452)
			(xy 171.326336 -381.067589) (xy 171.31983 -381.084786) (xy 171.319444 -381.09398) (xy 171.319444 -381.251206)
			(xy 171.318978 -381.261335) (xy 171.311245 -381.280059) (xy 171.296952 -381.294416) (xy 171.278263 -381.302232)
			(xy 171.268136 -381.302768) (xy 170.551856 -381.302768) (xy 170.541695 -381.302414) (xy 170.522936 -381.294598)
			(xy 170.508613 -381.28018) (xy 170.50092 -381.26137) (xy 170.500548 -381.251206) (xy 170.500548 -381.09398)
			(xy 170.500137 -381.084793) (xy 170.493623 -381.067609) (xy 170.487848 -381.060452) (xy 170.466002 -381.034771)
			(xy 170.42791 -380.97914) (xy 170.396755 -380.919347) (xy 170.372988 -380.856252) (xy 170.35695 -380.790764)
			(xy 170.348871 -380.723827) (xy 170.34887 -380.656403) (xy 167.070824 -380.656403) (xy 167.070831 -380.656462)
			(xy 167.070829 -380.723768) (xy 167.062783 -380.790592) (xy 167.046808 -380.855976) (xy 167.023133 -380.918981)
			(xy 166.992097 -380.978705) (xy 166.954145 -381.034292) (xy 166.932356 -381.059944) (xy 166.926553 -381.067084)
			(xy 166.920043 -381.084279) (xy 166.919656 -381.093472) (xy 166.919656 -381.251206) (xy 166.919171 -381.261365)
			(xy 166.911394 -381.280135) (xy 166.897025 -381.2945) (xy 166.878253 -381.302274) (xy 166.868094 -381.302768)
			(xy 166.151814 -381.302768) (xy 166.141644 -381.302325) (xy 166.122851 -381.294546) (xy 166.108466 -381.280166)
			(xy 166.100679 -381.261376) (xy 166.100252 -381.251206) (xy 166.100252 -381.093472) (xy 166.099844 -381.084285)
			(xy 166.093327 -381.067101) (xy 166.087552 -381.059944) (xy 166.065784 -381.034276) (xy 166.027833 -380.978692)
			(xy 165.996799 -380.918971) (xy 165.973124 -380.855968) (xy 165.957149 -380.790588) (xy 165.949103 -380.723767)
			(xy 165.949102 -380.656463) (xy 162.671063 -380.656463) (xy 162.671061 -380.723828) (xy 162.662983 -380.790768)
			(xy 162.646944 -380.856259) (xy 162.623176 -380.919357) (xy 162.59202 -380.979153) (xy 162.553927 -381.034787)
			(xy 162.53206 -381.060452) (xy 162.526254 -381.06759) (xy 162.519746 -381.084786) (xy 162.51936 -381.09398)
			(xy 162.51936 -381.251206) (xy 162.518878 -381.261333) (xy 162.511148 -381.280054) (xy 162.496861 -381.29441)
			(xy 162.478177 -381.302229) (xy 162.468052 -381.302768) (xy 161.751772 -381.302768) (xy 161.741644 -381.302406)
			(xy 161.722933 -381.294643) (xy 161.708619 -381.28031) (xy 161.70088 -381.261589) (xy 161.700464 -381.25146)
			(xy 161.700464 -381.09398) (xy 161.700049 -381.084794) (xy 161.693537 -381.06761) (xy 161.687764 -381.060452)
			(xy 161.665921 -381.03477) (xy 161.627834 -380.979137) (xy 161.596684 -380.919343) (xy 161.572921 -380.856248)
			(xy 161.556885 -380.790762) (xy 161.548808 -380.723826) (xy 161.548806 -380.656404) (xy 131.871003 -380.656404)
			(xy 131.87101 -380.656461) (xy 131.871008 -380.723769) (xy 131.862961 -380.790593) (xy 131.846985 -380.855977)
			(xy 131.823309 -380.918982) (xy 131.792271 -380.978706) (xy 131.754318 -381.034292) (xy 131.732528 -381.059944)
			(xy 131.726722 -381.067082) (xy 131.720215 -381.084278) (xy 131.719828 -381.093472) (xy 131.719828 -381.251206)
			(xy 131.71944 -381.261382) (xy 131.711647 -381.280184) (xy 131.69725 -381.294569) (xy 131.678443 -381.302348)
			(xy 131.668266 -381.302768) (xy 130.951986 -381.302768) (xy 130.941828 -381.302278) (xy 130.92306 -381.2945)
			(xy 130.908695 -381.280133) (xy 130.90092 -381.261364) (xy 130.900424 -381.251206) (xy 130.900424 -381.093472)
			(xy 130.900022 -381.084284) (xy 130.893502 -381.0671) (xy 130.887724 -381.059944) (xy 130.865956 -381.034276)
			(xy 130.828008 -380.978691) (xy 130.796975 -380.91897) (xy 130.773301 -380.855967) (xy 130.757327 -380.790587)
			(xy 130.749282 -380.723767) (xy 130.74928 -380.656463) (xy 127.471217 -380.656463) (xy 127.471215 -380.723827)
			(xy 127.463138 -380.790766) (xy 127.447101 -380.856256) (xy 127.423336 -380.919354) (xy 127.392185 -380.979151)
			(xy 127.354096 -381.034786) (xy 127.332232 -381.060452) (xy 127.326423 -381.067588) (xy 127.319918 -381.084786)
			(xy 127.319532 -381.09398) (xy 127.319532 -381.251206) (xy 127.319077 -381.261337) (xy 127.311342 -381.280063)
			(xy 127.297046 -381.29442) (xy 127.278352 -381.302234) (xy 127.268224 -381.302768) (xy 126.551944 -381.302768)
			(xy 126.541789 -381.302342) (xy 126.523031 -381.294555) (xy 126.508705 -381.280159) (xy 126.50101 -381.261363)
			(xy 126.500636 -381.251206) (xy 126.500636 -381.09398) (xy 126.500227 -381.084793) (xy 126.493712 -381.067609)
			(xy 126.487936 -381.060452) (xy 126.46609 -381.034771) (xy 126.427999 -380.97914) (xy 126.396845 -380.919346)
			(xy 126.373078 -380.856251) (xy 126.35704 -380.790764) (xy 126.348962 -380.723826) (xy 126.34896 -380.656404)
			(xy 123.070915 -380.656404) (xy 123.070922 -380.656462) (xy 123.07092 -380.723769) (xy 123.062874 -380.790593)
			(xy 123.046898 -380.855976) (xy 123.023223 -380.918982) (xy 122.992186 -380.978706) (xy 122.954234 -381.034292)
			(xy 122.932444 -381.059944) (xy 122.926639 -381.067083) (xy 122.920131 -381.084279) (xy 122.919744 -381.093472)
			(xy 122.919744 -381.251206) (xy 122.919341 -381.26138) (xy 122.91155 -381.280178) (xy 122.897158 -381.294564)
			(xy 122.878356 -381.302345) (xy 122.868182 -381.302768) (xy 122.151902 -381.302768) (xy 122.141745 -381.302265)
			(xy 122.122977 -381.294492) (xy 122.108612 -381.28013) (xy 122.100836 -381.261363) (xy 122.10034 -381.251206)
			(xy 122.10034 -381.093472) (xy 122.099934 -381.084285) (xy 122.093417 -381.067101) (xy 122.08764 -381.059944)
			(xy 122.065872 -381.034276) (xy 122.027923 -380.978691) (xy 121.996888 -380.91897) (xy 121.973215 -380.855968)
			(xy 121.95724 -380.790588) (xy 121.949194 -380.723767) (xy 121.949193 -380.656463) (xy 118.671154 -380.656463)
			(xy 118.671152 -380.723828) (xy 118.663073 -380.790769) (xy 118.647034 -380.85626) (xy 118.623265 -380.919357)
			(xy 118.592109 -380.979154) (xy 118.554015 -381.034788) (xy 118.532148 -381.060452) (xy 118.52634 -381.067589)
			(xy 118.519834 -381.084786) (xy 118.519448 -381.09398) (xy 118.519448 -381.251206) (xy 118.518978 -381.261335)
			(xy 118.511246 -381.280058) (xy 118.496954 -381.294415) (xy 118.478266 -381.302231) (xy 118.46814 -381.302768)
			(xy 117.75186 -381.302768) (xy 117.741699 -381.30241) (xy 117.72294 -381.294596) (xy 117.708617 -381.280179)
			(xy 117.700924 -381.261369) (xy 117.700552 -381.251206) (xy 117.700552 -381.09398) (xy 117.70014 -381.084793)
			(xy 117.693626 -381.06761) (xy 117.687852 -381.060452) (xy 117.666006 -381.034771) (xy 117.627913 -380.97914)
			(xy 117.596759 -380.919347) (xy 117.572991 -380.856252) (xy 117.556953 -380.790764) (xy 117.548874 -380.723827)
			(xy 117.548873 -380.656403) (xy 105.919524 -380.656403) (xy 105.919524 -380.877572) (xy 105.919034 -380.907556)
			(xy 105.911206 -380.967012) (xy 105.895685 -381.024937) (xy 105.872736 -381.080341) (xy 105.842752 -381.132275)
			(xy 105.806246 -381.179851) (xy 105.763841 -381.222256) (xy 105.716265 -381.258762) (xy 105.664331 -381.288746)
			(xy 105.608927 -381.311695) (xy 105.551002 -381.327216) (xy 105.491546 -381.335044) (xy 105.431578 -381.335044)
			(xy 105.372122 -381.327216) (xy 105.314197 -381.311695) (xy 105.258793 -381.288746) (xy 105.206859 -381.258762)
			(xy 105.159283 -381.222256) (xy 105.116878 -381.179851) (xy 105.080372 -381.132275) (xy 105.050388 -381.080341)
			(xy 105.027439 -381.024937) (xy 105.011918 -380.967012) (xy 105.00409 -380.907556) (xy 105.0036 -380.877572)
			(xy 87.838954 -380.877572) (xy 87.823216 -380.919355) (xy 87.792063 -380.979152) (xy 87.753973 -381.034787)
			(xy 87.732108 -381.060452) (xy 87.726308 -381.067595) (xy 87.719795 -381.084787) (xy 87.719408 -381.09398)
			(xy 87.719408 -381.251206) (xy 87.71888 -381.261327) (xy 87.711159 -381.280039) (xy 87.696886 -381.294394)
			(xy 87.678218 -381.302221) (xy 87.6681 -381.302768) (xy 86.95182 -381.302768) (xy 86.941695 -381.302367)
			(xy 86.922985 -381.294619) (xy 86.908669 -381.280298) (xy 86.900929 -381.261585) (xy 86.900512 -381.25146)
			(xy 86.900512 -381.09398) (xy 86.900109 -381.084792) (xy 86.89359 -381.067608) (xy 86.887812 -381.060452)
			(xy 86.865967 -381.034771) (xy 86.827877 -380.979139) (xy 86.796725 -380.919345) (xy 86.772959 -380.85625)
			(xy 86.756922 -380.790763) (xy 86.748844 -380.723826) (xy 86.748842 -380.656404) (xy 83.470797 -380.656404)
			(xy 83.470804 -380.656461) (xy 83.470802 -380.723769) (xy 83.462755 -380.790593) (xy 83.446779 -380.855977)
			(xy 83.423102 -380.918983) (xy 83.392064 -380.978706) (xy 83.35411 -381.034292) (xy 83.33232 -381.059944)
			(xy 83.326525 -381.06709) (xy 83.320009 -381.08428) (xy 83.31962 -381.093472) (xy 83.31962 -381.251206)
			(xy 83.31924 -381.261383) (xy 83.311445 -381.280186) (xy 83.297046 -381.294572) (xy 83.278236 -381.302349)
			(xy 83.268058 -381.302768) (xy 82.551778 -381.302768) (xy 82.54162 -381.302285) (xy 82.522851 -381.294504)
			(xy 82.508487 -381.280136) (xy 82.500712 -381.261365) (xy 82.500216 -381.251206) (xy 82.500216 -381.093472)
			(xy 82.499816 -381.084284) (xy 82.493295 -381.0671) (xy 82.487516 -381.059944) (xy 82.465749 -381.034275)
			(xy 82.427801 -380.978691) (xy 82.396768 -380.918969) (xy 82.373095 -380.855967) (xy 82.357121 -380.790587)
			(xy 82.349076 -380.723767) (xy 82.349074 -380.656464) (xy 79.071011 -380.656464) (xy 79.071009 -380.723827)
			(xy 79.062932 -380.790767) (xy 79.046895 -380.856256) (xy 79.02313 -380.919354) (xy 78.991978 -380.979151)
			(xy 78.953888 -381.034786) (xy 78.932024 -381.060452) (xy 78.926226 -381.067596) (xy 78.919711 -381.084787)
			(xy 78.919324 -381.09398) (xy 78.919324 -381.251206) (xy 78.918877 -381.261337) (xy 78.911141 -381.280066)
			(xy 78.896842 -381.294423) (xy 78.878145 -381.302235) (xy 78.868016 -381.302768) (xy 78.151736 -381.302768)
			(xy 78.141612 -381.302354) (xy 78.122903 -381.294611) (xy 78.108586 -381.280294) (xy 78.100846 -381.261584)
			(xy 78.100428 -381.25146) (xy 78.100428 -381.09398) (xy 78.100021 -381.084793) (xy 78.093505 -381.067609)
			(xy 78.087728 -381.060452) (xy 78.065883 -381.034771) (xy 78.027792 -380.979139) (xy 77.996638 -380.919346)
			(xy 77.972872 -380.856251) (xy 77.956834 -380.790763) (xy 77.948756 -380.723826) (xy 77.948754 -380.656404)
			(xy 74.670709 -380.656404) (xy 74.670716 -380.656462) (xy 74.670714 -380.723769) (xy 74.662667 -380.790593)
			(xy 74.646691 -380.855977) (xy 74.623015 -380.918982) (xy 74.591978 -380.978706) (xy 74.554026 -381.034292)
			(xy 74.532236 -381.059944) (xy 74.52643 -381.067082) (xy 74.519923 -381.084278) (xy 74.519536 -381.093472)
			(xy 74.519536 -381.251206) (xy 74.51914 -381.261381) (xy 74.511349 -381.280181) (xy 74.496954 -381.294567)
			(xy 74.478149 -381.302347) (xy 74.467974 -381.302768) (xy 73.751694 -381.302768) (xy 73.741537 -381.302272)
			(xy 73.722769 -381.294496) (xy 73.708404 -381.280131) (xy 73.700628 -381.261363) (xy 73.700132 -381.251206)
			(xy 73.700132 -381.093472) (xy 73.699728 -381.084284) (xy 73.693209 -381.0671) (xy 73.687432 -381.059944)
			(xy 73.665664 -381.034275) (xy 73.627715 -380.978691) (xy 73.596682 -380.91897) (xy 73.573008 -380.855967)
			(xy 73.557034 -380.790587) (xy 73.548988 -380.723767) (xy 73.548987 -380.656463) (xy 43.87119 -380.656463)
			(xy 43.871188 -380.723828) (xy 43.86311 -380.790767) (xy 43.847073 -380.856258) (xy 43.823306 -380.919355)
			(xy 43.792153 -380.979152) (xy 43.754061 -381.034787) (xy 43.732196 -381.060452) (xy 43.726394 -381.067594)
			(xy 43.719883 -381.084787) (xy 43.719496 -381.09398) (xy 43.719496 -381.251206) (xy 43.718979 -381.261329)
			(xy 43.711256 -381.280043) (xy 43.69698 -381.294398) (xy 43.678308 -381.302223) (xy 43.668188 -381.302768)
			(xy 42.951908 -381.302768) (xy 42.94175 -381.302371) (xy 42.922992 -381.294572) (xy 42.908667 -381.280167)
			(xy 42.900973 -381.261366) (xy 42.9006 -381.251206) (xy 42.9006 -381.09398) (xy 42.9002 -381.084792)
			(xy 42.893679 -381.067607) (xy 42.8879 -381.060452) (xy 42.866056 -381.034771) (xy 42.827966 -380.979138)
			(xy 42.796815 -380.919344) (xy 42.773049 -380.85625) (xy 42.757013 -380.790763) (xy 42.748935 -380.723826)
			(xy 42.748933 -380.656404) (xy 39.470887 -380.656404) (xy 39.470894 -380.656461) (xy 39.470893 -380.723769)
			(xy 39.462846 -380.790594) (xy 39.446869 -380.855978) (xy 39.423192 -380.918983) (xy 39.392153 -380.978707)
			(xy 39.354199 -381.034293) (xy 39.332408 -381.059944) (xy 39.326611 -381.067089) (xy 39.320096 -381.08428)
			(xy 39.319708 -381.093472) (xy 39.319708 -381.251206) (xy 39.319173 -381.261358) (xy 39.311405 -381.280119)
			(xy 39.297052 -381.294482) (xy 39.278298 -381.302265) (xy 39.268146 -381.302768) (xy 38.551866 -381.302768)
			(xy 38.541707 -381.302295) (xy 38.522938 -381.29451) (xy 38.508574 -381.280138) (xy 38.5008 -381.261365)
			(xy 38.500304 -381.251206) (xy 38.500304 -381.093472) (xy 38.499907 -381.084283) (xy 38.493384 -381.067099)
			(xy 38.487604 -381.059944) (xy 38.465837 -381.034275) (xy 38.42789 -380.97869) (xy 38.396858 -380.918969)
			(xy 38.373185 -380.855966) (xy 38.357212 -380.790587) (xy 38.349167 -380.723766) (xy 38.349165 -380.656464)
			(xy 35.071102 -380.656464) (xy 35.0711 -380.723828) (xy 35.063023 -380.790767) (xy 35.046985 -380.856257)
			(xy 35.023219 -380.919355) (xy 34.992067 -380.979151) (xy 34.953977 -381.034787) (xy 34.932112 -381.060452)
			(xy 34.926312 -381.067595) (xy 34.919799 -381.084787) (xy 34.919412 -381.09398) (xy 34.919412 -381.251206)
			(xy 34.91888 -381.261327) (xy 34.91116 -381.280038) (xy 34.896888 -381.294392) (xy 34.878222 -381.30222)
			(xy 34.868104 -381.302768) (xy 34.151824 -381.302768) (xy 34.141667 -381.302358) (xy 34.122909 -381.294565)
			(xy 34.108584 -381.280164) (xy 34.100889 -381.261365) (xy 34.100516 -381.251206) (xy 34.100516 -381.09398)
			(xy 34.100112 -381.084792) (xy 34.093594 -381.067608) (xy 34.087816 -381.060452) (xy 34.065971 -381.034771)
			(xy 34.027881 -380.979139) (xy 33.996728 -380.919345) (xy 33.972962 -380.85625) (xy 33.956925 -380.790763)
			(xy 33.948847 -380.723826) (xy 33.948845 -380.656404) (xy 30.6708 -380.656404) (xy 30.670807 -380.656461)
			(xy 30.670805 -380.723769) (xy 30.662758 -380.790593) (xy 30.646782 -380.855977) (xy 30.623105 -380.918982)
			(xy 30.592068 -380.978706) (xy 30.554114 -381.034292) (xy 30.532324 -381.059944) (xy 30.526529 -381.067091)
			(xy 30.520013 -381.08428) (xy 30.519624 -381.093472) (xy 30.519624 -381.251206) (xy 30.51924 -381.261383)
			(xy 30.511446 -381.280185) (xy 30.497048 -381.294571) (xy 30.478239 -381.302349) (xy 30.468062 -381.302768)
			(xy 29.751782 -381.302768) (xy 29.741624 -381.302282) (xy 29.722855 -381.294502) (xy 29.708491 -381.280135)
			(xy 29.700716 -381.261364) (xy 29.70022 -381.251206) (xy 29.70022 -381.093472) (xy 29.699819 -381.084284)
			(xy 29.693298 -381.0671) (xy 29.68752 -381.059944) (xy 29.665752 -381.034276) (xy 29.627804 -380.978691)
			(xy 29.596771 -380.918969) (xy 29.573098 -380.855967) (xy 29.557124 -380.790587) (xy 29.549079 -380.723767)
			(xy 29.549077 -380.656463) (xy 29.557119 -380.589643) (xy 29.573089 -380.524262) (xy 29.596759 -380.461258)
			(xy 29.627789 -380.401535) (xy 29.665734 -380.345948) (xy 29.68752 -380.320296) (xy 29.693303 -380.313141)
			(xy 29.699825 -380.295958) (xy 29.70022 -380.286768) (xy 29.70022 -379.7935) (xy 29.699806 -379.784313)
			(xy 29.693295 -379.767129) (xy 29.68752 -379.759972) (xy 29.66573 -379.734322) (xy 29.627781 -379.678735)
			(xy 29.596748 -379.619011) (xy 29.573075 -379.556006) (xy 29.557102 -379.490624) (xy 29.549058 -379.423801)
			(xy 28.447 -379.423801) (xy 28.447041 -379.423909) (xy 28.463077 -379.489397) (xy 28.471153 -379.556335)
			(xy 28.471153 -379.623759) (xy 28.463078 -379.690697) (xy 28.447043 -379.756186) (xy 28.423279 -379.819282)
			(xy 28.392128 -379.879078) (xy 28.35404 -379.934713) (xy 28.332176 -379.960378) (xy 28.326361 -379.96751)
			(xy 28.319858 -379.984711) (xy 28.319476 -379.993906) (xy 28.319476 -380.151386) (xy 28.318962 -380.16151)
			(xy 28.311242 -380.180228) (xy 28.296964 -380.194584) (xy 28.278289 -380.202406) (xy 28.268168 -380.202948)
			(xy 27.551888 -380.202948) (xy 27.541784 -380.202426) (xy 27.523115 -380.194693) (xy 27.508823 -380.180408)
			(xy 27.50108 -380.161743) (xy 27.50058 -380.15164) (xy 27.50058 -379.993906) (xy 27.500171 -379.984719)
			(xy 27.493657 -379.967534) (xy 27.48788 -379.960378) (xy 27.466012 -379.934716) (xy 27.427923 -379.879081)
			(xy 27.396771 -379.819285) (xy 27.373007 -379.756187) (xy 27.356972 -379.690698) (xy 27.348896 -379.623759)
			(xy 27.348896 -379.556335) (xy 27.356973 -379.489396) (xy 27.373009 -379.423907) (xy 27.396774 -379.36081)
			(xy 27.427926 -379.301013) (xy 27.466015 -379.245379) (xy 27.48788 -379.219714) (xy 27.493693 -379.21258)
			(xy 27.500199 -379.195381) (xy 27.50058 -379.186186) (xy 27.50058 -378.693934) (xy 27.500158 -378.684748)
			(xy 27.493653 -378.667563) (xy 27.48788 -378.660406) (xy 27.465991 -378.634761) (xy 27.427905 -378.579124)
			(xy 27.396756 -378.519324) (xy 27.372994 -378.456225) (xy 27.356961 -378.390733) (xy 27.348888 -378.323793)
			(xy 0.508 -378.323793) (xy 0.508 -382.223705) (xy 27.348899 -382.223705) (xy 27.3489 -382.15628)
			(xy 27.356976 -382.089342) (xy 27.373012 -382.023853) (xy 27.396777 -381.960755) (xy 27.427928 -381.900959)
			(xy 27.466016 -381.845324) (xy 27.48788 -381.819658) (xy 27.493675 -381.812511) (xy 27.500191 -381.795322)
			(xy 27.50058 -381.78613) (xy 27.50058 -381.628904) (xy 27.501088 -381.618798) (xy 27.508821 -381.600124)
			(xy 27.52311 -381.58583) (xy 27.541782 -381.578091) (xy 27.551888 -381.577596) (xy 28.268168 -381.577596)
			(xy 28.278288 -381.578042) (xy 28.29699 -381.585779) (xy 28.311306 -381.600086) (xy 28.319053 -381.618784)
			(xy 28.319476 -381.628904) (xy 28.319476 -381.78613) (xy 28.319877 -381.795318) (xy 28.326398 -381.812502)
			(xy 28.332176 -381.819658) (xy 28.354031 -381.845331) (xy 28.392122 -381.900964) (xy 28.423274 -381.960759)
			(xy 28.44704 -382.023855) (xy 28.463077 -382.089343) (xy 28.471154 -382.156281) (xy 28.471155 -382.223646)
			(xy 31.749194 -382.223646) (xy 31.749195 -382.156339) (xy 31.757241 -382.089516) (xy 31.773216 -382.024132)
			(xy 31.796891 -381.961127) (xy 31.827927 -381.901404) (xy 31.865879 -381.845818) (xy 31.887668 -381.820166)
			(xy 31.89347 -381.813025) (xy 31.899979 -381.795831) (xy 31.900368 -381.786638) (xy 31.900368 -381.628904)
			(xy 31.900824 -381.618754) (xy 31.908613 -381.600008) (xy 31.922998 -381.585686) (xy 31.941778 -381.57798)
			(xy 31.95193 -381.577596) (xy 32.66821 -381.577596) (xy 32.678332 -381.578117) (xy 32.697045 -381.58584)
			(xy 32.711399 -381.600115) (xy 32.719226 -381.618785) (xy 32.719772 -381.628904) (xy 32.719772 -381.786638)
			(xy 32.72017 -381.795826) (xy 32.726693 -381.81301) (xy 32.732472 -381.820166) (xy 32.75425 -381.845826)
			(xy 32.792198 -381.901412) (xy 32.823231 -381.961134) (xy 32.846904 -382.024138) (xy 32.862877 -382.089519)
			(xy 32.870922 -382.15634) (xy 32.870923 -382.223645) (xy 32.870916 -382.223704) (xy 36.148987 -382.223704)
			(xy 36.148988 -382.156281) (xy 36.157064 -382.089342) (xy 36.1731 -382.023853) (xy 36.196863 -381.960756)
			(xy 36.228013 -381.900959) (xy 36.266101 -381.845324) (xy 36.287964 -381.819658) (xy 36.293769 -381.812519)
			(xy 36.300277 -381.795323) (xy 36.300664 -381.78613) (xy 36.300664 -381.628904) (xy 36.301188 -381.6188)
			(xy 36.308917 -381.600129) (xy 36.323202 -381.585835) (xy 36.341868 -381.578094) (xy 36.351972 -381.577596)
			(xy 37.068252 -381.577596) (xy 37.078371 -381.578055) (xy 37.097073 -381.585787) (xy 37.111388 -381.60009)
			(xy 37.119136 -381.618786) (xy 37.11956 -381.628904) (xy 37.11956 -381.78613) (xy 37.119965 -381.795318)
			(xy 37.126483 -381.812501) (xy 37.13226 -381.819658) (xy 37.154116 -381.845331) (xy 37.192207 -381.900963)
			(xy 37.223361 -381.960758) (xy 37.247127 -382.023854) (xy 37.263164 -382.089343) (xy 37.271242 -382.156281)
			(xy 37.271243 -382.223704) (xy 37.271243 -382.223705) (xy 40.548753 -382.223705) (xy 40.548754 -382.15628)
			(xy 40.556832 -382.08934) (xy 40.57287 -382.02385) (xy 40.596638 -381.960752) (xy 40.627792 -381.900956)
			(xy 40.665886 -381.845322) (xy 40.687752 -381.819658) (xy 40.693555 -381.812518) (xy 40.700065 -381.795323)
			(xy 40.700452 -381.78613) (xy 40.700452 -381.628904) (xy 40.700987 -381.618801) (xy 40.708715 -381.600133)
			(xy 40.722996 -381.585839) (xy 40.741658 -381.578096) (xy 40.75176 -381.577596) (xy 41.46804 -381.577596)
			(xy 41.478151 -381.578052) (xy 41.496829 -381.585802) (xy 41.511122 -381.600108) (xy 41.518856 -381.618793)
			(xy 41.519348 -381.628904) (xy 41.519348 -381.78613) (xy 41.519755 -381.795317) (xy 41.526272 -381.812501)
			(xy 41.532048 -381.819658) (xy 41.553904 -381.84533) (xy 41.591996 -381.900963) (xy 41.62315 -381.960757)
			(xy 41.646917 -382.023853) (xy 41.662955 -382.089342) (xy 41.671033 -382.156281) (xy 41.671034 -382.223645)
			(xy 44.949073 -382.223645) (xy 44.949074 -382.15634) (xy 44.957119 -382.089516) (xy 44.973093 -382.024133)
			(xy 44.996767 -381.961128) (xy 45.027801 -381.901405) (xy 45.065751 -381.845818) (xy 45.08754 -381.820166)
			(xy 45.093339 -381.813022) (xy 45.099851 -381.795831) (xy 45.10024 -381.786638) (xy 45.10024 -381.628904)
			(xy 45.100626 -381.618745) (xy 45.108427 -381.599985) (xy 45.122836 -381.58566) (xy 45.141641 -381.577968)
			(xy 45.151802 -381.577596) (xy 45.868082 -381.577596) (xy 45.878202 -381.57814) (xy 45.896915 -381.585854)
			(xy 45.91127 -381.600122) (xy 45.919098 -381.618787) (xy 45.919644 -381.628904) (xy 45.919644 -381.786638)
			(xy 45.920049 -381.795826) (xy 45.926568 -381.813009) (xy 45.932344 -381.820166) (xy 45.954122 -381.845826)
			(xy 45.992072 -381.901411) (xy 46.023107 -381.961133) (xy 46.046781 -382.024137) (xy 46.062755 -382.089518)
			(xy 46.070801 -382.15634) (xy 46.070801 -382.223645) (xy 46.070794 -382.223705) (xy 71.348808 -382.223705)
			(xy 71.348809 -382.15628) (xy 71.356886 -382.089342) (xy 71.372922 -382.023852) (xy 71.396687 -381.960755)
			(xy 71.427838 -381.900958) (xy 71.465928 -381.845323) (xy 71.487792 -381.819658) (xy 71.493588 -381.812512)
			(xy 71.500103 -381.795322) (xy 71.500492 -381.78613) (xy 71.500492 -381.628904) (xy 71.500919 -381.618783)
			(xy 71.508664 -381.600081) (xy 71.522977 -381.585767) (xy 71.541679 -381.57802) (xy 71.5518 -381.577596)
			(xy 72.26808 -381.577596) (xy 72.278201 -381.578032) (xy 72.296903 -381.585773) (xy 72.311218 -381.600083)
			(xy 72.318965 -381.618783) (xy 72.319388 -381.628904) (xy 72.319388 -381.78613) (xy 72.319786 -381.795318)
			(xy 72.326308 -381.812503) (xy 72.332088 -381.819658) (xy 72.353943 -381.845331) (xy 72.392032 -381.900964)
			(xy 72.423184 -381.960759) (xy 72.446949 -382.023855) (xy 72.462986 -382.089343) (xy 72.471063 -382.156281)
			(xy 72.471064 -382.223646) (xy 75.749104 -382.223646) (xy 75.749104 -382.156339) (xy 75.75715 -382.089515)
			(xy 75.773125 -382.024132) (xy 75.796801 -381.961127) (xy 75.827838 -381.901403) (xy 75.86579 -381.845818)
			(xy 75.88758 -381.820166) (xy 75.893371 -381.813017) (xy 75.89989 -381.795829) (xy 75.90028 -381.786638)
			(xy 75.90028 -381.628904) (xy 75.900725 -381.618753) (xy 75.908515 -381.600004) (xy 75.922904 -381.585681)
			(xy 75.941689 -381.577978) (xy 75.951842 -381.577596) (xy 76.668122 -381.577596) (xy 76.678245 -381.578107)
			(xy 76.696958 -381.585834) (xy 76.711312 -381.600112) (xy 76.719138 -381.618784) (xy 76.719684 -381.628904)
			(xy 76.719684 -381.786638) (xy 76.720079 -381.795827) (xy 76.726604 -381.813011) (xy 76.732384 -381.820166)
			(xy 76.754161 -381.845826) (xy 76.792109 -381.901412) (xy 76.823141 -381.961135) (xy 76.846814 -382.024138)
			(xy 76.862787 -382.089519) (xy 76.870831 -382.156341) (xy 76.870832 -382.223644) (xy 76.870825 -382.223704)
			(xy 80.148896 -382.223704) (xy 80.148897 -382.15628) (xy 80.156973 -382.089342) (xy 80.173009 -382.023853)
			(xy 80.196773 -381.960755) (xy 80.227924 -381.900959) (xy 80.266012 -381.845324) (xy 80.287876 -381.819658)
			(xy 80.29367 -381.812511) (xy 80.300187 -381.795322) (xy 80.300576 -381.78613) (xy 80.300576 -381.628904)
			(xy 80.301088 -381.618798) (xy 80.30882 -381.600125) (xy 80.323108 -381.585831) (xy 80.341779 -381.578092)
			(xy 80.351884 -381.577596) (xy 81.068164 -381.577596) (xy 81.078284 -381.578046) (xy 81.096986 -381.585781)
			(xy 81.111301 -381.600087) (xy 81.119048 -381.618785) (xy 81.119472 -381.628904) (xy 81.119472 -381.78613)
			(xy 81.119874 -381.795318) (xy 81.126394 -381.812502) (xy 81.132172 -381.819658) (xy 81.154027 -381.845331)
			(xy 81.192118 -381.900964) (xy 81.223271 -381.960759) (xy 81.247037 -382.023854) (xy 81.263074 -382.089343)
			(xy 81.271151 -382.156281) (xy 81.271152 -382.223704) (xy 84.548687 -382.223704) (xy 84.548688 -382.156281)
			(xy 84.556764 -382.089342) (xy 84.5728 -382.023853) (xy 84.596563 -381.960756) (xy 84.627713 -381.900959)
			(xy 84.665801 -381.845324) (xy 84.687664 -381.819658) (xy 84.693469 -381.812519) (xy 84.699977 -381.795323)
			(xy 84.700364 -381.78613) (xy 84.700364 -381.628904) (xy 84.700888 -381.6188) (xy 84.708617 -381.600129)
			(xy 84.722902 -381.585835) (xy 84.741568 -381.578094) (xy 84.751672 -381.577596) (xy 85.467952 -381.577596)
			(xy 85.478071 -381.578055) (xy 85.496773 -381.585787) (xy 85.511088 -381.60009) (xy 85.518836 -381.618786)
			(xy 85.51926 -381.628904) (xy 85.51926 -381.78613) (xy 85.519665 -381.795318) (xy 85.526183 -381.812501)
			(xy 85.53196 -381.819658) (xy 85.553816 -381.845331) (xy 85.591907 -381.900963) (xy 85.623061 -381.960758)
			(xy 85.646827 -382.023854) (xy 85.662864 -382.089343) (xy 85.670942 -382.156281) (xy 85.670943 -382.223646)
			(xy 88.948982 -382.223646) (xy 88.948983 -382.156339) (xy 88.957028 -382.089516) (xy 88.973003 -382.024133)
			(xy 88.996677 -381.961128) (xy 89.027712 -381.901404) (xy 89.065663 -381.845818) (xy 89.087452 -381.820166)
			(xy 89.093252 -381.813023) (xy 89.099763 -381.795831) (xy 89.100152 -381.786638) (xy 89.100152 -381.628904)
			(xy 89.100624 -381.618756) (xy 89.108409 -381.600013) (xy 89.12279 -381.585691) (xy 89.141564 -381.577983)
			(xy 89.151714 -381.577596) (xy 89.867994 -381.577596) (xy 89.878115 -381.57813) (xy 89.896828 -381.585848)
			(xy 89.911183 -381.600119) (xy 89.91901 -381.618786) (xy 89.919556 -381.628904) (xy 89.919556 -381.786638)
			(xy 89.919958 -381.795826) (xy 89.926478 -381.81301) (xy 89.932256 -381.820166) (xy 89.954034 -381.845826)
			(xy 89.991983 -381.901411) (xy 90.023017 -381.961134) (xy 90.046691 -382.024137) (xy 90.062665 -382.089519)
			(xy 90.07071 -382.15634) (xy 90.070711 -382.223645) (xy 115.349246 -382.223645) (xy 115.349247 -382.15634)
			(xy 115.357291 -382.089517) (xy 115.373264 -382.024135) (xy 115.396937 -381.96113) (xy 115.427969 -381.901406)
			(xy 115.465917 -381.845819) (xy 115.487704 -381.820166) (xy 115.493498 -381.813019) (xy 115.500014 -381.79583)
			(xy 115.500404 -381.786638) (xy 115.500404 -381.628904) (xy 115.500825 -381.61875) (xy 115.50862 -381.599997)
			(xy 115.523017 -381.585673) (xy 115.54181 -381.577974) (xy 115.551966 -381.577596) (xy 116.268246 -381.577596)
			(xy 116.27837 -381.578088) (xy 116.297084 -381.585822) (xy 116.311437 -381.600106) (xy 116.319262 -381.618782)
			(xy 116.319808 -381.628904) (xy 116.319808 -381.786638) (xy 116.320198 -381.795827) (xy 116.326725 -381.813012)
			(xy 116.332508 -381.820166) (xy 116.354288 -381.845826) (xy 116.39224 -381.90141) (xy 116.423277 -381.961132)
			(xy 116.446952 -382.024135) (xy 116.462928 -382.089517) (xy 116.470973 -382.15634) (xy 116.470974 -382.223645)
			(xy 116.470967 -382.223705) (xy 119.749014 -382.223705) (xy 119.749015 -382.15628) (xy 119.757092 -382.089341)
			(xy 119.773128 -382.023852) (xy 119.796894 -381.960754) (xy 119.828046 -381.900958) (xy 119.866135 -381.845323)
			(xy 119.888 -381.819658) (xy 119.893797 -381.812513) (xy 119.900311 -381.795322) (xy 119.9007 -381.78613)
			(xy 119.9007 -381.628904) (xy 119.901119 -381.618782) (xy 119.908866 -381.600078) (xy 119.923182 -381.585764)
			(xy 119.941886 -381.578019) (xy 119.952008 -381.577596) (xy 120.668288 -381.577596) (xy 120.678409 -381.578026)
			(xy 120.697112 -381.585769) (xy 120.711426 -381.600081) (xy 120.719173 -381.618783) (xy 120.719596 -381.628904)
			(xy 120.719596 -381.78613) (xy 120.719992 -381.795319) (xy 120.726516 -381.812503) (xy 120.732296 -381.819658)
			(xy 120.75415 -381.845331) (xy 120.79224 -381.900965) (xy 120.823391 -381.96076) (xy 120.847156 -382.023855)
			(xy 120.863192 -382.089344) (xy 120.871269 -382.156281) (xy 120.87127 -382.223646) (xy 124.14931 -382.223646)
			(xy 124.14931 -382.156339) (xy 124.157356 -382.089515) (xy 124.173332 -382.024132) (xy 124.197008 -381.961127)
			(xy 124.228045 -381.901403) (xy 124.265998 -381.845818) (xy 124.287788 -381.820166) (xy 124.29358 -381.813018)
			(xy 124.300098 -381.79583) (xy 124.300488 -381.786638) (xy 124.300488 -381.628904) (xy 124.300925 -381.618752)
			(xy 124.308717 -381.600002) (xy 124.323109 -381.585679) (xy 124.341896 -381.577977) (xy 124.35205 -381.577596)
			(xy 125.06833 -381.577596) (xy 125.078453 -381.578101) (xy 125.097167 -381.58583) (xy 125.11152 -381.60011)
			(xy 125.119346 -381.618783) (xy 125.119892 -381.628904) (xy 125.119892 -381.786638) (xy 125.120286 -381.795827)
			(xy 125.126811 -381.813011) (xy 125.132592 -381.820166) (xy 125.154369 -381.845827) (xy 125.192316 -381.901413)
			(xy 125.223348 -381.961135) (xy 125.24702 -382.024139) (xy 125.262993 -382.089519) (xy 125.271037 -382.156341)
			(xy 125.271038 -382.223644) (xy 125.271038 -382.223646) (xy 128.5491 -382.223646) (xy 128.549101 -382.156339)
			(xy 128.557147 -382.089515) (xy 128.573122 -382.024132) (xy 128.596798 -381.961127) (xy 128.627834 -381.901404)
			(xy 128.665787 -381.845818) (xy 128.687576 -381.820166) (xy 128.693367 -381.813016) (xy 128.699886 -381.795829)
			(xy 128.700276 -381.786638) (xy 128.700276 -381.628904) (xy 128.700724 -381.618753) (xy 128.708514 -381.600005)
			(xy 128.722902 -381.585683) (xy 128.741685 -381.577979) (xy 128.751838 -381.577596) (xy 129.468118 -381.577596)
			(xy 129.47824 -381.57811) (xy 129.496954 -381.585836) (xy 129.511308 -381.600113) (xy 129.519134 -381.618784)
			(xy 129.51968 -381.628904) (xy 129.51968 -381.786638) (xy 129.520076 -381.795827) (xy 129.5266 -381.813011)
			(xy 129.53238 -381.820166) (xy 129.554157 -381.845826) (xy 129.592105 -381.901412) (xy 129.623138 -381.961135)
			(xy 129.64681 -382.024138) (xy 129.662784 -382.089519) (xy 129.670828 -382.156341) (xy 129.670829 -382.223644)
			(xy 129.670829 -382.223645) (xy 159.349155 -382.223645) (xy 159.349156 -382.15634) (xy 159.3572 -382.089517)
			(xy 159.373174 -382.024134) (xy 159.396847 -381.96113) (xy 159.42788 -381.901406) (xy 159.465828 -381.845818)
			(xy 159.487616 -381.820166) (xy 159.493411 -381.81302) (xy 159.499926 -381.79583) (xy 159.500316 -381.786638)
			(xy 159.500316 -381.628904) (xy 159.50072 -381.61878) (xy 159.508469 -381.600073) (xy 159.52279 -381.585758)
			(xy 159.5415 -381.578016) (xy 159.551624 -381.577596) (xy 160.268158 -381.577596) (xy 160.278277 -381.57816)
			(xy 160.296988 -381.585866) (xy 160.311345 -381.600128) (xy 160.319173 -381.618789) (xy 160.31972 -381.628904)
			(xy 160.31972 -381.786638) (xy 160.320108 -381.795828) (xy 160.326637 -381.813012) (xy 160.33242 -381.820166)
			(xy 160.354199 -381.845826) (xy 160.392151 -381.90141) (xy 160.423187 -381.961132) (xy 160.446862 -382.024136)
			(xy 160.462837 -382.089518) (xy 160.470882 -382.15634) (xy 160.470883 -382.223645) (xy 160.470876 -382.223705)
			(xy 163.748923 -382.223705) (xy 163.748924 -382.15628) (xy 163.757001 -382.089341) (xy 163.773038 -382.023851)
			(xy 163.796804 -381.960754) (xy 163.827956 -381.900957) (xy 163.866047 -381.845323) (xy 163.887912 -381.819658)
			(xy 163.89371 -381.812514) (xy 163.900224 -381.795323) (xy 163.900612 -381.78613) (xy 163.900612 -381.628904)
			(xy 163.90102 -381.61878) (xy 163.908769 -381.600074) (xy 163.923088 -381.58576) (xy 163.941796 -381.578016)
			(xy 163.95192 -381.577596) (xy 164.6682 -381.577596) (xy 164.678322 -381.578016) (xy 164.697025 -381.585763)
			(xy 164.711339 -381.600079) (xy 164.719085 -381.618782) (xy 164.719508 -381.628904) (xy 164.719508 -381.78613)
			(xy 164.719902 -381.795319) (xy 164.726426 -381.812503) (xy 164.732208 -381.819658) (xy 164.754062 -381.845331)
			(xy 164.79215 -381.900965) (xy 164.823301 -381.96076) (xy 164.847065 -382.023856) (xy 164.863101 -382.089344)
			(xy 164.871178 -382.156281) (xy 164.871179 -382.223645) (xy 168.149243 -382.223645) (xy 168.149244 -382.15634)
			(xy 168.157288 -382.089517) (xy 168.173261 -382.024135) (xy 168.196933 -381.96113) (xy 168.227965 -381.901406)
			(xy 168.265913 -381.845819) (xy 168.2877 -381.820166) (xy 168.293494 -381.813019) (xy 168.30001 -381.79583)
			(xy 168.3004 -381.786638) (xy 168.3004 -381.628904) (xy 168.300825 -381.61875) (xy 168.308619 -381.599998)
			(xy 168.323015 -381.585674) (xy 168.341806 -381.577975) (xy 168.351962 -381.577596) (xy 169.068242 -381.577596)
			(xy 169.078366 -381.578091) (xy 169.09708 -381.585824) (xy 169.111433 -381.600107) (xy 169.119258 -381.618783)
			(xy 169.119804 -381.628904) (xy 169.119804 -381.786638) (xy 169.120195 -381.795827) (xy 169.126722 -381.813012)
			(xy 169.132504 -381.820166) (xy 169.154281 -381.845827) (xy 169.192227 -381.901413) (xy 169.223258 -381.961136)
			(xy 169.24693 -382.024139) (xy 169.262902 -382.08952) (xy 169.270946 -382.156341) (xy 169.270947 -382.223644)
			(xy 169.270947 -382.223646) (xy 172.54901 -382.223646) (xy 172.54901 -382.156339) (xy 172.557056 -382.089515)
			(xy 172.573032 -382.024132) (xy 172.596708 -381.961127) (xy 172.627745 -381.901403) (xy 172.665698 -381.845818)
			(xy 172.687488 -381.820166) (xy 172.69328 -381.813018) (xy 172.699798 -381.79583) (xy 172.700188 -381.786638)
			(xy 172.700188 -381.628904) (xy 172.700625 -381.618752) (xy 172.708417 -381.600002) (xy 172.722809 -381.585679)
			(xy 172.741596 -381.577977) (xy 172.75175 -381.577596) (xy 173.46803 -381.577596) (xy 173.478153 -381.578101)
			(xy 173.496867 -381.58583) (xy 173.51122 -381.60011) (xy 173.519046 -381.618783) (xy 173.519592 -381.628904)
			(xy 173.519592 -381.786638) (xy 173.519986 -381.795827) (xy 173.526511 -381.813011) (xy 173.532292 -381.820166)
			(xy 173.554069 -381.845827) (xy 173.592016 -381.901413) (xy 173.623048 -381.961135) (xy 173.64672 -382.024139)
			(xy 173.662693 -382.089519) (xy 173.670737 -382.156341) (xy 173.670738 -382.223644) (xy 173.662695 -382.290466)
			(xy 173.646725 -382.355847) (xy 173.623054 -382.418851) (xy 173.592024 -382.478574) (xy 173.554078 -382.534161)
			(xy 173.532292 -382.559814) (xy 173.526506 -382.566967) (xy 173.519985 -382.584151) (xy 173.519592 -382.593342)
			(xy 173.519592 -383.086864) (xy 173.520021 -383.096049) (xy 173.526522 -383.113234) (xy 173.532292 -383.120392)
			(xy 173.554094 -383.146032) (xy 173.592041 -383.201621) (xy 173.623072 -383.261346) (xy 173.646507 -383.323727)
			(xy 174.749152 -383.323727) (xy 174.749155 -383.256419) (xy 174.757202 -383.189594) (xy 174.773179 -383.12421)
			(xy 174.796856 -383.061204) (xy 174.827893 -383.001479) (xy 174.865846 -382.945892) (xy 174.887636 -382.92024)
			(xy 174.893445 -382.913104) (xy 174.899951 -382.895906) (xy 174.900336 -382.886712) (xy 174.900336 -382.728724)
			(xy 174.900742 -382.718567) (xy 174.908536 -382.699808) (xy 174.922939 -382.685482) (xy 174.941739 -382.677788)
			(xy 174.951898 -382.677416) (xy 175.668178 -382.677416) (xy 175.6783 -382.677944) (xy 175.697017 -382.68566)
			(xy 175.711373 -382.699933) (xy 175.719197 -382.718605) (xy 175.71974 -382.728724) (xy 175.71974 -382.886712)
			(xy 175.720158 -382.895898) (xy 175.726668 -382.913082) (xy 175.73244 -382.92024) (xy 175.754193 -382.945921)
			(xy 175.792144 -383.001503) (xy 175.82318 -383.061222) (xy 175.846856 -383.124223) (xy 175.862832 -383.189602)
			(xy 175.870879 -383.256422) (xy 175.870883 -383.323724) (xy 175.862842 -383.390545) (xy 175.846872 -383.455925)
			(xy 175.823202 -383.518928) (xy 175.792172 -383.578651) (xy 175.754226 -383.634236) (xy 175.73244 -383.659888)
			(xy 175.726616 -383.667014) (xy 175.720119 -383.684219) (xy 175.71974 -383.693416) (xy 175.71974 -384.186684)
			(xy 175.720171 -384.195869) (xy 175.726672 -384.213053) (xy 175.73244 -384.220212) (xy 175.754264 -384.245835)
			(xy 175.792213 -384.301425) (xy 175.823246 -384.361152) (xy 175.846918 -384.424161) (xy 175.862889 -384.489547)
			(xy 175.87093 -384.556373) (xy 175.870927 -384.623681) (xy 175.862879 -384.690507) (xy 175.846902 -384.755891)
			(xy 175.823224 -384.818897) (xy 175.792185 -384.878622) (xy 175.754231 -384.934208) (xy 175.73244 -384.95986)
			(xy 175.726628 -384.966994) (xy 175.720124 -384.984193) (xy 175.71974 -384.993388) (xy 175.71974 -385.151376)
			(xy 175.71926 -385.161524) (xy 175.71148 -385.180268) (xy 175.697101 -385.194591) (xy 175.678327 -385.202298)
			(xy 175.668178 -385.202684) (xy 174.951898 -385.202684) (xy 174.941774 -385.202176) (xy 174.923058 -385.194452)
			(xy 174.908702 -385.180172) (xy 174.900879 -385.161497) (xy 174.900336 -385.151376) (xy 174.900336 -384.993388)
			(xy 174.899924 -384.984201) (xy 174.893411 -384.967017) (xy 174.887636 -384.95986) (xy 174.865884 -384.934179)
			(xy 174.827934 -384.878596) (xy 174.7969 -384.818877) (xy 174.773225 -384.755876) (xy 174.75725 -384.690497)
			(xy 174.749203 -384.623678) (xy 174.749199 -384.556376) (xy 174.75724 -384.489556) (xy 174.773209 -384.424176)
			(xy 174.796878 -384.361173) (xy 174.827906 -384.30145) (xy 174.865851 -384.245864) (xy 174.887636 -384.220212)
			(xy 174.893457 -384.213084) (xy 174.899956 -384.19588) (xy 174.900336 -384.186684) (xy 174.900336 -383.693416)
			(xy 174.89991 -383.684231) (xy 174.893407 -383.667046) (xy 174.887636 -383.659888) (xy 174.865813 -383.634265)
			(xy 174.827865 -383.578674) (xy 174.796834 -383.518947) (xy 174.773163 -383.455938) (xy 174.757193 -383.390553)
			(xy 174.749152 -383.323727) (xy 173.646507 -383.323727) (xy 173.646742 -383.324352) (xy 173.662713 -383.389736)
			(xy 173.670756 -383.456559) (xy 173.670754 -383.523865) (xy 173.662709 -383.590688) (xy 173.646735 -383.656071)
			(xy 173.623062 -383.719076) (xy 173.592028 -383.7788) (xy 173.55408 -383.834387) (xy 173.532292 -383.86004)
			(xy 173.526495 -383.867185) (xy 173.519981 -383.884376) (xy 173.519592 -383.893568) (xy 173.519592 -384.051556)
			(xy 173.519142 -384.061708) (xy 173.51136 -384.080461) (xy 173.496971 -384.094786) (xy 173.478184 -384.102486)
			(xy 173.46803 -384.102864) (xy 172.75175 -384.102864) (xy 172.741627 -384.102333) (xy 172.722908 -384.094622)
			(xy 172.70855 -384.080349) (xy 172.700728 -384.061676) (xy 172.700188 -384.051556) (xy 172.700188 -383.893568)
			(xy 172.699796 -383.884379) (xy 172.69327 -383.867194) (xy 172.687488 -383.86004) (xy 172.665715 -383.834376)
			(xy 172.627762 -383.778792) (xy 172.596725 -383.719071) (xy 172.57305 -383.656068) (xy 172.557074 -383.590686)
			(xy 172.549028 -383.523864) (xy 172.549026 -383.45656) (xy 172.55707 -383.389737) (xy 172.573042 -383.324355)
			(xy 172.596716 -383.261351) (xy 172.62775 -383.201629) (xy 172.6657 -383.146043) (xy 172.687488 -383.120392)
			(xy 172.693269 -383.113236) (xy 172.699793 -383.096054) (xy 172.700188 -383.086864) (xy 172.700188 -382.593342)
			(xy 172.69976 -382.584157) (xy 172.693259 -382.566972) (xy 172.687488 -382.559814) (xy 172.665689 -382.534171)
			(xy 172.627737 -382.478584) (xy 172.596702 -382.41886) (xy 172.573027 -382.355854) (xy 172.557054 -382.29047)
			(xy 172.54901 -382.223646) (xy 169.270947 -382.223646) (xy 169.262905 -382.290465) (xy 169.246934 -382.355847)
			(xy 169.223264 -382.41885) (xy 169.192235 -382.478574) (xy 169.15429 -382.534161) (xy 169.132504 -382.559814)
			(xy 169.126719 -382.566968) (xy 169.120197 -382.584152) (xy 169.119804 -382.593342) (xy 169.119804 -383.086864)
			(xy 169.120231 -383.096049) (xy 169.126733 -383.113234) (xy 169.132504 -383.120392) (xy 169.154306 -383.146032)
			(xy 169.192252 -383.201621) (xy 169.223282 -383.261347) (xy 169.246739 -383.323787) (xy 170.348832 -383.323787)
			(xy 170.348835 -383.256359) (xy 170.356915 -383.189418) (xy 170.372956 -383.123926) (xy 170.396726 -383.060827)
			(xy 170.427884 -383.001031) (xy 170.46598 -382.945396) (xy 170.487848 -382.919732) (xy 170.493662 -382.912599)
			(xy 170.500165 -382.895399) (xy 170.500548 -382.886204) (xy 170.500548 -382.728724) (xy 170.501103 -382.718623)
			(xy 170.508823 -382.699955) (xy 170.523098 -382.685662) (xy 170.541756 -382.677917) (xy 170.551856 -382.677416)
			(xy 171.268136 -382.677416) (xy 171.278249 -382.677856) (xy 171.296931 -382.685608) (xy 171.311225 -382.699919)
			(xy 171.318956 -382.71861) (xy 171.319444 -382.728724) (xy 171.319444 -382.886204) (xy 171.319865 -382.89539)
			(xy 171.326372 -382.912574) (xy 171.332144 -382.919732) (xy 171.353975 -382.945425) (xy 171.392068 -383.001055)
			(xy 171.423223 -383.060846) (xy 171.446992 -383.12394) (xy 171.463032 -383.189426) (xy 171.471111 -383.256362)
			(xy 171.471115 -383.323784) (xy 171.463041 -383.390721) (xy 171.447008 -383.456209) (xy 171.423246 -383.519304)
			(xy 171.392096 -383.579099) (xy 171.354008 -383.634732) (xy 171.332144 -383.660396) (xy 171.32636 -383.66755)
			(xy 171.319839 -383.684734) (xy 171.319444 -383.693924) (xy 171.319444 -384.186176) (xy 171.319878 -384.19536)
			(xy 171.326376 -384.212544) (xy 171.332144 -384.219704) (xy 171.354045 -384.245339) (xy 171.392137 -384.300977)
			(xy 171.423289 -384.360776) (xy 171.447054 -384.423877) (xy 171.463088 -384.489371) (xy 171.471162 -384.556313)
			(xy 171.471159 -384.623741) (xy 171.463078 -384.690683) (xy 171.447037 -384.756174) (xy 171.423267 -384.819273)
			(xy 171.392109 -384.87907) (xy 171.354012 -384.934704) (xy 171.332144 -384.960368) (xy 171.326329 -384.9675)
			(xy 171.319827 -384.984701) (xy 171.319444 -384.993896) (xy 171.319444 -385.151376) (xy 171.318896 -385.161478)
			(xy 171.311175 -385.180147) (xy 171.296897 -385.194441) (xy 171.278237 -385.202185) (xy 171.268136 -385.202684)
			(xy 170.551856 -385.202684) (xy 170.541742 -385.20225) (xy 170.52306 -385.194495) (xy 170.508766 -385.180183)
			(xy 170.501036 -385.16149) (xy 170.500548 -385.151376) (xy 170.500548 -384.993896) (xy 170.500129 -384.98471)
			(xy 170.49362 -384.967526) (xy 170.487848 -384.960368) (xy 170.466018 -384.934674) (xy 170.427925 -384.879045)
			(xy 170.39677 -384.819253) (xy 170.373001 -384.75616) (xy 170.356962 -384.690674) (xy 170.348883 -384.623738)
			(xy 170.348879 -384.556316) (xy 170.356952 -384.489379) (xy 170.372985 -384.423892) (xy 170.396748 -384.360796)
			(xy 170.427897 -384.301001) (xy 170.465984 -384.245368) (xy 170.487848 -384.219704) (xy 170.493631 -384.21255)
			(xy 170.500153 -384.195366) (xy 170.500548 -384.186176) (xy 170.500548 -383.693924) (xy 170.500116 -383.684739)
			(xy 170.493616 -383.667555) (xy 170.487848 -383.660396) (xy 170.465947 -383.634761) (xy 170.427856 -383.579123)
			(xy 170.396704 -383.519323) (xy 170.37294 -383.456222) (xy 170.356906 -383.390729) (xy 170.348832 -383.323787)
			(xy 169.246739 -383.323787) (xy 169.246952 -383.324353) (xy 169.262922 -383.389736) (xy 169.270965 -383.456559)
			(xy 169.270963 -383.523865) (xy 169.262918 -383.590688) (xy 169.246945 -383.65607) (xy 169.223272 -383.719075)
			(xy 169.192239 -383.7788) (xy 169.154291 -383.834387) (xy 169.132504 -383.86004) (xy 169.126708 -383.867186)
			(xy 169.120193 -383.884376) (xy 169.119804 -383.893568) (xy 169.119804 -384.051556) (xy 169.119342 -384.061707)
			(xy 169.111562 -384.080457) (xy 169.097177 -384.094782) (xy 169.078394 -384.102484) (xy 169.068242 -384.102864)
			(xy 168.351962 -384.102864) (xy 168.341833 -384.102405) (xy 168.323112 -384.094665) (xy 168.308757 -384.080371)
			(xy 168.300939 -384.061682) (xy 168.3004 -384.051556) (xy 168.3004 -383.893568) (xy 168.300005 -383.884379)
			(xy 168.293481 -383.867195) (xy 168.2877 -383.86004) (xy 168.265929 -383.834374) (xy 168.227982 -383.778789)
			(xy 168.196951 -383.719067) (xy 168.173279 -383.656064) (xy 168.157306 -383.590684) (xy 168.149261 -383.523864)
			(xy 168.149259 -383.456561) (xy 168.157301 -383.38974) (xy 168.173272 -383.324359) (xy 168.196941 -383.261355)
			(xy 168.22797 -383.201632) (xy 168.265914 -383.146045) (xy 168.2877 -383.120392) (xy 168.293482 -383.113237)
			(xy 168.300006 -383.096054) (xy 168.3004 -383.086864) (xy 168.3004 -382.593342) (xy 168.29997 -382.584157)
			(xy 168.29347 -382.566972) (xy 168.2877 -382.559814) (xy 168.265904 -382.534169) (xy 168.227958 -382.478581)
			(xy 168.196927 -382.418856) (xy 168.173256 -382.355851) (xy 168.157285 -382.290468) (xy 168.149243 -382.223645)
			(xy 164.871179 -382.223645) (xy 164.871179 -382.223704) (xy 164.863104 -382.290641) (xy 164.84707 -382.35613)
			(xy 164.823307 -382.419226) (xy 164.792158 -382.479022) (xy 164.754071 -382.534657) (xy 164.732208 -382.560322)
			(xy 164.726421 -382.567474) (xy 164.7199 -382.584659) (xy 164.719508 -382.59385) (xy 164.719508 -383.086356)
			(xy 164.719937 -383.095541) (xy 164.726437 -383.112726) (xy 164.732208 -383.119884) (xy 164.754087 -383.145536)
			(xy 164.792175 -383.201173) (xy 164.823325 -383.260971) (xy 164.846959 -383.323727) (xy 165.949064 -383.323727)
			(xy 165.949067 -383.256419) (xy 165.957115 -383.189594) (xy 165.973092 -383.124209) (xy 165.996769 -383.061203)
			(xy 166.027808 -383.001479) (xy 166.065762 -382.945892) (xy 166.087552 -382.92024) (xy 166.093363 -382.913105)
			(xy 166.099868 -382.895907) (xy 166.100252 -382.886712) (xy 166.100252 -382.728724) (xy 166.10074 -382.718577)
			(xy 166.108519 -382.699835) (xy 166.122895 -382.685512) (xy 166.141666 -382.677803) (xy 166.151814 -382.677416)
			(xy 166.868094 -382.677416) (xy 166.878217 -382.677931) (xy 166.896934 -382.685652) (xy 166.911289 -382.699929)
			(xy 166.919113 -382.718603) (xy 166.919656 -382.728724) (xy 166.919656 -382.886712) (xy 166.92007 -382.895899)
			(xy 166.926582 -382.913082) (xy 166.932356 -382.92024) (xy 166.954108 -382.945921) (xy 166.992059 -383.001503)
			(xy 167.023094 -383.061223) (xy 167.046769 -383.124224) (xy 167.062744 -383.189602) (xy 167.070791 -383.256422)
			(xy 167.070795 -383.323724) (xy 167.062754 -383.390544) (xy 167.046785 -383.455925) (xy 167.023116 -383.518928)
			(xy 166.992086 -383.57865) (xy 166.954142 -383.634236) (xy 166.932356 -383.659888) (xy 166.926534 -383.667015)
			(xy 166.920036 -383.68422) (xy 166.919656 -383.693416) (xy 166.919656 -384.186684) (xy 166.920084 -384.195869)
			(xy 166.926586 -384.213053) (xy 166.932356 -384.220212) (xy 166.954179 -384.245835) (xy 166.992127 -384.301425)
			(xy 167.023159 -384.361153) (xy 167.04683 -384.424161) (xy 167.062801 -384.489547) (xy 167.070842 -384.556373)
			(xy 167.070839 -384.623681) (xy 167.062791 -384.690506) (xy 167.046814 -384.75589) (xy 167.023137 -384.818897)
			(xy 166.9921 -384.878621) (xy 166.954146 -384.934208) (xy 166.932356 -384.95986) (xy 166.926546 -384.966995)
			(xy 166.92004 -384.984194) (xy 166.919656 -384.993388) (xy 166.919656 -385.151376) (xy 166.91916 -385.161522)
			(xy 166.911383 -385.180263) (xy 166.89701 -385.194585) (xy 166.878241 -385.202296) (xy 166.868094 -385.202684)
			(xy 166.151814 -385.202684) (xy 166.141691 -385.202163) (xy 166.122975 -385.194444) (xy 166.108619 -385.180169)
			(xy 166.100795 -385.161496) (xy 166.100252 -385.151376) (xy 166.100252 -384.993388) (xy 166.099836 -384.984202)
			(xy 166.093325 -384.967018) (xy 166.087552 -384.95986) (xy 166.065799 -384.934179) (xy 166.027849 -384.878597)
			(xy 165.996813 -384.818877) (xy 165.973138 -384.755877) (xy 165.957162 -384.690498) (xy 165.949115 -384.623678)
			(xy 165.949111 -384.556376) (xy 165.957152 -384.489555) (xy 165.973122 -384.424175) (xy 165.996791 -384.361172)
			(xy 166.027821 -384.30145) (xy 166.065766 -384.245864) (xy 166.087552 -384.220212) (xy 166.093375 -384.213086)
			(xy 166.099872 -384.19588) (xy 166.100252 -384.186684) (xy 166.100252 -383.693416) (xy 166.099823 -383.684231)
			(xy 166.093321 -383.667047) (xy 166.087552 -383.659888) (xy 166.065728 -383.634265) (xy 166.02778 -383.578675)
			(xy 165.996747 -383.518947) (xy 165.973076 -383.455939) (xy 165.957105 -383.390553) (xy 165.949064 -383.323727)
			(xy 164.846959 -383.323727) (xy 164.847088 -383.32407) (xy 164.863122 -383.38956) (xy 164.871196 -383.4565)
			(xy 164.871195 -383.523924) (xy 164.863117 -383.590864) (xy 164.84708 -383.656353) (xy 164.823315 -383.719451)
			(xy 164.792163 -383.779248) (xy 164.754073 -383.834883) (xy 164.732208 -383.860548) (xy 164.726409 -383.867692)
			(xy 164.719896 -383.884883) (xy 164.719508 -383.894076) (xy 164.719508 -384.051556) (xy 164.719048 -384.061675)
			(xy 164.711316 -384.080376) (xy 164.697013 -384.094691) (xy 164.678318 -384.102439) (xy 164.6682 -384.102864)
			(xy 163.95192 -384.102864) (xy 163.941794 -384.102467) (xy 163.923084 -384.094719) (xy 163.908768 -384.080396)
			(xy 163.901028 -384.061682) (xy 163.900612 -384.051556) (xy 163.900612 -383.894076) (xy 163.900211 -383.884888)
			(xy 163.893691 -383.867704) (xy 163.887912 -383.860548) (xy 163.866063 -383.83487) (xy 163.827973 -383.779238)
			(xy 163.796821 -383.719443) (xy 163.773056 -383.656348) (xy 163.757019 -383.59086) (xy 163.748941 -383.523923)
			(xy 163.74894 -383.456501) (xy 163.757014 -383.389563) (xy 163.773049 -383.324075) (xy 163.796811 -383.260979)
			(xy 163.827961 -383.201183) (xy 163.866049 -383.145549) (xy 163.887912 -383.119884) (xy 163.893699 -383.112732)
			(xy 163.900219 -383.095547) (xy 163.900612 -383.086356) (xy 163.900612 -382.59385) (xy 163.900175 -382.584666)
			(xy 163.89368 -382.567481) (xy 163.887912 -382.560322) (xy 163.866038 -382.534665) (xy 163.827949 -382.47903)
			(xy 163.796798 -382.419232) (xy 163.773034 -382.356134) (xy 163.756998 -382.290644) (xy 163.748923 -382.223705)
			(xy 160.470876 -382.223705) (xy 160.46284 -382.290468) (xy 160.446866 -382.35585) (xy 160.423193 -382.418854)
			(xy 160.392159 -382.478577) (xy 160.354208 -382.534162) (xy 160.33242 -382.559814) (xy 160.326637 -382.566969)
			(xy 160.320114 -382.584152) (xy 160.31972 -382.593342) (xy 160.31972 -383.086864) (xy 160.320143 -383.09605)
			(xy 160.326647 -383.113235) (xy 160.33242 -383.120392) (xy 160.354225 -383.146031) (xy 160.392176 -383.201618)
			(xy 160.42321 -383.261343) (xy 160.446672 -383.323786) (xy 161.548769 -383.323786) (xy 161.548772 -383.25636)
			(xy 161.556851 -383.18942) (xy 161.572889 -383.123929) (xy 161.596656 -383.060831) (xy 161.627809 -383.001034)
			(xy 161.665899 -382.945398) (xy 161.687764 -382.919732) (xy 161.69358 -382.912601) (xy 161.700081 -382.895399)
			(xy 161.700464 -382.886204) (xy 161.700464 -382.728724) (xy 161.701004 -382.718621) (xy 161.708727 -382.69995)
			(xy 161.723007 -382.685656) (xy 161.74167 -382.677914) (xy 161.751772 -382.677416) (xy 162.468052 -382.677416)
			(xy 162.478173 -382.677856) (xy 162.496879 -382.685591) (xy 162.511195 -382.699901) (xy 162.51894 -382.718603)
			(xy 162.51936 -382.728724) (xy 162.51936 -382.886204) (xy 162.519777 -382.89539) (xy 162.526287 -382.912574)
			(xy 162.53206 -382.919732) (xy 162.55389 -382.945426) (xy 162.591982 -383.001055) (xy 162.623137 -383.060847)
			(xy 162.646905 -383.12394) (xy 162.662944 -383.189426) (xy 162.671023 -383.256362) (xy 162.671027 -383.323784)
			(xy 162.662954 -383.39072) (xy 162.646921 -383.456208) (xy 162.623159 -383.519303) (xy 162.59201 -383.579098)
			(xy 162.553923 -383.634731) (xy 162.53206 -383.660396) (xy 162.526278 -383.667551) (xy 162.519755 -383.684734)
			(xy 162.51936 -383.693924) (xy 162.51936 -384.186176) (xy 162.51979 -384.195361) (xy 162.526291 -384.212545)
			(xy 162.53206 -384.219704) (xy 162.553961 -384.245339) (xy 162.592051 -384.300977) (xy 162.623202 -384.360777)
			(xy 162.646966 -384.423878) (xy 162.663 -384.489371) (xy 162.671074 -384.556313) (xy 162.671071 -384.623741)
			(xy 162.662991 -384.690682) (xy 162.64695 -384.756174) (xy 162.62318 -384.819272) (xy 162.592023 -384.879069)
			(xy 162.553928 -384.934703) (xy 162.53206 -384.960368) (xy 162.526247 -384.967501) (xy 162.519743 -384.984701)
			(xy 162.51936 -384.993896) (xy 162.51936 -385.151376) (xy 162.518964 -385.161502) (xy 162.511216 -385.180213)
			(xy 162.496893 -385.194529) (xy 162.478178 -385.202268) (xy 162.468052 -385.202684) (xy 161.751772 -385.202684)
			(xy 161.741659 -385.202238) (xy 161.722978 -385.194488) (xy 161.708683 -385.180179) (xy 161.700952 -385.161489)
			(xy 161.700464 -385.151376) (xy 161.700464 -384.993896) (xy 161.700041 -384.98471) (xy 161.693535 -384.967527)
			(xy 161.687764 -384.960368) (xy 161.665937 -384.934673) (xy 161.627849 -384.879042) (xy 161.596699 -384.819249)
			(xy 161.572934 -384.756157) (xy 161.556897 -384.690671) (xy 161.548819 -384.623737) (xy 161.548816 -384.556317)
			(xy 161.556888 -384.489382) (xy 161.572918 -384.423895) (xy 161.596677 -384.3608) (xy 161.627821 -384.301005)
			(xy 161.665903 -384.24537) (xy 161.687764 -384.219704) (xy 161.693549 -384.212551) (xy 161.700069 -384.195366)
			(xy 161.700464 -384.186176) (xy 161.700464 -383.693924) (xy 161.700028 -383.68474) (xy 161.693531 -383.667556)
			(xy 161.687764 -383.660396) (xy 161.665866 -383.634759) (xy 161.627781 -383.57912) (xy 161.596634 -383.519319)
			(xy 161.572873 -383.456219) (xy 161.556841 -383.390727) (xy 161.548769 -383.323786) (xy 160.446672 -383.323786)
			(xy 160.446884 -383.32435) (xy 160.462857 -383.389734) (xy 160.470901 -383.456558) (xy 160.470899 -383.523866)
			(xy 160.462853 -383.59069) (xy 160.446877 -383.656074) (xy 160.423201 -383.719079) (xy 160.392163 -383.778803)
			(xy 160.35421 -383.834388) (xy 160.33242 -383.86004) (xy 160.326626 -383.867187) (xy 160.320109 -383.884376)
			(xy 160.31972 -383.893568) (xy 160.31972 -384.051556) (xy 160.319248 -384.061673) (xy 160.311518 -384.080372)
			(xy 160.297219 -384.094687) (xy 160.278529 -384.102437) (xy 160.268412 -384.102864) (xy 159.551878 -384.102864)
			(xy 159.54175 -384.102392) (xy 159.523029 -384.094657) (xy 159.508674 -384.080367) (xy 159.500855 -384.061681)
			(xy 159.500316 -384.051556) (xy 159.500316 -383.893568) (xy 159.499918 -383.88438) (xy 159.493395 -383.867196)
			(xy 159.487616 -383.86004) (xy 159.465845 -383.834375) (xy 159.427897 -383.77879) (xy 159.396864 -383.719068)
			(xy 159.373191 -383.656065) (xy 159.357218 -383.590684) (xy 159.349173 -383.523864) (xy 159.349172 -383.45656)
			(xy 159.357214 -383.389739) (xy 159.373184 -383.324358) (xy 159.396854 -383.261354) (xy 159.427884 -383.201631)
			(xy 159.46583 -383.146044) (xy 159.487616 -383.120392) (xy 159.4934 -383.113238) (xy 159.499922 -383.096054)
			(xy 159.500316 -383.086864) (xy 159.500316 -382.593342) (xy 159.499882 -382.584157) (xy 159.493384 -382.566973)
			(xy 159.487616 -382.559814) (xy 159.465819 -382.53417) (xy 159.427872 -382.478582) (xy 159.396841 -382.418857)
			(xy 159.373169 -382.355851) (xy 159.357198 -382.290468) (xy 159.349155 -382.223645) (xy 129.670829 -382.223645)
			(xy 129.662786 -382.290466) (xy 129.646815 -382.355847) (xy 129.623144 -382.418851) (xy 129.592113 -382.478575)
			(xy 129.554167 -382.534162) (xy 129.53238 -382.559814) (xy 129.526593 -382.566966) (xy 129.520073 -382.584151)
			(xy 129.51968 -382.593342) (xy 129.51968 -383.086864) (xy 129.520112 -383.096049) (xy 129.526611 -383.113233)
			(xy 129.53238 -383.120392) (xy 129.554183 -383.146031) (xy 129.59213 -383.20162) (xy 129.623162 -383.261346)
			(xy 129.646598 -383.323727) (xy 130.749242 -383.323727) (xy 130.749246 -383.256419) (xy 130.757293 -383.189594)
			(xy 130.77327 -383.12421) (xy 130.796946 -383.061204) (xy 130.827982 -383.00148) (xy 130.865935 -382.945892)
			(xy 130.887724 -382.92024) (xy 130.893531 -382.913103) (xy 130.900039 -382.895906) (xy 130.900424 -382.886712)
			(xy 130.900424 -382.728724) (xy 130.900842 -382.718568) (xy 130.908634 -382.699812) (xy 130.923032 -382.685487)
			(xy 130.941828 -382.67779) (xy 130.951986 -382.677416) (xy 131.668266 -382.677416) (xy 131.678388 -382.677954)
			(xy 131.697103 -382.685666) (xy 131.71146 -382.699937) (xy 131.719284 -382.718606) (xy 131.719828 -382.728724)
			(xy 131.719828 -382.886712) (xy 131.720226 -382.895901) (xy 131.726747 -382.913085) (xy 131.732528 -382.92024)
			(xy 131.754281 -382.945921) (xy 131.792233 -383.001502) (xy 131.82327 -383.061222) (xy 131.846946 -383.124223)
			(xy 131.862923 -383.189602) (xy 131.87097 -383.256422) (xy 131.870973 -383.323724) (xy 131.862932 -383.390545)
			(xy 131.846962 -383.455926) (xy 131.823292 -383.518929) (xy 131.792261 -383.578651) (xy 131.754314 -383.634236)
			(xy 131.732528 -383.659888) (xy 131.726703 -383.667013) (xy 131.720207 -383.684219) (xy 131.719828 -383.693416)
			(xy 131.719828 -384.186684) (xy 131.720239 -384.195871) (xy 131.726751 -384.213056) (xy 131.732528 -384.220212)
			(xy 131.754352 -384.245834) (xy 131.792302 -384.301424) (xy 131.823336 -384.361152) (xy 131.847008 -384.42416)
			(xy 131.86298 -384.489546) (xy 131.871021 -384.556373) (xy 131.871018 -384.623681) (xy 131.86297 -384.690507)
			(xy 131.846992 -384.755892) (xy 131.823314 -384.818898) (xy 131.792274 -384.878622) (xy 131.754319 -384.934208)
			(xy 131.732528 -384.95986) (xy 131.726715 -384.966993) (xy 131.720212 -384.984193) (xy 131.719828 -384.993388)
			(xy 131.719828 -385.151376) (xy 131.719359 -385.161525) (xy 131.711577 -385.180272) (xy 131.697195 -385.194595)
			(xy 131.678417 -385.202301) (xy 131.668266 -385.202684) (xy 130.951986 -385.202684) (xy 130.941861 -385.202185)
			(xy 130.923145 -385.194457) (xy 130.90879 -385.180175) (xy 130.900967 -385.161498) (xy 130.900424 -385.151376)
			(xy 130.900424 -384.993388) (xy 130.900014 -384.984201) (xy 130.8935 -384.967017) (xy 130.887724 -384.95986)
			(xy 130.865972 -384.934178) (xy 130.828023 -384.878596) (xy 130.796989 -384.818876) (xy 130.773315 -384.755876)
			(xy 130.75734 -384.690497) (xy 130.749294 -384.623678) (xy 130.74929 -384.556376) (xy 130.757331 -384.489556)
			(xy 130.773299 -384.424176) (xy 130.796967 -384.361173) (xy 130.827996 -384.301451) (xy 130.865939 -384.245865)
			(xy 130.887724 -384.220212) (xy 130.893543 -384.213083) (xy 130.900044 -384.19588) (xy 130.900424 -384.186684)
			(xy 130.900424 -383.693416) (xy 130.900001 -383.68423) (xy 130.893495 -383.667046) (xy 130.887724 -383.659888)
			(xy 130.865901 -383.634265) (xy 130.827955 -383.578674) (xy 130.796924 -383.518946) (xy 130.773254 -383.455938)
			(xy 130.757284 -383.390552) (xy 130.749242 -383.323727) (xy 129.646598 -383.323727) (xy 129.646833 -383.324352)
			(xy 129.662804 -383.389735) (xy 129.670846 -383.456559) (xy 129.670845 -383.523865) (xy 129.6628 -383.590688)
			(xy 129.646826 -383.656071) (xy 129.623152 -383.719076) (xy 129.592118 -383.778801) (xy 129.554168 -383.834388)
			(xy 129.53238 -383.86004) (xy 129.526582 -383.867184) (xy 129.520069 -383.884375) (xy 129.51968 -383.893568)
			(xy 129.51968 -384.051556) (xy 129.519242 -384.06171) (xy 129.511457 -384.080465) (xy 129.497065 -384.094791)
			(xy 129.478274 -384.102488) (xy 129.468118 -384.102864) (xy 128.751838 -384.102864) (xy 128.741714 -384.102342)
			(xy 128.722995 -384.094628) (xy 128.708637 -384.080352) (xy 128.700816 -384.061677) (xy 128.700276 -384.051556)
			(xy 128.700276 -383.893568) (xy 128.699886 -383.884379) (xy 128.693359 -383.867194) (xy 128.687576 -383.86004)
			(xy 128.665803 -383.834375) (xy 128.627851 -383.778792) (xy 128.596815 -383.71907) (xy 128.57314 -383.656067)
			(xy 128.557165 -383.590686) (xy 128.549119 -383.523864) (xy 128.549117 -383.45656) (xy 128.55716 -383.389738)
			(xy 128.573133 -383.324356) (xy 128.596805 -383.261352) (xy 128.627839 -383.201629) (xy 128.665788 -383.146044)
			(xy 128.687576 -383.120392) (xy 128.693356 -383.113235) (xy 128.699881 -383.096054) (xy 128.700276 -383.086864)
			(xy 128.700276 -382.593342) (xy 128.699851 -382.584156) (xy 128.693348 -382.566971) (xy 128.687576 -382.559814)
			(xy 128.665777 -382.53417) (xy 128.627826 -382.478584) (xy 128.596792 -382.418859) (xy 128.573118 -382.355853)
			(xy 128.557144 -382.29047) (xy 128.5491 -382.223646) (xy 125.271038 -382.223646) (xy 125.262995 -382.290466)
			(xy 125.247025 -382.355847) (xy 125.223354 -382.418851) (xy 125.192324 -382.478574) (xy 125.154378 -382.534161)
			(xy 125.132592 -382.559814) (xy 125.126806 -382.566967) (xy 125.120285 -382.584151) (xy 125.119892 -382.593342)
			(xy 125.119892 -383.086864) (xy 125.120321 -383.096049) (xy 125.126822 -383.113234) (xy 125.132592 -383.120392)
			(xy 125.154394 -383.146032) (xy 125.192341 -383.201621) (xy 125.223372 -383.261346) (xy 125.24683 -383.323787)
			(xy 126.348923 -383.323787) (xy 126.348926 -383.256359) (xy 126.357006 -383.189418) (xy 126.373047 -383.123926)
			(xy 126.396816 -383.060828) (xy 126.427973 -383.001031) (xy 126.466069 -382.945397) (xy 126.487936 -382.919732)
			(xy 126.493749 -382.912598) (xy 126.500253 -382.895399) (xy 126.500636 -382.886204) (xy 126.500636 -382.728724)
			(xy 126.501036 -382.718599) (xy 126.508783 -382.699889) (xy 126.523105 -382.685572) (xy 126.541818 -382.677832)
			(xy 126.551944 -382.677416) (xy 127.268224 -382.677416) (xy 127.278336 -382.677866) (xy 127.297018 -382.685614)
			(xy 127.311313 -382.699922) (xy 127.319044 -382.718611) (xy 127.319532 -382.728724) (xy 127.319532 -382.886204)
			(xy 127.319956 -382.895389) (xy 127.326462 -382.912573) (xy 127.332232 -382.919732) (xy 127.354059 -382.945427)
			(xy 127.392147 -383.001058) (xy 127.423298 -383.06085) (xy 127.447062 -383.123943) (xy 127.463099 -383.189428)
			(xy 127.471178 -383.256363) (xy 127.471181 -383.323783) (xy 127.463109 -383.390718) (xy 127.447078 -383.456205)
			(xy 127.42332 -383.5193) (xy 127.392175 -383.579096) (xy 127.354093 -383.63473) (xy 127.332232 -383.660396)
			(xy 127.326446 -383.667549) (xy 127.319927 -383.684734) (xy 127.319532 -383.693924) (xy 127.319532 -384.186176)
			(xy 127.319969 -384.19536) (xy 127.326466 -384.212544) (xy 127.332232 -384.219704) (xy 127.35413 -384.245341)
			(xy 127.392216 -384.30098) (xy 127.423363 -384.36078) (xy 127.447124 -384.423881) (xy 127.463156 -384.489373)
			(xy 127.471228 -384.556314) (xy 127.471225 -384.62374) (xy 127.463146 -384.69068) (xy 127.447108 -384.756171)
			(xy 127.423341 -384.819269) (xy 127.392188 -384.879066) (xy 127.354097 -384.934702) (xy 127.332232 -384.960368)
			(xy 127.326416 -384.967499) (xy 127.319915 -384.984701) (xy 127.319532 -384.993896) (xy 127.319532 -385.151376)
			(xy 127.318996 -385.161479) (xy 127.311272 -385.180151) (xy 127.296991 -385.194445) (xy 127.278327 -385.202187)
			(xy 127.268224 -385.202684) (xy 126.551944 -385.202684) (xy 126.541822 -385.202247) (xy 126.523117 -385.194511)
			(xy 126.5088 -385.1802) (xy 126.501056 -385.161497) (xy 126.500636 -385.151376) (xy 126.500636 -384.993896)
			(xy 126.50022 -384.98471) (xy 126.49371 -384.967526) (xy 126.487936 -384.960368) (xy 126.466106 -384.934674)
			(xy 126.428014 -384.879045) (xy 126.39686 -384.819253) (xy 126.373092 -384.756159) (xy 126.357053 -384.690673)
			(xy 126.348974 -384.623738) (xy 126.34897 -384.556316) (xy 126.357043 -384.48938) (xy 126.373076 -384.423892)
			(xy 126.396838 -384.360797) (xy 126.427986 -384.301002) (xy 126.466073 -384.245369) (xy 126.487936 -384.219704)
			(xy 126.493718 -384.212549) (xy 126.50024 -384.195366) (xy 126.500636 -384.186176) (xy 126.500636 -383.693924)
			(xy 126.500206 -383.684739) (xy 126.493705 -383.667555) (xy 126.487936 -383.660396) (xy 126.466035 -383.634761)
			(xy 126.427945 -383.579123) (xy 126.396794 -383.519323) (xy 126.373031 -383.456222) (xy 126.356996 -383.390729)
			(xy 126.348923 -383.323787) (xy 125.24683 -383.323787) (xy 125.247042 -383.324352) (xy 125.263013 -383.389736)
			(xy 125.271056 -383.456559) (xy 125.271054 -383.523865) (xy 125.263009 -383.590688) (xy 125.247035 -383.656071)
			(xy 125.223362 -383.719076) (xy 125.192328 -383.7788) (xy 125.15438 -383.834387) (xy 125.132592 -383.86004)
			(xy 125.126795 -383.867185) (xy 125.120281 -383.884376) (xy 125.119892 -383.893568) (xy 125.119892 -384.051556)
			(xy 125.119442 -384.061708) (xy 125.11166 -384.080461) (xy 125.097271 -384.094786) (xy 125.078484 -384.102486)
			(xy 125.06833 -384.102864) (xy 124.35205 -384.102864) (xy 124.341927 -384.102333) (xy 124.323208 -384.094622)
			(xy 124.30885 -384.080349) (xy 124.301028 -384.061676) (xy 124.300488 -384.051556) (xy 124.300488 -383.893568)
			(xy 124.300096 -383.884379) (xy 124.29357 -383.867194) (xy 124.287788 -383.86004) (xy 124.266015 -383.834376)
			(xy 124.228062 -383.778792) (xy 124.197025 -383.719071) (xy 124.17335 -383.656068) (xy 124.157374 -383.590686)
			(xy 124.149328 -383.523864) (xy 124.149326 -383.45656) (xy 124.15737 -383.389737) (xy 124.173342 -383.324355)
			(xy 124.197016 -383.261351) (xy 124.22805 -383.201629) (xy 124.266 -383.146043) (xy 124.287788 -383.120392)
			(xy 124.293569 -383.113236) (xy 124.300093 -383.096054) (xy 124.300488 -383.086864) (xy 124.300488 -382.593342)
			(xy 124.30006 -382.584157) (xy 124.293559 -382.566972) (xy 124.287788 -382.559814) (xy 124.265989 -382.534171)
			(xy 124.228037 -382.478584) (xy 124.197002 -382.41886) (xy 124.173327 -382.355854) (xy 124.157354 -382.29047)
			(xy 124.14931 -382.223646) (xy 120.87127 -382.223646) (xy 120.87127 -382.223704) (xy 120.863195 -382.290642)
			(xy 120.84716 -382.35613) (xy 120.823397 -382.419227) (xy 120.792247 -382.479023) (xy 120.75416 -382.534657)
			(xy 120.732296 -382.560322) (xy 120.726507 -382.567473) (xy 120.719988 -382.584659) (xy 120.719596 -382.59385)
			(xy 120.719596 -383.086356) (xy 120.720028 -383.095541) (xy 120.726527 -383.112725) (xy 120.732296 -383.119884)
			(xy 120.754176 -383.145536) (xy 120.792264 -383.201173) (xy 120.823415 -383.26097) (xy 120.847049 -383.323727)
			(xy 121.949155 -383.323727) (xy 121.949158 -383.256419) (xy 121.957206 -383.189594) (xy 121.973182 -383.12421)
			(xy 121.996859 -383.061204) (xy 122.027897 -383.001479) (xy 122.06585 -382.945892) (xy 122.08764 -382.92024)
			(xy 122.09345 -382.913104) (xy 122.099955 -382.895906) (xy 122.10034 -382.886712) (xy 122.10034 -382.728724)
			(xy 122.100742 -382.718566) (xy 122.108537 -382.699807) (xy 122.122941 -382.685481) (xy 122.141742 -382.677788)
			(xy 122.151902 -382.677416) (xy 122.868182 -382.677416) (xy 122.878305 -382.677941) (xy 122.897021 -382.685658)
			(xy 122.911377 -382.699932) (xy 122.919201 -382.718604) (xy 122.919744 -382.728724) (xy 122.919744 -382.886712)
			(xy 122.920161 -382.895898) (xy 122.926671 -382.913082) (xy 122.932444 -382.92024) (xy 122.954197 -382.945921)
			(xy 122.992148 -383.001503) (xy 123.023183 -383.061222) (xy 123.046859 -383.124223) (xy 123.062835 -383.189602)
			(xy 123.070882 -383.256422) (xy 123.070886 -383.323724) (xy 123.062845 -383.390545) (xy 123.046875 -383.455925)
			(xy 123.023206 -383.518928) (xy 122.992176 -383.57865) (xy 122.95423 -383.634236) (xy 122.932444 -383.659888)
			(xy 122.926621 -383.667014) (xy 122.920124 -383.684219) (xy 122.919744 -383.693416) (xy 122.919744 -384.186684)
			(xy 122.920174 -384.195869) (xy 122.926675 -384.213053) (xy 122.932444 -384.220212) (xy 122.954268 -384.245835)
			(xy 122.992217 -384.301425) (xy 123.023249 -384.361152) (xy 123.046921 -384.424161) (xy 123.062892 -384.489547)
			(xy 123.070933 -384.556373) (xy 123.07093 -384.623681) (xy 123.062882 -384.690507) (xy 123.046905 -384.755891)
			(xy 123.023227 -384.818897) (xy 122.992189 -384.878622) (xy 122.954235 -384.934208) (xy 122.932444 -384.95986)
			(xy 122.926633 -384.966994) (xy 122.920128 -384.984193) (xy 122.919744 -384.993388) (xy 122.919744 -385.151376)
			(xy 122.91926 -385.161523) (xy 122.91148 -385.180267) (xy 122.897103 -385.194589) (xy 122.878331 -385.202298)
			(xy 122.868182 -385.202684) (xy 122.151902 -385.202684) (xy 122.141778 -385.202172) (xy 122.123062 -385.19445)
			(xy 122.108706 -385.180171) (xy 122.100883 -385.161497) (xy 122.10034 -385.151376) (xy 122.10034 -384.993388)
			(xy 122.099927 -384.984201) (xy 122.093414 -384.967017) (xy 122.08764 -384.95986) (xy 122.065888 -384.934179)
			(xy 122.027938 -384.878596) (xy 121.996903 -384.818877) (xy 121.973228 -384.755876) (xy 121.957253 -384.690498)
			(xy 121.949206 -384.623678) (xy 121.949202 -384.556376) (xy 121.957243 -384.489556) (xy 121.973212 -384.424176)
			(xy 121.996881 -384.361173) (xy 122.02791 -384.30145) (xy 122.065855 -384.245864) (xy 122.08764 -384.220212)
			(xy 122.093461 -384.213085) (xy 122.09996 -384.19588) (xy 122.10034 -384.186684) (xy 122.10034 -383.693416)
			(xy 122.099913 -383.684231) (xy 122.09341 -383.667047) (xy 122.08764 -383.659888) (xy 122.065817 -383.634265)
			(xy 122.027869 -383.578674) (xy 121.996837 -383.518947) (xy 121.973166 -383.455939) (xy 121.957196 -383.390553)
			(xy 121.949155 -383.323727) (xy 120.847049 -383.323727) (xy 120.847178 -383.324069) (xy 120.863212 -383.38956)
			(xy 120.871287 -383.4565) (xy 120.871286 -383.523925) (xy 120.863208 -383.590864) (xy 120.847171 -383.656354)
			(xy 120.823405 -383.719452) (xy 120.792252 -383.779248) (xy 120.754161 -383.834883) (xy 120.732296 -383.860548)
			(xy 120.726496 -383.867691) (xy 120.719984 -383.884883) (xy 120.719596 -383.894076) (xy 120.719596 -384.051556)
			(xy 120.719148 -384.061676) (xy 120.711413 -384.080379) (xy 120.697106 -384.094695) (xy 120.678408 -384.102441)
			(xy 120.668288 -384.102864) (xy 119.952008 -384.102864) (xy 119.941882 -384.102477) (xy 119.923171 -384.094724)
			(xy 119.908855 -384.080399) (xy 119.901116 -384.061683) (xy 119.9007 -384.051556) (xy 119.9007 -383.894076)
			(xy 119.900302 -383.884888) (xy 119.89378 -383.867703) (xy 119.888 -383.860548) (xy 119.866152 -383.83487)
			(xy 119.828063 -383.779237) (xy 119.796911 -383.719443) (xy 119.773146 -383.656348) (xy 119.75711 -383.59086)
			(xy 119.749032 -383.523923) (xy 119.749031 -383.456501) (xy 119.757105 -383.389564) (xy 119.773139 -383.324075)
			(xy 119.796901 -383.260979) (xy 119.82805 -383.201184) (xy 119.866137 -383.145549) (xy 119.888 -383.119884)
			(xy 119.893786 -383.112731) (xy 119.900307 -383.095547) (xy 119.9007 -383.086356) (xy 119.9007 -382.59385)
			(xy 119.900266 -382.584665) (xy 119.893769 -382.567481) (xy 119.888 -382.560322) (xy 119.866126 -382.534665)
			(xy 119.828038 -382.479029) (xy 119.796888 -382.419232) (xy 119.773124 -382.356134) (xy 119.757089 -382.290644)
			(xy 119.749014 -382.223705) (xy 116.470967 -382.223705) (xy 116.46293 -382.290468) (xy 116.446957 -382.35585)
			(xy 116.423283 -382.418855) (xy 116.392248 -382.478577) (xy 116.354297 -382.534163) (xy 116.332508 -382.559814)
			(xy 116.326724 -382.566968) (xy 116.320202 -382.584152) (xy 116.319808 -382.593342) (xy 116.319808 -383.086864)
			(xy 116.320234 -383.09605) (xy 116.326736 -383.113234) (xy 116.332508 -383.120392) (xy 116.354313 -383.146031)
			(xy 116.392265 -383.201618) (xy 116.4233 -383.261343) (xy 116.446764 -383.323787) (xy 117.548835 -383.323787)
			(xy 117.548838 -383.256359) (xy 117.556918 -383.189418) (xy 117.572959 -383.123926) (xy 117.59673 -383.060827)
			(xy 117.627888 -383.00103) (xy 117.665984 -382.945396) (xy 117.687852 -382.919732) (xy 117.693666 -382.9126)
			(xy 117.700169 -382.895399) (xy 117.700552 -382.886204) (xy 117.700552 -382.728724) (xy 117.701103 -382.718623)
			(xy 117.708824 -382.699954) (xy 117.7231 -382.68566) (xy 117.741759 -382.677916) (xy 117.75186 -382.677416)
			(xy 118.46814 -382.677416) (xy 118.478253 -382.677853) (xy 118.496935 -382.685607) (xy 118.511229 -382.699918)
			(xy 118.51896 -382.71861) (xy 118.519448 -382.728724) (xy 118.519448 -382.886204) (xy 118.519868 -382.89539)
			(xy 118.526376 -382.912574) (xy 118.532148 -382.919732) (xy 118.553978 -382.945426) (xy 118.592072 -383.001055)
			(xy 118.623227 -383.060847) (xy 118.646995 -383.12394) (xy 118.663035 -383.189426) (xy 118.671114 -383.256362)
			(xy 118.671118 -383.323784) (xy 118.663045 -383.390721) (xy 118.647011 -383.456208) (xy 118.623249 -383.519304)
			(xy 118.592099 -383.579099) (xy 118.554012 -383.634732) (xy 118.532148 -383.660396) (xy 118.526364 -383.66755)
			(xy 118.519843 -383.684734) (xy 118.519448 -383.693924) (xy 118.519448 -384.186176) (xy 118.519881 -384.195361)
			(xy 118.52638 -384.212545) (xy 118.532148 -384.219704) (xy 118.554049 -384.245339) (xy 118.59214 -384.300977)
			(xy 118.623292 -384.360777) (xy 118.647057 -384.423878) (xy 118.663091 -384.489371) (xy 118.671165 -384.556313)
			(xy 118.671162 -384.623741) (xy 118.663082 -384.690682) (xy 118.647041 -384.756174) (xy 118.62327 -384.819273)
			(xy 118.592112 -384.87907) (xy 118.554016 -384.934704) (xy 118.532148 -384.960368) (xy 118.526334 -384.9675)
			(xy 118.519831 -384.984701) (xy 118.519448 -384.993896) (xy 118.519448 -385.151376) (xy 118.518897 -385.161477)
			(xy 118.511176 -385.180146) (xy 118.4969 -385.19444) (xy 118.478241 -385.202184) (xy 118.46814 -385.202684)
			(xy 117.75186 -385.202684) (xy 117.741747 -385.202247) (xy 117.723065 -385.194493) (xy 117.708771 -385.180182)
			(xy 117.70104 -385.16149) (xy 117.700552 -385.151376) (xy 117.700552 -384.993896) (xy 117.700132 -384.98471)
			(xy 117.693624 -384.967526) (xy 117.687852 -384.960368) (xy 117.666022 -384.934674) (xy 117.627928 -384.879045)
			(xy 117.596773 -384.819253) (xy 117.573005 -384.75616) (xy 117.556965 -384.690674) (xy 117.548886 -384.623738)
			(xy 117.548882 -384.556316) (xy 117.556955 -384.489379) (xy 117.572989 -384.423892) (xy 117.596751 -384.360796)
			(xy 117.627901 -384.301001) (xy 117.665988 -384.245368) (xy 117.687852 -384.219704) (xy 117.693636 -384.21255)
			(xy 117.700157 -384.195366) (xy 117.700552 -384.186176) (xy 117.700552 -383.693924) (xy 117.700119 -383.684739)
			(xy 117.69362 -383.667555) (xy 117.687852 -383.660396) (xy 117.665951 -383.634761) (xy 117.62786 -383.579123)
			(xy 117.596708 -383.519323) (xy 117.572943 -383.456222) (xy 117.556909 -383.390729) (xy 117.548835 -383.323787)
			(xy 116.446764 -383.323787) (xy 116.446975 -383.324349) (xy 116.462948 -383.389733) (xy 116.470992 -383.456558)
			(xy 116.47099 -383.523866) (xy 116.462944 -383.59069) (xy 116.446967 -383.656074) (xy 116.423291 -383.719079)
			(xy 116.392252 -383.778803) (xy 116.354298 -383.834389) (xy 116.332508 -383.86004) (xy 116.326713 -383.867186)
			(xy 116.320197 -383.884376) (xy 116.319808 -383.893568) (xy 116.319808 -384.051556) (xy 116.319342 -384.061706)
			(xy 116.311563 -384.080456) (xy 116.297179 -384.094781) (xy 116.278398 -384.102483) (xy 116.268246 -384.102864)
			(xy 115.551966 -384.102864) (xy 115.541838 -384.102401) (xy 115.523116 -384.094663) (xy 115.508761 -384.08037)
			(xy 115.500943 -384.061682) (xy 115.500404 -384.051556) (xy 115.500404 -383.893568) (xy 115.500009 -383.884379)
			(xy 115.493485 -383.867195) (xy 115.487704 -383.86004) (xy 115.465933 -383.834374) (xy 115.427986 -383.778789)
			(xy 115.396954 -383.719067) (xy 115.373282 -383.656064) (xy 115.357309 -383.590684) (xy 115.349264 -383.523864)
			(xy 115.349262 -383.45656) (xy 115.357305 -383.38974) (xy 115.373275 -383.324359) (xy 115.396944 -383.261355)
			(xy 115.427974 -383.201632) (xy 115.465918 -383.146045) (xy 115.487704 -383.120392) (xy 115.493487 -383.113237)
			(xy 115.50001 -383.096054) (xy 115.500404 -383.086864) (xy 115.500404 -382.593342) (xy 115.499973 -382.584157)
			(xy 115.493474 -382.566973) (xy 115.487704 -382.559814) (xy 115.465908 -382.534169) (xy 115.427961 -382.478581)
			(xy 115.39693 -382.418856) (xy 115.37326 -382.355851) (xy 115.357288 -382.290468) (xy 115.349246 -382.223645)
			(xy 90.070711 -382.223645) (xy 90.062667 -382.290467) (xy 90.046695 -382.355848) (xy 90.023023 -382.418852)
			(xy 89.991991 -382.478576) (xy 89.954043 -382.534162) (xy 89.932256 -382.559814) (xy 89.926465 -382.566963)
			(xy 89.919948 -382.584151) (xy 89.919556 -382.593342) (xy 89.919556 -383.086864) (xy 89.919994 -383.096048)
			(xy 89.926489 -383.113232) (xy 89.932256 -383.120392) (xy 89.95406 -383.146031) (xy 89.992008 -383.201619)
			(xy 90.023041 -383.261345) (xy 90.046478 -383.323726) (xy 91.149124 -383.323726) (xy 91.149128 -383.256419)
			(xy 91.157175 -383.189595) (xy 91.17315 -383.124211) (xy 91.196825 -383.061205) (xy 91.227861 -383.001481)
			(xy 91.265811 -382.945893) (xy 91.2876 -382.92024) (xy 91.293405 -382.9131) (xy 91.299914 -382.895906)
			(xy 91.3003 -382.886712) (xy 91.3003 -382.728724) (xy 91.300741 -382.718571) (xy 91.308529 -382.699819)
			(xy 91.32292 -382.685495) (xy 91.341708 -382.677795) (xy 91.351862 -382.677416) (xy 92.068142 -382.677416)
			(xy 92.078268 -382.677891) (xy 92.096986 -382.685629) (xy 92.11134 -382.699918) (xy 92.119162 -382.7186)
			(xy 92.119704 -382.728724) (xy 92.119704 -382.886712) (xy 92.120108 -382.8959) (xy 92.126626 -382.913084)
			(xy 92.132404 -382.92024) (xy 92.154155 -382.945922) (xy 92.192102 -383.001505) (xy 92.223135 -383.061225)
			(xy 92.246808 -383.124225) (xy 92.262782 -383.189604) (xy 92.270828 -383.256422) (xy 92.270831 -383.323724)
			(xy 92.262791 -383.390543) (xy 92.246824 -383.455923) (xy 92.223157 -383.518926) (xy 92.19213 -383.578648)
			(xy 92.154188 -383.634235) (xy 92.132404 -383.659888) (xy 92.126588 -383.66702) (xy 92.120085 -383.68422)
			(xy 92.119704 -383.693416) (xy 92.119704 -384.186684) (xy 92.120121 -384.19587) (xy 92.12663 -384.213055)
			(xy 92.132404 -384.220212) (xy 92.154226 -384.245836) (xy 92.192171 -384.301427) (xy 92.2232 -384.361155)
			(xy 92.246869 -384.424163) (xy 92.262838 -384.489548) (xy 92.270879 -384.556374) (xy 92.270875 -384.623681)
			(xy 92.262828 -384.690505) (xy 92.246853 -384.755889) (xy 92.223178 -384.818894) (xy 92.192143 -384.878619)
			(xy 92.154193 -384.934207) (xy 92.132404 -384.95986) (xy 92.1266 -384.967) (xy 92.12009 -384.984194)
			(xy 92.119704 -384.993388) (xy 92.119704 -385.151376) (xy 92.119259 -385.161528) (xy 92.111472 -385.180279)
			(xy 92.097082 -385.194603) (xy 92.078296 -385.202305) (xy 92.068142 -385.202684) (xy 91.351862 -385.202684)
			(xy 91.341736 -385.202205) (xy 91.323018 -385.194469) (xy 91.308664 -385.180181) (xy 91.300842 -385.1615)
			(xy 91.3003 -385.151376) (xy 91.3003 -384.993388) (xy 91.299895 -384.9842) (xy 91.293378 -384.967016)
			(xy 91.2876 -384.95986) (xy 91.265849 -384.934178) (xy 91.227901 -384.878595) (xy 91.196869 -384.818875)
			(xy 91.173196 -384.755875) (xy 91.157221 -384.690497) (xy 91.149175 -384.623678) (xy 91.149172 -384.556376)
			(xy 91.157212 -384.489557) (xy 91.17318 -384.424177) (xy 91.196847 -384.361174) (xy 91.227874 -384.301451)
			(xy 91.265816 -384.245865) (xy 91.2876 -384.220212) (xy 91.293416 -384.213081) (xy 91.299919 -384.19588)
			(xy 91.3003 -384.186684) (xy 91.3003 -383.693416) (xy 91.299882 -383.68423) (xy 91.293374 -383.667045)
			(xy 91.2876 -383.659888) (xy 91.265778 -383.634264) (xy 91.227833 -383.578673) (xy 91.196803 -383.518945)
			(xy 91.173134 -383.455937) (xy 91.157165 -383.390552) (xy 91.149124 -383.323726) (xy 90.046478 -383.323726)
			(xy 90.046713 -383.324351) (xy 90.062685 -383.389735) (xy 90.070728 -383.456559) (xy 90.070727 -383.523865)
			(xy 90.062681 -383.590689) (xy 90.046706 -383.656072) (xy 90.023031 -383.719077) (xy 89.991996 -383.778801)
			(xy 89.954045 -383.834388) (xy 89.932256 -383.86004) (xy 89.926454 -383.867181) (xy 89.919944 -383.884375)
			(xy 89.919556 -383.893568) (xy 89.919556 -384.051556) (xy 89.919043 -384.0617) (xy 89.911273 -384.080441)
			(xy 89.896905 -384.094764) (xy 89.87814 -384.102475) (xy 89.867994 -384.102864) (xy 89.151714 -384.102864)
			(xy 89.141589 -384.102362) (xy 89.122869 -384.09464) (xy 89.108512 -384.080358) (xy 89.100692 -384.061679)
			(xy 89.100152 -384.051556) (xy 89.100152 -383.893568) (xy 89.099745 -383.884381) (xy 89.093228 -383.867197)
			(xy 89.087452 -383.86004) (xy 89.06568 -383.834375) (xy 89.02773 -383.778791) (xy 88.996695 -383.719069)
			(xy 88.973021 -383.656066) (xy 88.957046 -383.590685) (xy 88.949001 -383.523864) (xy 88.948999 -383.45656)
			(xy 88.957042 -383.389738) (xy 88.973014 -383.324357) (xy 88.996685 -383.261353) (xy 89.027717 -383.20163)
			(xy 89.065665 -383.146044) (xy 89.087452 -383.120392) (xy 89.093241 -383.113242) (xy 89.099759 -383.096055)
			(xy 89.100152 -383.086864) (xy 89.100152 -382.593342) (xy 89.09971 -382.584158) (xy 89.093217 -382.566975)
			(xy 89.087452 -382.559814) (xy 89.065654 -382.53417) (xy 89.027704 -382.478583) (xy 88.996671 -382.418858)
			(xy 88.972998 -382.355853) (xy 88.957025 -382.290469) (xy 88.948982 -382.223646) (xy 85.670943 -382.223646)
			(xy 85.670943 -382.223704) (xy 85.662867 -382.290643) (xy 85.646832 -382.356132) (xy 85.623067 -382.419228)
			(xy 85.591915 -382.479024) (xy 85.553825 -382.534657) (xy 85.53196 -382.560322) (xy 85.526167 -382.567469)
			(xy 85.519651 -382.584658) (xy 85.51926 -382.59385) (xy 85.51926 -383.086356) (xy 85.5197 -383.09554)
			(xy 85.526194 -383.112724) (xy 85.53196 -383.119884) (xy 85.553841 -383.145536) (xy 85.591932 -383.201171)
			(xy 85.623084 -383.260969) (xy 85.646743 -383.323786) (xy 86.748805 -383.323786) (xy 86.748808 -383.25636)
			(xy 86.756888 -383.189419) (xy 86.772927 -383.123927) (xy 86.796696 -383.060829) (xy 86.827852 -383.001032)
			(xy 86.865945 -382.945397) (xy 86.887812 -382.919732) (xy 86.893621 -382.912596) (xy 86.900128 -382.895398)
			(xy 86.900512 -382.886204) (xy 86.900512 -382.728724) (xy 86.900936 -382.718602) (xy 86.908678 -382.699896)
			(xy 86.922993 -382.685581) (xy 86.941698 -382.677837) (xy 86.95182 -382.677416) (xy 87.6681 -382.677416)
			(xy 87.678224 -382.677816) (xy 87.696931 -382.685568) (xy 87.711246 -382.699889) (xy 87.718988 -382.718599)
			(xy 87.719408 -382.728724) (xy 87.719408 -382.886204) (xy 87.719815 -382.895392) (xy 87.726331 -382.912576)
			(xy 87.732108 -382.919732) (xy 87.753936 -382.945427) (xy 87.792026 -383.001057) (xy 87.823177 -383.060849)
			(xy 87.846943 -383.123942) (xy 87.862981 -383.189428) (xy 87.87106 -383.256363) (xy 87.871063 -383.323783)
			(xy 87.862991 -383.390719) (xy 87.846959 -383.456206) (xy 87.8232 -383.519301) (xy 87.792053 -383.579096)
			(xy 87.75397 -383.634731) (xy 87.732108 -383.660396) (xy 87.726332 -383.667556) (xy 87.719805 -383.684735)
			(xy 87.719408 -383.693924) (xy 87.719408 -384.186176) (xy 87.719828 -384.195362) (xy 87.726335 -384.212547)
			(xy 87.732108 -384.219704) (xy 87.754007 -384.24534) (xy 87.792094 -384.300979) (xy 87.823243 -384.360779)
			(xy 87.847005 -384.42388) (xy 87.863037 -384.489373) (xy 87.87111 -384.556314) (xy 87.871107 -384.62374)
			(xy 87.863028 -384.690681) (xy 87.846989 -384.756172) (xy 87.823221 -384.81927) (xy 87.792066 -384.879067)
			(xy 87.753974 -384.934703) (xy 87.732108 -384.960368) (xy 87.726301 -384.967506) (xy 87.719792 -384.984702)
			(xy 87.719408 -384.993896) (xy 87.719408 -385.151376) (xy 87.718965 -385.161496) (xy 87.711226 -385.180198)
			(xy 87.696918 -385.194512) (xy 87.67822 -385.20226) (xy 87.6681 -385.202684) (xy 86.95182 -385.202684)
			(xy 86.941697 -385.202267) (xy 86.922991 -385.194523) (xy 86.908675 -385.180206) (xy 86.900932 -385.161499)
			(xy 86.900512 -385.151376) (xy 86.900512 -384.993896) (xy 86.900101 -384.984709) (xy 86.893587 -384.967525)
			(xy 86.887812 -384.960368) (xy 86.865983 -384.934674) (xy 86.827892 -384.879044) (xy 86.796739 -384.819252)
			(xy 86.772973 -384.756158) (xy 86.756934 -384.690673) (xy 86.748855 -384.623738) (xy 86.748852 -384.556316)
			(xy 86.756925 -384.48938) (xy 86.772957 -384.423893) (xy 86.796717 -384.360798) (xy 86.827865 -384.301003)
			(xy 86.86595 -384.245369) (xy 86.887812 -384.219704) (xy 86.893591 -384.212546) (xy 86.900116 -384.195365)
			(xy 86.900512 -384.186176) (xy 86.900512 -383.693924) (xy 86.900088 -383.684738) (xy 86.893583 -383.667554)
			(xy 86.887812 -383.660396) (xy 86.865912 -383.63476) (xy 86.827824 -383.579122) (xy 86.796674 -383.519322)
			(xy 86.772911 -383.456221) (xy 86.756878 -383.390728) (xy 86.748805 -383.323786) (xy 85.646743 -383.323786)
			(xy 85.646849 -383.324068) (xy 85.662885 -383.389559) (xy 85.67096 -383.456499) (xy 85.670959 -383.523925)
			(xy 85.662881 -383.590865) (xy 85.646842 -383.656355) (xy 85.623074 -383.719453) (xy 85.59192 -383.77925)
			(xy 85.553826 -383.834883) (xy 85.53196 -383.860548) (xy 85.526156 -383.867687) (xy 85.519647 -383.884883)
			(xy 85.51926 -383.894076) (xy 85.51926 -384.051556) (xy 85.518847 -384.061681) (xy 85.511106 -384.080391)
			(xy 85.496787 -384.094708) (xy 85.478077 -384.102448) (xy 85.467952 -384.102864) (xy 84.751672 -384.102864)
			(xy 84.741543 -384.102506) (xy 84.722832 -384.094742) (xy 84.708517 -384.080407) (xy 84.70078 -384.061685)
			(xy 84.700364 -384.051556) (xy 84.700364 -383.894076) (xy 84.699951 -383.884889) (xy 84.693438 -383.867706)
			(xy 84.687664 -383.860548) (xy 84.665817 -383.834869) (xy 84.62773 -383.779236) (xy 84.596581 -383.719441)
			(xy 84.572817 -383.656346) (xy 84.556782 -383.590859) (xy 84.548705 -383.523923) (xy 84.548704 -383.456501)
			(xy 84.556778 -383.389565) (xy 84.57281 -383.324077) (xy 84.596571 -383.260981) (xy 84.627718 -383.201185)
			(xy 84.665802 -383.14555) (xy 84.687664 -383.119884) (xy 84.693458 -383.112737) (xy 84.699972 -383.095548)
			(xy 84.700364 -383.086356) (xy 84.700364 -382.59385) (xy 84.699916 -382.584667) (xy 84.693427 -382.567483)
			(xy 84.687664 -382.560322) (xy 84.665791 -382.534664) (xy 84.627705 -382.479028) (xy 84.596557 -382.41923)
			(xy 84.572795 -382.356132) (xy 84.556761 -382.290643) (xy 84.548687 -382.223704) (xy 81.271152 -382.223704)
			(xy 81.263076 -382.290642) (xy 81.247041 -382.356131) (xy 81.223277 -382.419228) (xy 81.192126 -382.479023)
			(xy 81.154036 -382.534657) (xy 81.132172 -382.560322) (xy 81.12638 -382.56747) (xy 81.119863 -382.584659)
			(xy 81.119472 -382.59385) (xy 81.119472 -383.086356) (xy 81.11991 -383.09554) (xy 81.126405 -383.112724)
			(xy 81.132172 -383.119884) (xy 81.154053 -383.145536) (xy 81.192143 -383.201172) (xy 81.223294 -383.260969)
			(xy 81.246931 -383.323727) (xy 82.349036 -383.323727) (xy 82.34904 -383.256419) (xy 82.357087 -383.189595)
			(xy 82.373063 -383.124211) (xy 82.396739 -383.061205) (xy 82.427775 -383.00148) (xy 82.465727 -382.945892)
			(xy 82.487516 -382.92024) (xy 82.493322 -382.913102) (xy 82.499831 -382.895906) (xy 82.500216 -382.886712)
			(xy 82.500216 -382.728724) (xy 82.500636 -382.718601) (xy 82.508379 -382.699895) (xy 82.522695 -382.685579)
			(xy 82.541401 -382.677836) (xy 82.551524 -382.677416) (xy 83.268058 -382.677416) (xy 83.278179 -382.67796)
			(xy 83.296895 -382.68567) (xy 83.311252 -382.699938) (xy 83.319076 -382.718606) (xy 83.31962 -382.728724)
			(xy 83.31962 -382.886712) (xy 83.32002 -382.8959) (xy 83.32654 -382.913085) (xy 83.33232 -382.92024)
			(xy 83.354074 -382.945921) (xy 83.392026 -383.001502) (xy 83.423063 -383.061221) (xy 83.44674 -383.124222)
			(xy 83.462717 -383.189601) (xy 83.470764 -383.256421) (xy 83.470767 -383.323724) (xy 83.462726 -383.390545)
			(xy 83.446756 -383.455926) (xy 83.423085 -383.518929) (xy 83.392054 -383.578651) (xy 83.354107 -383.634236)
			(xy 83.33232 -383.659888) (xy 83.326506 -383.667021) (xy 83.320001 -383.684221) (xy 83.31962 -383.693416)
			(xy 83.31962 -384.186684) (xy 83.320033 -384.195871) (xy 83.326544 -384.213056) (xy 83.33232 -384.220212)
			(xy 83.354144 -384.245835) (xy 83.392095 -384.301424) (xy 83.423129 -384.361152) (xy 83.446801 -384.42416)
			(xy 83.462773 -384.489546) (xy 83.470815 -384.556373) (xy 83.470812 -384.623681) (xy 83.462763 -384.690507)
			(xy 83.446785 -384.755892) (xy 83.423107 -384.818898) (xy 83.392067 -384.878622) (xy 83.354111 -384.934208)
			(xy 83.33232 -384.95986) (xy 83.326518 -384.967001) (xy 83.320006 -384.984195) (xy 83.31962 -384.993388)
			(xy 83.31962 -385.151376) (xy 83.319165 -385.161494) (xy 83.311428 -385.180194) (xy 83.297124 -385.194508)
			(xy 83.27843 -385.202258) (xy 83.268312 -385.202684) (xy 82.551778 -385.202684) (xy 82.541653 -385.202192)
			(xy 82.522936 -385.194462) (xy 82.508581 -385.180178) (xy 82.500758 -385.161499) (xy 82.500216 -385.151376)
			(xy 82.500216 -384.993388) (xy 82.499808 -384.984201) (xy 82.493293 -384.967016) (xy 82.487516 -384.95986)
			(xy 82.465765 -384.934178) (xy 82.427816 -384.878595) (xy 82.396783 -384.818876) (xy 82.373109 -384.755875)
			(xy 82.357134 -384.690497) (xy 82.349088 -384.623678) (xy 82.349084 -384.556376) (xy 82.357125 -384.489556)
			(xy 82.373093 -384.424177) (xy 82.396761 -384.361174) (xy 82.427788 -384.301451) (xy 82.465731 -384.245865)
			(xy 82.487516 -384.220212) (xy 82.493334 -384.213082) (xy 82.499835 -384.19588) (xy 82.500216 -384.186684)
			(xy 82.500216 -383.693416) (xy 82.499794 -383.68423) (xy 82.493288 -383.667046) (xy 82.487516 -383.659888)
			(xy 82.465694 -383.634265) (xy 82.427747 -383.578674) (xy 82.396717 -383.518946) (xy 82.373047 -383.455938)
			(xy 82.357077 -383.390552) (xy 82.349036 -383.323727) (xy 81.246931 -383.323727) (xy 81.247059 -383.324068)
			(xy 81.263094 -383.389559) (xy 81.271169 -383.456499) (xy 81.271168 -383.523925) (xy 81.26309 -383.590865)
			(xy 81.247052 -383.656355) (xy 81.223285 -383.719453) (xy 81.19213 -383.779249) (xy 81.154038 -383.834883)
			(xy 81.132172 -383.860548) (xy 81.126369 -383.867688) (xy 81.119859 -383.884883) (xy 81.119472 -383.894076)
			(xy 81.119472 -384.051556) (xy 81.119047 -384.061679) (xy 81.111308 -384.080387) (xy 81.096994 -384.094704)
			(xy 81.078287 -384.102446) (xy 81.068164 -384.102864) (xy 80.351884 -384.102864) (xy 80.341756 -384.102496)
			(xy 80.323045 -384.094736) (xy 80.30873 -384.080405) (xy 80.300992 -384.061685) (xy 80.300576 -384.051556)
			(xy 80.300576 -383.894076) (xy 80.300183 -383.884887) (xy 80.293658 -383.867703) (xy 80.287876 -383.860548)
			(xy 80.266029 -383.834869) (xy 80.227941 -383.779236) (xy 80.196791 -383.719442) (xy 80.173027 -383.656347)
			(xy 80.156991 -383.590859) (xy 80.148914 -383.523923) (xy 80.148913 -383.456501) (xy 80.156987 -383.389564)
			(xy 80.17302 -383.324076) (xy 80.196781 -383.26098) (xy 80.227929 -383.201184) (xy 80.266014 -383.14555)
			(xy 80.287876 -383.119884) (xy 80.293659 -383.112729) (xy 80.300183 -383.095546) (xy 80.300576 -383.086356)
			(xy 80.300576 -382.59385) (xy 80.300147 -382.584665) (xy 80.293647 -382.56748) (xy 80.287876 -382.560322)
			(xy 80.266003 -382.534664) (xy 80.227916 -382.479028) (xy 80.196767 -382.419231) (xy 80.173005 -382.356133)
			(xy 80.156971 -382.290643) (xy 80.148896 -382.223704) (xy 76.870825 -382.223704) (xy 76.862789 -382.290466)
			(xy 76.846818 -382.355847) (xy 76.823147 -382.418851) (xy 76.792117 -382.478575) (xy 76.75417 -382.534162)
			(xy 76.732384 -382.559814) (xy 76.726597 -382.566966) (xy 76.720077 -382.584151) (xy 76.719684 -382.593342)
			(xy 76.719684 -383.086864) (xy 76.720115 -383.096049) (xy 76.726615 -383.113233) (xy 76.732384 -383.120392)
			(xy 76.754187 -383.146031) (xy 76.792134 -383.20162) (xy 76.823165 -383.261346) (xy 76.846624 -383.323787)
			(xy 77.948717 -383.323787) (xy 77.94872 -383.256359) (xy 77.9568 -383.189418) (xy 77.97284 -383.123927)
			(xy 77.99661 -383.060828) (xy 78.027766 -383.001031) (xy 78.065861 -382.945397) (xy 78.087728 -382.919732)
			(xy 78.09354 -382.912598) (xy 78.100045 -382.895399) (xy 78.100428 -382.886204) (xy 78.100428 -382.728724)
			(xy 78.100836 -382.7186) (xy 78.108582 -382.699891) (xy 78.122901 -382.685575) (xy 78.141611 -382.677834)
			(xy 78.151736 -382.677416) (xy 78.868016 -382.677416) (xy 78.878142 -382.677803) (xy 78.896849 -382.685559)
			(xy 78.911163 -382.699885) (xy 78.918905 -382.718598) (xy 78.919324 -382.728724) (xy 78.919324 -382.886204)
			(xy 78.919727 -382.895392) (xy 78.926245 -382.912577) (xy 78.932024 -382.919732) (xy 78.953852 -382.945427)
			(xy 78.99194 -383.001058) (xy 79.023091 -383.06085) (xy 79.046856 -383.123943) (xy 79.062893 -383.189428)
			(xy 79.070972 -383.256363) (xy 79.070975 -383.323783) (xy 79.062903 -383.390719) (xy 79.046872 -383.456205)
			(xy 79.023113 -383.519301) (xy 78.991968 -383.579096) (xy 78.953885 -383.63473) (xy 78.932024 -383.660396)
			(xy 78.926249 -383.667557) (xy 78.919721 -383.684735) (xy 78.919324 -383.693924) (xy 78.919324 -384.186176)
			(xy 78.91974 -384.195363) (xy 78.926249 -384.212547) (xy 78.932024 -384.219704) (xy 78.953922 -384.24534)
			(xy 78.992009 -384.30098) (xy 79.023156 -384.36078) (xy 79.046917 -384.423881) (xy 79.06295 -384.489373)
			(xy 79.071022 -384.556314) (xy 79.071019 -384.62374) (xy 79.06294 -384.69068) (xy 79.046901 -384.756171)
			(xy 79.023134 -384.819269) (xy 78.991981 -384.879067) (xy 78.953889 -384.934702) (xy 78.932024 -384.960368)
			(xy 78.926219 -384.967507) (xy 78.919709 -384.984702) (xy 78.919324 -384.993896) (xy 78.919324 -385.151376)
			(xy 78.918865 -385.161494) (xy 78.911129 -385.180193) (xy 78.896826 -385.194507) (xy 78.878134 -385.202257)
			(xy 78.868016 -385.202684) (xy 78.151736 -385.202684) (xy 78.141614 -385.202254) (xy 78.122908 -385.194515)
			(xy 78.108592 -385.180202) (xy 78.100848 -385.161498) (xy 78.100428 -385.151376) (xy 78.100428 -384.993896)
			(xy 78.100014 -384.984709) (xy 78.093502 -384.967525) (xy 78.087728 -384.960368) (xy 78.065898 -384.934674)
			(xy 78.027807 -384.879044) (xy 77.996653 -384.819252) (xy 77.972886 -384.756159) (xy 77.956847 -384.690673)
			(xy 77.948768 -384.623738) (xy 77.948764 -384.556316) (xy 77.956837 -384.48938) (xy 77.972869 -384.423893)
			(xy 77.996631 -384.360797) (xy 78.027779 -384.301002) (xy 78.065865 -384.245369) (xy 78.087728 -384.219704)
			(xy 78.093509 -384.212548) (xy 78.100032 -384.195366) (xy 78.100428 -384.186176) (xy 78.100428 -383.693924)
			(xy 78.1 -383.684739) (xy 78.093498 -383.667555) (xy 78.087728 -383.660396) (xy 78.065828 -383.63476)
			(xy 78.027738 -383.579122) (xy 77.996587 -383.519322) (xy 77.972824 -383.456221) (xy 77.95679 -383.390728)
			(xy 77.948717 -383.323787) (xy 76.846624 -383.323787) (xy 76.846836 -383.324352) (xy 76.862807 -383.389735)
			(xy 76.870849 -383.456559) (xy 76.870848 -383.523865) (xy 76.862803 -383.590688) (xy 76.846829 -383.656071)
			(xy 76.823155 -383.719076) (xy 76.792121 -383.7788) (xy 76.754172 -383.834388) (xy 76.732384 -383.86004)
			(xy 76.726586 -383.867184) (xy 76.720073 -383.884376) (xy 76.719684 -383.893568) (xy 76.719684 -384.051556)
			(xy 76.719242 -384.061709) (xy 76.711458 -384.080464) (xy 76.697067 -384.094789) (xy 76.678277 -384.102488)
			(xy 76.668122 -384.102864) (xy 75.951842 -384.102864) (xy 75.941718 -384.102339) (xy 75.922999 -384.094626)
			(xy 75.908642 -384.080351) (xy 75.90082 -384.061677) (xy 75.90028 -384.051556) (xy 75.90028 -383.893568)
			(xy 75.89989 -383.884379) (xy 75.893363 -383.867194) (xy 75.88758 -383.86004) (xy 75.865807 -383.834375)
			(xy 75.827855 -383.778792) (xy 75.796819 -383.71907) (xy 75.773143 -383.656067) (xy 75.757168 -383.590686)
			(xy 75.749122 -383.523864) (xy 75.74912 -383.45656) (xy 75.757164 -383.389738) (xy 75.773136 -383.324356)
			(xy 75.796809 -383.261352) (xy 75.827842 -383.201629) (xy 75.865792 -383.146044) (xy 75.88758 -383.120392)
			(xy 75.89336 -383.113235) (xy 75.899885 -383.096054) (xy 75.90028 -383.086864) (xy 75.90028 -382.593342)
			(xy 75.899854 -382.584156) (xy 75.893352 -382.566972) (xy 75.88758 -382.559814) (xy 75.865781 -382.53417)
			(xy 75.82783 -382.478584) (xy 75.796795 -382.418859) (xy 75.773121 -382.355854) (xy 75.757147 -382.29047)
			(xy 75.749104 -382.223646) (xy 72.471064 -382.223646) (xy 72.471064 -382.223704) (xy 72.462989 -382.290642)
			(xy 72.446954 -382.356131) (xy 72.42319 -382.419227) (xy 72.39204 -382.479023) (xy 72.353952 -382.534657)
			(xy 72.332088 -382.560322) (xy 72.326298 -382.567472) (xy 72.31978 -382.584659) (xy 72.319388 -382.59385)
			(xy 72.319388 -383.086356) (xy 72.319822 -383.095541) (xy 72.326319 -383.112725) (xy 72.332088 -383.119884)
			(xy 72.353968 -383.145536) (xy 72.392057 -383.201172) (xy 72.423208 -383.26097) (xy 72.446843 -383.323727)
			(xy 73.548949 -383.323727) (xy 73.548952 -383.256419) (xy 73.556999 -383.189594) (xy 73.572976 -383.12421)
			(xy 73.596652 -383.061204) (xy 73.62769 -383.001479) (xy 73.665642 -382.945892) (xy 73.687432 -382.92024)
			(xy 73.693241 -382.913103) (xy 73.699747 -382.895906) (xy 73.700132 -382.886712) (xy 73.700132 -382.728724)
			(xy 73.700542 -382.718567) (xy 73.708335 -382.699809) (xy 73.722736 -382.685484) (xy 73.741535 -382.677789)
			(xy 73.751694 -382.677416) (xy 74.467974 -382.677416) (xy 74.478096 -382.677947) (xy 74.496812 -382.685662)
			(xy 74.511169 -382.699934) (xy 74.518993 -382.718605) (xy 74.519536 -382.728724) (xy 74.519536 -382.886712)
			(xy 74.519955 -382.895898) (xy 74.526464 -382.913082) (xy 74.532236 -382.92024) (xy 74.553989 -382.945921)
			(xy 74.591941 -383.001503) (xy 74.622977 -383.061222) (xy 74.646653 -383.124223) (xy 74.662629 -383.189602)
			(xy 74.670676 -383.256422) (xy 74.670679 -383.323724) (xy 74.662639 -383.390545) (xy 74.646669 -383.455925)
			(xy 74.622999 -383.518928) (xy 74.591968 -383.578651) (xy 74.554022 -383.634236) (xy 74.532236 -383.659888)
			(xy 74.526412 -383.667013) (xy 74.519915 -383.684219) (xy 74.519536 -383.693416) (xy 74.519536 -384.186684)
			(xy 74.519968 -384.195869) (xy 74.526468 -384.213052) (xy 74.532236 -384.220212) (xy 74.55406 -384.245835)
			(xy 74.592009 -384.301425) (xy 74.623043 -384.361152) (xy 74.646714 -384.424161) (xy 74.662686 -384.489547)
			(xy 74.670727 -384.556373) (xy 74.670724 -384.623681) (xy 74.662676 -384.690507) (xy 74.646698 -384.755891)
			(xy 74.623021 -384.818897) (xy 74.591982 -384.878622) (xy 74.554027 -384.934208) (xy 74.532236 -384.95986)
			(xy 74.526424 -384.966994) (xy 74.51992 -384.984193) (xy 74.519536 -384.993388) (xy 74.519536 -385.151376)
			(xy 74.51906 -385.161524) (xy 74.511279 -385.180269) (xy 74.496899 -385.194592) (xy 74.478124 -385.202299)
			(xy 74.467974 -385.202684) (xy 73.751694 -385.202684) (xy 73.74157 -385.202179) (xy 73.722853 -385.194454)
			(xy 73.708498 -385.180173) (xy 73.700675 -385.161497) (xy 73.700132 -385.151376) (xy 73.700132 -384.993388)
			(xy 73.699721 -384.984201) (xy 73.693207 -384.967017) (xy 73.687432 -384.95986) (xy 73.66568 -384.934178)
			(xy 73.627731 -384.878596) (xy 73.596696 -384.818877) (xy 73.573022 -384.755876) (xy 73.557047 -384.690497)
			(xy 73.549 -384.623678) (xy 73.548996 -384.556376) (xy 73.557037 -384.489556) (xy 73.573006 -384.424176)
			(xy 73.596674 -384.361173) (xy 73.627703 -384.30145) (xy 73.665647 -384.245864) (xy 73.687432 -384.220212)
			(xy 73.693253 -384.213084) (xy 73.699752 -384.19588) (xy 73.700132 -384.186684) (xy 73.700132 -383.693416)
			(xy 73.699707 -383.684231) (xy 73.693203 -383.667046) (xy 73.687432 -383.659888) (xy 73.665609 -383.634265)
			(xy 73.627662 -383.578674) (xy 73.59663 -383.518946) (xy 73.57296 -383.455938) (xy 73.55699 -383.390553)
			(xy 73.548949 -383.323727) (xy 72.446843 -383.323727) (xy 72.446972 -383.324069) (xy 72.463006 -383.38956)
			(xy 72.471081 -383.456499) (xy 72.47108 -383.523925) (xy 72.463002 -383.590864) (xy 72.446964 -383.656354)
			(xy 72.423198 -383.719452) (xy 72.392045 -383.779248) (xy 72.353953 -383.834883) (xy 72.332088 -383.860548)
			(xy 72.326287 -383.86769) (xy 72.319775 -383.884883) (xy 72.319388 -383.894076) (xy 72.319388 -384.051556)
			(xy 72.318948 -384.061677) (xy 72.311212 -384.080382) (xy 72.296902 -384.094698) (xy 72.278201 -384.102443)
			(xy 72.26808 -384.102864) (xy 71.5518 -384.102864) (xy 71.541673 -384.102483) (xy 71.522963 -384.094728)
			(xy 71.508647 -384.0804) (xy 71.500908 -384.061683) (xy 71.500492 -384.051556) (xy 71.500492 -383.894076)
			(xy 71.500095 -383.884887) (xy 71.493572 -383.867703) (xy 71.487792 -383.860548) (xy 71.465944 -383.83487)
			(xy 71.427855 -383.779237) (xy 71.396704 -383.719442) (xy 71.37294 -383.656347) (xy 71.356903 -383.59086)
			(xy 71.348826 -383.523923) (xy 71.348825 -383.456501) (xy 71.356899 -383.389564) (xy 71.372933 -383.324076)
			(xy 71.396695 -383.26098) (xy 71.427843 -383.201184) (xy 71.465929 -383.145549) (xy 71.487792 -383.119884)
			(xy 71.493577 -383.11273) (xy 71.500099 -383.095546) (xy 71.500492 -383.086356) (xy 71.500492 -382.59385)
			(xy 71.50006 -382.584665) (xy 71.493562 -382.56748) (xy 71.487792 -382.560322) (xy 71.465918 -382.534665)
			(xy 71.427831 -382.479029) (xy 71.396681 -382.419231) (xy 71.372918 -382.356134) (xy 71.356883 -382.290644)
			(xy 71.348808 -382.223705) (xy 46.070794 -382.223705) (xy 46.062758 -382.290467) (xy 46.046786 -382.355849)
			(xy 46.023113 -382.418853) (xy 45.99208 -382.478576) (xy 45.954131 -382.534162) (xy 45.932344 -382.559814)
			(xy 45.926552 -382.566962) (xy 45.920036 -382.584151) (xy 45.919644 -382.593342) (xy 45.919644 -383.086864)
			(xy 45.920084 -383.096048) (xy 45.926578 -383.113232) (xy 45.932344 -383.120392) (xy 45.954148 -383.146031)
			(xy 45.992098 -383.201619) (xy 46.023131 -383.261344) (xy 46.04657 -383.323727) (xy 47.149191 -383.323727)
			(xy 47.149195 -383.256419) (xy 47.157243 -383.189593) (xy 47.173221 -383.124208) (xy 47.1969 -383.061202)
			(xy 47.22794 -383.001477) (xy 47.265897 -382.945892) (xy 47.287688 -382.92024) (xy 47.293491 -382.913099)
			(xy 47.300002 -382.895905) (xy 47.300388 -382.886712) (xy 47.300388 -382.728724) (xy 47.300841 -382.718573)
			(xy 47.308626 -382.699823) (xy 47.323013 -382.685499) (xy 47.341797 -382.677797) (xy 47.35195 -382.677416)
			(xy 48.06823 -382.677416) (xy 48.078356 -382.677901) (xy 48.097073 -382.685634) (xy 48.111427 -382.699921)
			(xy 48.11925 -382.718601) (xy 48.119792 -382.728724) (xy 48.119792 -382.886712) (xy 48.120198 -382.8959)
			(xy 48.126715 -382.913084) (xy 48.132492 -382.92024) (xy 48.154243 -382.945922) (xy 48.192191 -383.001505)
			(xy 48.223224 -383.061224) (xy 48.246898 -383.124225) (xy 48.262872 -383.189603) (xy 48.270919 -383.256422)
			(xy 48.270922 -383.323724) (xy 48.262882 -383.390543) (xy 48.246914 -383.455923) (xy 48.223247 -383.518926)
			(xy 48.192219 -383.578649) (xy 48.154277 -383.634236) (xy 48.132492 -383.659888) (xy 48.126675 -383.667018)
			(xy 48.120173 -383.68422) (xy 48.119792 -383.693416) (xy 48.119792 -384.186684) (xy 48.120212 -384.19587)
			(xy 48.126719 -384.213054) (xy 48.132492 -384.220212) (xy 48.154314 -384.245835) (xy 48.19226 -384.301427)
			(xy 48.22329 -384.361155) (xy 48.246959 -384.424163) (xy 48.262929 -384.489548) (xy 48.27097 -384.556373)
			(xy 48.270966 -384.623681) (xy 48.262919 -384.690505) (xy 48.246943 -384.755889) (xy 48.223268 -384.818895)
			(xy 48.192232 -384.87862) (xy 48.154281 -384.934207) (xy 48.132492 -384.95986) (xy 48.126687 -384.966999)
			(xy 48.120177 -384.984194) (xy 48.119792 -384.993388) (xy 48.119792 -385.151376) (xy 48.119359 -385.16153)
			(xy 48.11157 -385.180283) (xy 48.097176 -385.194608) (xy 48.078386 -385.202307) (xy 48.06823 -385.202684)
			(xy 47.35195 -385.202684) (xy 47.341829 -385.202133) (xy 47.323114 -385.194426) (xy 47.308757 -385.18016)
			(xy 47.300932 -385.161493) (xy 47.300388 -385.151376) (xy 47.300388 -384.993388) (xy 47.299986 -384.9842)
			(xy 47.293467 -384.967016) (xy 47.287688 -384.95986) (xy 47.265934 -384.934179) (xy 47.227981 -384.878598)
			(xy 47.196944 -384.818879) (xy 47.173267 -384.755878) (xy 47.15729 -384.690499) (xy 47.149242 -384.623679)
			(xy 47.149239 -384.556376) (xy 47.15728 -384.489554) (xy 47.173251 -384.424174) (xy 47.196921 -384.361171)
			(xy 47.227953 -384.301448) (xy 47.265901 -384.245863) (xy 47.287688 -384.220212) (xy 47.293503 -384.21308)
			(xy 47.300007 -384.195879) (xy 47.300388 -384.186684) (xy 47.300388 -383.693416) (xy 47.299973 -383.684229)
			(xy 47.293463 -383.667045) (xy 47.287688 -383.659888) (xy 47.265863 -383.634266) (xy 47.227913 -383.578676)
			(xy 47.196878 -383.518949) (xy 47.173205 -383.45594) (xy 47.157233 -383.390554) (xy 47.149191 -383.323727)
			(xy 46.04657 -383.323727) (xy 46.046804 -383.32435) (xy 46.062776 -383.389734) (xy 46.070819 -383.456559)
			(xy 46.070818 -383.523865) (xy 46.062772 -383.590689) (xy 46.046797 -383.656073) (xy 46.023121 -383.719078)
			(xy 45.992085 -383.778802) (xy 45.954133 -383.834388) (xy 45.932344 -383.86004) (xy 45.926541 -383.86718)
			(xy 45.920032 -383.884375) (xy 45.919644 -383.893568) (xy 45.919644 -384.051556) (xy 45.919143 -384.061702)
			(xy 45.91137 -384.080445) (xy 45.896998 -384.094768) (xy 45.878229 -384.102477) (xy 45.868082 -384.102864)
			(xy 45.151802 -384.102864) (xy 45.141676 -384.102372) (xy 45.122956 -384.094645) (xy 45.108599 -384.080361)
			(xy 45.100779 -384.06168) (xy 45.10024 -384.051556) (xy 45.10024 -383.893568) (xy 45.099836 -383.88438)
			(xy 45.093317 -383.867197) (xy 45.08754 -383.86004) (xy 45.065768 -383.834375) (xy 45.027819 -383.77879)
			(xy 44.996785 -383.719068) (xy 44.973111 -383.656066) (xy 44.957137 -383.590685) (xy 44.949092 -383.523864)
			(xy 44.94909 -383.45656) (xy 44.957133 -383.389739) (xy 44.973104 -383.324357) (xy 44.996775 -383.261354)
			(xy 45.027806 -383.20163) (xy 45.065753 -383.146044) (xy 45.08754 -383.120392) (xy 45.093328 -383.113241)
			(xy 45.099847 -383.096055) (xy 45.10024 -383.086864) (xy 45.10024 -382.593342) (xy 45.0998 -382.584158)
			(xy 45.093306 -382.566974) (xy 45.08754 -382.559814) (xy 45.065742 -382.53417) (xy 45.027794 -382.478582)
			(xy 44.996761 -382.418858) (xy 44.973088 -382.355852) (xy 44.957116 -382.290469) (xy 44.949073 -382.223645)
			(xy 41.671034 -382.223645) (xy 41.671034 -382.223704) (xy 41.662958 -382.290643) (xy 41.646922 -382.356132)
			(xy 41.623157 -382.419229) (xy 41.592004 -382.479024) (xy 41.553913 -382.534658) (xy 41.532048 -382.560322)
			(xy 41.526253 -382.567468) (xy 41.519739 -382.584658) (xy 41.519348 -382.59385) (xy 41.519348 -383.086356)
			(xy 41.519791 -383.095539) (xy 41.526283 -383.112723) (xy 41.532048 -383.119884) (xy 41.55393 -383.145535)
			(xy 41.592021 -383.201171) (xy 41.623174 -383.260968) (xy 41.646834 -383.323786) (xy 42.748896 -383.323786)
			(xy 42.748899 -383.25636) (xy 42.756978 -383.189419) (xy 42.773018 -383.123928) (xy 42.796786 -383.06083)
			(xy 42.827941 -383.001032) (xy 42.866034 -382.945397) (xy 42.8879 -382.919732) (xy 42.893708 -382.912595)
			(xy 42.900216 -382.895398) (xy 42.9006 -382.886204) (xy 42.9006 -382.728724) (xy 42.901035 -382.718603)
			(xy 42.908776 -382.6999) (xy 42.923086 -382.685585) (xy 42.941787 -382.677839) (xy 42.951908 -382.677416)
			(xy 43.668188 -382.677416) (xy 43.678312 -382.677826) (xy 43.697018 -382.685573) (xy 43.711333 -382.699892)
			(xy 43.719076 -382.7186) (xy 43.719496 -382.728724) (xy 43.719496 -382.886204) (xy 43.719905 -382.895391)
			(xy 43.72642 -382.912575) (xy 43.732196 -382.919732) (xy 43.754025 -382.945426) (xy 43.792115 -383.001057)
			(xy 43.823267 -383.060849) (xy 43.847034 -383.123942) (xy 43.863072 -383.189427) (xy 43.871151 -383.256363)
			(xy 43.871154 -383.323783) (xy 43.863081 -383.390719) (xy 43.84705 -383.456206) (xy 43.823289 -383.519302)
			(xy 43.792143 -383.579097) (xy 43.754058 -383.634731) (xy 43.732196 -383.660396) (xy 43.726418 -383.667554)
			(xy 43.719892 -383.684735) (xy 43.719496 -383.693924) (xy 43.719496 -384.186176) (xy 43.719919 -384.195362)
			(xy 43.726424 -384.212546) (xy 43.732196 -384.219704) (xy 43.754095 -384.24534) (xy 43.792183 -384.300979)
			(xy 43.823333 -384.360779) (xy 43.847095 -384.42388) (xy 43.863128 -384.489372) (xy 43.871201 -384.556314)
			(xy 43.871198 -384.62374) (xy 43.863118 -384.690681) (xy 43.847079 -384.756172) (xy 43.823311 -384.819271)
			(xy 43.792156 -384.879068) (xy 43.754062 -384.934703) (xy 43.732196 -384.960368) (xy 43.726388 -384.967505)
			(xy 43.71988 -384.984702) (xy 43.719496 -384.993896) (xy 43.719496 -385.151376) (xy 43.719064 -385.161497)
			(xy 43.711323 -385.180201) (xy 43.697011 -385.194517) (xy 43.678309 -385.202262) (xy 43.668188 -385.202684)
			(xy 42.951908 -385.202684) (xy 42.941784 -385.202277) (xy 42.923078 -385.194529) (xy 42.908762 -385.180209)
			(xy 42.90102 -385.1615) (xy 42.9006 -385.151376) (xy 42.9006 -384.993896) (xy 42.900192 -384.984709)
			(xy 42.893677 -384.967524) (xy 42.8879 -384.960368) (xy 42.866071 -384.934674) (xy 42.827982 -384.879043)
			(xy 42.796829 -384.819251) (xy 42.773063 -384.756158) (xy 42.757025 -384.690672) (xy 42.748946 -384.623737)
			(xy 42.748943 -384.556317) (xy 42.757015 -384.489381) (xy 42.773047 -384.423894) (xy 42.796807 -384.360798)
			(xy 42.827954 -384.301003) (xy 42.866038 -384.245369) (xy 42.8879 -384.219704) (xy 42.893677 -384.212545)
			(xy 42.900204 -384.195365) (xy 42.9006 -384.186176) (xy 42.9006 -383.693924) (xy 42.900178 -383.684738)
			(xy 42.893673 -383.667554) (xy 42.8879 -383.660396) (xy 42.866001 -383.63476) (xy 42.827913 -383.579121)
			(xy 42.796764 -383.519321) (xy 42.773002 -383.45622) (xy 42.756969 -383.390728) (xy 42.748896 -383.323786)
			(xy 41.646834 -383.323786) (xy 41.64694 -383.324067) (xy 41.662976 -383.389558) (xy 41.671051 -383.456499)
			(xy 41.67105 -383.523925) (xy 41.662971 -383.590865) (xy 41.646933 -383.656356) (xy 41.623164 -383.719454)
			(xy 41.592009 -383.77925) (xy 41.553915 -383.834884) (xy 41.532048 -383.860548) (xy 41.526242 -383.867686)
			(xy 41.519734 -383.884882) (xy 41.519348 -383.894076) (xy 41.519348 -384.051556) (xy 41.518849 -384.06167)
			(xy 41.511124 -384.080363) (xy 41.496834 -384.094677) (xy 41.478153 -384.102432) (xy 41.46804 -384.102864)
			(xy 40.75176 -384.102864) (xy 40.74163 -384.102516) (xy 40.722919 -384.094748) (xy 40.708605 -384.08041)
			(xy 40.700868 -384.061686) (xy 40.700452 -384.051556) (xy 40.700452 -383.894076) (xy 40.700042 -383.884889)
			(xy 40.693527 -383.867705) (xy 40.687752 -383.860548) (xy 40.665902 -383.834871) (xy 40.627809 -383.779239)
			(xy 40.596655 -383.719445) (xy 40.572888 -383.65635) (xy 40.556849 -383.590862) (xy 40.548772 -383.523924)
			(xy 40.54877 -383.4565) (xy 40.556845 -383.389562) (xy 40.572881 -383.324073) (xy 40.596645 -383.260977)
			(xy 40.627797 -383.201182) (xy 40.665887 -383.145548) (xy 40.687752 -383.119884) (xy 40.693544 -383.112736)
			(xy 40.70006 -383.095547) (xy 40.700452 -383.086356) (xy 40.700452 -382.59385) (xy 40.700006 -382.584667)
			(xy 40.693516 -382.567483) (xy 40.687752 -382.560322) (xy 40.665876 -382.534666) (xy 40.627785 -382.479031)
			(xy 40.596631 -382.419234) (xy 40.572865 -382.356136) (xy 40.556829 -382.290645) (xy 40.548753 -382.223705)
			(xy 37.271243 -382.223705) (xy 37.263167 -382.290643) (xy 37.247132 -382.356132) (xy 37.223367 -382.419228)
			(xy 37.192215 -382.479024) (xy 37.154125 -382.534657) (xy 37.13226 -382.560322) (xy 37.126467 -382.567469)
			(xy 37.119951 -382.584658) (xy 37.11956 -382.59385) (xy 37.11956 -383.086356) (xy 37.12 -383.09554)
			(xy 37.126494 -383.112724) (xy 37.13226 -383.119884) (xy 37.154141 -383.145536) (xy 37.192232 -383.201171)
			(xy 37.223384 -383.260969) (xy 37.247021 -383.323727) (xy 38.349127 -383.323727) (xy 38.349131 -383.256419)
			(xy 38.357178 -383.189595) (xy 38.373154 -383.124211) (xy 38.396829 -383.061205) (xy 38.427864 -383.00148)
			(xy 38.465815 -382.945893) (xy 38.487604 -382.92024) (xy 38.493409 -382.913101) (xy 38.499919 -382.895906)
			(xy 38.500304 -382.886712) (xy 38.500304 -382.728724) (xy 38.500741 -382.718571) (xy 38.50853 -382.699818)
			(xy 38.522922 -382.685494) (xy 38.541711 -382.677794) (xy 38.551866 -382.677416) (xy 39.268146 -382.677416)
			(xy 39.278273 -382.677888) (xy 39.29699 -382.685627) (xy 39.311344 -382.699917) (xy 39.319166 -382.7186)
			(xy 39.319708 -382.728724) (xy 39.319708 -382.886712) (xy 39.320111 -382.8959) (xy 39.326629 -382.913084)
			(xy 39.332408 -382.92024) (xy 39.354162 -382.945921) (xy 39.392115 -383.001502) (xy 39.423153 -383.061221)
			(xy 39.44683 -383.124222) (xy 39.462807 -383.189601) (xy 39.470855 -383.256421) (xy 39.470858 -383.323725)
			(xy 39.462817 -383.390546) (xy 39.446846 -383.455926) (xy 39.423175 -383.51893) (xy 39.392143 -383.578652)
			(xy 39.354195 -383.634237) (xy 39.332408 -383.659888) (xy 39.326592 -383.66702) (xy 39.320089 -383.684221)
			(xy 39.319708 -383.693416) (xy 39.319708 -384.186684) (xy 39.320124 -384.195871) (xy 39.326633 -384.213055)
			(xy 39.332408 -384.220212) (xy 39.354233 -384.245834) (xy 39.392184 -384.301424) (xy 39.423219 -384.361151)
			(xy 39.446892 -384.42416) (xy 39.462864 -384.489546) (xy 39.470906 -384.556373) (xy 39.470902 -384.623682)
			(xy 39.462854 -384.690507) (xy 39.446876 -384.755892) (xy 39.423196 -384.818898) (xy 39.392156 -384.878623)
			(xy 39.354199 -384.934209) (xy 39.332408 -384.95986) (xy 39.326604 -384.967) (xy 39.320094 -384.984195)
			(xy 39.319708 -384.993388) (xy 39.319708 -385.151376) (xy 39.319259 -385.161528) (xy 39.311473 -385.180278)
			(xy 39.297085 -385.194602) (xy 39.278299 -385.202304) (xy 39.268146 -385.202684) (xy 38.551866 -385.202684)
			(xy 38.54174 -385.202202) (xy 38.523023 -385.194468) (xy 38.508668 -385.18018) (xy 38.500846 -385.1615)
			(xy 38.500304 -385.151376) (xy 38.500304 -384.993388) (xy 38.499899 -384.9842) (xy 38.493381 -384.967016)
			(xy 38.487604 -384.95986) (xy 38.465853 -384.934178) (xy 38.427905 -384.878595) (xy 38.396872 -384.818875)
			(xy 38.373199 -384.755875) (xy 38.357224 -384.690497) (xy 38.349178 -384.623678) (xy 38.349175 -384.556376)
			(xy 38.357215 -384.489557) (xy 38.373183 -384.424177) (xy 38.39685 -384.361174) (xy 38.427877 -384.301451)
			(xy 38.465819 -384.245865) (xy 38.487604 -384.220212) (xy 38.493421 -384.213081) (xy 38.499923 -384.19588)
			(xy 38.500304 -384.186684) (xy 38.500304 -383.693416) (xy 38.499885 -383.68423) (xy 38.493377 -383.667045)
			(xy 38.487604 -383.659888) (xy 38.465782 -383.634264) (xy 38.427837 -383.578673) (xy 38.396807 -383.518945)
			(xy 38.373138 -383.455937) (xy 38.357168 -383.390552) (xy 38.349127 -383.323727) (xy 37.247021 -383.323727)
			(xy 37.247149 -383.324068) (xy 37.263185 -383.389559) (xy 37.27126 -383.456499) (xy 37.271259 -383.523925)
			(xy 37.263181 -383.590865) (xy 37.247142 -383.656355) (xy 37.223374 -383.719453) (xy 37.19222 -383.77925)
			(xy 37.154126 -383.834883) (xy 37.13226 -383.860548) (xy 37.126456 -383.867687) (xy 37.119947 -383.884883)
			(xy 37.11956 -383.894076) (xy 37.11956 -384.051556) (xy 37.119147 -384.061681) (xy 37.111406 -384.080391)
			(xy 37.097087 -384.094708) (xy 37.078377 -384.102448) (xy 37.068252 -384.102864) (xy 36.351972 -384.102864)
			(xy 36.341843 -384.102506) (xy 36.323132 -384.094742) (xy 36.308817 -384.080407) (xy 36.30108 -384.061685)
			(xy 36.300664 -384.051556) (xy 36.300664 -383.894076) (xy 36.300251 -383.884889) (xy 36.293738 -383.867706)
			(xy 36.287964 -383.860548) (xy 36.266117 -383.834869) (xy 36.22803 -383.779236) (xy 36.196881 -383.719441)
			(xy 36.173117 -383.656346) (xy 36.157082 -383.590859) (xy 36.149005 -383.523923) (xy 36.149004 -383.456501)
			(xy 36.157078 -383.389565) (xy 36.17311 -383.324077) (xy 36.196871 -383.260981) (xy 36.228018 -383.201185)
			(xy 36.266102 -383.14555) (xy 36.287964 -383.119884) (xy 36.293758 -383.112737) (xy 36.300272 -383.095548)
			(xy 36.300664 -383.086356) (xy 36.300664 -382.59385) (xy 36.300216 -382.584667) (xy 36.293727 -382.567483)
			(xy 36.287964 -382.560322) (xy 36.266091 -382.534664) (xy 36.228005 -382.479028) (xy 36.196857 -382.41923)
			(xy 36.173095 -382.356132) (xy 36.157061 -382.290643) (xy 36.148987 -382.223704) (xy 32.870916 -382.223704)
			(xy 32.86288 -382.290466) (xy 32.846909 -382.355848) (xy 32.823237 -382.418852) (xy 32.792206 -382.478575)
			(xy 32.754259 -382.534162) (xy 32.732472 -382.559814) (xy 32.726683 -382.566965) (xy 32.720165 -382.584151)
			(xy 32.719772 -382.593342) (xy 32.719772 -383.086864) (xy 32.720206 -383.096049) (xy 32.726704 -383.113233)
			(xy 32.732472 -383.120392) (xy 32.754275 -383.146031) (xy 32.792223 -383.20162) (xy 32.823255 -383.261345)
			(xy 32.846714 -383.323786) (xy 33.948808 -383.323786) (xy 33.948811 -383.25636) (xy 33.956891 -383.189419)
			(xy 33.972931 -383.123927) (xy 33.996699 -383.060829) (xy 34.027855 -383.001032) (xy 34.065949 -382.945397)
			(xy 34.087816 -382.919732) (xy 34.093626 -382.912596) (xy 34.100132 -382.895398) (xy 34.100516 -382.886204)
			(xy 34.100516 -382.728724) (xy 34.100936 -382.718601) (xy 34.108679 -382.699895) (xy 34.122995 -382.685579)
			(xy 34.141701 -382.677836) (xy 34.151824 -382.677416) (xy 34.868104 -382.677416) (xy 34.878229 -382.677813)
			(xy 34.896935 -382.685566) (xy 34.91125 -382.699888) (xy 34.918992 -382.718599) (xy 34.919412 -382.728724)
			(xy 34.919412 -382.886204) (xy 34.919818 -382.895392) (xy 34.926334 -382.912576) (xy 34.932112 -382.919732)
			(xy 34.95394 -382.945427) (xy 34.992029 -383.001057) (xy 35.023181 -383.060849) (xy 35.046946 -383.123942)
			(xy 35.062984 -383.189428) (xy 35.071063 -383.256363) (xy 35.071066 -383.323783) (xy 35.062994 -383.390719)
			(xy 35.046962 -383.456206) (xy 35.023203 -383.519301) (xy 34.992057 -383.579096) (xy 34.953973 -383.634731)
			(xy 34.932112 -383.660396) (xy 34.926336 -383.667556) (xy 34.919809 -383.684735) (xy 34.919412 -383.693924)
			(xy 34.919412 -384.186176) (xy 34.919831 -384.195362) (xy 34.926338 -384.212547) (xy 34.932112 -384.219704)
			(xy 34.954011 -384.24534) (xy 34.992098 -384.300979) (xy 35.023246 -384.36078) (xy 35.047008 -384.42388)
			(xy 35.06304 -384.489373) (xy 35.071113 -384.556314) (xy 35.07111 -384.62374) (xy 35.063031 -384.690681)
			(xy 35.046992 -384.756172) (xy 35.023224 -384.81927) (xy 34.99207 -384.879067) (xy 34.953978 -384.934703)
			(xy 34.932112 -384.960368) (xy 34.926305 -384.967506) (xy 34.919796 -384.984702) (xy 34.919412 -384.993896)
			(xy 34.919412 -385.151376) (xy 34.918965 -385.161495) (xy 34.911227 -385.180196) (xy 34.89692 -385.194511)
			(xy 34.878223 -385.202259) (xy 34.868104 -385.202684) (xy 34.151824 -385.202684) (xy 34.141701 -385.202264)
			(xy 34.122995 -385.194521) (xy 34.108679 -385.180205) (xy 34.100936 -385.161499) (xy 34.100516 -385.151376)
			(xy 34.100516 -384.993896) (xy 34.100104 -384.984709) (xy 34.093591 -384.967525) (xy 34.087816 -384.960368)
			(xy 34.065987 -384.934674) (xy 34.027896 -384.879044) (xy 33.996743 -384.819252) (xy 33.972976 -384.756159)
			(xy 33.956937 -384.690673) (xy 33.948858 -384.623738) (xy 33.948855 -384.556316) (xy 33.956928 -384.48938)
			(xy 33.97296 -384.423893) (xy 33.996721 -384.360798) (xy 34.027868 -384.301003) (xy 34.065954 -384.245369)
			(xy 34.087816 -384.219704) (xy 34.093595 -384.212547) (xy 34.10012 -384.195365) (xy 34.100516 -384.186176)
			(xy 34.100516 -383.693924) (xy 34.100091 -383.684739) (xy 34.093587 -383.667554) (xy 34.087816 -383.660396)
			(xy 34.065916 -383.63476) (xy 34.027827 -383.579122) (xy 33.996677 -383.519322) (xy 33.972915 -383.456221)
			(xy 33.956881 -383.390728) (xy 33.948808 -383.323786) (xy 32.846714 -383.323786) (xy 32.846926 -383.324351)
			(xy 32.862898 -383.389735) (xy 32.87094 -383.456559) (xy 32.870939 -383.523865) (xy 32.862893 -383.590689)
			(xy 32.846919 -383.656072) (xy 32.823245 -383.719077) (xy 32.79221 -383.778801) (xy 32.75426 -383.834388)
			(xy 32.732472 -383.86004) (xy 32.726672 -383.867183) (xy 32.72016 -383.884375) (xy 32.719772 -383.893568)
			(xy 32.719772 -384.051556) (xy 32.719342 -384.061711) (xy 32.711555 -384.080468) (xy 32.697161 -384.094793)
			(xy 32.678367 -384.10249) (xy 32.66821 -384.102864) (xy 31.95193 -384.102864) (xy 31.941806 -384.102349)
			(xy 31.923086 -384.094632) (xy 31.908729 -384.080354) (xy 31.900908 -384.061678) (xy 31.900368 -384.051556)
			(xy 31.900368 -383.893568) (xy 31.899958 -383.884381) (xy 31.893443 -383.867197) (xy 31.887668 -383.86004)
			(xy 31.865895 -383.834375) (xy 31.827944 -383.778791) (xy 31.796908 -383.71907) (xy 31.773234 -383.656067)
			(xy 31.757259 -383.590686) (xy 31.749213 -383.523864) (xy 31.749211 -383.45656) (xy 31.757254 -383.389738)
			(xy 31.773226 -383.324356) (xy 31.796899 -383.261352) (xy 31.827932 -383.201629) (xy 31.86588 -383.146044)
			(xy 31.887668 -383.120392) (xy 31.893459 -383.113243) (xy 31.899975 -383.096055) (xy 31.900368 -383.086864)
			(xy 31.900368 -382.593342) (xy 31.899923 -382.584159) (xy 31.893432 -382.566975) (xy 31.887668 -382.559814)
			(xy 31.86587 -382.53417) (xy 31.827919 -382.478583) (xy 31.796885 -382.418859) (xy 31.773211 -382.355853)
			(xy 31.757238 -382.29047) (xy 31.749194 -382.223646) (xy 28.471155 -382.223646) (xy 28.471155 -382.223704)
			(xy 28.463079 -382.290642) (xy 28.447044 -382.356131) (xy 28.42328 -382.419228) (xy 28.392129 -382.479023)
			(xy 28.35404 -382.534657) (xy 28.332176 -382.560322) (xy 28.326385 -382.567471) (xy 28.319868 -382.584659)
			(xy 28.319476 -382.59385) (xy 28.319476 -383.086356) (xy 28.319913 -383.09554) (xy 28.326409 -383.112725)
			(xy 28.332176 -383.119884) (xy 28.354057 -383.145536) (xy 28.392146 -383.201172) (xy 28.423298 -383.26097)
			(xy 28.446934 -383.323727) (xy 29.549039 -383.323727) (xy 29.549043 -383.256419) (xy 29.55709 -383.189594)
			(xy 29.573066 -383.12421) (xy 29.596742 -383.061205) (xy 29.627779 -383.00148) (xy 29.665731 -382.945892)
			(xy 29.68752 -382.92024) (xy 29.693327 -382.913102) (xy 29.699835 -382.895906) (xy 29.70022 -382.886712)
			(xy 29.70022 -382.728724) (xy 29.700636 -382.718601) (xy 29.70838 -382.699894) (xy 29.722697 -382.685578)
			(xy 29.741405 -382.677835) (xy 29.751528 -382.677416) (xy 30.468062 -382.677416) (xy 30.478183 -382.677957)
			(xy 30.496899 -382.685668) (xy 30.511256 -382.699938) (xy 30.51908 -382.718606) (xy 30.519624 -382.728724)
			(xy 30.519624 -382.886712) (xy 30.520023 -382.8959) (xy 30.526544 -382.913085) (xy 30.532324 -382.92024)
			(xy 30.554077 -382.945921) (xy 30.59203 -383.001502) (xy 30.623067 -383.061222) (xy 30.646743 -383.124222)
			(xy 30.66272 -383.189601) (xy 30.670767 -383.256421) (xy 30.67077 -383.323724) (xy 30.662729 -383.390545)
			(xy 30.646759 -383.455926) (xy 30.623089 -383.518929) (xy 30.592058 -383.578651) (xy 30.554111 -383.634236)
			(xy 30.532324 -383.659888) (xy 30.52651 -383.667021) (xy 30.520005 -383.684221) (xy 30.519624 -383.693416)
			(xy 30.519624 -384.186684) (xy 30.520036 -384.195871) (xy 30.526548 -384.213056) (xy 30.532324 -384.220212)
			(xy 30.554149 -384.245834) (xy 30.592099 -384.301424) (xy 30.623132 -384.361152) (xy 30.646805 -384.42416)
			(xy 30.662776 -384.489546) (xy 30.670818 -384.556373) (xy 30.670815 -384.623681) (xy 30.662767 -384.690507)
			(xy 30.646789 -384.755892) (xy 30.62311 -384.818898) (xy 30.592071 -384.878622) (xy 30.554115 -384.934209)
			(xy 30.532324 -384.95986) (xy 30.526522 -384.967002) (xy 30.52001 -384.984195) (xy 30.519624 -384.993388)
			(xy 30.519624 -385.151376) (xy 30.519165 -385.161494) (xy 30.511429 -385.180193) (xy 30.497126 -385.194507)
			(xy 30.478434 -385.202257) (xy 30.468316 -385.202684) (xy 29.751782 -385.202684) (xy 29.741657 -385.202189)
			(xy 29.72294 -385.19446) (xy 29.708585 -385.180177) (xy 29.700762 -385.161498) (xy 29.70022 -385.151376)
			(xy 29.70022 -384.993388) (xy 29.699811 -384.984201) (xy 29.693296 -384.967017) (xy 29.68752 -384.95986)
			(xy 29.665769 -384.934178) (xy 29.62782 -384.878596) (xy 29.596786 -384.818876) (xy 29.573112 -384.755875)
			(xy 29.557137 -384.690497) (xy 29.549091 -384.623678) (xy 29.549087 -384.556376) (xy 29.557128 -384.489556)
			(xy 29.573096 -384.424176) (xy 29.596764 -384.361174) (xy 29.627792 -384.301451) (xy 29.665735 -384.245865)
			(xy 29.68752 -384.220212) (xy 29.693339 -384.213083) (xy 29.69984 -384.19588) (xy 29.70022 -384.186684)
			(xy 29.70022 -383.693416) (xy 29.699797 -383.68423) (xy 29.693292 -383.667046) (xy 29.68752 -383.659888)
			(xy 29.665697 -383.634265) (xy 29.627751 -383.578674) (xy 29.59672 -383.518946) (xy 29.57305 -383.455938)
			(xy 29.55708 -383.390552) (xy 29.549039 -383.323727) (xy 28.446934 -383.323727) (xy 28.447062 -383.324068)
			(xy 28.463097 -383.389559) (xy 28.471172 -383.456499) (xy 28.471171 -383.523925) (xy 28.463093 -383.590865)
			(xy 28.447055 -383.656355) (xy 28.423288 -383.719452) (xy 28.392134 -383.779249) (xy 28.354042 -383.834883)
			(xy 28.332176 -383.860548) (xy 28.326374 -383.867689) (xy 28.319863 -383.884883) (xy 28.319476 -383.894076)
			(xy 28.319476 -384.051556) (xy 28.319047 -384.061679) (xy 28.311309 -384.080386) (xy 28.296996 -384.094702)
			(xy 28.27829 -384.102445) (xy 28.268168 -384.102864) (xy 27.551888 -384.102864) (xy 27.54176 -384.102493)
			(xy 27.523049 -384.094734) (xy 27.508734 -384.080404) (xy 27.500996 -384.061684) (xy 27.50058 -384.051556)
			(xy 27.50058 -383.894076) (xy 27.500186 -383.884887) (xy 27.493661 -383.867703) (xy 27.48788 -383.860548)
			(xy 27.466032 -383.834869) (xy 27.427945 -383.779236) (xy 27.396794 -383.719442) (xy 27.37303 -383.656347)
			(xy 27.356994 -383.59086) (xy 27.348917 -383.523923) (xy 27.348916 -383.456501) (xy 27.35699 -383.389564)
			(xy 27.373023 -383.324076) (xy 27.396784 -383.26098) (xy 27.427932 -383.201184) (xy 27.466018 -383.14555)
			(xy 27.48788 -383.119884) (xy 27.493664 -383.112729) (xy 27.500187 -383.095546) (xy 27.50058 -383.086356)
			(xy 27.50058 -382.59385) (xy 27.50015 -382.584665) (xy 27.49365 -382.56748) (xy 27.48788 -382.560322)
			(xy 27.466007 -382.534665) (xy 27.42792 -382.479028) (xy 27.396771 -382.419231) (xy 27.373008 -382.356133)
			(xy 27.356974 -382.290643) (xy 27.348899 -382.223705) (xy 0.508 -382.223705) (xy 0.508 -385.583938)
			(xy 100.447856 -385.583938) (xy 100.447856 -384.720338) (xy 100.448346 -384.690354) (xy 100.456174 -384.630898)
			(xy 100.471695 -384.572973) (xy 100.494644 -384.517569) (xy 100.524628 -384.465635) (xy 100.561134 -384.418059)
			(xy 100.603539 -384.375654) (xy 100.651115 -384.339148) (xy 100.703049 -384.309164) (xy 100.758453 -384.286215)
			(xy 100.816378 -384.270694) (xy 100.875834 -384.262866) (xy 100.935802 -384.262866) (xy 100.995258 -384.270694)
			(xy 101.053183 -384.286215) (xy 101.108587 -384.309164) (xy 101.160521 -384.339148) (xy 101.208097 -384.375654)
			(xy 101.250502 -384.418059) (xy 101.287008 -384.465635) (xy 101.316992 -384.517569) (xy 101.339941 -384.572973)
			(xy 101.355462 -384.630898) (xy 101.36329 -384.690354) (xy 101.36378 -384.720338) (xy 101.36378 -385.319283)
			(xy 104.635826 -385.319283) (xy 104.635826 -385.259317) (xy 104.643653 -385.199864) (xy 104.659172 -385.141942)
			(xy 104.682119 -385.08654) (xy 104.7121 -385.034608) (xy 104.748603 -384.987032) (xy 104.791004 -384.944628)
			(xy 104.838576 -384.908121) (xy 104.890506 -384.878136) (xy 104.945906 -384.855184) (xy 105.003827 -384.83966)
			(xy 105.063279 -384.831828) (xy 105.093262 -384.831336) (xy 105.956862 -384.831336) (xy 105.986849 -384.831807)
			(xy 106.046311 -384.83963) (xy 106.104243 -384.855149) (xy 106.159653 -384.878097) (xy 106.211594 -384.908081)
			(xy 106.259176 -384.944589) (xy 106.301586 -384.986995) (xy 106.338098 -385.034574) (xy 106.368087 -385.086513)
			(xy 106.391039 -385.141921) (xy 106.406562 -385.199852) (xy 106.414391 -385.259313) (xy 106.414391 -385.319287)
			(xy 106.406562 -385.378748) (xy 106.391039 -385.436679) (xy 106.368087 -385.492087) (xy 106.338098 -385.544026)
			(xy 106.301586 -385.591605) (xy 106.259176 -385.634011) (xy 106.211594 -385.670519) (xy 106.159653 -385.700503)
			(xy 106.104243 -385.723451) (xy 106.046311 -385.73897) (xy 105.986849 -385.746793) (xy 105.956862 -385.74726)
			(xy 105.093262 -385.74726) (xy 105.063279 -385.746772) (xy 105.003827 -385.73894) (xy 104.945906 -385.723416)
			(xy 104.890506 -385.700464) (xy 104.838576 -385.670479) (xy 104.791004 -385.633972) (xy 104.748603 -385.591568)
			(xy 104.7121 -385.543992) (xy 104.682119 -385.49206) (xy 104.659172 -385.436658) (xy 104.643653 -385.378736)
			(xy 104.635826 -385.319283) (xy 101.36378 -385.319283) (xy 101.36378 -385.583938) (xy 101.36329 -385.613922)
			(xy 101.355462 -385.673378) (xy 101.339941 -385.731303) (xy 101.316992 -385.786707) (xy 101.287008 -385.838641)
			(xy 101.250502 -385.886217) (xy 101.208097 -385.928622) (xy 101.160521 -385.965128) (xy 101.108587 -385.995112)
			(xy 101.053183 -386.018061) (xy 100.995258 -386.033582) (xy 100.935802 -386.04141) (xy 100.875834 -386.04141)
			(xy 100.816378 -386.033582) (xy 100.758453 -386.018061) (xy 100.703049 -385.995112) (xy 100.651115 -385.965128)
			(xy 100.603539 -385.928622) (xy 100.561134 -385.886217) (xy 100.524628 -385.838641) (xy 100.494644 -385.786707)
			(xy 100.471695 -385.731303) (xy 100.456174 -385.673378) (xy 100.448346 -385.613922) (xy 100.447856 -385.583938)
			(xy 0.508 -385.583938) (xy 0.508 -388.37489) (xy 1.56972 -388.37489) (xy 1.56972 -387.51129) (xy 1.57021 -387.481322)
			(xy 1.578033 -387.4219) (xy 1.593546 -387.364007) (xy 1.616482 -387.308634) (xy 1.646449 -387.256728)
			(xy 1.682936 -387.209178) (xy 1.725316 -387.166798) (xy 1.772866 -387.130311) (xy 1.824772 -387.100344)
			(xy 1.880145 -387.077408) (xy 1.938038 -387.061895) (xy 1.99746 -387.054072) (xy 2.057396 -387.054072)
			(xy 2.116818 -387.061895) (xy 2.174711 -387.077408) (xy 2.230084 -387.100344) (xy 2.28199 -387.130311)
			(xy 2.32954 -387.166798) (xy 2.37192 -387.209178) (xy 2.408407 -387.256728) (xy 2.438374 -387.308634)
			(xy 2.46131 -387.364007) (xy 2.476823 -387.4219) (xy 2.484646 -387.481322) (xy 2.485136 -387.51129)
			(xy 2.485136 -388.37489) (xy 2.484646 -388.404858) (xy 2.476823 -388.46428) (xy 2.46131 -388.522173)
			(xy 2.438374 -388.577546) (xy 2.408407 -388.629452) (xy 2.37192 -388.677002) (xy 2.32954 -388.719382)
			(xy 2.28199 -388.755869) (xy 2.230084 -388.785836) (xy 2.174711 -388.808772) (xy 2.116818 -388.824285)
			(xy 2.057396 -388.832108) (xy 1.99746 -388.832108) (xy 1.938038 -388.824285) (xy 1.880145 -388.808772)
			(xy 1.824772 -388.785836) (xy 1.772866 -388.755869) (xy 1.725316 -388.719382) (xy 1.682936 -388.677002)
			(xy 1.646449 -388.629452) (xy 1.616482 -388.577546) (xy 1.593546 -388.522173) (xy 1.578033 -388.46428)
			(xy 1.57021 -388.404858) (xy 1.56972 -388.37489) (xy 0.508 -388.37489) (xy 0.508 -398.164722) (xy 3.141726 -398.164722)
			(xy 3.141726 -398.035362) (xy 3.149849 -397.906256) (xy 3.166062 -397.777916) (xy 3.190302 -397.650846)
			(xy 3.222472 -397.52555) (xy 3.262447 -397.40252) (xy 3.310068 -397.282244) (xy 3.365147 -397.165195)
			(xy 3.427467 -397.051835) (xy 3.496782 -396.942612) (xy 3.572818 -396.837957) (xy 3.655276 -396.738283)
			(xy 3.743829 -396.643983) (xy 3.838129 -396.55543) (xy 3.937803 -396.472972) (xy 4.042458 -396.396936)
			(xy 4.151681 -396.327621) (xy 4.265041 -396.265301) (xy 4.38209 -396.210222) (xy 4.502366 -396.162601)
			(xy 4.625396 -396.122626) (xy 4.750692 -396.090456) (xy 4.877762 -396.066216) (xy 5.006102 -396.050003)
			(xy 5.135208 -396.04188) (xy 5.199888 -396.041372) (xy 6.800088 -396.041372) (xy 6.864769 -396.041866)
			(xy 6.993875 -396.049988) (xy 7.122217 -396.066201) (xy 7.249287 -396.090441) (xy 7.374584 -396.122612)
			(xy 7.497614 -396.162587) (xy 7.617892 -396.210208) (xy 7.734942 -396.265287) (xy 7.848302 -396.327608)
			(xy 7.957526 -396.396923) (xy 8.062181 -396.47296) (xy 8.161856 -396.555418) (xy 8.256157 -396.643972)
			(xy 8.344711 -396.738272) (xy 8.427169 -396.837947) (xy 8.503206 -396.942603) (xy 8.572521 -397.051826)
			(xy 8.634842 -397.165187) (xy 8.689921 -397.282236) (xy 8.737543 -397.402514) (xy 8.777518 -397.525544)
			(xy 8.809688 -397.650841) (xy 8.833928 -397.777911) (xy 8.839736 -397.823885) (xy 27.348879 -397.823885)
			(xy 27.348883 -397.756458) (xy 27.356962 -397.689518) (xy 27.373001 -397.624027) (xy 27.396769 -397.560929)
			(xy 27.427923 -397.501131) (xy 27.466014 -397.445496) (xy 27.48788 -397.41983) (xy 27.493686 -397.412692)
			(xy 27.500196 -397.395496) (xy 27.50058 -397.386302) (xy 27.50058 -396.89405) (xy 27.50015 -396.884865)
			(xy 27.49365 -396.86768) (xy 27.48788 -396.860522) (xy 27.466007 -396.834865) (xy 27.42792 -396.779228)
			(xy 27.396771 -396.719431) (xy 27.373008 -396.656333) (xy 27.356974 -396.590843) (xy 27.348899 -396.523905)
			(xy 27.3489 -396.45648) (xy 27.356976 -396.389542) (xy 27.373012 -396.324053) (xy 27.396777 -396.260955)
			(xy 27.427928 -396.201159) (xy 27.466016 -396.145524) (xy 27.48788 -396.119858) (xy 27.493675 -396.112711)
			(xy 27.500191 -396.095522) (xy 27.50058 -396.08633) (xy 27.50058 -395.92885) (xy 27.501069 -395.918722)
			(xy 27.508787 -395.899994) (xy 27.523074 -395.885635) (xy 27.541762 -395.877821) (xy 27.551888 -395.877288)
			(xy 28.268168 -395.877288) (xy 28.278319 -395.877747) (xy 28.297068 -395.88553) (xy 28.311392 -395.899915)
			(xy 28.319095 -395.918698) (xy 28.319476 -395.92885) (xy 28.319476 -396.08633) (xy 28.319877 -396.095518)
			(xy 28.326398 -396.112702) (xy 28.332176 -396.119858) (xy 28.354031 -396.145531) (xy 28.392122 -396.201164)
			(xy 28.423274 -396.260959) (xy 28.44704 -396.324055) (xy 28.463077 -396.389543) (xy 28.471154 -396.456481)
			(xy 28.471155 -396.523904) (xy 28.463079 -396.590842) (xy 28.447044 -396.656331) (xy 28.42328 -396.719428)
			(xy 28.392129 -396.779223) (xy 28.35404 -396.834857) (xy 28.332176 -396.860522) (xy 28.326385 -396.867671)
			(xy 28.319868 -396.884859) (xy 28.319476 -396.89405) (xy 28.319476 -397.386302) (xy 28.31989 -397.395489)
			(xy 28.326402 -397.412673) (xy 28.332176 -397.41983) (xy 28.354003 -397.445526) (xy 28.392095 -397.501155)
			(xy 28.420857 -397.556356) (xy 29.549071 -397.556356) (xy 29.557114 -397.489534) (xy 29.573085 -397.424153)
			(xy 29.596756 -397.361149) (xy 29.627787 -397.301425) (xy 29.665733 -397.245838) (xy 29.68752 -397.220186)
			(xy 29.693307 -397.213034) (xy 29.699827 -397.195849) (xy 29.70022 -397.186658) (xy 29.70022 -397.028924)
			(xy 29.700641 -397.018769) (xy 29.708433 -397.000013) (xy 29.72283 -396.985688) (xy 29.741625 -396.977991)
			(xy 29.751782 -396.977616) (xy 30.468062 -396.977616) (xy 30.478183 -396.978157) (xy 30.496899 -396.985868)
			(xy 30.511256 -397.000138) (xy 30.51908 -397.018806) (xy 30.519624 -397.028924) (xy 30.519624 -397.186658)
			(xy 30.520049 -397.195844) (xy 30.526552 -397.213029) (xy 30.532324 -397.220186) (xy 30.554123 -397.24583)
			(xy 30.592074 -397.301416) (xy 30.623108 -397.361141) (xy 30.646782 -397.424147) (xy 30.662756 -397.48953)
			(xy 30.6708 -397.556354) (xy 30.670799 -397.623661) (xy 30.662753 -397.690485) (xy 30.646778 -397.755868)
			(xy 30.623102 -397.818873) (xy 30.620528 -397.823826) (xy 31.749174 -397.823826) (xy 31.749178 -397.756517)
			(xy 31.757226 -397.689691) (xy 31.773204 -397.624307) (xy 31.796882 -397.5613) (xy 31.827922 -397.501576)
			(xy 31.865877 -397.44599) (xy 31.887668 -397.420338) (xy 31.893482 -397.413205) (xy 31.899984 -397.396005)
			(xy 31.900368 -397.38681) (xy 31.900368 -396.893542) (xy 31.899923 -396.884359) (xy 31.893432 -396.867175)
			(xy 31.887668 -396.860014) (xy 31.86587 -396.83437) (xy 31.827919 -396.778783) (xy 31.796885 -396.719059)
			(xy 31.773211 -396.656053) (xy 31.757238 -396.59067) (xy 31.749194 -396.523846) (xy 31.749195 -396.456539)
			(xy 31.757241 -396.389716) (xy 31.773216 -396.324332) (xy 31.796891 -396.261327) (xy 31.827927 -396.201604)
			(xy 31.865879 -396.146018) (xy 31.887668 -396.120366) (xy 31.89347 -396.113225) (xy 31.899979 -396.096031)
			(xy 31.900368 -396.086838) (xy 31.900368 -395.92885) (xy 31.900805 -395.918678) (xy 31.90858 -395.899879)
			(xy 31.922962 -395.885491) (xy 31.941758 -395.877709) (xy 31.95193 -395.877288) (xy 32.66821 -395.877288)
			(xy 32.678388 -395.877657) (xy 32.697193 -395.885455) (xy 32.711579 -395.899858) (xy 32.719355 -395.918671)
			(xy 32.719772 -395.92885) (xy 32.719772 -396.086838) (xy 32.72017 -396.096026) (xy 32.726693 -396.11321)
			(xy 32.732472 -396.120366) (xy 32.75425 -396.146026) (xy 32.792198 -396.201612) (xy 32.823231 -396.261334)
			(xy 32.846904 -396.324338) (xy 32.862877 -396.389719) (xy 32.870922 -396.45654) (xy 32.870923 -396.523845)
			(xy 32.86288 -396.590666) (xy 32.846909 -396.656048) (xy 32.823237 -396.719052) (xy 32.792206 -396.778775)
			(xy 32.754259 -396.834362) (xy 32.732472 -396.860014) (xy 32.726683 -396.867165) (xy 32.720165 -396.884351)
			(xy 32.719772 -396.893542) (xy 32.719772 -397.38681) (xy 32.720183 -397.395997) (xy 32.726697 -397.413181)
			(xy 32.732472 -397.420338) (xy 32.754222 -397.446021) (xy 32.792171 -397.501603) (xy 32.820593 -397.556296)
			(xy 33.948839 -397.556296) (xy 33.956914 -397.489358) (xy 33.972949 -397.423869) (xy 33.996713 -397.360773)
			(xy 34.027863 -397.300977) (xy 34.065952 -397.245343) (xy 34.087816 -397.219678) (xy 34.093606 -397.212528)
			(xy 34.100124 -397.195341) (xy 34.100516 -397.18615) (xy 34.100516 -397.028924) (xy 34.100936 -397.018801)
			(xy 34.108679 -397.000095) (xy 34.122995 -396.985779) (xy 34.141701 -396.978036) (xy 34.151824 -396.977616)
			(xy 34.868104 -396.977616) (xy 34.878229 -396.978013) (xy 34.896935 -396.985766) (xy 34.91125 -397.000088)
			(xy 34.918992 -397.018799) (xy 34.919412 -397.028924) (xy 34.919412 -397.18615) (xy 34.919843 -397.195335)
			(xy 34.926342 -397.21252) (xy 34.932112 -397.219678) (xy 34.953985 -397.245335) (xy 34.992073 -397.300971)
			(xy 35.023223 -397.360769) (xy 35.046986 -397.423867) (xy 35.06302 -397.489356) (xy 35.071095 -397.556295)
			(xy 35.071094 -397.62372) (xy 35.063017 -397.690658) (xy 35.046981 -397.756148) (xy 35.023216 -397.819245)
			(xy 35.020799 -397.823884) (xy 36.148967 -397.823884) (xy 36.148971 -397.756458) (xy 36.15705 -397.689518)
			(xy 36.173088 -397.624028) (xy 36.196855 -397.560929) (xy 36.228008 -397.501132) (xy 36.266099 -397.445496)
			(xy 36.287964 -397.41983) (xy 36.293781 -397.412699) (xy 36.300282 -397.395497) (xy 36.300664 -397.386302)
			(xy 36.300664 -396.89405) (xy 36.300216 -396.884867) (xy 36.293727 -396.867683) (xy 36.287964 -396.860522)
			(xy 36.266091 -396.834864) (xy 36.228005 -396.779228) (xy 36.196857 -396.71943) (xy 36.173095 -396.656332)
			(xy 36.157061 -396.590843) (xy 36.148987 -396.523904) (xy 36.148988 -396.456481) (xy 36.157064 -396.389542)
			(xy 36.1731 -396.324053) (xy 36.196863 -396.260956) (xy 36.228013 -396.201159) (xy 36.266101 -396.145524)
			(xy 36.287964 -396.119858) (xy 36.293769 -396.112719) (xy 36.300277 -396.095523) (xy 36.300664 -396.08633)
			(xy 36.300664 -395.92885) (xy 36.301168 -395.918724) (xy 36.308884 -395.899999) (xy 36.323166 -395.88564)
			(xy 36.341848 -395.877823) (xy 36.351972 -395.877288) (xy 37.068252 -395.877288) (xy 37.078402 -395.877761)
			(xy 37.097151 -395.885538) (xy 37.111475 -395.899919) (xy 37.119179 -395.918699) (xy 37.11956 -395.92885)
			(xy 37.11956 -396.08633) (xy 37.119965 -396.095518) (xy 37.126483 -396.112701) (xy 37.13226 -396.119858)
			(xy 37.154116 -396.145531) (xy 37.192207 -396.201163) (xy 37.223361 -396.260958) (xy 37.247127 -396.324054)
			(xy 37.263164 -396.389543) (xy 37.271242 -396.456481) (xy 37.271243 -396.523904) (xy 37.263167 -396.590843)
			(xy 37.247132 -396.656332) (xy 37.223367 -396.719428) (xy 37.192215 -396.779224) (xy 37.154125 -396.834857)
			(xy 37.13226 -396.860522) (xy 37.126467 -396.867669) (xy 37.119951 -396.884858) (xy 37.11956 -396.89405)
			(xy 37.11956 -397.386302) (xy 37.119978 -397.395488) (xy 37.126487 -397.412672) (xy 37.13226 -397.41983)
			(xy 37.154088 -397.445525) (xy 37.192181 -397.501155) (xy 37.220943 -397.556356) (xy 38.349159 -397.556356)
			(xy 38.357201 -397.489534) (xy 38.373172 -397.424153) (xy 38.396842 -397.361149) (xy 38.427873 -397.301426)
			(xy 38.465818 -397.245839) (xy 38.487604 -397.220186) (xy 38.493389 -397.213033) (xy 38.499911 -397.195848)
			(xy 38.500304 -397.186658) (xy 38.500304 -397.028924) (xy 38.500741 -397.018771) (xy 38.50853 -397.000018)
			(xy 38.522922 -396.985694) (xy 38.541711 -396.977994) (xy 38.551866 -396.977616) (xy 39.268146 -396.977616)
			(xy 39.278273 -396.978088) (xy 39.29699 -396.985827) (xy 39.311344 -397.000117) (xy 39.319166 -397.0188)
			(xy 39.319708 -397.028924) (xy 39.319708 -397.186658) (xy 39.320136 -397.195843) (xy 39.326637 -397.213028)
			(xy 39.332408 -397.220186) (xy 39.354207 -397.245829) (xy 39.392159 -397.301416) (xy 39.423195 -397.36114)
			(xy 39.446869 -397.424146) (xy 39.462843 -397.48953) (xy 39.470887 -397.556354) (xy 39.470887 -397.623661)
			(xy 39.462841 -397.690485) (xy 39.446865 -397.755869) (xy 39.423189 -397.818874) (xy 39.420585 -397.823885)
			(xy 40.548734 -397.823885) (xy 40.548737 -397.756458) (xy 40.556817 -397.689516) (xy 40.572859 -397.624024)
			(xy 40.596629 -397.560925) (xy 40.627787 -397.501128) (xy 40.665884 -397.445494) (xy 40.687752 -397.41983)
			(xy 40.693567 -397.412698) (xy 40.700069 -397.395497) (xy 40.700452 -397.386302) (xy 40.700452 -396.89405)
			(xy 40.700006 -396.884867) (xy 40.693516 -396.867683) (xy 40.687752 -396.860522) (xy 40.665876 -396.834866)
			(xy 40.627785 -396.779231) (xy 40.596631 -396.719434) (xy 40.572865 -396.656336) (xy 40.556829 -396.590845)
			(xy 40.548753 -396.523905) (xy 40.548754 -396.45648) (xy 40.556832 -396.38954) (xy 40.57287 -396.32405)
			(xy 40.596638 -396.260952) (xy 40.627792 -396.201156) (xy 40.665886 -396.145522) (xy 40.687752 -396.119858)
			(xy 40.693555 -396.112718) (xy 40.700065 -396.095523) (xy 40.700452 -396.08633) (xy 40.700452 -395.92885)
			(xy 40.700968 -395.918725) (xy 40.708682 -395.900003) (xy 40.722959 -395.885644) (xy 40.741638 -395.877825)
			(xy 40.75176 -395.877288) (xy 41.46804 -395.877288) (xy 41.478195 -395.877689) (xy 41.496946 -395.885495)
			(xy 41.511268 -395.899898) (xy 41.518968 -395.918693) (xy 41.519348 -395.92885) (xy 41.519348 -396.08633)
			(xy 41.519755 -396.095517) (xy 41.526272 -396.112701) (xy 41.532048 -396.119858) (xy 41.553904 -396.14553)
			(xy 41.591996 -396.201163) (xy 41.62315 -396.260957) (xy 41.646917 -396.324053) (xy 41.662955 -396.389542)
			(xy 41.671033 -396.456481) (xy 41.671034 -396.523904) (xy 41.662958 -396.590843) (xy 41.646922 -396.656332)
			(xy 41.623157 -396.719429) (xy 41.592004 -396.779224) (xy 41.553913 -396.834858) (xy 41.532048 -396.860522)
			(xy 41.526253 -396.867668) (xy 41.519739 -396.884858) (xy 41.519348 -396.89405) (xy 41.519348 -397.386302)
			(xy 41.519769 -397.395488) (xy 41.526276 -397.412672) (xy 41.532048 -397.41983) (xy 41.553876 -397.445525)
			(xy 41.59197 -397.501154) (xy 41.620702 -397.556296) (xy 42.748927 -397.556296) (xy 42.757002 -397.489358)
			(xy 42.773037 -397.42387) (xy 42.7968 -397.360774) (xy 42.827949 -397.300978) (xy 42.866037 -397.245343)
			(xy 42.8879 -397.219678) (xy 42.893688 -397.212527) (xy 42.900208 -397.195341) (xy 42.9006 -397.18615)
			(xy 42.9006 -397.028924) (xy 42.901035 -397.018803) (xy 42.908776 -397.0001) (xy 42.923086 -396.985785)
			(xy 42.941787 -396.978039) (xy 42.951908 -396.977616) (xy 43.668188 -396.977616) (xy 43.678312 -396.978026)
			(xy 43.697018 -396.985773) (xy 43.711333 -397.000092) (xy 43.719076 -397.0188) (xy 43.719496 -397.028924)
			(xy 43.719496 -397.18615) (xy 43.719931 -397.195335) (xy 43.726427 -397.212519) (xy 43.732196 -397.219678)
			(xy 43.75407 -397.245335) (xy 43.792159 -397.300971) (xy 43.823309 -397.360768) (xy 43.847073 -397.423866)
			(xy 43.863108 -397.489356) (xy 43.871183 -397.556295) (xy 43.871182 -397.62372) (xy 43.863105 -397.690659)
			(xy 43.847068 -397.756148) (xy 43.823303 -397.819246) (xy 43.820917 -397.823825) (xy 44.949053 -397.823825)
			(xy 44.949057 -397.756517) (xy 44.957105 -397.689692) (xy 44.973082 -397.624308) (xy 44.996759 -397.561302)
			(xy 45.027796 -397.501577) (xy 45.06575 -397.44599) (xy 45.08754 -397.420338) (xy 45.09335 -397.413203)
			(xy 45.099856 -397.396004) (xy 45.10024 -397.38681) (xy 45.10024 -396.893542) (xy 45.0998 -396.884358)
			(xy 45.093306 -396.867174) (xy 45.08754 -396.860014) (xy 45.065742 -396.83437) (xy 45.027794 -396.778782)
			(xy 44.996761 -396.719058) (xy 44.973088 -396.656052) (xy 44.957116 -396.590669) (xy 44.949073 -396.523845)
			(xy 44.949074 -396.45654) (xy 44.957119 -396.389716) (xy 44.973093 -396.324333) (xy 44.996767 -396.261328)
			(xy 45.027801 -396.201605) (xy 45.065751 -396.146018) (xy 45.08754 -396.120366) (xy 45.093339 -396.113222)
			(xy 45.099851 -396.096031) (xy 45.10024 -396.086838) (xy 45.10024 -395.92885) (xy 45.100705 -395.918681)
			(xy 45.108474 -395.899887) (xy 45.122847 -395.885501) (xy 45.141634 -395.877714) (xy 45.151802 -395.877288)
			(xy 45.868082 -395.877288) (xy 45.878259 -395.87768) (xy 45.897063 -395.885468) (xy 45.91145 -395.899864)
			(xy 45.919227 -395.918673) (xy 45.919644 -395.92885) (xy 45.919644 -396.086838) (xy 45.920049 -396.096026)
			(xy 45.926568 -396.113209) (xy 45.932344 -396.120366) (xy 45.954122 -396.146026) (xy 45.992072 -396.201611)
			(xy 46.023107 -396.261333) (xy 46.046781 -396.324337) (xy 46.062755 -396.389718) (xy 46.070801 -396.45654)
			(xy 46.070801 -396.523845) (xy 46.062758 -396.590667) (xy 46.046786 -396.656049) (xy 46.023113 -396.719053)
			(xy 45.99208 -396.778776) (xy 45.954131 -396.834362) (xy 45.932344 -396.860014) (xy 45.926552 -396.867162)
			(xy 45.920036 -396.884351) (xy 45.919644 -396.893542) (xy 45.919644 -397.38681) (xy 45.920062 -397.395996)
			(xy 45.926572 -397.41318) (xy 45.932344 -397.420338) (xy 45.954095 -397.446021) (xy 45.992046 -397.501602)
			(xy 46.020501 -397.556355) (xy 47.149223 -397.556355) (xy 47.157267 -397.489532) (xy 47.17324 -397.42415)
			(xy 47.196914 -397.361146) (xy 47.227949 -397.301423) (xy 47.265899 -397.245837) (xy 47.287688 -397.220186)
			(xy 47.293472 -397.213032) (xy 47.299994 -397.195848) (xy 47.300388 -397.186658) (xy 47.300388 -397.028924)
			(xy 47.300841 -397.018773) (xy 47.308626 -397.000023) (xy 47.323013 -396.985699) (xy 47.341797 -396.977997)
			(xy 47.35195 -396.977616) (xy 48.06823 -396.977616) (xy 48.078356 -396.978101) (xy 48.097073 -396.985834)
			(xy 48.111427 -397.000121) (xy 48.11925 -397.018801) (xy 48.119792 -397.028924) (xy 48.119792 -397.186658)
			(xy 48.120224 -397.195843) (xy 48.126723 -397.213027) (xy 48.132492 -397.220186) (xy 48.154289 -397.24583)
			(xy 48.192235 -397.301419) (xy 48.223266 -397.361144) (xy 48.246937 -397.424149) (xy 48.262908 -397.489532)
			(xy 48.270951 -397.556355) (xy 48.27095 -397.62366) (xy 48.262906 -397.690483) (xy 48.246933 -397.755865)
			(xy 48.22326 -397.81887) (xy 48.192227 -397.878594) (xy 48.154279 -397.934181) (xy 48.132492 -397.959834)
			(xy 48.126698 -397.966981) (xy 48.120182 -397.98417) (xy 48.119792 -397.993362) (xy 48.119792 -398.486884)
			(xy 48.120212 -398.49607) (xy 48.126719 -398.513254) (xy 48.132492 -398.520412) (xy 48.154314 -398.546035)
			(xy 48.19226 -398.601627) (xy 48.22329 -398.661355) (xy 48.246959 -398.724363) (xy 48.262929 -398.789748)
			(xy 48.27097 -398.856573) (xy 48.270966 -398.923881) (xy 48.262919 -398.990705) (xy 48.246943 -399.056089)
			(xy 48.223268 -399.119095) (xy 48.192232 -399.17882) (xy 48.154281 -399.234407) (xy 48.132492 -399.26006)
			(xy 48.126687 -399.267199) (xy 48.120177 -399.284394) (xy 48.119792 -399.293588) (xy 48.119792 -399.451576)
			(xy 48.119359 -399.46173) (xy 48.11157 -399.480483) (xy 48.097176 -399.494808) (xy 48.078386 -399.502507)
			(xy 48.06823 -399.502884) (xy 47.35195 -399.502884) (xy 47.341829 -399.502333) (xy 47.323114 -399.494626)
			(xy 47.308757 -399.48036) (xy 47.300932 -399.461693) (xy 47.300388 -399.451576) (xy 47.300388 -399.293588)
			(xy 47.299986 -399.2844) (xy 47.293467 -399.267216) (xy 47.287688 -399.26006) (xy 47.265934 -399.234379)
			(xy 47.227981 -399.178798) (xy 47.196944 -399.119079) (xy 47.173267 -399.056078) (xy 47.15729 -398.990699)
			(xy 47.149242 -398.923879) (xy 47.149239 -398.856576) (xy 47.15728 -398.789754) (xy 47.173251 -398.724374)
			(xy 47.196921 -398.661371) (xy 47.227953 -398.601648) (xy 47.265901 -398.546063) (xy 47.287688 -398.520412)
			(xy 47.293503 -398.51328) (xy 47.300007 -398.496079) (xy 47.300388 -398.486884) (xy 47.300388 -397.993362)
			(xy 47.299999 -397.984172) (xy 47.293471 -397.966988) (xy 47.287688 -397.959834) (xy 47.265909 -397.934174)
			(xy 47.227956 -397.87859) (xy 47.19692 -397.818868) (xy 47.173244 -397.755864) (xy 47.157269 -397.690483)
			(xy 47.149224 -397.62366) (xy 47.149223 -397.556355) (xy 46.020501 -397.556355) (xy 46.023082 -397.561322)
			(xy 46.046757 -397.624322) (xy 46.062733 -397.689701) (xy 46.070781 -397.75652) (xy 46.070784 -397.823823)
			(xy 46.062744 -397.890643) (xy 46.046774 -397.956023) (xy 46.023105 -398.019026) (xy 45.992075 -398.078748)
			(xy 45.95413 -398.134334) (xy 45.932344 -398.159986) (xy 45.926522 -398.167113) (xy 45.920024 -398.184318)
			(xy 45.919644 -398.193514) (xy 45.919644 -398.351502) (xy 45.919237 -398.361676) (xy 45.911448 -398.380474)
			(xy 45.897057 -398.39486) (xy 45.878256 -398.402641) (xy 45.868082 -398.403064) (xy 45.151802 -398.403064)
			(xy 45.141645 -398.402565) (xy 45.122876 -398.394792) (xy 45.108511 -398.380427) (xy 45.100736 -398.361659)
			(xy 45.10024 -398.351502) (xy 45.10024 -398.193514) (xy 45.099814 -398.184329) (xy 45.093311 -398.167145)
			(xy 45.08754 -398.159986) (xy 45.065715 -398.134365) (xy 45.027767 -398.078774) (xy 44.996735 -398.019046)
			(xy 44.973065 -397.956037) (xy 44.957094 -397.890651) (xy 44.949053 -397.823825) (xy 43.820917 -397.823825)
			(xy 43.792151 -397.879042) (xy 43.754061 -397.934677) (xy 43.732196 -397.960342) (xy 43.726399 -397.967487)
			(xy 43.719885 -397.984678) (xy 43.719496 -397.99387) (xy 43.719496 -398.486376) (xy 43.719919 -398.495562)
			(xy 43.726424 -398.512746) (xy 43.732196 -398.519904) (xy 43.754095 -398.54554) (xy 43.792183 -398.601179)
			(xy 43.823333 -398.660979) (xy 43.847095 -398.72408) (xy 43.863128 -398.789572) (xy 43.871201 -398.856514)
			(xy 43.871198 -398.92394) (xy 43.863118 -398.990881) (xy 43.847079 -399.056372) (xy 43.823311 -399.119471)
			(xy 43.792156 -399.179268) (xy 43.754062 -399.234903) (xy 43.732196 -399.260568) (xy 43.726388 -399.267705)
			(xy 43.71988 -399.284902) (xy 43.719496 -399.294096) (xy 43.719496 -399.451576) (xy 43.719064 -399.461697)
			(xy 43.711323 -399.480401) (xy 43.697011 -399.494717) (xy 43.678309 -399.502462) (xy 43.668188 -399.502884)
			(xy 42.951908 -399.502884) (xy 42.941784 -399.502477) (xy 42.923078 -399.494729) (xy 42.908762 -399.480409)
			(xy 42.90102 -399.4617) (xy 42.9006 -399.451576) (xy 42.9006 -399.294096) (xy 42.900192 -399.284909)
			(xy 42.893677 -399.267724) (xy 42.8879 -399.260568) (xy 42.866071 -399.234874) (xy 42.827982 -399.179243)
			(xy 42.796829 -399.119451) (xy 42.773063 -399.056358) (xy 42.757025 -398.990872) (xy 42.748946 -398.923937)
			(xy 42.748943 -398.856517) (xy 42.757015 -398.789581) (xy 42.773047 -398.724094) (xy 42.796807 -398.660998)
			(xy 42.827954 -398.601203) (xy 42.866038 -398.545569) (xy 42.8879 -398.519904) (xy 42.893677 -398.512745)
			(xy 42.900204 -398.495565) (xy 42.9006 -398.486376) (xy 42.9006 -397.99387) (xy 42.900204 -397.984681)
			(xy 42.893681 -397.967497) (xy 42.8879 -397.960342) (xy 42.866046 -397.934669) (xy 42.827957 -397.879035)
			(xy 42.796806 -397.81924) (xy 42.773041 -397.756144) (xy 42.757005 -397.690656) (xy 42.748928 -397.623719)
			(xy 42.748927 -397.556296) (xy 41.620702 -397.556296) (xy 41.623125 -397.560946) (xy 41.646894 -397.624039)
			(xy 41.662933 -397.689525) (xy 41.671013 -397.756461) (xy 41.671016 -397.823882) (xy 41.662944 -397.890819)
			(xy 41.646911 -397.956307) (xy 41.623148 -398.019402) (xy 41.591999 -398.079197) (xy 41.553912 -398.13483)
			(xy 41.532048 -398.160494) (xy 41.526265 -398.167649) (xy 41.519744 -398.184832) (xy 41.519348 -398.194022)
			(xy 41.519348 -398.351502) (xy 41.518875 -398.36163) (xy 41.511144 -398.380354) (xy 41.496853 -398.39471)
			(xy 41.478166 -398.402527) (xy 41.46804 -398.403064) (xy 40.75176 -398.403064) (xy 40.741599 -398.40271)
			(xy 40.722839 -398.394895) (xy 40.708515 -398.380477) (xy 40.700824 -398.361666) (xy 40.700452 -398.351502)
			(xy 40.700452 -398.194022) (xy 40.70002 -398.184837) (xy 40.69352 -398.167653) (xy 40.687752 -398.160494)
			(xy 40.665849 -398.13486) (xy 40.627758 -398.079223) (xy 40.596606 -398.019423) (xy 40.572842 -397.956321)
			(xy 40.556807 -397.890828) (xy 40.548734 -397.823885) (xy 39.420585 -397.823885) (xy 39.392151 -397.878597)
			(xy 39.354198 -397.934183) (xy 39.332408 -397.959834) (xy 39.326615 -397.966982) (xy 39.320098 -397.98417)
			(xy 39.319708 -397.993362) (xy 39.319708 -398.486884) (xy 39.320124 -398.496071) (xy 39.326633 -398.513255)
			(xy 39.332408 -398.520412) (xy 39.354233 -398.546034) (xy 39.392184 -398.601624) (xy 39.423219 -398.661351)
			(xy 39.446892 -398.72436) (xy 39.462864 -398.789746) (xy 39.470906 -398.856573) (xy 39.470902 -398.923882)
			(xy 39.462854 -398.990707) (xy 39.446876 -399.056092) (xy 39.423196 -399.119098) (xy 39.392156 -399.178823)
			(xy 39.354199 -399.234409) (xy 39.332408 -399.26006) (xy 39.326604 -399.2672) (xy 39.320094 -399.284395)
			(xy 39.319708 -399.293588) (xy 39.319708 -399.451576) (xy 39.319259 -399.461728) (xy 39.311473 -399.480478)
			(xy 39.297085 -399.494802) (xy 39.278299 -399.502504) (xy 39.268146 -399.502884) (xy 38.551866 -399.502884)
			(xy 38.54174 -399.502402) (xy 38.523023 -399.494668) (xy 38.508668 -399.48038) (xy 38.500846 -399.4617)
			(xy 38.500304 -399.451576) (xy 38.500304 -399.293588) (xy 38.499899 -399.2844) (xy 38.493381 -399.267216)
			(xy 38.487604 -399.26006) (xy 38.465853 -399.234378) (xy 38.427905 -399.178795) (xy 38.396872 -399.119075)
			(xy 38.373199 -399.056075) (xy 38.357224 -398.990697) (xy 38.349178 -398.923878) (xy 38.349175 -398.856576)
			(xy 38.357215 -398.789757) (xy 38.373183 -398.724377) (xy 38.39685 -398.661374) (xy 38.427877 -398.601651)
			(xy 38.465819 -398.546065) (xy 38.487604 -398.520412) (xy 38.493421 -398.513281) (xy 38.499923 -398.49608)
			(xy 38.500304 -398.486884) (xy 38.500304 -397.993362) (xy 38.499911 -397.984173) (xy 38.493385 -397.966989)
			(xy 38.487604 -397.959834) (xy 38.465827 -397.934173) (xy 38.42788 -397.878587) (xy 38.396849 -397.818865)
			(xy 38.373177 -397.755861) (xy 38.357204 -397.69048) (xy 38.34916 -397.623659) (xy 38.349159 -397.556356)
			(xy 37.220943 -397.556356) (xy 37.223335 -397.560946) (xy 37.247103 -397.624039) (xy 37.263142 -397.689525)
			(xy 37.271222 -397.756461) (xy 37.271225 -397.823882) (xy 37.263153 -397.890819) (xy 37.24712 -397.956306)
			(xy 37.223358 -398.019402) (xy 37.19221 -398.079196) (xy 37.154123 -398.134829) (xy 37.13226 -398.160494)
			(xy 37.126478 -398.16765) (xy 37.119956 -398.184832) (xy 37.11956 -398.194022) (xy 37.11956 -398.351502)
			(xy 37.119075 -398.361629) (xy 37.111347 -398.38035) (xy 37.09706 -398.394706) (xy 37.078376 -398.402525)
			(xy 37.068252 -398.403064) (xy 36.351972 -398.403064) (xy 36.341812 -398.402701) (xy 36.323052 -398.394889)
			(xy 36.308728 -398.380474) (xy 36.301036 -398.361665) (xy 36.300664 -398.351502) (xy 36.300664 -398.194022)
			(xy 36.300229 -398.184838) (xy 36.293731 -398.167654) (xy 36.287964 -398.160494) (xy 36.266064 -398.134859)
			(xy 36.227979 -398.079219) (xy 36.196832 -398.019419) (xy 36.173071 -397.956318) (xy 36.15704 -397.890825)
			(xy 36.148967 -397.823884) (xy 35.020799 -397.823884) (xy 34.992065 -397.879042) (xy 34.953976 -397.934677)
			(xy 34.932112 -397.960342) (xy 34.926316 -397.967488) (xy 34.919801 -397.984678) (xy 34.919412 -397.99387)
			(xy 34.919412 -398.486376) (xy 34.919831 -398.495562) (xy 34.926338 -398.512747) (xy 34.932112 -398.519904)
			(xy 34.954011 -398.54554) (xy 34.992098 -398.601179) (xy 35.023246 -398.66098) (xy 35.047008 -398.72408)
			(xy 35.06304 -398.789573) (xy 35.071113 -398.856514) (xy 35.07111 -398.92394) (xy 35.063031 -398.990881)
			(xy 35.046992 -399.056372) (xy 35.023224 -399.11947) (xy 34.99207 -399.179267) (xy 34.953978 -399.234903)
			(xy 34.932112 -399.260568) (xy 34.926305 -399.267706) (xy 34.919796 -399.284902) (xy 34.919412 -399.294096)
			(xy 34.919412 -399.451576) (xy 34.918965 -399.461695) (xy 34.911227 -399.480396) (xy 34.89692 -399.494711)
			(xy 34.878223 -399.502459) (xy 34.868104 -399.502884) (xy 34.151824 -399.502884) (xy 34.141701 -399.502464)
			(xy 34.122995 -399.494721) (xy 34.108679 -399.480405) (xy 34.100936 -399.461699) (xy 34.100516 -399.451576)
			(xy 34.100516 -399.294096) (xy 34.100104 -399.284909) (xy 34.093591 -399.267725) (xy 34.087816 -399.260568)
			(xy 34.065987 -399.234874) (xy 34.027896 -399.179244) (xy 33.996743 -399.119452) (xy 33.972976 -399.056359)
			(xy 33.956937 -398.990873) (xy 33.948858 -398.923938) (xy 33.948855 -398.856516) (xy 33.956928 -398.78958)
			(xy 33.97296 -398.724093) (xy 33.996721 -398.660998) (xy 34.027868 -398.601203) (xy 34.065954 -398.545569)
			(xy 34.087816 -398.519904) (xy 34.093595 -398.512747) (xy 34.10012 -398.495565) (xy 34.100516 -398.486376)
			(xy 34.100516 -397.99387) (xy 34.100117 -397.984682) (xy 34.093595 -397.967498) (xy 34.087816 -397.960342)
			(xy 34.065961 -397.934669) (xy 34.027871 -397.879036) (xy 33.996719 -397.819241) (xy 33.972954 -397.756145)
			(xy 33.956917 -397.690657) (xy 33.94884 -397.623719) (xy 33.948839 -397.556296) (xy 32.820593 -397.556296)
			(xy 32.823205 -397.561323) (xy 32.84688 -397.624323) (xy 32.862855 -397.689702) (xy 32.870902 -397.756521)
			(xy 32.870905 -397.823822) (xy 32.862865 -397.890642) (xy 32.846897 -397.956022) (xy 32.823229 -398.019025)
			(xy 32.7922 -398.078747) (xy 32.754257 -398.134334) (xy 32.732472 -398.159986) (xy 32.726653 -398.167115)
			(xy 32.720152 -398.184318) (xy 32.719772 -398.193514) (xy 32.719772 -398.351502) (xy 32.719268 -398.361659)
			(xy 32.711495 -398.380426) (xy 32.697133 -398.394791) (xy 32.678367 -398.402567) (xy 32.66821 -398.403064)
			(xy 31.95193 -398.403064) (xy 31.941761 -398.402611) (xy 31.922967 -398.394837) (xy 31.908581 -398.38046)
			(xy 31.900795 -398.361671) (xy 31.900368 -398.351502) (xy 31.900368 -398.193514) (xy 31.899936 -398.184329)
			(xy 31.893436 -398.167146) (xy 31.887668 -398.159986) (xy 31.865842 -398.134365) (xy 31.827892 -398.078775)
			(xy 31.796859 -398.019047) (xy 31.773187 -397.956039) (xy 31.757216 -397.890652) (xy 31.749174 -397.823826)
			(xy 30.620528 -397.823826) (xy 30.592066 -397.878596) (xy 30.554113 -397.934182) (xy 30.532324 -397.959834)
			(xy 30.526533 -397.966984) (xy 30.520014 -397.984171) (xy 30.519624 -397.993362) (xy 30.519624 -398.486884)
			(xy 30.520036 -398.496071) (xy 30.526548 -398.513256) (xy 30.532324 -398.520412) (xy 30.554149 -398.546034)
			(xy 30.592099 -398.601624) (xy 30.623132 -398.661352) (xy 30.646805 -398.72436) (xy 30.662776 -398.789746)
			(xy 30.670818 -398.856573) (xy 30.670815 -398.923881) (xy 30.662767 -398.990707) (xy 30.646789 -399.056092)
			(xy 30.62311 -399.119098) (xy 30.592071 -399.178822) (xy 30.554115 -399.234409) (xy 30.532324 -399.26006)
			(xy 30.526522 -399.267202) (xy 30.52001 -399.284395) (xy 30.519624 -399.293588) (xy 30.519624 -399.451576)
			(xy 30.519159 -399.461726) (xy 30.511376 -399.480473) (xy 30.496993 -399.494796) (xy 30.478213 -399.502501)
			(xy 30.468062 -399.502884) (xy 29.751782 -399.502884) (xy 29.741657 -399.502389) (xy 29.72294 -399.49466)
			(xy 29.708585 -399.480377) (xy 29.700762 -399.461698) (xy 29.70022 -399.451576) (xy 29.70022 -399.293588)
			(xy 29.699811 -399.284401) (xy 29.693296 -399.267217) (xy 29.68752 -399.26006) (xy 29.665769 -399.234378)
			(xy 29.62782 -399.178796) (xy 29.596786 -399.119076) (xy 29.573112 -399.056075) (xy 29.557137 -398.990697)
			(xy 29.549091 -398.923878) (xy 29.549087 -398.856576) (xy 29.557128 -398.789756) (xy 29.573096 -398.724376)
			(xy 29.596764 -398.661374) (xy 29.627792 -398.601651) (xy 29.665735 -398.546065) (xy 29.68752 -398.520412)
			(xy 29.693339 -398.513283) (xy 29.69984 -398.49608) (xy 29.70022 -398.486884) (xy 29.70022 -397.993362)
			(xy 29.699824 -397.984173) (xy 29.6933 -397.966989) (xy 29.68752 -397.959834) (xy 29.665743 -397.934174)
			(xy 29.627795 -397.878588) (xy 29.596762 -397.818865) (xy 29.57309 -397.755862) (xy 29.557116 -397.690481)
			(xy 29.549072 -397.623659) (xy 29.549071 -397.556356) (xy 28.420857 -397.556356) (xy 28.423249 -397.560947)
			(xy 28.447016 -397.62404) (xy 28.463055 -397.689526) (xy 28.471134 -397.756461) (xy 28.471138 -397.823882)
			(xy 28.463065 -397.890818) (xy 28.447033 -397.956305) (xy 28.423272 -398.019401) (xy 28.392124 -398.079196)
			(xy 28.354039 -398.134829) (xy 28.332176 -398.160494) (xy 28.326397 -398.167651) (xy 28.319873 -398.184833)
			(xy 28.319476 -398.194022) (xy 28.319476 -398.351502) (xy 28.318975 -398.361627) (xy 28.31125 -398.380345)
			(xy 28.296968 -398.394701) (xy 28.27829 -398.402523) (xy 28.268168 -398.403064) (xy 27.551888 -398.403064)
			(xy 27.541729 -398.402688) (xy 27.522969 -398.394881) (xy 27.508645 -398.38047) (xy 27.500952 -398.361664)
			(xy 27.50058 -398.351502) (xy 27.50058 -398.194022) (xy 27.500164 -398.184835) (xy 27.493655 -398.167651)
			(xy 27.48788 -398.160494) (xy 27.465979 -398.134859) (xy 27.427893 -398.07922) (xy 27.396745 -398.019419)
			(xy 27.372984 -397.956318) (xy 27.356952 -397.890826) (xy 27.348879 -397.823885) (xy 8.839736 -397.823885)
			(xy 8.850142 -397.906253) (xy 8.858264 -398.035359) (xy 8.858264 -398.164721) (xy 8.850142 -398.293827)
			(xy 8.833928 -398.422169) (xy 8.809688 -398.549239) (xy 8.777518 -398.674536) (xy 8.737543 -398.797566)
			(xy 8.689921 -398.917844) (xy 8.634842 -399.034893) (xy 8.572521 -399.148254) (xy 8.503206 -399.257477)
			(xy 8.427169 -399.362133) (xy 8.344711 -399.461808) (xy 8.256157 -399.556108) (xy 8.161856 -399.644662)
			(xy 8.062181 -399.72712) (xy 7.957526 -399.803157) (xy 7.848302 -399.872472) (xy 7.734942 -399.934793)
			(xy 7.617892 -399.989872) (xy 7.497614 -400.037493) (xy 7.374584 -400.077468) (xy 7.249287 -400.109639)
			(xy 7.122217 -400.133879) (xy 6.993875 -400.150092) (xy 6.864769 -400.158214) (xy 6.800088 -400.158712)
			(xy 5.199888 -400.158712) (xy 5.135208 -400.158204) (xy 5.006102 -400.150081) (xy 4.877762 -400.133868)
			(xy 4.750692 -400.109628) (xy 4.625396 -400.077458) (xy 4.502366 -400.037483) (xy 4.38209 -399.989862)
			(xy 4.265041 -399.934783) (xy 4.151681 -399.872463) (xy 4.042458 -399.803148) (xy 3.937803 -399.727112)
			(xy 3.838129 -399.644654) (xy 3.743829 -399.556101) (xy 3.655276 -399.461801) (xy 3.572818 -399.362127)
			(xy 3.496782 -399.257472) (xy 3.427467 -399.148249) (xy 3.365147 -399.034889) (xy 3.310068 -398.91784)
			(xy 3.262447 -398.797564) (xy 3.222472 -398.674534) (xy 3.190302 -398.549238) (xy 3.166062 -398.422168)
			(xy 3.149849 -398.293828) (xy 3.141726 -398.164722) (xy 0.508 -398.164722) (xy 0.508 -401.723796)
			(xy 27.348891 -401.723796) (xy 27.348893 -401.656371) (xy 27.35697 -401.589432) (xy 27.373007 -401.523942)
			(xy 27.396773 -401.460844) (xy 27.427925 -401.401047) (xy 27.466015 -401.345412) (xy 27.48788 -401.319746)
			(xy 27.49368 -401.312603) (xy 27.500193 -401.295411) (xy 27.50058 -401.286218) (xy 27.50058 -400.793966)
			(xy 27.500191 -400.784777) (xy 27.493663 -400.767592) (xy 27.48788 -400.760438) (xy 27.466023 -400.734768)
			(xy 27.427935 -400.679133) (xy 27.396785 -400.619338) (xy 27.373022 -400.556241) (xy 27.356986 -400.490753)
			(xy 27.34891 -400.423816) (xy 27.34891 -400.356393) (xy 27.356985 -400.289456) (xy 27.373019 -400.223967)
			(xy 27.396782 -400.160871) (xy 27.42793 -400.101074) (xy 27.466017 -400.04544) (xy 27.48788 -400.019774)
			(xy 27.493668 -400.012622) (xy 27.500188 -399.995437) (xy 27.50058 -399.986246) (xy 27.50058 -399.828766)
			(xy 27.501 -399.818632) (xy 27.508746 -399.799903) (xy 27.523053 -399.785546) (xy 27.541756 -399.777735)
			(xy 27.551888 -399.777204) (xy 28.268168 -399.777204) (xy 28.278321 -399.777648) (xy 28.297073 -399.785433)
			(xy 28.311398 -399.799824) (xy 28.319098 -399.818612) (xy 28.319476 -399.828766) (xy 28.319476 -399.986246)
			(xy 28.319918 -399.99543) (xy 28.32641 -400.012614) (xy 28.332176 -400.019774) (xy 28.354047 -400.045434)
			(xy 28.392137 -400.101069) (xy 28.423289 -400.160865) (xy 28.447053 -400.223963) (xy 28.463089 -400.289453)
			(xy 28.471165 -400.356392) (xy 28.471165 -400.423817) (xy 28.463088 -400.490756) (xy 28.447051 -400.556246)
			(xy 28.423285 -400.619343) (xy 28.392132 -400.679139) (xy 28.354041 -400.734773) (xy 28.332176 -400.760438)
			(xy 28.326378 -400.767582) (xy 28.319865 -400.784774) (xy 28.319476 -400.793966) (xy 28.319476 -401.286218)
			(xy 28.319883 -401.295405) (xy 28.326399 -401.31259) (xy 28.332176 -401.319746) (xy 28.354019 -401.345429)
			(xy 28.39211 -401.40106) (xy 28.423263 -401.460854) (xy 28.446989 -401.523838) (xy 29.549051 -401.523838)
			(xy 29.549053 -401.456532) (xy 29.557098 -401.389708) (xy 29.573073 -401.324325) (xy 29.596747 -401.26132)
			(xy 29.627782 -401.201596) (xy 29.665732 -401.146008) (xy 29.68752 -401.120356) (xy 29.69332 -401.113213)
			(xy 29.699832 -401.096021) (xy 29.70022 -401.086828) (xy 29.70022 -400.92884) (xy 29.700655 -400.918686)
			(xy 29.708441 -400.899931) (xy 29.722834 -400.885605) (xy 29.741626 -400.877908) (xy 29.751782 -400.877532)
			(xy 30.468062 -400.877532) (xy 30.478185 -400.878058) (xy 30.496904 -400.885771) (xy 30.511261 -400.900046)
			(xy 30.519083 -400.91872) (xy 30.519624 -400.92884) (xy 30.519624 -401.086828) (xy 30.520015 -401.096017)
			(xy 30.526542 -401.113202) (xy 30.532324 -401.120356) (xy 30.554093 -401.146024) (xy 30.592045 -401.201607)
			(xy 30.623081 -401.261328) (xy 30.646757 -401.324331) (xy 30.662732 -401.389711) (xy 30.670778 -401.456533)
			(xy 30.67078 -401.523837) (xy 30.662738 -401.590659) (xy 30.646766 -401.65604) (xy 30.623093 -401.719044)
			(xy 30.620654 -401.723737) (xy 31.749186 -401.723737) (xy 31.749188 -401.65643) (xy 31.757235 -401.589605)
			(xy 31.773211 -401.524221) (xy 31.796887 -401.461216) (xy 31.827925 -401.401492) (xy 31.865878 -401.345906)
			(xy 31.887668 -401.320254) (xy 31.893475 -401.313116) (xy 31.899981 -401.29592) (xy 31.900368 -401.286726)
			(xy 31.900368 -400.793458) (xy 31.899963 -400.784271) (xy 31.893444 -400.767087) (xy 31.887668 -400.75993)
			(xy 31.865885 -400.734273) (xy 31.827935 -400.678688) (xy 31.796899 -400.618966) (xy 31.773225 -400.555962)
			(xy 31.757251 -400.49058) (xy 31.749206 -400.423757) (xy 31.749205 -400.356452) (xy 31.757249 -400.289629)
			(xy 31.773222 -400.224247) (xy 31.796896 -400.161243) (xy 31.82793 -400.10152) (xy 31.86588 -400.045934)
			(xy 31.887668 -400.020282) (xy 31.893463 -400.013136) (xy 31.899977 -399.995946) (xy 31.900368 -399.986754)
			(xy 31.900368 -399.828766) (xy 31.900806 -399.818602) (xy 31.908597 -399.799827) (xy 31.92298 -399.785462)
			(xy 31.941766 -399.777694) (xy 31.95193 -399.777204) (xy 32.66821 -399.777204) (xy 32.678364 -399.777725)
			(xy 32.697127 -399.785496) (xy 32.711491 -399.799853) (xy 32.719271 -399.818612) (xy 32.719772 -399.828766)
			(xy 32.719772 -399.986754) (xy 32.720211 -399.995938) (xy 32.726705 -400.013122) (xy 32.732472 -400.020282)
			(xy 32.754265 -400.045929) (xy 32.792213 -400.101517) (xy 32.823246 -400.161241) (xy 32.846918 -400.224246)
			(xy 32.86289 -400.289629) (xy 32.870933 -400.356452) (xy 32.870933 -400.423757) (xy 32.862888 -400.49058)
			(xy 32.846915 -400.555962) (xy 32.823242 -400.618967) (xy 32.792209 -400.678691) (xy 32.75426 -400.734278)
			(xy 32.732472 -400.75993) (xy 32.726677 -400.767076) (xy 32.720162 -400.784266) (xy 32.719772 -400.793458)
			(xy 32.719772 -401.286726) (xy 32.720176 -401.295914) (xy 32.726695 -401.313098) (xy 32.732472 -401.320254)
			(xy 32.754237 -401.345924) (xy 32.792186 -401.401508) (xy 32.82322 -401.46123) (xy 32.846893 -401.524232)
			(xy 32.862868 -401.589612) (xy 32.870913 -401.656432) (xy 32.870915 -401.723735) (xy 32.862873 -401.790556)
			(xy 32.846903 -401.855937) (xy 32.823233 -401.91894) (xy 32.792203 -401.978663) (xy 32.754258 -402.03425)
			(xy 32.732472 -402.059902) (xy 32.726688 -402.067056) (xy 32.720167 -402.08424) (xy 32.719772 -402.09343)
			(xy 32.719772 -402.251418) (xy 32.719282 -402.261576) (xy 32.711503 -402.280343) (xy 32.697137 -402.294708)
			(xy 32.678368 -402.302483) (xy 32.66821 -402.30298) (xy 31.95193 -402.30298) (xy 31.941763 -402.302512)
			(xy 31.922972 -402.29474) (xy 31.908587 -402.280368) (xy 31.900798 -402.261585) (xy 31.900368 -402.251418)
			(xy 31.900368 -402.09343) (xy 31.899928 -402.084246) (xy 31.893434 -402.067062) (xy 31.887668 -402.059902)
			(xy 31.865858 -402.034268) (xy 31.827908 -401.97868) (xy 31.796874 -401.918954) (xy 31.773201 -401.855947)
			(xy 31.757229 -401.790562) (xy 31.749186 -401.723737) (xy 30.620654 -401.723737) (xy 30.59206 -401.778767)
			(xy 30.554112 -401.834352) (xy 30.532324 -401.860004) (xy 30.526546 -401.867163) (xy 30.520019 -401.884343)
			(xy 30.519624 -401.893532) (xy 30.519624 -402.3868) (xy 30.520029 -402.395988) (xy 30.526546 -402.413172)
			(xy 30.532324 -402.420328) (xy 30.554114 -402.445978) (xy 30.592063 -402.501565) (xy 30.623097 -402.561289)
			(xy 30.64677 -402.624293) (xy 30.662743 -402.689676) (xy 30.670787 -402.756499) (xy 30.670787 -402.823804)
			(xy 30.670778 -402.823878) (xy 33.948799 -402.823878) (xy 33.948804 -402.75645) (xy 33.956885 -402.689508)
			(xy 33.972926 -402.624016) (xy 33.996696 -402.560917) (xy 34.027853 -402.50112) (xy 34.065949 -402.445485)
			(xy 34.087816 -402.41982) (xy 34.093631 -402.412688) (xy 34.100134 -402.395487) (xy 34.100516 -402.386292)
			(xy 34.100516 -401.89404) (xy 34.100083 -401.884855) (xy 34.093585 -401.867671) (xy 34.087816 -401.860512)
			(xy 34.065932 -401.834863) (xy 34.027843 -401.779227) (xy 33.996692 -401.719428) (xy 33.972928 -401.656329)
			(xy 33.956894 -401.590838) (xy 33.948819 -401.523898) (xy 33.948821 -401.456472) (xy 33.956899 -401.389532)
			(xy 33.972937 -401.324042) (xy 33.996704 -401.260944) (xy 34.027858 -401.201147) (xy 34.06595 -401.145513)
			(xy 34.087816 -401.119848) (xy 34.093619 -401.112707) (xy 34.100129 -401.095513) (xy 34.100516 -401.08632)
			(xy 34.100516 -400.92884) (xy 34.100949 -400.918718) (xy 34.108687 -400.900012) (xy 34.122999 -400.885696)
			(xy 34.141702 -400.877952) (xy 34.151824 -400.877532) (xy 34.868104 -400.877532) (xy 34.878231 -400.877914)
			(xy 34.89694 -400.885669) (xy 34.911256 -400.899997) (xy 34.918995 -400.918713) (xy 34.919412 -400.92884)
			(xy 34.919412 -401.08632) (xy 34.91981 -401.095509) (xy 34.926332 -401.112693) (xy 34.932112 -401.119848)
			(xy 34.953956 -401.14553) (xy 34.992044 -401.201162) (xy 35.023195 -401.260956) (xy 35.04696 -401.324051)
			(xy 35.062997 -401.389538) (xy 35.071074 -401.456474) (xy 35.071076 -401.523896) (xy 35.063002 -401.590833)
			(xy 35.046969 -401.65632) (xy 35.023208 -401.719416) (xy 35.020926 -401.723796) (xy 36.148978 -401.723796)
			(xy 36.14898 -401.656371) (xy 36.157058 -401.589432) (xy 36.173095 -401.523942) (xy 36.19686 -401.460845)
			(xy 36.228011 -401.401047) (xy 36.2661 -401.345412) (xy 36.287964 -401.319746) (xy 36.293774 -401.312611)
			(xy 36.300279 -401.295412) (xy 36.300664 -401.286218) (xy 36.300664 -400.793966) (xy 36.300256 -400.784779)
			(xy 36.293739 -400.767595) (xy 36.287964 -400.760438) (xy 36.266107 -400.734767) (xy 36.228021 -400.679133)
			(xy 36.196872 -400.619337) (xy 36.173109 -400.556241) (xy 36.157074 -400.490753) (xy 36.148998 -400.423816)
			(xy 36.148998 -400.356393) (xy 36.157072 -400.289456) (xy 36.173106 -400.223968) (xy 36.196868 -400.160871)
			(xy 36.228016 -400.101075) (xy 36.266102 -400.04544) (xy 36.287964 -400.019774) (xy 36.293762 -400.01263)
			(xy 36.300274 -399.995438) (xy 36.300664 -399.986246) (xy 36.300664 -399.828766) (xy 36.301099 -399.818634)
			(xy 36.308843 -399.799908) (xy 36.323145 -399.785552) (xy 36.341842 -399.777738) (xy 36.351972 -399.777204)
			(xy 37.068252 -399.777204) (xy 37.078404 -399.777661) (xy 37.097156 -399.785442) (xy 37.111481 -399.799828)
			(xy 37.119181 -399.818613) (xy 37.11956 -399.828766) (xy 37.11956 -399.986246) (xy 37.120005 -399.995429)
			(xy 37.126496 -400.012613) (xy 37.13226 -400.019774) (xy 37.154131 -400.045434) (xy 37.192222 -400.101068)
			(xy 37.223375 -400.160865) (xy 37.247141 -400.223962) (xy 37.263177 -400.289453) (xy 37.271253 -400.356392)
			(xy 37.271252 -400.423817) (xy 37.263175 -400.490756) (xy 37.247138 -400.556246) (xy 37.223371 -400.619344)
			(xy 37.192218 -400.67914) (xy 37.154126 -400.734773) (xy 37.13226 -400.760438) (xy 37.12646 -400.76758)
			(xy 37.119948 -400.784773) (xy 37.11956 -400.793966) (xy 37.11956 -401.286218) (xy 37.11997 -401.295405)
			(xy 37.126485 -401.312589) (xy 37.13226 -401.319746) (xy 37.154104 -401.345428) (xy 37.192196 -401.40106)
			(xy 37.22335 -401.460853) (xy 37.247117 -401.523948) (xy 37.263155 -401.589435) (xy 37.271233 -401.656372)
			(xy 37.271235 -401.723795) (xy 37.263161 -401.790732) (xy 37.247127 -401.856221) (xy 37.223363 -401.919317)
			(xy 37.192213 -401.979112) (xy 37.154124 -402.034745) (xy 37.13226 -402.06041) (xy 37.126472 -402.067561)
			(xy 37.119953 -402.084747) (xy 37.11956 -402.093938) (xy 37.11956 -402.251418) (xy 37.119088 -402.261546)
			(xy 37.111355 -402.280268) (xy 37.097064 -402.294623) (xy 37.078378 -402.302442) (xy 37.068252 -402.30298)
			(xy 36.351972 -402.30298) (xy 36.341814 -402.302601) (xy 36.323057 -402.294792) (xy 36.308734 -402.280383)
			(xy 36.301038 -402.261579) (xy 36.300664 -402.251418) (xy 36.300664 -402.093938) (xy 36.300221 -402.084755)
			(xy 36.293729 -402.067571) (xy 36.287964 -402.06041) (xy 36.26608 -402.034762) (xy 36.227994 -401.979124)
			(xy 36.196846 -401.919325) (xy 36.173085 -401.856226) (xy 36.157052 -401.790735) (xy 36.148978 -401.723796)
			(xy 35.020926 -401.723796) (xy 34.99206 -401.779212) (xy 34.953974 -401.834847) (xy 34.932112 -401.860512)
			(xy 34.926329 -401.867667) (xy 34.919806 -401.88485) (xy 34.919412 -401.89404) (xy 34.919412 -402.386292)
			(xy 34.919823 -402.395479) (xy 34.926336 -402.412664) (xy 34.932112 -402.41982) (xy 34.953928 -402.445524)
			(xy 34.992018 -402.501154) (xy 35.02317 -402.560944) (xy 35.046936 -402.624036) (xy 35.062975 -402.68952)
			(xy 35.071054 -402.756454) (xy 35.071059 -402.823818) (xy 38.349119 -402.823818) (xy 38.349123 -402.75651)
			(xy 38.357172 -402.689685) (xy 38.373149 -402.6243) (xy 38.396825 -402.561294) (xy 38.427862 -402.501569)
			(xy 38.465814 -402.445981) (xy 38.487604 -402.420328) (xy 38.493414 -402.413192) (xy 38.499921 -402.395995)
			(xy 38.500304 -402.3868) (xy 38.500304 -401.893532) (xy 38.499878 -401.884347) (xy 38.493375 -401.867162)
			(xy 38.487604 -401.860004) (xy 38.465798 -401.834368) (xy 38.427852 -401.778778) (xy 38.396821 -401.719052)
			(xy 38.373151 -401.656045) (xy 38.357181 -401.590662) (xy 38.349139 -401.523838) (xy 38.34914 -401.456532)
			(xy 38.357186 -401.389709) (xy 38.37316 -401.324326) (xy 38.396834 -401.261321) (xy 38.427867 -401.201596)
			(xy 38.465816 -401.146009) (xy 38.487604 -401.120356) (xy 38.493402 -401.113212) (xy 38.499916 -401.096021)
			(xy 38.500304 -401.086828) (xy 38.500304 -400.92884) (xy 38.500755 -400.918688) (xy 38.508538 -400.899936)
			(xy 38.522926 -400.885611) (xy 38.541712 -400.87791) (xy 38.551866 -400.877532) (xy 39.268146 -400.877532)
			(xy 39.278275 -400.877989) (xy 39.296995 -400.88573) (xy 39.31135 -400.900025) (xy 39.319169 -400.918714)
			(xy 39.319708 -400.92884) (xy 39.319708 -401.086828) (xy 39.320103 -401.096017) (xy 39.326627 -401.113201)
			(xy 39.332408 -401.120356) (xy 39.354178 -401.146024) (xy 39.392131 -401.201607) (xy 39.423168 -401.261328)
			(xy 39.446844 -401.32433) (xy 39.46282 -401.389711) (xy 39.470866 -401.456533) (xy 39.470868 -401.523837)
			(xy 39.462825 -401.590659) (xy 39.446853 -401.656041) (xy 39.42318 -401.719045) (xy 39.420711 -401.723797)
			(xy 40.548745 -401.723797) (xy 40.548747 -401.65637) (xy 40.556826 -401.58943) (xy 40.572865 -401.523939)
			(xy 40.596634 -401.460841) (xy 40.62779 -401.401044) (xy 40.665885 -401.34541) (xy 40.687752 -401.319746)
			(xy 40.69356 -401.312609) (xy 40.700067 -401.295412) (xy 40.700452 -401.286218) (xy 40.700452 -400.793966)
			(xy 40.700046 -400.784779) (xy 40.693528 -400.767595) (xy 40.687752 -400.760438) (xy 40.665892 -400.734769)
			(xy 40.6278 -400.679136) (xy 40.596646 -400.619341) (xy 40.572879 -400.556244) (xy 40.556842 -400.490755)
			(xy 40.548764 -400.423817) (xy 40.548764 -400.356392) (xy 40.55684 -400.289454) (xy 40.572876 -400.223964)
			(xy 40.596642 -400.160867) (xy 40.627795 -400.101072) (xy 40.665887 -400.045438) (xy 40.687752 -400.019774)
			(xy 40.693549 -400.012629) (xy 40.700062 -399.995438) (xy 40.700452 -399.986246) (xy 40.700452 -399.828766)
			(xy 40.700899 -399.818636) (xy 40.70864 -399.799911) (xy 40.722939 -399.785556) (xy 40.741632 -399.77774)
			(xy 40.75176 -399.777204) (xy 41.46804 -399.777204) (xy 41.478197 -399.777589) (xy 41.496951 -399.785399)
			(xy 41.511273 -399.799806) (xy 41.518971 -399.818606) (xy 41.519348 -399.828766) (xy 41.519348 -399.986246)
			(xy 41.519796 -399.995429) (xy 41.526285 -400.012613) (xy 41.532048 -400.019774) (xy 41.55392 -400.045433)
			(xy 41.592012 -400.101068) (xy 41.623165 -400.160864) (xy 41.646931 -400.223962) (xy 41.662968 -400.289452)
			(xy 41.671044 -400.356392) (xy 41.671043 -400.423817) (xy 41.662966 -400.490757) (xy 41.646928 -400.556247)
			(xy 41.623161 -400.619344) (xy 41.592007 -400.67914) (xy 41.553914 -400.734774) (xy 41.532048 -400.760438)
			(xy 41.526246 -400.767579) (xy 41.519736 -400.784773) (xy 41.519348 -400.793966) (xy 41.519348 -401.286218)
			(xy 41.519761 -401.295405) (xy 41.526274 -401.312588) (xy 41.532048 -401.319746) (xy 41.553892 -401.345428)
			(xy 41.591985 -401.401059) (xy 41.62314 -401.460852) (xy 41.646907 -401.523947) (xy 41.662946 -401.589435)
			(xy 41.671024 -401.656372) (xy 41.671026 -401.723795) (xy 41.662952 -401.790733) (xy 41.646917 -401.856221)
			(xy 41.623153 -401.919317) (xy 41.592002 -401.979113) (xy 41.553912 -402.034746) (xy 41.532048 -402.06041)
			(xy 41.526258 -402.06756) (xy 41.519741 -402.084747) (xy 41.519348 -402.093938) (xy 41.519348 -402.251418)
			(xy 41.518888 -402.261547) (xy 41.511152 -402.280271) (xy 41.496858 -402.294627) (xy 41.478167 -402.302444)
			(xy 41.46804 -402.30298) (xy 40.75176 -402.30298) (xy 40.741601 -402.302611) (xy 40.722844 -402.294798)
			(xy 40.708521 -402.280385) (xy 40.700826 -402.26158) (xy 40.700452 -402.251418) (xy 40.700452 -402.093938)
			(xy 40.700012 -402.084754) (xy 40.693518 -402.06757) (xy 40.687752 -402.06041) (xy 40.665865 -402.034763)
			(xy 40.627773 -401.979127) (xy 40.59662 -401.919329) (xy 40.572855 -401.85623) (xy 40.55682 -401.790738)
			(xy 40.548745 -401.723797) (xy 39.420711 -401.723797) (xy 39.392146 -401.778768) (xy 39.354196 -401.834353)
			(xy 39.332408 -401.860004) (xy 39.326628 -401.867161) (xy 39.320103 -401.884342) (xy 39.319708 -401.893532)
			(xy 39.319708 -402.3868) (xy 39.320116 -402.395987) (xy 39.326631 -402.413172) (xy 39.332408 -402.420328)
			(xy 39.35415 -402.446018) (xy 39.392104 -402.501598) (xy 39.423142 -402.561316) (xy 39.44682 -402.624315)
			(xy 39.462798 -402.689694) (xy 39.470847 -402.756513) (xy 39.470851 -402.823815) (xy 39.470843 -402.823878)
			(xy 42.748887 -402.823878) (xy 42.748892 -402.75645) (xy 42.756972 -402.689509) (xy 42.773013 -402.624017)
			(xy 42.796782 -402.560918) (xy 42.827939 -402.501121) (xy 42.866033 -402.445485) (xy 42.8879 -402.41982)
			(xy 42.893713 -402.412686) (xy 42.900218 -402.395487) (xy 42.9006 -402.386292) (xy 42.9006 -401.89404)
			(xy 42.900171 -401.884855) (xy 42.89367 -401.86767) (xy 42.8879 -401.860512) (xy 42.866016 -401.834863)
			(xy 42.827928 -401.779226) (xy 42.796778 -401.719428) (xy 42.773015 -401.656329) (xy 42.756981 -401.590838)
			(xy 42.748907 -401.523898) (xy 42.748909 -401.456472) (xy 42.756987 -401.389533) (xy 42.773024 -401.324043)
			(xy 42.796791 -401.260945) (xy 42.827944 -401.201148) (xy 42.866035 -401.145513) (xy 42.8879 -401.119848)
			(xy 42.893701 -401.112706) (xy 42.900213 -401.095513) (xy 42.9006 -401.08632) (xy 42.9006 -400.92884)
			(xy 42.901049 -400.91872) (xy 42.908784 -400.900017) (xy 42.923091 -400.885702) (xy 42.941788 -400.877955)
			(xy 42.951908 -400.877532) (xy 43.668188 -400.877532) (xy 43.678314 -400.877927) (xy 43.697023 -400.885677)
			(xy 43.711339 -400.9) (xy 43.719079 -400.918714) (xy 43.719496 -400.92884) (xy 43.719496 -401.08632)
			(xy 43.719897 -401.095508) (xy 43.726417 -401.112692) (xy 43.732196 -401.119848) (xy 43.75404 -401.145529)
			(xy 43.79213 -401.201162) (xy 43.823282 -401.260955) (xy 43.847047 -401.32405) (xy 43.863084 -401.389537)
			(xy 43.871162 -401.456474) (xy 43.871164 -401.523896) (xy 43.86309 -401.590833) (xy 43.847056 -401.656321)
			(xy 43.823294 -401.719417) (xy 43.821044 -401.723737) (xy 44.949064 -401.723737) (xy 44.949066 -401.65643)
			(xy 44.957113 -401.589606) (xy 44.973088 -401.524222) (xy 44.996763 -401.461217) (xy 45.027799 -401.401493)
			(xy 45.065751 -401.345906) (xy 45.08754 -401.320254) (xy 45.093344 -401.313114) (xy 45.099853 -401.295919)
			(xy 45.10024 -401.286726) (xy 45.10024 -400.793458) (xy 45.099841 -400.78427) (xy 45.093319 -400.767086)
			(xy 45.08754 -400.75993) (xy 45.065758 -400.734273) (xy 45.027809 -400.678687) (xy 44.996776 -400.618964)
			(xy 44.973103 -400.55596) (xy 44.957129 -400.490579) (xy 44.949085 -400.423757) (xy 44.949084 -400.356452)
			(xy 44.957128 -400.28963) (xy 44.9731 -400.224248) (xy 44.996772 -400.161244) (xy 45.027805 -400.101521)
			(xy 45.065753 -400.045934) (xy 45.08754 -400.020282) (xy 45.093332 -400.013134) (xy 45.099848 -399.995945)
			(xy 45.10024 -399.986754) (xy 45.10024 -399.828766) (xy 45.100706 -399.818606) (xy 45.108492 -399.799835)
			(xy 45.122866 -399.785471) (xy 45.141641 -399.777698) (xy 45.151802 -399.777204) (xy 45.868082 -399.777204)
			(xy 45.878234 -399.777747) (xy 45.896997 -399.785509) (xy 45.911361 -399.79986) (xy 45.919143 -399.818614)
			(xy 45.919644 -399.828766) (xy 45.919644 -399.986754) (xy 45.920089 -399.995937) (xy 45.92658 -400.013121)
			(xy 45.932344 -400.020282) (xy 45.954138 -400.045929) (xy 45.992088 -400.101516) (xy 46.023122 -400.16124)
			(xy 46.046795 -400.224245) (xy 46.062768 -400.289628) (xy 46.070812 -400.356452) (xy 46.070811 -400.423757)
			(xy 46.062766 -400.490581) (xy 46.046792 -400.555963) (xy 46.023118 -400.618968) (xy 45.992083 -400.678692)
			(xy 45.954132 -400.734278) (xy 45.932344 -400.75993) (xy 45.926545 -400.767073) (xy 45.920033 -400.784266)
			(xy 45.919644 -400.793458) (xy 45.919644 -401.286726) (xy 45.920054 -401.295913) (xy 45.926569 -401.313097)
			(xy 45.932344 -401.320254) (xy 45.95411 -401.345924) (xy 45.992061 -401.401507) (xy 46.023096 -401.461228)
			(xy 46.046771 -401.524231) (xy 46.062746 -401.589611) (xy 46.070792 -401.656432) (xy 46.070794 -401.723735)
			(xy 46.062752 -401.790557) (xy 46.046781 -401.855938) (xy 46.02311 -401.918941) (xy 45.992078 -401.978664)
			(xy 45.954131 -402.03425) (xy 45.932344 -402.059902) (xy 45.926557 -402.067054) (xy 45.920038 -402.084239)
			(xy 45.919644 -402.09343) (xy 45.919644 -402.251418) (xy 45.919181 -402.261579) (xy 45.911397 -402.280352)
			(xy 45.897022 -402.294718) (xy 45.878244 -402.302488) (xy 45.868082 -402.30298) (xy 45.151802 -402.30298)
			(xy 45.141647 -402.302465) (xy 45.122881 -402.294695) (xy 45.108516 -402.280336) (xy 45.100739 -402.261573)
			(xy 45.10024 -402.251418) (xy 45.10024 -402.09343) (xy 45.099806 -402.084246) (xy 45.093308 -402.067061)
			(xy 45.08754 -402.059902) (xy 45.06573 -402.034268) (xy 45.027782 -401.978679) (xy 44.99675 -401.918953)
			(xy 44.973078 -401.855946) (xy 44.957107 -401.790561) (xy 44.949064 -401.723737) (xy 43.821044 -401.723737)
			(xy 43.792146 -401.779213) (xy 43.754059 -401.834847) (xy 43.732196 -401.860512) (xy 43.726411 -401.867666)
			(xy 43.71989 -401.88485) (xy 43.719496 -401.89404) (xy 43.719496 -402.386292) (xy 43.719911 -402.395479)
			(xy 43.726421 -402.412663) (xy 43.732196 -402.41982) (xy 43.754013 -402.445524) (xy 43.792103 -402.501153)
			(xy 43.823256 -402.560944) (xy 43.847023 -402.624036) (xy 43.863062 -402.68952) (xy 43.871142 -402.756454)
			(xy 43.871146 -402.823874) (xy 43.863075 -402.890809) (xy 43.847045 -402.956295) (xy 43.823286 -403.01939)
			(xy 43.792141 -403.079185) (xy 43.754057 -403.134819) (xy 43.732196 -403.160484) (xy 43.726381 -403.167616)
			(xy 43.719877 -403.184817) (xy 43.719496 -403.194012) (xy 43.719496 -403.351492) (xy 43.719077 -403.361614)
			(xy 43.711331 -403.380319) (xy 43.697015 -403.394633) (xy 43.67831 -403.402378) (xy 43.668188 -403.4028)
			(xy 42.951908 -403.4028) (xy 42.941786 -403.402377) (xy 42.923083 -403.394632) (xy 42.908768 -403.380317)
			(xy 42.901023 -403.361614) (xy 42.9006 -403.351492) (xy 42.9006 -403.194012) (xy 42.900184 -403.184825)
			(xy 42.893674 -403.167641) (xy 42.8879 -403.160484) (xy 42.865989 -403.134858) (xy 42.827902 -403.079218)
			(xy 42.796753 -403.019416) (xy 42.772992 -402.956314) (xy 42.756959 -402.89082) (xy 42.748887 -402.823878)
			(xy 39.470843 -402.823878) (xy 39.462811 -402.890635) (xy 39.446841 -402.956016) (xy 39.423172 -403.019018)
			(xy 39.392141 -403.07874) (xy 39.354194 -403.134325) (xy 39.332408 -403.159976) (xy 39.326598 -403.167111)
			(xy 39.320091 -403.184309) (xy 39.319708 -403.193504) (xy 39.319708 -403.351492) (xy 39.319272 -403.361645)
			(xy 39.311481 -403.380395) (xy 39.297088 -403.394719) (xy 39.278301 -403.40242) (xy 39.268146 -403.4028)
			(xy 38.551866 -403.4028) (xy 38.541742 -403.402303) (xy 38.523028 -403.394571) (xy 38.508674 -403.380289)
			(xy 38.500849 -403.361613) (xy 38.500304 -403.351492) (xy 38.500304 -403.193504) (xy 38.499891 -403.184317)
			(xy 38.493379 -403.167133) (xy 38.487604 -403.159976) (xy 38.46577 -403.134362) (xy 38.427825 -403.078769)
			(xy 38.396796 -403.01904) (xy 38.373127 -402.956031) (xy 38.357159 -402.890644) (xy 38.349119 -402.823818)
			(xy 35.071059 -402.823818) (xy 35.071059 -402.823874) (xy 35.062988 -402.890809) (xy 35.046958 -402.956295)
			(xy 35.023199 -403.01939) (xy 34.992055 -403.079185) (xy 34.953973 -403.134819) (xy 34.932112 -403.160484)
			(xy 34.926299 -403.167617) (xy 34.919794 -403.184817) (xy 34.919412 -403.194012) (xy 34.919412 -403.351492)
			(xy 34.918978 -403.361612) (xy 34.911234 -403.380314) (xy 34.896924 -403.394628) (xy 34.878224 -403.402375)
			(xy 34.868104 -403.4028) (xy 34.151824 -403.4028) (xy 34.141703 -403.402365) (xy 34.123 -403.394624)
			(xy 34.108685 -403.380314) (xy 34.100939 -403.361613) (xy 34.100516 -403.351492) (xy 34.100516 -403.194012)
			(xy 34.100096 -403.184826) (xy 34.093589 -403.167642) (xy 34.087816 -403.160484) (xy 34.065904 -403.134858)
			(xy 34.027816 -403.079218) (xy 33.996666 -403.019417) (xy 33.972904 -402.956315) (xy 33.956872 -402.890821)
			(xy 33.948799 -402.823878) (xy 30.670778 -402.823878) (xy 30.662742 -402.890627) (xy 30.646769 -402.956009)
			(xy 30.623096 -403.019014) (xy 30.592062 -403.078738) (xy 30.554112 -403.134324) (xy 30.532324 -403.159976)
			(xy 30.526515 -403.167113) (xy 30.520007 -403.18431) (xy 30.519624 -403.193504) (xy 30.519624 -403.351492)
			(xy 30.519172 -403.361643) (xy 30.511384 -403.38039) (xy 30.496997 -403.394713) (xy 30.478214 -403.402417)
			(xy 30.468062 -403.4028) (xy 29.751782 -403.4028) (xy 29.741659 -403.40229) (xy 29.722945 -403.394563)
			(xy 29.708591 -403.380285) (xy 29.700765 -403.361612) (xy 29.70022 -403.351492) (xy 29.70022 -403.193504)
			(xy 29.699804 -403.184318) (xy 29.693294 -403.167133) (xy 29.68752 -403.159976) (xy 29.665734 -403.134322)
			(xy 29.627785 -403.078736) (xy 29.596752 -403.019013) (xy 29.573079 -402.956008) (xy 29.557106 -402.890626)
			(xy 29.549061 -402.823804) (xy 29.549061 -402.756499) (xy 29.557105 -402.689677) (xy 29.573078 -402.624294)
			(xy 29.59675 -402.56129) (xy 29.627784 -402.501566) (xy 29.665732 -402.44598) (xy 29.68752 -402.420328)
			(xy 29.693332 -402.413194) (xy 29.699837 -402.395995) (xy 29.70022 -402.3868) (xy 29.70022 -401.893532)
			(xy 29.69979 -401.884347) (xy 29.69329 -401.867163) (xy 29.68752 -401.860004) (xy 29.665713 -401.834368)
			(xy 29.627766 -401.778779) (xy 29.596735 -401.719053) (xy 29.573064 -401.656046) (xy 29.557093 -401.590662)
			(xy 29.549051 -401.523838) (xy 28.446989 -401.523838) (xy 28.44703 -401.523948) (xy 28.463067 -401.589436)
			(xy 28.471145 -401.656372) (xy 28.471147 -401.723795) (xy 28.463073 -401.790732) (xy 28.447039 -401.85622)
			(xy 28.423277 -401.919316) (xy 28.392127 -401.979111) (xy 28.354039 -402.034745) (xy 28.332176 -402.06041)
			(xy 28.32639 -402.067562) (xy 28.31987 -402.084748) (xy 28.319476 -402.093938) (xy 28.319476 -402.251418)
			(xy 28.318989 -402.261544) (xy 28.311258 -402.280263) (xy 28.296972 -402.294618) (xy 28.278291 -402.302439)
			(xy 28.268168 -402.30298) (xy 27.551888 -402.30298) (xy 27.541731 -402.302588) (xy 27.522974 -402.294785)
			(xy 27.50865 -402.280379) (xy 27.500954 -402.261578) (xy 27.50058 -402.251418) (xy 27.50058 -402.093938)
			(xy 27.500156 -402.084752) (xy 27.493653 -402.067567) (xy 27.48788 -402.06041) (xy 27.465995 -402.034762)
			(xy 27.427908 -401.979125) (xy 27.39676 -401.919326) (xy 27.372998 -401.856227) (xy 27.356964 -401.790736)
			(xy 27.348891 -401.723796) (xy 0.508 -401.723796) (xy 0.508 -405.623707) (xy 27.348902 -405.623707)
			(xy 27.348902 -405.556284) (xy 27.356979 -405.489345) (xy 27.373014 -405.423856) (xy 27.396778 -405.360759)
			(xy 27.427928 -405.300963) (xy 27.466016 -405.245328) (xy 27.48788 -405.219662) (xy 27.493673 -405.212514)
			(xy 27.50019 -405.195326) (xy 27.50058 -405.186134) (xy 27.50058 -404.693882) (xy 27.500183 -404.684693)
			(xy 27.493661 -404.667509) (xy 27.48788 -404.660354) (xy 27.466038 -404.634671) (xy 27.42795 -404.579038)
			(xy 27.3968 -404.519244) (xy 27.373035 -404.45615) (xy 27.356999 -404.390663) (xy 27.348922 -404.323727)
			(xy 27.34892 -404.256306) (xy 27.356993 -404.189369) (xy 27.373025 -404.123882) (xy 27.396786 -404.060786)
			(xy 27.427933 -404.00099) (xy 27.466018 -403.945356) (xy 27.48788 -403.91969) (xy 27.493661 -403.912534)
			(xy 27.500186 -403.895352) (xy 27.50058 -403.886162) (xy 27.50058 -403.728682) (xy 27.501013 -403.718549)
			(xy 27.508754 -403.69982) (xy 27.523057 -403.685463) (xy 27.541757 -403.677651) (xy 27.551888 -403.67712)
			(xy 28.268168 -403.67712) (xy 28.278323 -403.677548) (xy 28.297078 -403.685337) (xy 28.311404 -403.699732)
			(xy 28.319101 -403.718525) (xy 28.319476 -403.728682) (xy 28.319476 -403.886162) (xy 28.31991 -403.895347)
			(xy 28.326408 -403.912531) (xy 28.332176 -403.91969) (xy 28.354062 -403.945337) (xy 28.392152 -404.000974)
			(xy 28.423303 -404.060772) (xy 28.447067 -404.123871) (xy 28.463102 -404.189363) (xy 28.471176 -404.256304)
			(xy 28.471174 -404.323729) (xy 28.463096 -404.39067) (xy 28.447057 -404.45616) (xy 28.42329 -404.519258)
			(xy 28.392135 -404.579055) (xy 28.354042 -404.634689) (xy 28.332176 -404.660354) (xy 28.326371 -404.667493)
			(xy 28.319862 -404.684688) (xy 28.319476 -404.693882) (xy 28.319476 -405.186134) (xy 28.319875 -405.195322)
			(xy 28.326397 -405.212506) (xy 28.332176 -405.219662) (xy 28.354035 -405.245332) (xy 28.392125 -405.300965)
			(xy 28.423278 -405.36076) (xy 28.447043 -405.423857) (xy 28.46308 -405.489345) (xy 28.471157 -405.556284)
			(xy 28.471157 -405.623707) (xy 28.463081 -405.690646) (xy 28.447046 -405.756135) (xy 28.423281 -405.819231)
			(xy 28.39213 -405.879027) (xy 28.35404 -405.934661) (xy 28.332176 -405.960326) (xy 28.326383 -405.967474)
			(xy 28.319867 -405.984662) (xy 28.319476 -405.993854) (xy 28.319476 -406.151334) (xy 28.319002 -406.161461)
			(xy 28.311266 -406.18018) (xy 28.296976 -406.194534) (xy 28.278293 -406.202355) (xy 28.268168 -406.202896)
			(xy 27.551888 -406.202896) (xy 27.541733 -406.202488) (xy 27.522979 -406.194688) (xy 27.508656 -406.180287)
			(xy 27.500957 -406.161492) (xy 27.50058 -406.151334) (xy 27.50058 -405.993854) (xy 27.500148 -405.984669)
			(xy 27.49365 -405.967484) (xy 27.48788 -405.960326) (xy 27.466011 -405.934665) (xy 27.427924 -405.87903)
			(xy 27.396774 -405.819233) (xy 27.373011 -405.756135) (xy 27.356977 -405.690646) (xy 27.348902 -405.623707)
			(xy 0.508 -405.623707) (xy 0.508 -406.72373) (xy 29.549042 -406.72373) (xy 29.549045 -406.656422)
			(xy 29.557092 -406.589598) (xy 29.573068 -406.524214) (xy 29.596744 -406.461208) (xy 29.627779 -406.401484)
			(xy 29.665731 -406.345896) (xy 29.68752 -406.320244) (xy 29.693325 -406.313105) (xy 29.699834 -406.29591)
			(xy 29.70022 -406.286716) (xy 29.70022 -405.793448) (xy 29.699782 -405.784264) (xy 29.693287 -405.767079)
			(xy 29.68752 -405.75992) (xy 29.665729 -405.734271) (xy 29.627781 -405.678684) (xy 29.596749 -405.618959)
			(xy 29.573078 -405.555955) (xy 29.557105 -405.490572) (xy 29.549062 -405.423749) (xy 29.549062 -405.356444)
			(xy 29.557107 -405.289622) (xy 29.573079 -405.22424) (xy 29.596752 -405.161235) (xy 29.627784 -405.101511)
			(xy 29.665733 -405.045924) (xy 29.68752 -405.020272) (xy 29.693313 -405.013125) (xy 29.699829 -404.995936)
			(xy 29.70022 -404.986744) (xy 29.70022 -404.828756) (xy 29.700586 -404.818597) (xy 29.7084 -404.799839)
			(xy 29.722814 -404.785517) (xy 29.74162 -404.777822) (xy 29.751782 -404.777448) (xy 30.468062 -404.777448)
			(xy 30.478187 -404.777958) (xy 30.496909 -404.785675) (xy 30.511267 -404.799954) (xy 30.519086 -404.818634)
			(xy 30.519624 -404.828756) (xy 30.519624 -404.986744) (xy 30.520008 -404.995934) (xy 30.526539 -405.013118)
			(xy 30.532324 -405.020272) (xy 30.554109 -405.045927) (xy 30.59206 -405.101512) (xy 30.623096 -405.161235)
			(xy 30.64677 -405.224239) (xy 30.662745 -405.289621) (xy 30.67079 -405.356444) (xy 30.67079 -405.42375)
			(xy 30.662746 -405.490573) (xy 30.646772 -405.555955) (xy 30.623098 -405.61896) (xy 30.620661 -405.623649)
			(xy 31.749197 -405.623649) (xy 31.749198 -405.556342) (xy 31.757243 -405.489519) (xy 31.773217 -405.424136)
			(xy 31.796892 -405.361131) (xy 31.827928 -405.301408) (xy 31.865879 -405.245822) (xy 31.887668 -405.22017)
			(xy 31.893468 -405.213028) (xy 31.899979 -405.195835) (xy 31.900368 -405.186642) (xy 31.900368 -404.693374)
			(xy 31.899955 -404.684187) (xy 31.893441 -404.667004) (xy 31.887668 -404.659846) (xy 31.865901 -404.634176)
			(xy 31.82795 -404.578593) (xy 31.796914 -404.518872) (xy 31.773239 -404.45587) (xy 31.757263 -404.39049)
			(xy 31.749217 -404.323668) (xy 31.749215 -404.256365) (xy 31.757257 -404.189543) (xy 31.773229 -404.124162)
			(xy 31.7969 -404.061158) (xy 31.827933 -404.001435) (xy 31.865881 -403.94585) (xy 31.887668 -403.920198)
			(xy 31.893456 -403.913047) (xy 31.899974 -403.895861) (xy 31.900368 -403.88667) (xy 31.900368 -403.728682)
			(xy 31.90075 -403.718506) (xy 31.908547 -403.699705) (xy 31.922945 -403.68532) (xy 31.941753 -403.677541)
			(xy 31.95193 -403.67712) (xy 32.66821 -403.67712) (xy 32.678366 -403.677625) (xy 32.697132 -403.685399)
			(xy 32.711496 -403.699761) (xy 32.719273 -403.718526) (xy 32.719772 -403.728682) (xy 32.719772 -403.88667)
			(xy 32.720203 -403.895855) (xy 32.726703 -403.913039) (xy 32.732472 -403.920198) (xy 32.754281 -403.945832)
			(xy 32.792229 -404.001422) (xy 32.82326 -404.061148) (xy 32.846931 -404.124155) (xy 32.862902 -404.189539)
			(xy 32.870945 -404.256363) (xy 32.870943 -404.32367) (xy 32.862897 -404.390494) (xy 32.846922 -404.455877)
			(xy 32.823247 -404.518882) (xy 32.792212 -404.578607) (xy 32.754261 -404.634194) (xy 32.732472 -404.659846)
			(xy 32.72667 -404.666987) (xy 32.720159 -404.684181) (xy 32.719772 -404.693374) (xy 32.719772 -405.186642)
			(xy 32.720168 -405.195831) (xy 32.726692 -405.213014) (xy 32.732472 -405.22017) (xy 32.754254 -405.245827)
			(xy 32.792202 -405.301413) (xy 32.823235 -405.361136) (xy 32.846907 -405.42414) (xy 32.862881 -405.489521)
			(xy 32.870925 -405.556343) (xy 32.870926 -405.623648) (xy 32.862882 -405.69047) (xy 32.84691 -405.755851)
			(xy 32.823239 -405.818856) (xy 32.792207 -405.878579) (xy 32.754259 -405.934166) (xy 32.732472 -405.959818)
			(xy 32.726682 -405.966967) (xy 32.720164 -405.984155) (xy 32.719772 -405.993346) (xy 32.719772 -406.151334)
			(xy 32.719295 -406.161493) (xy 32.711511 -406.180261) (xy 32.697141 -406.194624) (xy 32.678369 -406.202399)
			(xy 32.66821 -406.202896) (xy 31.95193 -406.202896) (xy 31.941778 -406.202343) (xy 31.923016 -406.194585)
			(xy 31.908651 -406.180237) (xy 31.900869 -406.161485) (xy 31.900368 -406.151334) (xy 31.900368 -405.993346)
			(xy 31.899921 -405.984163) (xy 31.893431 -405.966979) (xy 31.887668 -405.959818) (xy 31.865874 -405.934171)
			(xy 31.827923 -405.878584) (xy 31.796888 -405.81886) (xy 31.773215 -405.755855) (xy 31.757241 -405.690472)
			(xy 31.749197 -405.623649) (xy 30.620661 -405.623649) (xy 30.592063 -405.678683) (xy 30.554113 -405.734268)
			(xy 30.532324 -405.75992) (xy 30.526539 -405.767074) (xy 30.520017 -405.784258) (xy 30.519624 -405.793448)
			(xy 30.519624 -406.286716) (xy 30.520021 -406.295905) (xy 30.526543 -406.313089) (xy 30.532324 -406.320244)
			(xy 30.554081 -406.345922) (xy 30.592034 -406.401503) (xy 30.62307 -406.461223) (xy 30.646746 -406.524224)
			(xy 30.662723 -406.589604) (xy 30.67077 -406.656424) (xy 30.670773 -406.723728) (xy 30.670766 -406.723789)
			(xy 33.948811 -406.723789) (xy 33.948814 -406.656363) (xy 33.956893 -406.589422) (xy 33.972932 -406.523931)
			(xy 33.996701 -406.460833) (xy 34.027856 -406.401036) (xy 34.06595 -406.345401) (xy 34.087816 -406.319736)
			(xy 34.093624 -406.312599) (xy 34.100131 -406.295402) (xy 34.100516 -406.286208) (xy 34.100516 -405.793956)
			(xy 34.100123 -405.784767) (xy 34.093597 -405.767583) (xy 34.087816 -405.760428) (xy 34.065948 -405.734766)
			(xy 34.027858 -405.679132) (xy 33.996706 -405.619335) (xy 33.972942 -405.556238) (xy 33.956906 -405.490748)
			(xy 33.94883 -405.423809) (xy 33.948831 -405.356385) (xy 33.956907 -405.289446) (xy 33.972944 -405.223957)
			(xy 33.996709 -405.160859) (xy 34.027861 -405.101063) (xy 34.065951 -405.045429) (xy 34.087816 -405.019764)
			(xy 34.093612 -405.012619) (xy 34.100127 -404.995428) (xy 34.100516 -404.986236) (xy 34.100516 -404.828756)
			(xy 34.10095 -404.818642) (xy 34.108705 -404.79996) (xy 34.123017 -404.785666) (xy 34.14171 -404.777936)
			(xy 34.151824 -404.777448) (xy 34.868104 -404.777448) (xy 34.878207 -404.777981) (xy 34.896875 -404.78571)
			(xy 34.911168 -404.799992) (xy 34.918911 -404.818654) (xy 34.919412 -404.828756) (xy 34.919412 -404.986236)
			(xy 34.919802 -404.995425) (xy 34.926329 -405.01261) (xy 34.932112 -405.019764) (xy 34.953972 -405.045433)
			(xy 34.99206 -405.101067) (xy 35.02321 -405.160863) (xy 35.046974 -405.223959) (xy 35.063009 -405.289448)
			(xy 35.071085 -405.356385) (xy 35.071085 -405.423809) (xy 35.06301 -405.490746) (xy 35.046976 -405.556235)
			(xy 35.023212 -405.619332) (xy 35.020933 -405.623707) (xy 36.14899 -405.623707) (xy 36.14899 -405.556284)
			(xy 36.157066 -405.489346) (xy 36.173101 -405.423857) (xy 36.196864 -405.36076) (xy 36.228014 -405.300963)
			(xy 36.266101 -405.245328) (xy 36.287964 -405.219662) (xy 36.293767 -405.212522) (xy 36.300276 -405.195327)
			(xy 36.300664 -405.186134) (xy 36.300664 -404.693882) (xy 36.300248 -404.684696) (xy 36.293737 -404.667512)
			(xy 36.287964 -404.660354) (xy 36.266123 -404.63467) (xy 36.228036 -404.579038) (xy 36.196886 -404.519244)
			(xy 36.173122 -404.456149) (xy 36.157087 -404.390663) (xy 36.149009 -404.323727) (xy 36.149007 -404.256306)
			(xy 36.157081 -404.18937) (xy 36.173113 -404.123882) (xy 36.196873 -404.060787) (xy 36.228019 -404.000991)
			(xy 36.266103 -403.945356) (xy 36.287964 -403.91969) (xy 36.293755 -403.912541) (xy 36.300271 -403.895353)
			(xy 36.300664 -403.886162) (xy 36.300664 -403.728682) (xy 36.301112 -403.718551) (xy 36.30885 -403.699825)
			(xy 36.323149 -403.685468) (xy 36.341843 -403.677654) (xy 36.351972 -403.67712) (xy 37.068252 -403.67712)
			(xy 37.078405 -403.677561) (xy 37.097161 -403.685345) (xy 37.111486 -403.699736) (xy 37.119184 -403.718527)
			(xy 37.11956 -403.728682) (xy 37.11956 -403.886162) (xy 37.119998 -403.895346) (xy 37.126493 -403.91253)
			(xy 37.13226 -403.91969) (xy 37.154147 -403.945337) (xy 37.192238 -404.000973) (xy 37.22339 -404.060771)
			(xy 37.247154 -404.123871) (xy 37.26319 -404.189362) (xy 37.271264 -404.256303) (xy 37.271262 -404.32373)
			(xy 37.263184 -404.39067) (xy 37.247145 -404.456161) (xy 37.223376 -404.519259) (xy 37.192221 -404.579055)
			(xy 37.154127 -404.634689) (xy 37.13226 -404.660354) (xy 37.126453 -404.667492) (xy 37.119946 -404.684688)
			(xy 37.11956 -404.693882) (xy 37.11956 -405.186134) (xy 37.119963 -405.195322) (xy 37.126483 -405.212506)
			(xy 37.13226 -405.219662) (xy 37.154119 -405.245331) (xy 37.192211 -405.300964) (xy 37.223364 -405.36076)
			(xy 37.24713 -405.423856) (xy 37.263168 -405.489345) (xy 37.271245 -405.556284) (xy 37.271245 -405.623707)
			(xy 37.263169 -405.690646) (xy 37.247133 -405.756135) (xy 37.223368 -405.819232) (xy 37.192216 -405.879028)
			(xy 37.154125 -405.934661) (xy 37.13226 -405.960326) (xy 37.126465 -405.967472) (xy 37.11995 -405.984662)
			(xy 37.11956 -405.993854) (xy 37.11956 -406.151334) (xy 37.119101 -406.161463) (xy 37.111362 -406.180185)
			(xy 37.097068 -406.19454) (xy 37.078379 -406.202358) (xy 37.068252 -406.202896) (xy 36.351972 -406.202896)
			(xy 36.341816 -406.202501) (xy 36.323062 -406.194696) (xy 36.308739 -406.180291) (xy 36.301041 -406.161493)
			(xy 36.300664 -406.151334) (xy 36.300664 -405.993854) (xy 36.300214 -405.984671) (xy 36.293726 -405.967487)
			(xy 36.287964 -405.960326) (xy 36.266095 -405.934665) (xy 36.228009 -405.879029) (xy 36.196861 -405.819232)
			(xy 36.173099 -405.756135) (xy 36.157065 -405.690645) (xy 36.14899 -405.623707) (xy 35.020933 -405.623707)
			(xy 34.992063 -405.679128) (xy 34.953975 -405.734763) (xy 34.932112 -405.760428) (xy 34.926322 -405.767578)
			(xy 34.919803 -405.784765) (xy 34.919412 -405.793956) (xy 34.919412 -406.286208) (xy 34.919816 -406.295396)
			(xy 34.926334 -406.31258) (xy 34.932112 -406.319736) (xy 34.953944 -406.345427) (xy 34.992033 -406.401058)
			(xy 35.023184 -406.460851) (xy 35.04695 -406.523945) (xy 35.062987 -406.58943) (xy 35.071065 -406.656366)
			(xy 35.071068 -406.723729) (xy 38.34913 -406.723729) (xy 38.349133 -406.656422) (xy 38.35718 -406.589598)
			(xy 38.373155 -406.524215) (xy 38.39683 -406.461209) (xy 38.427865 -406.401484) (xy 38.465815 -406.345897)
			(xy 38.487604 -406.320244) (xy 38.493407 -406.313104) (xy 38.499918 -406.295909) (xy 38.500304 -406.286716)
			(xy 38.500304 -405.793448) (xy 38.49987 -405.784263) (xy 38.493373 -405.767079) (xy 38.487604 -405.75992)
			(xy 38.465813 -405.734271) (xy 38.427867 -405.678683) (xy 38.396836 -405.618959) (xy 38.373165 -405.555954)
			(xy 38.357193 -405.490572) (xy 38.34915 -405.423749) (xy 38.34915 -405.356445) (xy 38.357194 -405.289622)
			(xy 38.373167 -405.22424) (xy 38.396838 -405.161236) (xy 38.42787 -405.101512) (xy 38.465817 -405.045925)
			(xy 38.487604 -405.020272) (xy 38.493395 -405.013123) (xy 38.499913 -404.995935) (xy 38.500304 -404.986744)
			(xy 38.500304 -404.828756) (xy 38.500686 -404.818599) (xy 38.508497 -404.799844) (xy 38.522905 -404.785523)
			(xy 38.541706 -404.777825) (xy 38.551866 -404.777448) (xy 39.268146 -404.777448) (xy 39.278277 -404.777889)
			(xy 39.297 -404.785634) (xy 39.311355 -404.799934) (xy 39.319171 -404.818627) (xy 39.319708 -404.828756)
			(xy 39.319708 -404.986744) (xy 39.320095 -404.995934) (xy 39.326624 -405.013118) (xy 39.332408 -405.020272)
			(xy 39.354193 -405.045927) (xy 39.392146 -405.101512) (xy 39.423182 -405.161234) (xy 39.446858 -405.224239)
			(xy 39.462832 -405.289621) (xy 39.470878 -405.356444) (xy 39.470878 -405.42375) (xy 39.462833 -405.490573)
			(xy 39.446859 -405.555956) (xy 39.423185 -405.61896) (xy 39.420718 -405.623708) (xy 40.548756 -405.623708)
			(xy 40.548757 -405.556283) (xy 40.556834 -405.489343) (xy 40.572872 -405.423853) (xy 40.596639 -405.360756)
			(xy 40.627793 -405.30096) (xy 40.665886 -405.245326) (xy 40.687752 -405.219662) (xy 40.693554 -405.212521)
			(xy 40.700064 -405.195327) (xy 40.700452 -405.186134) (xy 40.700452 -404.693882) (xy 40.700039 -404.684695)
			(xy 40.693526 -404.667512) (xy 40.687752 -404.660354) (xy 40.665908 -404.634672) (xy 40.627815 -404.579041)
			(xy 40.59666 -404.519248) (xy 40.572893 -404.456153) (xy 40.556854 -404.390665) (xy 40.548776 -404.323728)
			(xy 40.548774 -404.256305) (xy 40.556848 -404.189367) (xy 40.572883 -404.123879) (xy 40.596647 -404.060783)
			(xy 40.627798 -404.000987) (xy 40.665888 -403.945354) (xy 40.687752 -403.91969) (xy 40.693542 -403.91254)
			(xy 40.700059 -403.895353) (xy 40.700452 -403.886162) (xy 40.700452 -403.728682) (xy 40.700912 -403.718553)
			(xy 40.708648 -403.699829) (xy 40.722942 -403.685473) (xy 40.741633 -403.677656) (xy 40.75176 -403.67712)
			(xy 41.46804 -403.67712) (xy 41.478199 -403.677489) (xy 41.496956 -403.685302) (xy 41.511279 -403.699715)
			(xy 41.518974 -403.71852) (xy 41.519348 -403.728682) (xy 41.519348 -403.886162) (xy 41.519788 -403.895346)
			(xy 41.526282 -403.91253) (xy 41.532048 -403.91969) (xy 41.553935 -403.945337) (xy 41.592027 -404.000973)
			(xy 41.62318 -404.060771) (xy 41.646945 -404.12387) (xy 41.66298 -404.189362) (xy 41.671055 -404.256303)
			(xy 41.671053 -404.32373) (xy 41.662974 -404.39067) (xy 41.646935 -404.456161) (xy 41.623166 -404.519259)
			(xy 41.59201 -404.579056) (xy 41.553915 -404.63469) (xy 41.532048 -404.660354) (xy 41.52624 -404.667491)
			(xy 41.519733 -404.684688) (xy 41.519348 -404.693882) (xy 41.519348 -405.186134) (xy 41.519754 -405.195321)
			(xy 41.526272 -405.212505) (xy 41.532048 -405.219662) (xy 41.553908 -405.245331) (xy 41.592 -405.300964)
			(xy 41.623154 -405.360759) (xy 41.646921 -405.423856) (xy 41.662958 -405.489345) (xy 41.671036 -405.556283)
			(xy 41.671036 -405.623708) (xy 41.66296 -405.690646) (xy 41.646924 -405.756136) (xy 41.623158 -405.819233)
			(xy 41.592005 -405.879028) (xy 41.553913 -405.934662) (xy 41.532048 -405.960326) (xy 41.526251 -405.967471)
			(xy 41.519738 -405.984662) (xy 41.519348 -405.993854) (xy 41.519348 -406.151334) (xy 41.518901 -406.161464)
			(xy 41.51116 -406.180189) (xy 41.496861 -406.194544) (xy 41.478168 -406.20236) (xy 41.46804 -406.202896)
			(xy 40.75176 -406.202896) (xy 40.741603 -406.202511) (xy 40.722849 -406.194701) (xy 40.708527 -406.180294)
			(xy 40.700829 -406.161494) (xy 40.700452 -406.151334) (xy 40.700452 -405.993854) (xy 40.700004 -405.984671)
			(xy 40.693515 -405.967487) (xy 40.687752 -405.960326) (xy 40.66588 -405.934667) (xy 40.627788 -405.879032)
			(xy 40.596635 -405.819236) (xy 40.572869 -405.756138) (xy 40.556832 -405.690648) (xy 40.548756 -405.623708)
			(xy 39.420718 -405.623708) (xy 39.392149 -405.678683) (xy 39.354197 -405.734269) (xy 39.332408 -405.75992)
			(xy 39.326621 -405.767072) (xy 39.3201 -405.784257) (xy 39.319708 -405.793448) (xy 39.319708 -406.286716)
			(xy 39.320109 -406.295904) (xy 39.326629 -406.313088) (xy 39.332408 -406.320244) (xy 39.354166 -406.345921)
			(xy 39.392119 -406.401503) (xy 39.423157 -406.461222) (xy 39.446834 -406.524224) (xy 39.46281 -406.589604)
			(xy 39.470858 -406.656424) (xy 39.470861 -406.723728) (xy 39.470854 -406.723789) (xy 42.748899 -406.723789)
			(xy 42.748901 -406.656363) (xy 42.756981 -406.589422) (xy 42.773019 -406.523932) (xy 42.796787 -406.460833)
			(xy 42.827942 -406.401036) (xy 42.866034 -406.345401) (xy 42.8879 -406.319736) (xy 42.893706 -406.312598)
			(xy 42.900215 -406.295402) (xy 42.9006 -406.286208) (xy 42.9006 -405.793956) (xy 42.900211 -405.784767)
			(xy 42.893683 -405.767582) (xy 42.8879 -405.760428) (xy 42.866032 -405.734766) (xy 42.827944 -405.679131)
			(xy 42.796793 -405.619334) (xy 42.773029 -405.556237) (xy 42.756994 -405.490748) (xy 42.748918 -405.423809)
			(xy 42.748919 -405.356385) (xy 42.756995 -405.289446) (xy 42.773031 -405.223957) (xy 42.796795 -405.16086)
			(xy 42.827947 -405.101064) (xy 42.866036 -405.045429) (xy 42.8879 -405.019764) (xy 42.893694 -405.012617)
			(xy 42.90021 -404.995428) (xy 42.9006 -404.986236) (xy 42.9006 -404.828756) (xy 42.901049 -404.818644)
			(xy 42.908801 -404.799965) (xy 42.923109 -404.785672) (xy 42.941796 -404.777939) (xy 42.951908 -404.777448)
			(xy 43.668188 -404.777448) (xy 43.67829 -404.777994) (xy 43.696958 -404.785718) (xy 43.711251 -404.799995)
			(xy 43.718995 -404.818655) (xy 43.719496 -404.828756) (xy 43.719496 -404.986236) (xy 43.71989 -404.995425)
			(xy 43.726415 -405.012609) (xy 43.732196 -405.019764) (xy 43.754056 -405.045432) (xy 43.792145 -405.101066)
			(xy 43.823296 -405.160862) (xy 43.847061 -405.223959) (xy 43.863097 -405.289447) (xy 43.871173 -405.356385)
			(xy 43.871173 -405.423809) (xy 43.863098 -405.490747) (xy 43.847063 -405.556236) (xy 43.823299 -405.619332)
			(xy 43.792148 -405.679128) (xy 43.75406 -405.734763) (xy 43.732196 -405.760428) (xy 43.726405 -405.767577)
			(xy 43.719887 -405.784765) (xy 43.719496 -405.793956) (xy 43.719496 -406.286208) (xy 43.719903 -406.295395)
			(xy 43.726419 -406.31258) (xy 43.732196 -406.319736) (xy 43.754029 -406.345427) (xy 43.792119 -406.401058)
			(xy 43.823271 -406.46085) (xy 43.847037 -406.523944) (xy 43.863075 -406.58943) (xy 43.871153 -406.656365)
			(xy 43.871156 -406.72373) (xy 47.149194 -406.72373) (xy 47.149197 -406.656422) (xy 47.157245 -406.589596)
			(xy 47.173223 -406.524212) (xy 47.196901 -406.461206) (xy 47.227941 -406.401481) (xy 47.265897 -406.345896)
			(xy 47.287688 -406.320244) (xy 47.293489 -406.313102) (xy 47.300002 -406.295909) (xy 47.300388 -406.286716)
			(xy 47.300388 -405.793448) (xy 47.299958 -405.784263) (xy 47.293458 -405.767078) (xy 47.287688 -405.75992)
			(xy 47.265895 -405.734272) (xy 47.227943 -405.678686) (xy 47.196907 -405.618962) (xy 47.173232 -405.555957)
			(xy 47.157258 -405.490574) (xy 47.149214 -405.42375) (xy 47.149214 -405.356444) (xy 47.157259 -405.28962)
			(xy 47.173234 -405.224237) (xy 47.19691 -405.161232) (xy 47.227946 -405.101509) (xy 47.265899 -405.045924)
			(xy 47.287688 -405.020272) (xy 47.293478 -405.013122) (xy 47.299997 -404.995935) (xy 47.300388 -404.986744)
			(xy 47.300388 -404.828756) (xy 47.300785 -404.818601) (xy 47.308593 -404.79985) (xy 47.322997 -404.785528)
			(xy 47.341792 -404.777828) (xy 47.35195 -404.777448) (xy 48.06823 -404.777448) (xy 48.07836 -404.777902)
			(xy 48.097083 -404.785641) (xy 48.111439 -404.799937) (xy 48.119255 -404.818629) (xy 48.119792 -404.828756)
			(xy 48.119792 -404.986744) (xy 48.120183 -404.995933) (xy 48.12671 -405.013117) (xy 48.132492 -405.020272)
			(xy 48.154275 -405.045928) (xy 48.192222 -405.101514) (xy 48.223254 -405.161238) (xy 48.246925 -405.224242)
			(xy 48.262897 -405.289623) (xy 48.270941 -405.356445) (xy 48.270942 -405.423749) (xy 48.262899 -405.490571)
			(xy 48.246927 -405.555952) (xy 48.223256 -405.618957) (xy 48.192225 -405.67868) (xy 48.154279 -405.734267)
			(xy 48.132492 -405.75992) (xy 48.126704 -405.767071) (xy 48.120184 -405.784257) (xy 48.119792 -405.793448)
			(xy 48.119792 -406.286716) (xy 48.120196 -406.295904) (xy 48.126714 -406.313088) (xy 48.132492 -406.320244)
			(xy 48.154247 -406.345922) (xy 48.192195 -406.401506) (xy 48.223228 -406.461226) (xy 48.246901 -406.524227)
			(xy 48.262876 -406.589606) (xy 48.270922 -406.656425) (xy 48.270925 -406.723727) (xy 48.262884 -406.790547)
			(xy 48.246916 -406.855927) (xy 48.223248 -406.91893) (xy 48.19222 -406.978653) (xy 48.154277 -407.034239)
			(xy 48.132492 -407.059892) (xy 48.126715 -407.067051) (xy 48.120189 -407.084231) (xy 48.119792 -407.09342)
			(xy 48.119792 -407.251408) (xy 48.119385 -407.261564) (xy 48.111585 -407.280318) (xy 48.097184 -407.294641)
			(xy 48.078388 -407.302339) (xy 48.06823 -407.302716) (xy 47.35195 -407.302716) (xy 47.341821 -407.302231)
			(xy 47.323093 -407.294512) (xy 47.308733 -407.280224) (xy 47.30092 -407.261534) (xy 47.300388 -407.251408)
			(xy 47.300388 -407.09342) (xy 47.299971 -407.084233) (xy 47.293462 -407.067049) (xy 47.287688 -407.059892)
			(xy 47.265867 -407.034266) (xy 47.227916 -406.978677) (xy 47.196882 -406.91895) (xy 47.173209 -406.855942)
			(xy 47.157236 -406.790556) (xy 47.149194 -406.72373) (xy 43.871156 -406.72373) (xy 43.871156 -406.723787)
			(xy 43.863084 -406.790723) (xy 43.847051 -406.85621) (xy 43.823291 -406.919306) (xy 43.792143 -406.979101)
			(xy 43.754058 -407.034735) (xy 43.732196 -407.0604) (xy 43.726416 -407.067557) (xy 43.719892 -407.084739)
			(xy 43.719496 -407.093928) (xy 43.719496 -407.251408) (xy 43.71909 -407.261531) (xy 43.711339 -407.280236)
			(xy 43.697019 -407.29455) (xy 43.678312 -407.302294) (xy 43.668188 -407.302716) (xy 42.951908 -407.302716)
			(xy 42.941802 -407.302209) (xy 42.923127 -407.294477) (xy 42.908832 -407.280187) (xy 42.901094 -407.261514)
			(xy 42.9006 -407.251408) (xy 42.9006 -407.093928) (xy 42.900176 -407.084742) (xy 42.893672 -407.067558)
			(xy 42.8879 -407.0604) (xy 42.866005 -407.034761) (xy 42.827917 -406.979122) (xy 42.796768 -406.919323)
			(xy 42.773005 -406.856222) (xy 42.756972 -406.79073) (xy 42.748899 -406.723789) (xy 39.470854 -406.723789)
			(xy 39.462819 -406.790549) (xy 39.446848 -406.85593) (xy 39.423176 -406.918933) (xy 39.392144 -406.978656)
			(xy 39.354195 -407.034241) (xy 39.332408 -407.059892) (xy 39.326633 -407.067053) (xy 39.320105 -407.084231)
			(xy 39.319708 -407.09342) (xy 39.319708 -407.251408) (xy 39.319285 -407.261562) (xy 39.311488 -407.280313)
			(xy 39.297092 -407.294635) (xy 39.278302 -407.302336) (xy 39.268146 -407.302716) (xy 38.551866 -407.302716)
			(xy 38.541732 -407.3023) (xy 38.523001 -407.294553) (xy 38.508645 -407.280245) (xy 38.500835 -407.261541)
			(xy 38.500304 -407.251408) (xy 38.500304 -407.09342) (xy 38.499883 -407.084234) (xy 38.493377 -407.06705)
			(xy 38.487604 -407.059892) (xy 38.465786 -407.034265) (xy 38.42784 -406.978674) (xy 38.39681 -406.918947)
			(xy 38.373141 -406.855939) (xy 38.357171 -406.790554) (xy 38.34913 -406.723729) (xy 35.071068 -406.723729)
			(xy 35.071068 -406.723786) (xy 35.062996 -406.790722) (xy 35.046964 -406.856209) (xy 35.023204 -406.919305)
			(xy 34.992058 -406.9791) (xy 34.953974 -407.034735) (xy 34.932112 -407.0604) (xy 34.926334 -407.067559)
			(xy 34.919808 -407.084739) (xy 34.919412 -407.093928) (xy 34.919412 -407.251408) (xy 34.918922 -407.261516)
			(xy 34.911184 -407.280192) (xy 34.896888 -407.294486) (xy 34.878212 -407.302222) (xy 34.868104 -407.302716)
			(xy 34.151824 -407.302716) (xy 34.141705 -407.302265) (xy 34.123005 -407.294528) (xy 34.10869 -407.280222)
			(xy 34.100941 -407.261527) (xy 34.100516 -407.251408) (xy 34.100516 -407.093928) (xy 34.100089 -407.084743)
			(xy 34.093586 -407.067558) (xy 34.087816 -407.0604) (xy 34.06592 -407.034761) (xy 34.027831 -406.979123)
			(xy 33.996681 -406.919323) (xy 33.972918 -406.856223) (xy 33.956884 -406.790731) (xy 33.948811 -406.723789)
			(xy 30.670766 -406.723789) (xy 30.662731 -406.790549) (xy 30.646761 -406.855929) (xy 30.62309 -406.918933)
			(xy 30.592058 -406.978655) (xy 30.554111 -407.03424) (xy 30.532324 -407.059892) (xy 30.526551 -407.067054)
			(xy 30.520022 -407.084232) (xy 30.519624 -407.09342) (xy 30.519624 -407.251408) (xy 30.519185 -407.26156)
			(xy 30.511392 -407.280307) (xy 30.497001 -407.29463) (xy 30.478216 -407.302333) (xy 30.468062 -407.302716)
			(xy 29.751782 -407.302716) (xy 29.741649 -407.302287) (xy 29.722919 -407.294545) (xy 29.708561 -407.280241)
			(xy 29.700751 -407.261539) (xy 29.70022 -407.251408) (xy 29.70022 -407.09342) (xy 29.699796 -407.084234)
			(xy 29.693291 -407.06705) (xy 29.68752 -407.059892) (xy 29.665701 -407.034265) (xy 29.627755 -406.978675)
			(xy 29.596724 -406.918948) (xy 29.573054 -406.85594) (xy 29.557084 -406.790555) (xy 29.549042 -406.72373)
			(xy 0.508 -406.72373) (xy 0.508 -409.523886) (xy 27.348881 -409.523886) (xy 27.348884 -409.45646)
			(xy 27.356963 -409.38952) (xy 27.373002 -409.324029) (xy 27.396769 -409.26093) (xy 27.427923 -409.201133)
			(xy 27.466015 -409.145498) (xy 27.48788 -409.119832) (xy 27.493686 -409.112693) (xy 27.500196 -409.095498)
			(xy 27.50058 -409.086304) (xy 27.50058 -408.594052) (xy 27.500149 -408.584867) (xy 27.49365 -408.567682)
			(xy 27.48788 -408.560524) (xy 27.466009 -408.534865) (xy 27.427922 -408.479229) (xy 27.396772 -408.419432)
			(xy 27.37301 -408.356334) (xy 27.356975 -408.290845) (xy 27.3489 -408.223906) (xy 27.348901 -408.156482)
			(xy 27.356977 -408.089544) (xy 27.373013 -408.024054) (xy 27.396777 -407.960957) (xy 27.427928 -407.901161)
			(xy 27.466016 -407.845526) (xy 27.48788 -407.81986) (xy 27.493674 -407.812713) (xy 27.500191 -407.795524)
			(xy 27.50058 -407.786332) (xy 27.50058 -407.628852) (xy 27.501045 -407.618743) (xy 27.508795 -407.600067)
			(xy 27.523098 -407.585775) (xy 27.541778 -407.578038) (xy 27.551888 -407.577544) (xy 28.268168 -407.577544)
			(xy 28.278268 -407.57811) (xy 28.296935 -407.585826) (xy 28.311229 -407.600098) (xy 28.318975 -407.618753)
			(xy 28.319476 -407.628852) (xy 28.319476 -407.786332) (xy 28.319876 -407.79552) (xy 28.326397 -407.812704)
			(xy 28.332176 -407.81986) (xy 28.354033 -407.845531) (xy 28.392123 -407.901164) (xy 28.423276 -407.96096)
			(xy 28.447042 -408.024056) (xy 28.463078 -408.089544) (xy 28.471155 -408.156482) (xy 28.471156 -408.223906)
			(xy 28.46308 -408.290844) (xy 28.447045 -408.356333) (xy 28.423281 -408.419429) (xy 28.39213 -408.479225)
			(xy 28.35404 -408.534859) (xy 28.332176 -408.560524) (xy 28.326384 -408.567672) (xy 28.319867 -408.584861)
			(xy 28.319476 -408.594052) (xy 28.319476 -409.086304) (xy 28.319889 -409.095491) (xy 28.326401 -409.112675)
			(xy 28.332176 -409.119832) (xy 28.354005 -409.145526) (xy 28.392097 -409.201156) (xy 28.42325 -409.260948)
			(xy 28.447018 -409.324041) (xy 28.463056 -409.389527) (xy 28.471135 -409.456462) (xy 28.471139 -409.523884)
			(xy 28.463066 -409.59082) (xy 28.447034 -409.656307) (xy 28.423273 -409.719403) (xy 28.392125 -409.779198)
			(xy 28.354039 -409.834831) (xy 28.332176 -409.860496) (xy 28.326396 -409.867653) (xy 28.319872 -409.884835)
			(xy 28.319476 -409.894024) (xy 28.319476 -410.051504) (xy 28.319087 -410.06163) (xy 28.311333 -410.080338)
			(xy 28.297008 -410.094653) (xy 28.278294 -410.102394) (xy 28.268168 -410.102812) (xy 27.551888 -410.102812)
			(xy 27.54178 -410.102325) (xy 27.523104 -410.094585) (xy 27.50881 -410.080289) (xy 27.501074 -410.061612)
			(xy 27.50058 -410.051504) (xy 27.50058 -409.894024) (xy 27.500163 -409.884837) (xy 27.493655 -409.867653)
			(xy 27.48788 -409.860496) (xy 27.465981 -409.83486) (xy 27.427895 -409.77922) (xy 27.396747 -409.71942)
			(xy 27.372986 -409.656319) (xy 27.356953 -409.590827) (xy 27.348881 -409.523886) (xy 0.508 -409.523886)
			(xy 0.508 -410.623641) (xy 29.549054 -410.623641) (xy 29.549055 -410.556335) (xy 29.5571 -410.489512)
			(xy 29.573074 -410.424129) (xy 29.596748 -410.361124) (xy 29.627782 -410.301399) (xy 29.665732 -410.245812)
			(xy 29.68752 -410.22016) (xy 29.693318 -410.213016) (xy 29.699831 -410.195825) (xy 29.70022 -410.186632)
			(xy 29.70022 -409.693364) (xy 29.699823 -409.684176) (xy 29.6933 -409.666992) (xy 29.68752 -409.659836)
			(xy 29.665745 -409.634174) (xy 29.627797 -409.578588) (xy 29.596764 -409.518866) (xy 29.573091 -409.455863)
			(xy 29.557118 -409.390482) (xy 29.549073 -409.323661) (xy 29.549072 -409.256357) (xy 29.557115 -409.189536)
			(xy 29.573086 -409.124154) (xy 29.596757 -409.06115) (xy 29.627787 -409.001427) (xy 29.665734 -408.94584)
			(xy 29.68752 -408.920188) (xy 29.693306 -408.913036) (xy 29.699827 -408.895851) (xy 29.70022 -408.88666)
			(xy 29.70022 -408.728672) (xy 29.700599 -408.718514) (xy 29.708408 -408.699757) (xy 29.722817 -408.685434)
			(xy 29.741621 -408.677738) (xy 29.751782 -408.677364) (xy 30.468062 -408.677364) (xy 30.478189 -408.677859)
			(xy 30.496914 -408.685578) (xy 30.511272 -408.699863) (xy 30.519089 -408.718547) (xy 30.519624 -408.728672)
			(xy 30.519624 -408.88666) (xy 30.520048 -408.895846) (xy 30.526551 -408.913031) (xy 30.532324 -408.920188)
			(xy 30.554125 -408.94583) (xy 30.592075 -409.001417) (xy 30.62311 -409.061142) (xy 30.646784 -409.124148)
			(xy 30.662757 -409.189531) (xy 30.670801 -409.256356) (xy 30.6708 -409.323662) (xy 30.662754 -409.390486)
			(xy 30.646779 -409.45587) (xy 30.623103 -409.518875) (xy 30.62053 -409.523827) (xy 31.749176 -409.523827)
			(xy 31.749179 -409.456519) (xy 31.757227 -409.389693) (xy 31.773205 -409.324309) (xy 31.796883 -409.261302)
			(xy 31.827922 -409.201578) (xy 31.865877 -409.145992) (xy 31.887668 -409.12034) (xy 31.893481 -409.113207)
			(xy 31.899984 -409.096007) (xy 31.900368 -409.086812) (xy 31.900368 -408.593544) (xy 31.899922 -408.584361)
			(xy 31.893432 -408.567177) (xy 31.887668 -408.560016) (xy 31.865872 -408.534371) (xy 31.827921 -408.478784)
			(xy 31.796887 -408.41906) (xy 31.773213 -408.356054) (xy 31.75724 -408.290671) (xy 31.749196 -408.223847)
			(xy 31.749197 -408.156541) (xy 31.757242 -408.089717) (xy 31.773217 -408.024334) (xy 31.796892 -407.961329)
			(xy 31.827927 -407.901606) (xy 31.865879 -407.84602) (xy 31.887668 -407.820368) (xy 31.893469 -407.813226)
			(xy 31.899979 -407.796033) (xy 31.900368 -407.78684) (xy 31.900368 -407.628852) (xy 31.900782 -407.618699)
			(xy 31.908587 -407.599952) (xy 31.922985 -407.585631) (xy 31.941775 -407.577927) (xy 31.95193 -407.577544)
			(xy 32.66821 -407.577544) (xy 32.678338 -407.578019) (xy 32.69706 -407.58575) (xy 32.711416 -407.60004)
			(xy 32.719234 -407.618727) (xy 32.719772 -407.628852) (xy 32.719772 -407.78684) (xy 32.720169 -407.796028)
			(xy 32.726693 -407.813212) (xy 32.732472 -407.820368) (xy 32.754252 -407.846027) (xy 32.7922 -407.901612)
			(xy 32.823233 -407.961335) (xy 32.846906 -408.024339) (xy 32.862879 -408.08972) (xy 32.870924 -408.156542)
			(xy 32.870924 -408.223846) (xy 32.862881 -408.290668) (xy 32.846909 -408.35605) (xy 32.823238 -408.419054)
			(xy 32.792206 -408.478777) (xy 32.754259 -408.534364) (xy 32.732472 -408.560016) (xy 32.726682 -408.567166)
			(xy 32.720164 -408.584353) (xy 32.719772 -408.593544) (xy 32.719772 -409.086812) (xy 32.720183 -409.095999)
			(xy 32.726697 -409.113183) (xy 32.732472 -409.12034) (xy 32.754224 -409.146022) (xy 32.792173 -409.201604)
			(xy 32.823207 -409.261324) (xy 32.846881 -409.324324) (xy 32.862857 -409.389703) (xy 32.870903 -409.456522)
			(xy 32.870907 -409.523824) (xy 32.862866 -409.590644) (xy 32.846897 -409.656024) (xy 32.823229 -409.719027)
			(xy 32.792201 -409.778749) (xy 32.754257 -409.834336) (xy 32.732472 -409.859988) (xy 32.726652 -409.867116)
			(xy 32.720152 -409.88432) (xy 32.719772 -409.893516) (xy 32.719772 -410.051504) (xy 32.719381 -410.061662)
			(xy 32.711579 -410.08042) (xy 32.697172 -410.094744) (xy 32.67837 -410.102438) (xy 32.66821 -410.102812)
			(xy 31.95193 -410.102812) (xy 31.941812 -410.102251) (xy 31.923101 -410.094542) (xy 31.908745 -410.080279)
			(xy 31.900916 -410.061619) (xy 31.900368 -410.051504) (xy 31.900368 -409.893516) (xy 31.899935 -409.884332)
			(xy 31.893436 -409.867148) (xy 31.887668 -409.859988) (xy 31.865844 -409.834366) (xy 31.827894 -409.778775)
			(xy 31.796861 -409.719048) (xy 31.773189 -409.65604) (xy 31.757217 -409.590654) (xy 31.749176 -409.523827)
			(xy 30.62053 -409.523827) (xy 30.592066 -409.578598) (xy 30.554113 -409.634184) (xy 30.532324 -409.659836)
			(xy 30.526532 -409.666985) (xy 30.520014 -409.684172) (xy 30.519624 -409.693364) (xy 30.519624 -410.186632)
			(xy 30.520014 -410.195821) (xy 30.526541 -410.213006) (xy 30.532324 -410.22016) (xy 30.554097 -410.245825)
			(xy 30.592049 -410.301408) (xy 30.623085 -410.36113) (xy 30.64676 -410.424133) (xy 30.662735 -410.489514)
			(xy 30.670781 -410.556336) (xy 30.670783 -410.62364) (xy 30.670776 -410.623701) (xy 33.948822 -410.623701)
			(xy 33.948823 -410.556275) (xy 33.956901 -410.489336) (xy 33.972939 -410.423846) (xy 33.996705 -410.360748)
			(xy 34.027859 -410.300951) (xy 34.065951 -410.245317) (xy 34.087816 -410.219652) (xy 34.093617 -410.21251)
			(xy 34.100129 -410.195317) (xy 34.100516 -410.186124) (xy 34.100516 -409.693872) (xy 34.100116 -409.684684)
			(xy 34.093595 -409.6675) (xy 34.087816 -409.660344) (xy 34.065963 -409.634669) (xy 34.027873 -409.579037)
			(xy 33.996721 -409.519242) (xy 33.972955 -409.456146) (xy 33.956919 -409.390658) (xy 33.948842 -409.323721)
			(xy 33.948841 -409.256297) (xy 33.956915 -409.18936) (xy 33.97295 -409.123871) (xy 33.996714 -409.060775)
			(xy 34.027864 -409.000979) (xy 34.065952 -408.945345) (xy 34.087816 -408.91968) (xy 34.093605 -408.91253)
			(xy 34.100124 -408.895343) (xy 34.100516 -408.886152) (xy 34.100516 -408.728672) (xy 34.100962 -408.718559)
			(xy 34.108712 -408.699878) (xy 34.123021 -408.685583) (xy 34.141711 -408.677852) (xy 34.151824 -408.677364)
			(xy 34.868104 -408.677364) (xy 34.878209 -408.677881) (xy 34.89688 -408.685613) (xy 34.911173 -408.6999)
			(xy 34.918914 -408.718568) (xy 34.919412 -408.728672) (xy 34.919412 -408.886152) (xy 34.919842 -408.895337)
			(xy 34.926342 -408.912522) (xy 34.932112 -408.91968) (xy 34.953987 -408.945336) (xy 34.992075 -409.000972)
			(xy 35.023224 -409.06077) (xy 35.046987 -409.123868) (xy 35.063022 -409.189358) (xy 35.071096 -409.256297)
			(xy 35.071095 -409.323721) (xy 35.063018 -409.39066) (xy 35.046982 -409.45615) (xy 35.023217 -409.519247)
			(xy 35.0208 -409.523886) (xy 36.148969 -409.523886) (xy 36.148972 -409.45646) (xy 36.157051 -409.38952)
			(xy 36.173089 -409.324029) (xy 36.196856 -409.260931) (xy 36.228009 -409.201134) (xy 36.266099 -409.145498)
			(xy 36.287964 -409.119832) (xy 36.29378 -409.112701) (xy 36.300281 -409.095499) (xy 36.300664 -409.086304)
			(xy 36.300664 -408.594052) (xy 36.300215 -408.584869) (xy 36.293727 -408.567685) (xy 36.287964 -408.560524)
			(xy 36.266093 -408.534865) (xy 36.228007 -408.479228) (xy 36.196859 -408.419431) (xy 36.173097 -408.356334)
			(xy 36.157063 -408.290844) (xy 36.148988 -408.223906) (xy 36.148989 -408.156482) (xy 36.157065 -408.089544)
			(xy 36.1731 -408.024055) (xy 36.196864 -407.960958) (xy 36.228014 -407.901161) (xy 36.266101 -407.845526)
			(xy 36.287964 -407.81986) (xy 36.293768 -407.81272) (xy 36.300276 -407.795525) (xy 36.300664 -407.786332)
			(xy 36.300664 -407.628852) (xy 36.301145 -407.618745) (xy 36.308892 -407.600072) (xy 36.323189 -407.585781)
			(xy 36.341864 -407.578041) (xy 36.351972 -407.577544) (xy 37.068252 -407.577544) (xy 37.078351 -407.578123)
			(xy 37.097017 -407.585835) (xy 37.111312 -407.600102) (xy 37.119058 -407.618754) (xy 37.11956 -407.628852)
			(xy 37.11956 -407.786332) (xy 37.119964 -407.79552) (xy 37.126483 -407.812703) (xy 37.13226 -407.81986)
			(xy 37.154118 -407.845531) (xy 37.192209 -407.901164) (xy 37.223362 -407.960959) (xy 37.247129 -408.024055)
			(xy 37.263166 -408.089544) (xy 37.271243 -408.156482) (xy 37.271244 -408.223906) (xy 37.263168 -408.290844)
			(xy 37.247132 -408.356333) (xy 37.223367 -408.41943) (xy 37.192215 -408.479226) (xy 37.154125 -408.534859)
			(xy 37.13226 -408.560524) (xy 37.126466 -408.567671) (xy 37.119951 -408.58486) (xy 37.11956 -408.594052)
			(xy 37.11956 -409.086304) (xy 37.119977 -409.09549) (xy 37.126487 -409.112674) (xy 37.13226 -409.119832)
			(xy 37.15409 -409.145526) (xy 37.192182 -409.201155) (xy 37.223337 -409.260947) (xy 37.247105 -409.32404)
			(xy 37.263144 -409.389526) (xy 37.271223 -409.456462) (xy 37.271227 -409.523884) (xy 37.263154 -409.59082)
			(xy 37.247121 -409.656308) (xy 37.223359 -409.719403) (xy 37.19221 -409.779198) (xy 37.154123 -409.834831)
			(xy 37.13226 -409.860496) (xy 37.126478 -409.867651) (xy 37.119955 -409.884834) (xy 37.11956 -409.894024)
			(xy 37.11956 -410.051504) (xy 37.119186 -410.061632) (xy 37.111429 -410.080343) (xy 37.097099 -410.094659)
			(xy 37.07838 -410.102396) (xy 37.068252 -410.102812) (xy 36.351972 -410.102812) (xy 36.341863 -410.102338)
			(xy 36.323186 -410.094594) (xy 36.308893 -410.080293) (xy 36.301157 -410.061613) (xy 36.300664 -410.051504)
			(xy 36.300664 -409.894024) (xy 36.300228 -409.88484) (xy 36.293731 -409.867656) (xy 36.287964 -409.860496)
			(xy 36.266066 -409.834859) (xy 36.227981 -409.77922) (xy 36.196834 -409.719419) (xy 36.173073 -409.656319)
			(xy 36.157041 -409.590827) (xy 36.148969 -409.523886) (xy 35.0208 -409.523886) (xy 34.992066 -409.579044)
			(xy 34.953976 -409.634679) (xy 34.932112 -409.660344) (xy 34.926316 -409.667489) (xy 34.9198 -409.68468)
			(xy 34.919412 -409.693872) (xy 34.919412 -410.186124) (xy 34.919808 -410.195313) (xy 34.926331 -410.212497)
			(xy 34.932112 -410.219652) (xy 34.95396 -410.24533) (xy 34.992048 -410.300963) (xy 35.023199 -410.360758)
			(xy 35.046964 -410.423853) (xy 35.063 -410.48934) (xy 35.071077 -410.556277) (xy 35.071078 -410.623641)
			(xy 38.349141 -410.623641) (xy 38.349143 -410.556335) (xy 38.357188 -410.489512) (xy 38.373162 -410.424129)
			(xy 38.396835 -410.361124) (xy 38.427868 -410.3014) (xy 38.465816 -410.245813) (xy 38.487604 -410.22016)
			(xy 38.493401 -410.213015) (xy 38.499915 -410.195824) (xy 38.500304 -410.186632) (xy 38.500304 -409.693364)
			(xy 38.49991 -409.684175) (xy 38.493385 -409.666991) (xy 38.487604 -409.659836) (xy 38.465829 -409.634174)
			(xy 38.427882 -409.578588) (xy 38.39685 -409.518865) (xy 38.373178 -409.455862) (xy 38.357206 -409.390482)
			(xy 38.349161 -409.323661) (xy 38.34916 -409.256357) (xy 38.357202 -409.189536) (xy 38.373173 -409.124155)
			(xy 38.396843 -409.061151) (xy 38.427873 -409.001428) (xy 38.465818 -408.945841) (xy 38.487604 -408.920188)
			(xy 38.493389 -408.913034) (xy 38.49991 -408.89585) (xy 38.500304 -408.88666) (xy 38.500304 -408.728672)
			(xy 38.500699 -408.718516) (xy 38.508504 -408.699762) (xy 38.522909 -408.685439) (xy 38.541707 -408.677741)
			(xy 38.551866 -408.677364) (xy 39.268146 -408.677364) (xy 39.278279 -408.67779) (xy 39.297005 -408.685537)
			(xy 39.311361 -408.699842) (xy 39.319174 -408.718541) (xy 39.319708 -408.728672) (xy 39.319708 -408.88666)
			(xy 39.320136 -408.895845) (xy 39.326637 -408.91303) (xy 39.332408 -408.920188) (xy 39.354209 -408.94583)
			(xy 39.392161 -409.001416) (xy 39.423197 -409.061141) (xy 39.446871 -409.124147) (xy 39.462845 -409.189531)
			(xy 39.470889 -409.256356) (xy 39.470888 -409.323663) (xy 39.462842 -409.390487) (xy 39.446866 -409.45587)
			(xy 39.423189 -409.518876) (xy 39.420585 -409.523887) (xy 40.548735 -409.523887) (xy 40.548738 -409.456459)
			(xy 40.556818 -409.389518) (xy 40.572859 -409.324026) (xy 40.59663 -409.260927) (xy 40.627788 -409.20113)
			(xy 40.665884 -409.145496) (xy 40.687752 -409.119832) (xy 40.693566 -409.1127) (xy 40.700069 -409.095499)
			(xy 40.700452 -409.086304) (xy 40.700452 -408.594052) (xy 40.700005 -408.584869) (xy 40.693516 -408.567685)
			(xy 40.687752 -408.560524) (xy 40.665878 -408.534866) (xy 40.627786 -408.479232) (xy 40.596633 -408.419435)
			(xy 40.572867 -408.356337) (xy 40.556831 -408.290847) (xy 40.548755 -408.223907) (xy 40.548755 -408.156481)
			(xy 40.556833 -408.089542) (xy 40.572871 -408.024051) (xy 40.596638 -407.960954) (xy 40.627793 -407.901158)
			(xy 40.665886 -407.845524) (xy 40.687752 -407.81986) (xy 40.693554 -407.812719) (xy 40.700064 -407.795525)
			(xy 40.700452 -407.786332) (xy 40.700452 -407.628852) (xy 40.700945 -407.618746) (xy 40.708689 -407.600076)
			(xy 40.722983 -407.585785) (xy 40.741654 -407.578043) (xy 40.75176 -407.577544) (xy 41.46804 -407.577544)
			(xy 41.478144 -407.578051) (xy 41.496813 -407.585791) (xy 41.511104 -407.600081) (xy 41.518847 -407.618748)
			(xy 41.519348 -407.628852) (xy 41.519348 -407.786332) (xy 41.519755 -407.795519) (xy 41.526272 -407.812703)
			(xy 41.532048 -407.81986) (xy 41.553906 -407.845531) (xy 41.591998 -407.901163) (xy 41.623152 -407.960958)
			(xy 41.646919 -408.024055) (xy 41.662957 -408.089543) (xy 41.671034 -408.156482) (xy 41.671035 -408.223906)
			(xy 41.662959 -408.290845) (xy 41.646923 -408.356334) (xy 41.623157 -408.419431) (xy 41.592004 -408.479226)
			(xy 41.553913 -408.53486) (xy 41.532048 -408.560524) (xy 41.526252 -408.56767) (xy 41.519739 -408.58486)
			(xy 41.519348 -408.594052) (xy 41.519348 -409.086304) (xy 41.519768 -409.09549) (xy 41.526276 -409.112674)
			(xy 41.532048 -409.119832) (xy 41.553878 -409.145526) (xy 41.591972 -409.201155) (xy 41.623127 -409.260947)
			(xy 41.646895 -409.32404) (xy 41.662935 -409.389526) (xy 41.671014 -409.456462) (xy 41.671018 -409.523884)
			(xy 41.662945 -409.590821) (xy 41.646911 -409.656308) (xy 41.623149 -409.719404) (xy 41.591999 -409.779199)
			(xy 41.553912 -409.834832) (xy 41.532048 -409.860496) (xy 41.526264 -409.86765) (xy 41.519743 -409.884834)
			(xy 41.519348 -409.894024) (xy 41.519348 -410.051504) (xy 41.518819 -410.061607) (xy 41.511089 -410.080276)
			(xy 41.496806 -410.094569) (xy 41.478143 -410.102312) (xy 41.46804 -410.102812) (xy 40.75176 -410.102812)
			(xy 40.74165 -410.102348) (xy 40.722973 -410.094599) (xy 40.70868 -410.080296) (xy 40.700945 -410.061614)
			(xy 40.700452 -410.051504) (xy 40.700452 -409.894024) (xy 40.700019 -409.884839) (xy 40.69352 -409.867655)
			(xy 40.687752 -409.860496) (xy 40.665851 -409.834861) (xy 40.62776 -409.779223) (xy 40.596608 -409.719423)
			(xy 40.572843 -409.656322) (xy 40.556809 -409.590829) (xy 40.548735 -409.523887) (xy 39.420585 -409.523887)
			(xy 39.392152 -409.578599) (xy 39.354198 -409.634185) (xy 39.332408 -409.659836) (xy 39.326615 -409.666984)
			(xy 39.320098 -409.684172) (xy 39.319708 -409.693364) (xy 39.319708 -410.186632) (xy 39.320101 -410.195821)
			(xy 39.326626 -410.213005) (xy 39.332408 -410.22016) (xy 39.354182 -410.245824) (xy 39.392134 -410.301408)
			(xy 39.423171 -410.361129) (xy 39.446847 -410.424132) (xy 39.462823 -410.489513) (xy 39.470869 -410.556336)
			(xy 39.470871 -410.62364) (xy 39.470864 -410.6237) (xy 42.74891 -410.6237) (xy 42.748911 -410.556276)
			(xy 42.756989 -410.489336) (xy 42.773026 -410.423846) (xy 42.796792 -410.360749) (xy 42.827944 -410.300952)
			(xy 42.866035 -410.245317) (xy 42.8879 -410.219652) (xy 42.893699 -410.212509) (xy 42.900212 -410.195317)
			(xy 42.9006 -410.186124) (xy 42.9006 -409.693872) (xy 42.900204 -409.684683) (xy 42.89368 -409.667499)
			(xy 42.8879 -409.660344) (xy 42.866048 -409.634669) (xy 42.827959 -409.579036) (xy 42.796808 -409.519241)
			(xy 42.773043 -409.456145) (xy 42.757006 -409.390658) (xy 42.74893 -409.32372) (xy 42.748928 -409.256298)
			(xy 42.757003 -409.18936) (xy 42.773037 -409.123872) (xy 42.7968 -409.060775) (xy 42.827949 -409.00098)
			(xy 42.866037 -408.945345) (xy 42.8879 -408.91968) (xy 42.893688 -408.912528) (xy 42.900208 -408.895343)
			(xy 42.9006 -408.886152) (xy 42.9006 -408.728672) (xy 42.901062 -408.718561) (xy 42.908809 -408.699883)
			(xy 42.923113 -408.685589) (xy 42.941797 -408.677855) (xy 42.951908 -408.677364) (xy 43.668188 -408.677364)
			(xy 43.678292 -408.677894) (xy 43.696963 -408.685621) (xy 43.711257 -408.699904) (xy 43.718998 -408.718569)
			(xy 43.719496 -408.728672) (xy 43.719496 -408.886152) (xy 43.71993 -408.895337) (xy 43.726427 -408.912521)
			(xy 43.732196 -408.91968) (xy 43.754072 -408.945335) (xy 43.792161 -409.000971) (xy 43.823311 -409.060769)
			(xy 43.847075 -409.123867) (xy 43.863109 -409.189357) (xy 43.871184 -409.256297) (xy 43.871183 -409.323721)
			(xy 43.863106 -409.390661) (xy 43.847069 -409.45615) (xy 43.823304 -409.519248) (xy 43.792151 -409.579044)
			(xy 43.754061 -409.634679) (xy 43.732196 -409.660344) (xy 43.726398 -409.667488) (xy 43.719884 -409.684679)
			(xy 43.719496 -409.693872) (xy 43.719496 -410.186124) (xy 43.719895 -410.195312) (xy 43.726417 -410.212497)
			(xy 43.732196 -410.219652) (xy 43.754044 -410.24533) (xy 43.792134 -410.300963) (xy 43.823285 -410.360757)
			(xy 43.847051 -410.423852) (xy 43.863087 -410.48934) (xy 43.871165 -410.556277) (xy 43.871166 -410.623642)
			(xy 47.149205 -410.623642) (xy 47.149207 -410.556334) (xy 47.157253 -410.48951) (xy 47.173229 -410.424126)
			(xy 47.196906 -410.361121) (xy 47.227944 -410.301397) (xy 47.265898 -410.245812) (xy 47.287688 -410.22016)
			(xy 47.293483 -410.213013) (xy 47.299999 -410.195824) (xy 47.300388 -410.186632) (xy 47.300388 -409.693364)
			(xy 47.299998 -409.684175) (xy 47.293471 -409.66699) (xy 47.287688 -409.659836) (xy 47.265911 -409.634175)
			(xy 47.227958 -409.578591) (xy 47.196922 -409.518869) (xy 47.173246 -409.455866) (xy 47.157271 -409.390484)
			(xy 47.149225 -409.323662) (xy 47.149224 -409.256357) (xy 47.157268 -409.189534) (xy 47.173241 -409.124152)
			(xy 47.196914 -409.061148) (xy 47.227949 -409.001425) (xy 47.2659 -408.945839) (xy 47.287688 -408.920188)
			(xy 47.293471 -408.913033) (xy 47.299994 -408.89585) (xy 47.300388 -408.88666) (xy 47.300388 -408.728672)
			(xy 47.300798 -408.718518) (xy 47.308601 -408.699767) (xy 47.323001 -408.685445) (xy 47.341793 -408.677744)
			(xy 47.35195 -408.677364) (xy 48.06823 -408.677364) (xy 48.078362 -408.677803) (xy 48.097088 -408.685545)
			(xy 48.111444 -408.699846) (xy 48.119258 -408.718542) (xy 48.119792 -408.728672) (xy 48.119792 -408.88666)
			(xy 48.120223 -408.895845) (xy 48.126722 -408.913029) (xy 48.132492 -408.920188) (xy 48.154291 -408.945831)
			(xy 48.192237 -409.001419) (xy 48.223268 -409.061145) (xy 48.246939 -409.12415) (xy 48.26291 -409.189533)
			(xy 48.270953 -409.256356) (xy 48.270952 -409.323662) (xy 48.262907 -409.390485) (xy 48.246933 -409.455867)
			(xy 48.223261 -409.518872) (xy 48.192228 -409.578596) (xy 48.15428 -409.634183) (xy 48.132492 -409.659836)
			(xy 48.126697 -409.666982) (xy 48.120182 -409.684172) (xy 48.119792 -409.693364) (xy 48.119792 -410.186632)
			(xy 48.120188 -410.195821) (xy 48.126712 -410.213005) (xy 48.132492 -410.22016) (xy 48.154263 -410.245825)
			(xy 48.19221 -410.301411) (xy 48.223243 -410.361133) (xy 48.246915 -410.424135) (xy 48.262888 -410.489516)
			(xy 48.270933 -410.556336) (xy 48.270934 -410.62364) (xy 48.262892 -410.690461) (xy 48.246922 -410.755842)
			(xy 48.223252 -410.818845) (xy 48.192223 -410.878569) (xy 48.154278 -410.934155) (xy 48.132492 -410.959808)
			(xy 48.126709 -410.966963) (xy 48.120186 -410.984146) (xy 48.119792 -410.993336) (xy 48.119792 -411.151324)
			(xy 48.119398 -411.161481) (xy 48.111593 -411.180235) (xy 48.097188 -411.194558) (xy 48.078389 -411.202255)
			(xy 48.06823 -411.202632) (xy 47.35195 -411.202632) (xy 47.341823 -411.202132) (xy 47.323098 -411.194415)
			(xy 47.308739 -411.180132) (xy 47.300923 -411.161448) (xy 47.300388 -411.151324) (xy 47.300388 -410.993336)
			(xy 47.299963 -410.98415) (xy 47.29346 -410.966966) (xy 47.287688 -410.959808) (xy 47.265883 -410.934169)
			(xy 47.227932 -410.878582) (xy 47.196896 -410.818857) (xy 47.173222 -410.755851) (xy 47.157249 -410.690466)
			(xy 47.149205 -410.623642) (xy 43.871166 -410.623642) (xy 43.871166 -410.623699) (xy 43.863092 -410.690636)
			(xy 43.847058 -410.756125) (xy 43.823295 -410.819221) (xy 43.792146 -410.879017) (xy 43.754059 -410.934651)
			(xy 43.732196 -410.960316) (xy 43.72641 -410.967468) (xy 43.719889 -410.984653) (xy 43.719496 -410.993844)
			(xy 43.719496 -411.151324) (xy 43.719035 -411.161435) (xy 43.711288 -411.180114) (xy 43.696984 -411.194408)
			(xy 43.678299 -411.202142) (xy 43.668188 -411.202632) (xy 42.951908 -411.202632) (xy 42.941804 -411.202109)
			(xy 42.923132 -411.19438) (xy 42.908838 -411.180095) (xy 42.901097 -411.161428) (xy 42.9006 -411.151324)
			(xy 42.9006 -410.993844) (xy 42.900169 -410.984659) (xy 42.89367 -410.967474) (xy 42.8879 -410.960316)
			(xy 42.86602 -410.934664) (xy 42.827932 -410.879027) (xy 42.796782 -410.819229) (xy 42.773019 -410.756131)
			(xy 42.756984 -410.69064) (xy 42.74891 -410.6237) (xy 39.470864 -410.6237) (xy 39.462827 -410.690463)
			(xy 39.446854 -410.755845) (xy 39.423181 -410.818849) (xy 39.392147 -410.878572) (xy 39.354196 -410.934157)
			(xy 39.332408 -410.959808) (xy 39.326626 -410.966964) (xy 39.320103 -410.984146) (xy 39.319708 -410.993336)
			(xy 39.319708 -411.151324) (xy 39.319298 -411.161479) (xy 39.311496 -411.18023) (xy 39.297096 -411.194552)
			(xy 39.278303 -411.202253) (xy 39.268146 -411.202632) (xy 38.551866 -411.202632) (xy 38.541734 -411.202201)
			(xy 38.523006 -411.194456) (xy 38.50865 -411.180153) (xy 38.500837 -411.161454) (xy 38.500304 -411.151324)
			(xy 38.500304 -410.993336) (xy 38.499876 -410.984151) (xy 38.493375 -410.966966) (xy 38.487604 -410.959808)
			(xy 38.465802 -410.934168) (xy 38.427856 -410.878579) (xy 38.396825 -410.818854) (xy 38.373155 -410.755848)
			(xy 38.357184 -410.690464) (xy 38.349141 -410.623641) (xy 35.071078 -410.623641) (xy 35.071078 -410.623699)
			(xy 35.063004 -410.690636) (xy 35.046971 -410.756124) (xy 35.023209 -410.81922) (xy 34.992061 -410.879016)
			(xy 34.953975 -410.934651) (xy 34.932112 -410.960316) (xy 34.926328 -410.96747) (xy 34.919805 -410.984654)
			(xy 34.919412 -410.993844) (xy 34.919412 -411.151324) (xy 34.918935 -411.161433) (xy 34.911192 -411.180109)
			(xy 34.896893 -411.194403) (xy 34.878213 -411.202139) (xy 34.868104 -411.202632) (xy 34.151824 -411.202632)
			(xy 34.141721 -411.202096) (xy 34.123049 -411.194372) (xy 34.108755 -411.180091) (xy 34.101013 -411.161427)
			(xy 34.100516 -411.151324) (xy 34.100516 -410.993844) (xy 34.100081 -410.98466) (xy 34.093584 -410.967475)
			(xy 34.087816 -410.960316) (xy 34.065936 -410.934664) (xy 34.027846 -410.879028) (xy 33.996696 -410.81923)
			(xy 33.972932 -410.756131) (xy 33.956897 -410.690641) (xy 33.948822 -410.623701) (xy 30.670776 -410.623701)
			(xy 30.66274 -410.690462) (xy 30.646767 -410.755844) (xy 30.623095 -410.818848) (xy 30.592061 -410.878571)
			(xy 30.554112 -410.934156) (xy 30.532324 -410.959808) (xy 30.526544 -410.966965) (xy 30.520019 -410.984146)
			(xy 30.519624 -410.993336) (xy 30.519624 -411.151324) (xy 30.519199 -411.161477) (xy 30.5114 -411.180225)
			(xy 30.497005 -411.194547) (xy 30.478217 -411.20225) (xy 30.468062 -411.202632) (xy 29.751782 -411.202632)
			(xy 29.741651 -411.202188) (xy 29.722924 -411.194449) (xy 29.708567 -411.180149) (xy 29.700753 -411.161453)
			(xy 29.70022 -411.151324) (xy 29.70022 -410.993336) (xy 29.699788 -410.984151) (xy 29.693289 -410.966967)
			(xy 29.68752 -410.959808) (xy 29.665717 -410.934169) (xy 29.62777 -410.87858) (xy 29.596738 -410.818854)
			(xy 29.573067 -410.755848) (xy 29.557096 -410.690465) (xy 29.549054 -410.623641) (xy 0.508 -410.623641)
			(xy 0.508 -416.589972) (xy 0.508522 -416.645779) (xy 0.516863 -416.757081) (xy 0.533498 -416.867448)
			(xy 0.558335 -416.976264) (xy 0.591234 -417.082919) (xy 0.632011 -417.186818) (xy 0.680438 -417.287379)
			(xy 0.681656 -417.289488) (xy 53.073808 -417.289488) (xy 53.073808 -394.27912) (xy 66.477388 -394.27912)
			(xy 66.525648 -394.32738) (xy 66.525648 -397.823885) (xy 71.348788 -397.823885) (xy 71.348792 -397.756458)
			(xy 71.356871 -397.689518) (xy 71.372911 -397.624026) (xy 71.396679 -397.560928) (xy 71.427833 -397.501131)
			(xy 71.465926 -397.445495) (xy 71.487792 -397.41983) (xy 71.4936 -397.412693) (xy 71.500108 -397.395496)
			(xy 71.500492 -397.386302) (xy 71.500492 -396.89405) (xy 71.50006 -396.884865) (xy 71.493562 -396.86768)
			(xy 71.487792 -396.860522) (xy 71.465918 -396.834865) (xy 71.427831 -396.779229) (xy 71.396681 -396.719431)
			(xy 71.372918 -396.656334) (xy 71.356883 -396.590844) (xy 71.348808 -396.523905) (xy 71.348809 -396.45648)
			(xy 71.356886 -396.389542) (xy 71.372922 -396.324052) (xy 71.396687 -396.260955) (xy 71.427838 -396.201158)
			(xy 71.465928 -396.145523) (xy 71.487792 -396.119858) (xy 71.493588 -396.112712) (xy 71.500103 -396.095522)
			(xy 71.500492 -396.08633) (xy 71.500492 -395.92885) (xy 71.501066 -395.918732) (xy 71.508769 -395.900021)
			(xy 71.523028 -395.885665) (xy 71.541686 -395.877836) (xy 71.5518 -395.877288) (xy 72.26808 -395.877288)
			(xy 72.278231 -395.877738) (xy 72.296981 -395.885524) (xy 72.311305 -395.899912) (xy 72.319007 -395.918697)
			(xy 72.319388 -395.92885) (xy 72.319388 -396.08633) (xy 72.319786 -396.095518) (xy 72.326308 -396.112703)
			(xy 72.332088 -396.119858) (xy 72.353943 -396.145531) (xy 72.392032 -396.201164) (xy 72.423184 -396.260959)
			(xy 72.446949 -396.324055) (xy 72.462986 -396.389543) (xy 72.471063 -396.456481) (xy 72.471064 -396.523904)
			(xy 72.462989 -396.590842) (xy 72.446954 -396.656331) (xy 72.42319 -396.719427) (xy 72.39204 -396.779223)
			(xy 72.353952 -396.834857) (xy 72.332088 -396.860522) (xy 72.326298 -396.867672) (xy 72.31978 -396.884859)
			(xy 72.319388 -396.89405) (xy 72.319388 -397.386302) (xy 72.3198 -397.395489) (xy 72.326313 -397.412673)
			(xy 72.332088 -397.41983) (xy 72.353915 -397.445526) (xy 72.392006 -397.501156) (xy 72.420766 -397.556355)
			(xy 73.54898 -397.556355) (xy 73.557023 -397.489534) (xy 73.572995 -397.424152) (xy 73.596666 -397.361148)
			(xy 73.627698 -397.301425) (xy 73.665645 -397.245838) (xy 73.687432 -397.220186) (xy 73.693221 -397.213036)
			(xy 73.69974 -397.195849) (xy 73.700132 -397.186658) (xy 73.700132 -397.028924) (xy 73.700542 -397.018767)
			(xy 73.708335 -397.000009) (xy 73.722736 -396.985684) (xy 73.741535 -396.977989) (xy 73.751694 -396.977616)
			(xy 74.467974 -396.977616) (xy 74.478096 -396.978147) (xy 74.496812 -396.985862) (xy 74.511169 -397.000134)
			(xy 74.518993 -397.018805) (xy 74.519536 -397.028924) (xy 74.519536 -397.186658) (xy 74.519981 -397.195841)
			(xy 74.526472 -397.213025) (xy 74.532236 -397.220186) (xy 74.554034 -397.24583) (xy 74.591984 -397.301417)
			(xy 74.623019 -397.361141) (xy 74.646692 -397.424147) (xy 74.662665 -397.48953) (xy 74.670709 -397.556354)
			(xy 74.670708 -397.623661) (xy 74.662662 -397.690484) (xy 74.646687 -397.755867) (xy 74.623012 -397.818872)
			(xy 74.620438 -397.823826) (xy 75.749084 -397.823826) (xy 75.749087 -397.756517) (xy 75.757136 -397.689691)
			(xy 75.773114 -397.624306) (xy 75.796793 -397.5613) (xy 75.827833 -397.501576) (xy 75.865789 -397.44599)
			(xy 75.88758 -397.420338) (xy 75.893383 -397.413197) (xy 75.899895 -397.396003) (xy 75.90028 -397.38681)
			(xy 75.90028 -396.893542) (xy 75.899854 -396.884356) (xy 75.893352 -396.867172) (xy 75.88758 -396.860014)
			(xy 75.865781 -396.83437) (xy 75.82783 -396.778784) (xy 75.796795 -396.719059) (xy 75.773121 -396.656054)
			(xy 75.757147 -396.59067) (xy 75.749104 -396.523846) (xy 75.749104 -396.456539) (xy 75.75715 -396.389715)
			(xy 75.773125 -396.324332) (xy 75.796801 -396.261327) (xy 75.827838 -396.201603) (xy 75.86579 -396.146018)
			(xy 75.88758 -396.120366) (xy 75.893371 -396.113217) (xy 75.89989 -396.096029) (xy 75.90028 -396.086838)
			(xy 75.90028 -395.92885) (xy 75.900706 -395.918676) (xy 75.908482 -395.899875) (xy 75.922868 -395.885487)
			(xy 75.941668 -395.877707) (xy 75.951842 -395.877288) (xy 76.668122 -395.877288) (xy 76.678301 -395.877647)
			(xy 76.697106 -395.885449) (xy 76.711492 -395.899855) (xy 76.719267 -395.91867) (xy 76.719684 -395.92885)
			(xy 76.719684 -396.086838) (xy 76.720079 -396.096027) (xy 76.726604 -396.113211) (xy 76.732384 -396.120366)
			(xy 76.754161 -396.146026) (xy 76.792109 -396.201612) (xy 76.823141 -396.261335) (xy 76.846814 -396.324338)
			(xy 76.862787 -396.389719) (xy 76.870831 -396.456541) (xy 76.870832 -396.523844) (xy 76.862789 -396.590666)
			(xy 76.846818 -396.656047) (xy 76.823147 -396.719051) (xy 76.792117 -396.778775) (xy 76.75417 -396.834362)
			(xy 76.732384 -396.860014) (xy 76.726597 -396.867166) (xy 76.720077 -396.884351) (xy 76.719684 -396.893542)
			(xy 76.719684 -397.38681) (xy 76.720093 -397.395997) (xy 76.726608 -397.413181) (xy 76.732384 -397.420338)
			(xy 76.754133 -397.446021) (xy 76.792082 -397.501604) (xy 76.820503 -397.556296) (xy 77.948748 -397.556296)
			(xy 77.956824 -397.489358) (xy 77.972859 -397.423869) (xy 77.996623 -397.360772) (xy 78.027774 -397.300977)
			(xy 78.065864 -397.245343) (xy 78.087728 -397.219678) (xy 78.09352 -397.21253) (xy 78.100037 -397.195341)
			(xy 78.100428 -397.18615) (xy 78.100428 -397.028924) (xy 78.100836 -397.0188) (xy 78.108582 -397.000091)
			(xy 78.122901 -396.985775) (xy 78.141611 -396.978034) (xy 78.151736 -396.977616) (xy 78.868016 -396.977616)
			(xy 78.878142 -396.978003) (xy 78.896849 -396.985759) (xy 78.911163 -397.000085) (xy 78.918905 -397.018798)
			(xy 78.919324 -397.028924) (xy 78.919324 -397.18615) (xy 78.919753 -397.195335) (xy 78.926253 -397.21252)
			(xy 78.932024 -397.219678) (xy 78.953897 -397.245336) (xy 78.991984 -397.300972) (xy 79.023133 -397.360769)
			(xy 79.046895 -397.423867) (xy 79.062929 -397.489357) (xy 79.071004 -397.556296) (xy 79.071003 -397.62372)
			(xy 79.062927 -397.690658) (xy 79.046891 -397.756147) (xy 79.023127 -397.819245) (xy 79.02071 -397.823885)
			(xy 80.148876 -397.823885) (xy 80.14888 -397.756458) (xy 80.156959 -397.689518) (xy 80.172998 -397.624027)
			(xy 80.196765 -397.560929) (xy 80.227919 -397.501131) (xy 80.266011 -397.445496) (xy 80.287876 -397.41983)
			(xy 80.293682 -397.412691) (xy 80.300192 -397.395496) (xy 80.300576 -397.386302) (xy 80.300576 -396.89405)
			(xy 80.300147 -396.884865) (xy 80.293647 -396.86768) (xy 80.287876 -396.860522) (xy 80.266003 -396.834864)
			(xy 80.227916 -396.779228) (xy 80.196767 -396.719431) (xy 80.173005 -396.656333) (xy 80.156971 -396.590843)
			(xy 80.148896 -396.523904) (xy 80.148897 -396.45648) (xy 80.156973 -396.389542) (xy 80.173009 -396.324053)
			(xy 80.196773 -396.260955) (xy 80.227924 -396.201159) (xy 80.266012 -396.145524) (xy 80.287876 -396.119858)
			(xy 80.29367 -396.112711) (xy 80.300187 -396.095522) (xy 80.300576 -396.08633) (xy 80.300576 -395.92885)
			(xy 80.301069 -395.918722) (xy 80.308787 -395.899995) (xy 80.323072 -395.885636) (xy 80.341759 -395.877821)
			(xy 80.351884 -395.877288) (xy 81.068164 -395.877288) (xy 81.078314 -395.877751) (xy 81.097063 -395.885532)
			(xy 81.111388 -395.899917) (xy 81.119091 -395.918698) (xy 81.119472 -395.92885) (xy 81.119472 -396.08633)
			(xy 81.119874 -396.095518) (xy 81.126394 -396.112702) (xy 81.132172 -396.119858) (xy 81.154027 -396.145531)
			(xy 81.192118 -396.201164) (xy 81.223271 -396.260959) (xy 81.247037 -396.324054) (xy 81.263074 -396.389543)
			(xy 81.271151 -396.456481) (xy 81.271152 -396.523904) (xy 81.263076 -396.590842) (xy 81.247041 -396.656331)
			(xy 81.223277 -396.719428) (xy 81.192126 -396.779223) (xy 81.154036 -396.834857) (xy 81.132172 -396.860522)
			(xy 81.12638 -396.86767) (xy 81.119863 -396.884859) (xy 81.119472 -396.89405) (xy 81.119472 -397.386302)
			(xy 81.119887 -397.395489) (xy 81.126398 -397.412673) (xy 81.132172 -397.41983) (xy 81.154 -397.445526)
			(xy 81.192091 -397.501155) (xy 81.220853 -397.556356) (xy 82.349068 -397.556356) (xy 82.357111 -397.489534)
			(xy 82.373082 -397.424153) (xy 82.396753 -397.361149) (xy 82.427783 -397.301425) (xy 82.46573 -397.245838)
			(xy 82.487516 -397.220186) (xy 82.493303 -397.213034) (xy 82.499823 -397.195849) (xy 82.500216 -397.186658)
			(xy 82.500216 -397.028924) (xy 82.500641 -397.018769) (xy 82.508432 -397.000014) (xy 82.522828 -396.98569)
			(xy 82.541621 -396.977992) (xy 82.551778 -396.977616) (xy 83.268058 -396.977616) (xy 83.278179 -396.97816)
			(xy 83.296895 -396.98587) (xy 83.311252 -397.000138) (xy 83.319076 -397.018806) (xy 83.31962 -397.028924)
			(xy 83.31962 -397.186658) (xy 83.320046 -397.195844) (xy 83.326548 -397.213028) (xy 83.33232 -397.220186)
			(xy 83.354119 -397.24583) (xy 83.39207 -397.301416) (xy 83.423105 -397.361141) (xy 83.446779 -397.424146)
			(xy 83.462753 -397.48953) (xy 83.470796 -397.556354) (xy 83.470796 -397.623661) (xy 83.46275 -397.690485)
			(xy 83.446775 -397.755868) (xy 83.423099 -397.818873) (xy 83.420495 -397.823884) (xy 84.548667 -397.823884)
			(xy 84.548671 -397.756458) (xy 84.55675 -397.689518) (xy 84.572788 -397.624028) (xy 84.596555 -397.560929)
			(xy 84.627708 -397.501132) (xy 84.665799 -397.445496) (xy 84.687664 -397.41983) (xy 84.693481 -397.412699)
			(xy 84.699982 -397.395497) (xy 84.700364 -397.386302) (xy 84.700364 -396.89405) (xy 84.699916 -396.884867)
			(xy 84.693427 -396.867683) (xy 84.687664 -396.860522) (xy 84.665791 -396.834864) (xy 84.627705 -396.779228)
			(xy 84.596557 -396.71943) (xy 84.572795 -396.656332) (xy 84.556761 -396.590843) (xy 84.548687 -396.523904)
			(xy 84.548688 -396.456481) (xy 84.556764 -396.389542) (xy 84.5728 -396.324053) (xy 84.596563 -396.260956)
			(xy 84.627713 -396.201159) (xy 84.665801 -396.145524) (xy 84.687664 -396.119858) (xy 84.693469 -396.112719)
			(xy 84.699977 -396.095523) (xy 84.700364 -396.08633) (xy 84.700364 -395.92885) (xy 84.700868 -395.918724)
			(xy 84.708584 -395.899999) (xy 84.722866 -395.88564) (xy 84.741548 -395.877823) (xy 84.751672 -395.877288)
			(xy 85.467952 -395.877288) (xy 85.478102 -395.877761) (xy 85.496851 -395.885538) (xy 85.511175 -395.899919)
			(xy 85.518879 -395.918699) (xy 85.51926 -395.92885) (xy 85.51926 -396.08633) (xy 85.519665 -396.095518)
			(xy 85.526183 -396.112701) (xy 85.53196 -396.119858) (xy 85.553816 -396.145531) (xy 85.591907 -396.201163)
			(xy 85.623061 -396.260958) (xy 85.646827 -396.324054) (xy 85.662864 -396.389543) (xy 85.670942 -396.456481)
			(xy 85.670943 -396.523904) (xy 85.662867 -396.590843) (xy 85.646832 -396.656332) (xy 85.623067 -396.719428)
			(xy 85.591915 -396.779224) (xy 85.553825 -396.834857) (xy 85.53196 -396.860522) (xy 85.526167 -396.867669)
			(xy 85.519651 -396.884858) (xy 85.51926 -396.89405) (xy 85.51926 -397.386302) (xy 85.519678 -397.395488)
			(xy 85.526187 -397.412672) (xy 85.53196 -397.41983) (xy 85.553788 -397.445525) (xy 85.591881 -397.501155)
			(xy 85.620612 -397.556296) (xy 86.748836 -397.556296) (xy 86.756911 -397.489358) (xy 86.772946 -397.423869)
			(xy 86.79671 -397.360773) (xy 86.82786 -397.300977) (xy 86.865948 -397.245343) (xy 86.887812 -397.219678)
			(xy 86.893602 -397.212528) (xy 86.90012 -397.195341) (xy 86.900512 -397.18615) (xy 86.900512 -397.028924)
			(xy 86.900936 -397.018802) (xy 86.908678 -397.000096) (xy 86.922993 -396.985781) (xy 86.941698 -396.978037)
			(xy 86.95182 -396.977616) (xy 87.6681 -396.977616) (xy 87.678224 -396.978016) (xy 87.696931 -396.985768)
			(xy 87.711246 -397.000089) (xy 87.718988 -397.018799) (xy 87.719408 -397.028924) (xy 87.719408 -397.18615)
			(xy 87.71984 -397.195335) (xy 87.726338 -397.21252) (xy 87.732108 -397.219678) (xy 87.753982 -397.245335)
			(xy 87.792069 -397.300971) (xy 87.823219 -397.360769) (xy 87.846982 -397.423866) (xy 87.863017 -397.489356)
			(xy 87.871092 -397.556295) (xy 87.871091 -397.62372) (xy 87.863014 -397.690658) (xy 87.846978 -397.756148)
			(xy 87.823213 -397.819245) (xy 87.820827 -397.823826) (xy 88.948962 -397.823826) (xy 88.948966 -397.756517)
			(xy 88.957014 -397.689692) (xy 88.972991 -397.624307) (xy 88.996669 -397.561301) (xy 89.027707 -397.501577)
			(xy 89.065661 -397.44599) (xy 89.087452 -397.420338) (xy 89.093264 -397.413204) (xy 89.099768 -397.396005)
			(xy 89.100152 -397.38681) (xy 89.100152 -396.893542) (xy 89.09971 -396.884358) (xy 89.093217 -396.867175)
			(xy 89.087452 -396.860014) (xy 89.065654 -396.83437) (xy 89.027704 -396.778783) (xy 88.996671 -396.719058)
			(xy 88.972998 -396.656053) (xy 88.957025 -396.590669) (xy 88.948982 -396.523846) (xy 88.948983 -396.456539)
			(xy 88.957028 -396.389716) (xy 88.973003 -396.324333) (xy 88.996677 -396.261328) (xy 89.027712 -396.201604)
			(xy 89.065663 -396.146018) (xy 89.087452 -396.120366) (xy 89.093252 -396.113223) (xy 89.099763 -396.096031)
			(xy 89.100152 -396.086838) (xy 89.100152 -395.92885) (xy 89.100605 -395.91868) (xy 89.108376 -395.899884)
			(xy 89.122753 -395.885496) (xy 89.141544 -395.877712) (xy 89.151714 -395.877288) (xy 89.867994 -395.877288)
			(xy 89.878171 -395.87767) (xy 89.896976 -395.885462) (xy 89.911362 -395.899861) (xy 89.919139 -395.918672)
			(xy 89.919556 -395.92885) (xy 89.919556 -396.086838) (xy 89.919958 -396.096026) (xy 89.926478 -396.11321)
			(xy 89.932256 -396.120366) (xy 89.954034 -396.146026) (xy 89.991983 -396.201611) (xy 90.023017 -396.261334)
			(xy 90.046691 -396.324337) (xy 90.062665 -396.389719) (xy 90.07071 -396.45654) (xy 90.070711 -396.523845)
			(xy 90.062667 -396.590667) (xy 90.046695 -396.656048) (xy 90.023023 -396.719052) (xy 89.991991 -396.778776)
			(xy 89.954043 -396.834362) (xy 89.932256 -396.860014) (xy 89.926465 -396.867163) (xy 89.919948 -396.884351)
			(xy 89.919556 -396.893542) (xy 89.919556 -397.38681) (xy 89.919971 -397.395996) (xy 89.926482 -397.41318)
			(xy 89.932256 -397.420338) (xy 89.954006 -397.446021) (xy 89.991957 -397.501603) (xy 90.020411 -397.556356)
			(xy 91.149156 -397.556356) (xy 91.157198 -397.489535) (xy 91.173169 -397.424153) (xy 91.196839 -397.361149)
			(xy 91.227869 -397.301426) (xy 91.265814 -397.245839) (xy 91.2876 -397.220186) (xy 91.293385 -397.213033)
			(xy 91.299907 -397.195848) (xy 91.3003 -397.186658) (xy 91.3003 -397.028924) (xy 91.300741 -397.018771)
			(xy 91.308529 -397.000019) (xy 91.32292 -396.985695) (xy 91.341708 -396.977995) (xy 91.351862 -396.977616)
			(xy 92.068142 -396.977616) (xy 92.078268 -396.978091) (xy 92.096986 -396.985829) (xy 92.11134 -397.000118)
			(xy 92.119162 -397.0188) (xy 92.119704 -397.028924) (xy 92.119704 -397.186658) (xy 92.120133 -397.195843)
			(xy 92.126634 -397.213028) (xy 92.132404 -397.220186) (xy 92.1542 -397.245831) (xy 92.192146 -397.301419)
			(xy 92.223176 -397.361144) (xy 92.246847 -397.42415) (xy 92.262818 -397.489532) (xy 92.27086 -397.556355)
			(xy 92.270859 -397.62366) (xy 92.262815 -397.690483) (xy 92.246842 -397.755865) (xy 92.22317 -397.81887)
			(xy 92.220595 -397.823825) (xy 115.349226 -397.823825) (xy 115.349229 -397.756518) (xy 115.357277 -397.689693)
			(xy 115.373253 -397.624309) (xy 115.396928 -397.561303) (xy 115.427964 -397.501578) (xy 115.465915 -397.445991)
			(xy 115.487704 -397.420338) (xy 115.49351 -397.413199) (xy 115.500019 -397.396004) (xy 115.500404 -397.38681)
			(xy 115.500404 -396.893542) (xy 115.499973 -396.884357) (xy 115.493474 -396.867173) (xy 115.487704 -396.860014)
			(xy 115.465908 -396.834369) (xy 115.427961 -396.778781) (xy 115.39693 -396.719056) (xy 115.37326 -396.656051)
			(xy 115.357288 -396.590668) (xy 115.349246 -396.523845) (xy 115.349247 -396.45654) (xy 115.357291 -396.389717)
			(xy 115.373264 -396.324335) (xy 115.396937 -396.26133) (xy 115.427969 -396.201606) (xy 115.465917 -396.146019)
			(xy 115.487704 -396.120366) (xy 115.493498 -396.113219) (xy 115.500014 -396.09603) (xy 115.500404 -396.086838)
			(xy 115.500404 -395.92885) (xy 115.500904 -395.918686) (xy 115.508666 -395.899899) (xy 115.523028 -395.885513)
			(xy 115.541803 -395.87772) (xy 115.551966 -395.877288) (xy 116.268246 -395.877288) (xy 116.278427 -395.877627)
			(xy 116.297232 -395.885437) (xy 116.311617 -395.899849) (xy 116.319392 -395.918668) (xy 116.319808 -395.92885)
			(xy 116.319808 -396.086838) (xy 116.320198 -396.096027) (xy 116.326725 -396.113212) (xy 116.332508 -396.120366)
			(xy 116.354288 -396.146026) (xy 116.39224 -396.20161) (xy 116.423277 -396.261332) (xy 116.446952 -396.324335)
			(xy 116.462928 -396.389717) (xy 116.470973 -396.45654) (xy 116.470974 -396.523845) (xy 116.46293 -396.590668)
			(xy 116.446957 -396.65605) (xy 116.423283 -396.719055) (xy 116.392248 -396.778777) (xy 116.354297 -396.834363)
			(xy 116.332508 -396.860014) (xy 116.326724 -396.867168) (xy 116.320202 -396.884352) (xy 116.319808 -396.893542)
			(xy 116.319808 -397.38681) (xy 116.320212 -397.395998) (xy 116.32673 -397.413182) (xy 116.332508 -397.420338)
			(xy 116.35426 -397.44602) (xy 116.392213 -397.501601) (xy 116.42064 -397.556296) (xy 117.548866 -397.556296)
			(xy 117.556942 -397.489357) (xy 117.572978 -397.423868) (xy 117.596743 -397.360771) (xy 117.627896 -397.300976)
			(xy 117.665987 -397.245342) (xy 117.687852 -397.219678) (xy 117.693647 -397.212532) (xy 117.700161 -397.195342)
			(xy 117.700552 -397.18615) (xy 117.700552 -397.028924) (xy 117.701103 -397.018823) (xy 117.708824 -397.000154)
			(xy 117.7231 -396.98586) (xy 117.741759 -396.978116) (xy 117.75186 -396.977616) (xy 118.46814 -396.977616)
			(xy 118.478253 -396.978053) (xy 118.496935 -396.985807) (xy 118.511229 -397.000118) (xy 118.51896 -397.01881)
			(xy 118.519448 -397.028924) (xy 118.519448 -397.18615) (xy 118.519894 -397.195333) (xy 118.526384 -397.212517)
			(xy 118.532148 -397.219678) (xy 118.554024 -397.245334) (xy 118.592115 -397.300969) (xy 118.623269 -397.360766)
			(xy 118.647035 -397.423864) (xy 118.663071 -397.489355) (xy 118.671147 -397.556295) (xy 118.671146 -397.62372)
			(xy 118.663068 -397.69066) (xy 118.64703 -397.75615) (xy 118.623262 -397.819248) (xy 118.620846 -397.823885)
			(xy 119.748994 -397.823885) (xy 119.748998 -397.756458) (xy 119.757077 -397.689517) (xy 119.773117 -397.624026)
			(xy 119.796885 -397.560928) (xy 119.828041 -397.50113) (xy 119.866134 -397.445495) (xy 119.888 -397.41983)
			(xy 119.893809 -397.412693) (xy 119.900316 -397.395496) (xy 119.9007 -397.386302) (xy 119.9007 -396.89405)
			(xy 119.900266 -396.884865) (xy 119.893769 -396.867681) (xy 119.888 -396.860522) (xy 119.866126 -396.834865)
			(xy 119.828038 -396.779229) (xy 119.796888 -396.719432) (xy 119.773124 -396.656334) (xy 119.757089 -396.590844)
			(xy 119.749014 -396.523905) (xy 119.749015 -396.45648) (xy 119.757092 -396.389541) (xy 119.773128 -396.324052)
			(xy 119.796894 -396.260954) (xy 119.828046 -396.201158) (xy 119.866135 -396.145523) (xy 119.888 -396.119858)
			(xy 119.893797 -396.112713) (xy 119.900311 -396.095522) (xy 119.9007 -396.08633) (xy 119.9007 -395.92885)
			(xy 119.901266 -395.918731) (xy 119.90897 -395.900019) (xy 119.923232 -395.885662) (xy 119.941893 -395.877834)
			(xy 119.952008 -395.877288) (xy 120.668288 -395.877288) (xy 120.678408 -395.877725) (xy 120.697109 -395.885467)
			(xy 120.711424 -395.899777) (xy 120.719171 -395.918476) (xy 120.719596 -395.928596) (xy 120.719596 -396.08633)
			(xy 120.719992 -396.095519) (xy 120.726516 -396.112703) (xy 120.732296 -396.119858) (xy 120.75415 -396.145531)
			(xy 120.79224 -396.201165) (xy 120.823391 -396.26096) (xy 120.847156 -396.324055) (xy 120.863192 -396.389544)
			(xy 120.871269 -396.456481) (xy 120.87127 -396.523904) (xy 120.863195 -396.590842) (xy 120.84716 -396.65633)
			(xy 120.823397 -396.719427) (xy 120.792247 -396.779223) (xy 120.75416 -396.834857) (xy 120.732296 -396.860522)
			(xy 120.726507 -396.867673) (xy 120.719988 -396.884859) (xy 120.719596 -396.89405) (xy 120.719596 -397.386302)
			(xy 120.720006 -397.395489) (xy 120.72652 -397.412673) (xy 120.732296 -397.41983) (xy 120.754123 -397.445526)
			(xy 120.792213 -397.501156) (xy 120.820972 -397.556355) (xy 121.949186 -397.556355) (xy 121.95723 -397.489533)
			(xy 121.973202 -397.424152) (xy 121.996873 -397.361148) (xy 122.027905 -397.301425) (xy 122.065853 -397.245838)
			(xy 122.08764 -397.220186) (xy 122.09343 -397.213036) (xy 122.099948 -397.195849) (xy 122.10034 -397.186658)
			(xy 122.10034 -397.028924) (xy 122.100736 -397.018798) (xy 122.108484 -397.000087) (xy 122.122807 -396.985771)
			(xy 122.141522 -396.978032) (xy 122.151648 -396.977616) (xy 122.868182 -396.977616) (xy 122.878305 -396.978141)
			(xy 122.897021 -396.985858) (xy 122.911377 -397.000132) (xy 122.919201 -397.018804) (xy 122.919744 -397.028924)
			(xy 122.919744 -397.186658) (xy 122.920187 -397.195841) (xy 122.926679 -397.213026) (xy 122.932444 -397.220186)
			(xy 122.954242 -397.24583) (xy 122.992192 -397.301417) (xy 123.023225 -397.361142) (xy 123.046898 -397.424147)
			(xy 123.062871 -397.489531) (xy 123.070915 -397.556354) (xy 123.070914 -397.623661) (xy 123.062868 -397.690484)
			(xy 123.046894 -397.755867) (xy 123.023219 -397.818872) (xy 123.020645 -397.823826) (xy 124.14929 -397.823826)
			(xy 124.149293 -397.756517) (xy 124.157342 -397.689691) (xy 124.17332 -397.624306) (xy 124.197 -397.5613)
			(xy 124.22804 -397.501575) (xy 124.265997 -397.44599) (xy 124.287788 -397.420338) (xy 124.293592 -397.413198)
			(xy 124.300103 -397.396004) (xy 124.300488 -397.38681) (xy 124.300488 -396.893542) (xy 124.30006 -396.884357)
			(xy 124.293559 -396.867172) (xy 124.287788 -396.860014) (xy 124.265989 -396.834371) (xy 124.228037 -396.778784)
			(xy 124.197002 -396.71906) (xy 124.173327 -396.656054) (xy 124.157354 -396.59067) (xy 124.14931 -396.523846)
			(xy 124.14931 -396.456539) (xy 124.157356 -396.389715) (xy 124.173332 -396.324332) (xy 124.197008 -396.261327)
			(xy 124.228045 -396.201603) (xy 124.265998 -396.146018) (xy 124.287788 -396.120366) (xy 124.29358 -396.113218)
			(xy 124.300098 -396.09603) (xy 124.300488 -396.086838) (xy 124.300488 -395.92885) (xy 124.300906 -395.918675)
			(xy 124.308684 -395.899872) (xy 124.323072 -395.885484) (xy 124.341875 -395.877706) (xy 124.35205 -395.877288)
			(xy 125.06833 -395.877288) (xy 125.07851 -395.87764) (xy 125.097315 -395.885445) (xy 125.1117 -395.899852)
			(xy 125.119475 -395.91867) (xy 125.119892 -395.92885) (xy 125.119892 -396.086838) (xy 125.120286 -396.096027)
			(xy 125.126811 -396.113211) (xy 125.132592 -396.120366) (xy 125.154369 -396.146027) (xy 125.192316 -396.201613)
			(xy 125.223348 -396.261335) (xy 125.24702 -396.324339) (xy 125.262993 -396.389719) (xy 125.271037 -396.456541)
			(xy 125.271038 -396.523844) (xy 125.262995 -396.590666) (xy 125.247025 -396.656047) (xy 125.223354 -396.719051)
			(xy 125.192324 -396.778774) (xy 125.154378 -396.834361) (xy 125.132592 -396.860014) (xy 125.126806 -396.867167)
			(xy 125.120285 -396.884351) (xy 125.119892 -396.893542) (xy 125.119892 -397.38681) (xy 125.120299 -397.395998)
			(xy 125.126815 -397.413182) (xy 125.132592 -397.420338) (xy 125.154341 -397.446021) (xy 125.192289 -397.501604)
			(xy 125.22071 -397.556296) (xy 126.348954 -397.556296) (xy 126.35703 -397.489357) (xy 126.373065 -397.423869)
			(xy 126.39683 -397.360772) (xy 126.427981 -397.300976) (xy 126.466071 -397.245343) (xy 126.487936 -397.219678)
			(xy 126.493729 -397.21253) (xy 126.500245 -397.195342) (xy 126.500636 -397.18615) (xy 126.500636 -397.028924)
			(xy 126.501036 -397.018799) (xy 126.508783 -397.000089) (xy 126.523105 -396.985772) (xy 126.541818 -396.978032)
			(xy 126.551944 -396.977616) (xy 127.268224 -396.977616) (xy 127.278336 -396.978066) (xy 127.297018 -396.985814)
			(xy 127.311313 -397.000122) (xy 127.319044 -397.018811) (xy 127.319532 -397.028924) (xy 127.319532 -397.18615)
			(xy 127.319981 -397.195333) (xy 127.326469 -397.212517) (xy 127.332232 -397.219678) (xy 127.354105 -397.245336)
			(xy 127.392191 -397.300972) (xy 127.423339 -397.36077) (xy 127.447102 -397.423867) (xy 127.463135 -397.489357)
			(xy 127.47121 -397.556296) (xy 127.471209 -397.623719) (xy 127.463133 -397.690658) (xy 127.447097 -397.756147)
			(xy 127.423333 -397.819244) (xy 127.420946 -397.823826) (xy 128.54908 -397.823826) (xy 128.549084 -397.756517)
			(xy 128.557132 -397.689691) (xy 128.57311 -397.624306) (xy 128.596789 -397.5613) (xy 128.627829 -397.501576)
			(xy 128.665785 -397.445989) (xy 128.687576 -397.420338) (xy 128.693379 -397.413197) (xy 128.69989 -397.396003)
			(xy 128.700276 -397.38681) (xy 128.700276 -396.893542) (xy 128.699851 -396.884356) (xy 128.693348 -396.867171)
			(xy 128.687576 -396.860014) (xy 128.665777 -396.83437) (xy 128.627826 -396.778784) (xy 128.596792 -396.719059)
			(xy 128.573118 -396.656053) (xy 128.557144 -396.59067) (xy 128.5491 -396.523846) (xy 128.549101 -396.456539)
			(xy 128.557147 -396.389715) (xy 128.573122 -396.324332) (xy 128.596798 -396.261327) (xy 128.627834 -396.201604)
			(xy 128.665787 -396.146018) (xy 128.687576 -396.120366) (xy 128.693367 -396.113216) (xy 128.699886 -396.096029)
			(xy 128.700276 -396.086838) (xy 128.700276 -395.92885) (xy 128.700706 -395.918677) (xy 128.708481 -395.899876)
			(xy 128.722866 -395.885488) (xy 128.741665 -395.877708) (xy 128.751838 -395.877288) (xy 129.468118 -395.877288)
			(xy 129.478297 -395.87765) (xy 129.497102 -395.885451) (xy 129.511487 -395.899856) (xy 129.519263 -395.91867)
			(xy 129.51968 -395.92885) (xy 129.51968 -396.086838) (xy 129.520076 -396.096027) (xy 129.5266 -396.113211)
			(xy 129.53238 -396.120366) (xy 129.554157 -396.146026) (xy 129.592105 -396.201612) (xy 129.623138 -396.261335)
			(xy 129.64681 -396.324338) (xy 129.662784 -396.389719) (xy 129.670828 -396.456541) (xy 129.670829 -396.523844)
			(xy 129.662786 -396.590666) (xy 129.646815 -396.656047) (xy 129.623144 -396.719051) (xy 129.592113 -396.778775)
			(xy 129.554167 -396.834362) (xy 129.53238 -396.860014) (xy 129.526593 -396.867166) (xy 129.520073 -396.884351)
			(xy 129.51968 -396.893542) (xy 129.51968 -397.38681) (xy 129.52009 -397.395997) (xy 129.526604 -397.413181)
			(xy 129.53238 -397.420338) (xy 129.55413 -397.446021) (xy 129.592078 -397.501604) (xy 129.620531 -397.556356)
			(xy 130.749274 -397.556356) (xy 130.757317 -397.489534) (xy 130.773288 -397.424152) (xy 130.796959 -397.361148)
			(xy 130.827991 -397.301425) (xy 130.865937 -397.245838) (xy 130.887724 -397.220186) (xy 130.893512 -397.213035)
			(xy 130.900031 -397.195849) (xy 130.900424 -397.186658) (xy 130.900424 -397.028924) (xy 130.900842 -397.018768)
			(xy 130.908634 -397.000012) (xy 130.923032 -396.985687) (xy 130.941828 -396.97799) (xy 130.951986 -396.977616)
			(xy 131.668266 -396.977616) (xy 131.678388 -396.978154) (xy 131.697103 -396.985866) (xy 131.71146 -397.000137)
			(xy 131.719284 -397.018806) (xy 131.719828 -397.028924) (xy 131.719828 -397.186658) (xy 131.720252 -397.195844)
			(xy 131.726756 -397.213029) (xy 131.732528 -397.220186) (xy 131.754326 -397.24583) (xy 131.792277 -397.301417)
			(xy 131.823312 -397.361141) (xy 131.846985 -397.424147) (xy 131.862959 -397.48953) (xy 131.871003 -397.556354)
			(xy 131.871002 -397.623661) (xy 131.862956 -397.690485) (xy 131.846981 -397.755868) (xy 131.823306 -397.818873)
			(xy 131.792269 -397.878596) (xy 131.754317 -397.934182) (xy 131.732528 -397.959834) (xy 131.726726 -397.966975)
			(xy 131.720217 -397.984169) (xy 131.719828 -397.993362) (xy 131.719828 -398.486884) (xy 131.720239 -398.496071)
			(xy 131.726751 -398.513256) (xy 131.732528 -398.520412) (xy 131.754352 -398.546034) (xy 131.792302 -398.601624)
			(xy 131.823336 -398.661352) (xy 131.847008 -398.72436) (xy 131.86298 -398.789746) (xy 131.871021 -398.856573)
			(xy 131.871018 -398.923881) (xy 131.86297 -398.990707) (xy 131.846992 -399.056092) (xy 131.823314 -399.119098)
			(xy 131.792274 -399.178822) (xy 131.754319 -399.234408) (xy 131.732528 -399.26006) (xy 131.726715 -399.267193)
			(xy 131.720212 -399.284393) (xy 131.719828 -399.293588) (xy 131.719828 -399.451576) (xy 131.719359 -399.461725)
			(xy 131.711577 -399.480472) (xy 131.697195 -399.494795) (xy 131.678417 -399.502501) (xy 131.668266 -399.502884)
			(xy 130.951986 -399.502884) (xy 130.941861 -399.502385) (xy 130.923145 -399.494657) (xy 130.90879 -399.480375)
			(xy 130.900967 -399.461698) (xy 130.900424 -399.451576) (xy 130.900424 -399.293588) (xy 130.900014 -399.284401)
			(xy 130.8935 -399.267217) (xy 130.887724 -399.26006) (xy 130.865972 -399.234378) (xy 130.828023 -399.178796)
			(xy 130.796989 -399.119076) (xy 130.773315 -399.056076) (xy 130.75734 -398.990697) (xy 130.749294 -398.923878)
			(xy 130.74929 -398.856576) (xy 130.757331 -398.789756) (xy 130.773299 -398.724376) (xy 130.796967 -398.661373)
			(xy 130.827996 -398.601651) (xy 130.865939 -398.546065) (xy 130.887724 -398.520412) (xy 130.893543 -398.513283)
			(xy 130.900044 -398.49608) (xy 130.900424 -398.486884) (xy 130.900424 -397.993362) (xy 130.900027 -397.984174)
			(xy 130.893504 -397.96699) (xy 130.887724 -397.959834) (xy 130.865946 -397.934174) (xy 130.827998 -397.878588)
			(xy 130.796965 -397.818865) (xy 130.773293 -397.755862) (xy 130.75732 -397.690481) (xy 130.749275 -397.62366)
			(xy 130.749274 -397.556356) (xy 129.620531 -397.556356) (xy 129.623112 -397.561323) (xy 129.646786 -397.624324)
			(xy 129.662761 -397.689702) (xy 129.670808 -397.756521) (xy 129.670811 -397.823822) (xy 129.662771 -397.890642)
			(xy 129.646803 -397.956022) (xy 129.623135 -398.019025) (xy 129.592108 -398.078747) (xy 129.554165 -398.134333)
			(xy 129.53238 -398.159986) (xy 129.526562 -398.167116) (xy 129.520061 -398.184318) (xy 129.51968 -398.193514)
			(xy 129.51968 -398.351502) (xy 129.519169 -398.361658) (xy 129.511397 -398.380423) (xy 129.497037 -398.394788)
			(xy 129.478274 -398.402565) (xy 129.468118 -398.403064) (xy 128.751838 -398.403064) (xy 128.741669 -398.402605)
			(xy 128.722876 -398.394833) (xy 128.70849 -398.380458) (xy 128.700703 -398.361671) (xy 128.700276 -398.351502)
			(xy 128.700276 -398.193514) (xy 128.699865 -398.184327) (xy 128.693352 -398.167142) (xy 128.687576 -398.159986)
			(xy 128.66575 -398.134365) (xy 128.627799 -398.078775) (xy 128.596766 -398.019048) (xy 128.573093 -397.956039)
			(xy 128.557122 -397.890652) (xy 128.54908 -397.823826) (xy 127.420946 -397.823826) (xy 127.392183 -397.879041)
			(xy 127.354095 -397.934676) (xy 127.332232 -397.960342) (xy 127.326427 -397.967481) (xy 127.319919 -397.984676)
			(xy 127.319532 -397.99387) (xy 127.319532 -398.486376) (xy 127.319969 -398.49556) (xy 127.326466 -398.512744)
			(xy 127.332232 -398.519904) (xy 127.35413 -398.545541) (xy 127.392216 -398.60118) (xy 127.423363 -398.66098)
			(xy 127.447124 -398.724081) (xy 127.463156 -398.789573) (xy 127.471228 -398.856514) (xy 127.471225 -398.92394)
			(xy 127.463146 -398.99088) (xy 127.447108 -399.056371) (xy 127.423341 -399.119469) (xy 127.392188 -399.179266)
			(xy 127.354097 -399.234902) (xy 127.332232 -399.260568) (xy 127.326416 -399.267699) (xy 127.319915 -399.284901)
			(xy 127.319532 -399.294096) (xy 127.319532 -399.451576) (xy 127.318996 -399.461679) (xy 127.311272 -399.480351)
			(xy 127.296991 -399.494645) (xy 127.278327 -399.502387) (xy 127.268224 -399.502884) (xy 126.551944 -399.502884)
			(xy 126.541822 -399.502447) (xy 126.523117 -399.494711) (xy 126.5088 -399.4804) (xy 126.501056 -399.461697)
			(xy 126.500636 -399.451576) (xy 126.500636 -399.294096) (xy 126.50022 -399.28491) (xy 126.49371 -399.267726)
			(xy 126.487936 -399.260568) (xy 126.466106 -399.234874) (xy 126.428014 -399.179245) (xy 126.39686 -399.119453)
			(xy 126.373092 -399.056359) (xy 126.357053 -398.990873) (xy 126.348974 -398.923938) (xy 126.34897 -398.856516)
			(xy 126.357043 -398.78958) (xy 126.373076 -398.724092) (xy 126.396838 -398.660997) (xy 126.427986 -398.601202)
			(xy 126.466073 -398.545569) (xy 126.487936 -398.519904) (xy 126.493718 -398.512749) (xy 126.50024 -398.495566)
			(xy 126.500636 -398.486376) (xy 126.500636 -397.99387) (xy 126.500232 -397.984682) (xy 126.493713 -397.967498)
			(xy 126.487936 -397.960342) (xy 126.466081 -397.934669) (xy 126.427989 -397.879037) (xy 126.396836 -397.819242)
			(xy 126.37307 -397.756146) (xy 126.357032 -397.690657) (xy 126.348955 -397.623719) (xy 126.348954 -397.556296)
			(xy 125.22071 -397.556296) (xy 125.223323 -397.561324) (xy 125.246996 -397.624324) (xy 125.262971 -397.689702)
			(xy 125.271018 -397.756521) (xy 125.271021 -397.823822) (xy 125.262981 -397.890642) (xy 125.247013 -397.956021)
			(xy 125.223346 -398.019024) (xy 125.192319 -398.078747) (xy 125.154377 -398.134334) (xy 125.132592 -398.159986)
			(xy 125.126775 -398.167117) (xy 125.120273 -398.184318) (xy 125.119892 -398.193514) (xy 125.119892 -398.351502)
			(xy 125.119369 -398.361656) (xy 125.111599 -398.38042) (xy 125.097243 -398.394784) (xy 125.078484 -398.402563)
			(xy 125.06833 -398.403064) (xy 124.35205 -398.403064) (xy 124.341882 -398.402595) (xy 124.323089 -398.394827)
			(xy 124.308702 -398.380455) (xy 124.300915 -398.36167) (xy 124.300488 -398.351502) (xy 124.300488 -398.193514)
			(xy 124.300074 -398.184327) (xy 124.293563 -398.167143) (xy 124.287788 -398.159986) (xy 124.265961 -398.134365)
			(xy 124.228011 -398.078775) (xy 124.196976 -398.019048) (xy 124.173304 -397.956039) (xy 124.157332 -397.890653)
			(xy 124.14929 -397.823826) (xy 123.020645 -397.823826) (xy 122.992184 -397.878596) (xy 122.954233 -397.934182)
			(xy 122.932444 -397.959834) (xy 122.926644 -397.966976) (xy 122.920133 -397.984169) (xy 122.919744 -397.993362)
			(xy 122.919744 -398.486884) (xy 122.920174 -398.496069) (xy 122.926675 -398.513253) (xy 122.932444 -398.520412)
			(xy 122.954268 -398.546035) (xy 122.992217 -398.601625) (xy 123.023249 -398.661352) (xy 123.046921 -398.724361)
			(xy 123.062892 -398.789747) (xy 123.070933 -398.856573) (xy 123.07093 -398.923881) (xy 123.062882 -398.990707)
			(xy 123.046905 -399.056091) (xy 123.023227 -399.119097) (xy 122.992189 -399.178822) (xy 122.954235 -399.234408)
			(xy 122.932444 -399.26006) (xy 122.926633 -399.267194) (xy 122.920128 -399.284393) (xy 122.919744 -399.293588)
			(xy 122.919744 -399.451576) (xy 122.919196 -399.461678) (xy 122.911475 -399.480347) (xy 122.897197 -399.494641)
			(xy 122.878537 -399.502385) (xy 122.868436 -399.502884) (xy 122.151902 -399.502884) (xy 122.141778 -399.502372)
			(xy 122.123062 -399.49465) (xy 122.108706 -399.480371) (xy 122.100883 -399.461697) (xy 122.10034 -399.451576)
			(xy 122.10034 -399.293588) (xy 122.099927 -399.284401) (xy 122.093414 -399.267217) (xy 122.08764 -399.26006)
			(xy 122.065888 -399.234379) (xy 122.027938 -399.178796) (xy 121.996903 -399.119077) (xy 121.973228 -399.056076)
			(xy 121.957253 -398.990698) (xy 121.949206 -398.923878) (xy 121.949202 -398.856576) (xy 121.957243 -398.789756)
			(xy 121.973212 -398.724376) (xy 121.996881 -398.661373) (xy 122.02791 -398.60165) (xy 122.065855 -398.546064)
			(xy 122.08764 -398.520412) (xy 122.093461 -398.513285) (xy 122.09996 -398.49608) (xy 122.10034 -398.486884)
			(xy 122.10034 -397.993362) (xy 122.099939 -397.984174) (xy 122.093418 -397.96699) (xy 122.08764 -397.959834)
			(xy 122.065862 -397.934174) (xy 122.027913 -397.878588) (xy 121.996879 -397.818866) (xy 121.973206 -397.755863)
			(xy 121.957232 -397.690481) (xy 121.949187 -397.62366) (xy 121.949186 -397.556355) (xy 120.820972 -397.556355)
			(xy 120.823365 -397.560948) (xy 120.847132 -397.624041) (xy 120.86317 -397.689526) (xy 120.871249 -397.756461)
			(xy 120.871253 -397.823882) (xy 120.86318 -397.890818) (xy 120.847149 -397.956305) (xy 120.823389 -398.0194)
			(xy 120.792242 -398.079195) (xy 120.754158 -398.134829) (xy 120.732296 -398.160494) (xy 120.726519 -398.167653)
			(xy 120.719993 -398.184833) (xy 120.719596 -398.194022) (xy 120.719596 -398.351502) (xy 120.719076 -398.361624)
			(xy 120.711354 -398.380339) (xy 120.697079 -398.394694) (xy 120.678408 -398.402519) (xy 120.668288 -398.403064)
			(xy 119.952008 -398.403064) (xy 119.941882 -398.402677) (xy 119.923171 -398.394924) (xy 119.908855 -398.380599)
			(xy 119.901116 -398.361883) (xy 119.9007 -398.351756) (xy 119.9007 -398.194022) (xy 119.900279 -398.184836)
			(xy 119.893773 -398.167651) (xy 119.888 -398.160494) (xy 119.866099 -398.13486) (xy 119.828011 -398.079221)
			(xy 119.796862 -398.01942) (xy 119.7731 -397.956319) (xy 119.757067 -397.890826) (xy 119.748994 -397.823885)
			(xy 118.620846 -397.823885) (xy 118.592108 -397.879044) (xy 118.554014 -397.934678) (xy 118.532148 -397.960342)
			(xy 118.526345 -397.967482) (xy 118.519835 -397.984677) (xy 118.519448 -397.99387) (xy 118.519448 -398.486376)
			(xy 118.519881 -398.495561) (xy 118.52638 -398.512745) (xy 118.532148 -398.519904) (xy 118.554049 -398.545539)
			(xy 118.59214 -398.601177) (xy 118.623292 -398.660977) (xy 118.647057 -398.724078) (xy 118.663091 -398.789571)
			(xy 118.671165 -398.856513) (xy 118.671162 -398.923941) (xy 118.663082 -398.990882) (xy 118.647041 -399.056374)
			(xy 118.62327 -399.119473) (xy 118.592112 -399.17927) (xy 118.554016 -399.234904) (xy 118.532148 -399.260568)
			(xy 118.526334 -399.2677) (xy 118.519831 -399.284901) (xy 118.519448 -399.294096) (xy 118.519448 -399.451576)
			(xy 118.518897 -399.461677) (xy 118.511176 -399.480346) (xy 118.4969 -399.49464) (xy 118.478241 -399.502384)
			(xy 118.46814 -399.502884) (xy 117.75186 -399.502884) (xy 117.741747 -399.502447) (xy 117.723065 -399.494693)
			(xy 117.708771 -399.480382) (xy 117.70104 -399.46169) (xy 117.700552 -399.451576) (xy 117.700552 -399.294096)
			(xy 117.700132 -399.28491) (xy 117.693624 -399.267726) (xy 117.687852 -399.260568) (xy 117.666022 -399.234874)
			(xy 117.627928 -399.179245) (xy 117.596773 -399.119453) (xy 117.573005 -399.05636) (xy 117.556965 -398.990874)
			(xy 117.548886 -398.923938) (xy 117.548882 -398.856516) (xy 117.556955 -398.789579) (xy 117.572989 -398.724092)
			(xy 117.596751 -398.660996) (xy 117.627901 -398.601201) (xy 117.665988 -398.545568) (xy 117.687852 -398.519904)
			(xy 117.693636 -398.51275) (xy 117.700157 -398.495566) (xy 117.700552 -398.486376) (xy 117.700552 -397.99387)
			(xy 117.700145 -397.984683) (xy 117.693628 -397.967499) (xy 117.687852 -397.960342) (xy 117.665996 -397.93467)
			(xy 117.627904 -397.879037) (xy 117.59675 -397.819243) (xy 117.572983 -397.756147) (xy 117.556945 -397.690658)
			(xy 117.548867 -397.623719) (xy 117.548866 -397.556296) (xy 116.42064 -397.556296) (xy 116.423251 -397.56132)
			(xy 116.446929 -397.624321) (xy 116.462906 -397.6897) (xy 116.470954 -397.75652) (xy 116.470957 -397.823823)
			(xy 116.462916 -397.890644) (xy 116.446945 -397.956025) (xy 116.423275 -398.019028) (xy 116.392243 -398.07875)
			(xy 116.354295 -398.134335) (xy 116.332508 -398.159986) (xy 116.326693 -398.167118) (xy 116.320189 -398.184319)
			(xy 116.319808 -398.193514) (xy 116.319808 -398.351502) (xy 116.319269 -398.361654) (xy 116.311503 -398.380415)
			(xy 116.297152 -398.394778) (xy 116.278398 -398.402561) (xy 116.268246 -398.403064) (xy 115.551966 -398.403064)
			(xy 115.541806 -398.402595) (xy 115.523037 -398.394809) (xy 115.508673 -398.380436) (xy 115.500899 -398.361662)
			(xy 115.500404 -398.351502) (xy 115.500404 -398.193514) (xy 115.499986 -398.184328) (xy 115.493478 -398.167143)
			(xy 115.487704 -398.159986) (xy 115.46588 -398.134364) (xy 115.427935 -398.078772) (xy 115.396905 -398.019044)
			(xy 115.373236 -397.956036) (xy 115.357267 -397.89065) (xy 115.349226 -397.823825) (xy 92.220595 -397.823825)
			(xy 92.192138 -397.878594) (xy 92.154191 -397.934181) (xy 92.132404 -397.959834) (xy 92.126611 -397.966982)
			(xy 92.120094 -397.98417) (xy 92.119704 -397.993362) (xy 92.119704 -398.486884) (xy 92.120121 -398.49607)
			(xy 92.12663 -398.513255) (xy 92.132404 -398.520412) (xy 92.154226 -398.546036) (xy 92.192171 -398.601627)
			(xy 92.2232 -398.661355) (xy 92.246869 -398.724363) (xy 92.262838 -398.789748) (xy 92.270879 -398.856574)
			(xy 92.270875 -398.923881) (xy 92.262828 -398.990705) (xy 92.246853 -399.056089) (xy 92.223178 -399.119094)
			(xy 92.192143 -399.178819) (xy 92.154193 -399.234407) (xy 92.132404 -399.26006) (xy 92.1266 -399.2672)
			(xy 92.12009 -399.284394) (xy 92.119704 -399.293588) (xy 92.119704 -399.451576) (xy 92.119259 -399.461728)
			(xy 92.111472 -399.480479) (xy 92.097082 -399.494803) (xy 92.078296 -399.502505) (xy 92.068142 -399.502884)
			(xy 91.351862 -399.502884) (xy 91.341736 -399.502405) (xy 91.323018 -399.494669) (xy 91.308664 -399.480381)
			(xy 91.300842 -399.4617) (xy 91.3003 -399.451576) (xy 91.3003 -399.293588) (xy 91.299895 -399.2844)
			(xy 91.293378 -399.267216) (xy 91.2876 -399.26006) (xy 91.265849 -399.234378) (xy 91.227901 -399.178795)
			(xy 91.196869 -399.119075) (xy 91.173196 -399.056075) (xy 91.157221 -398.990697) (xy 91.149175 -398.923878)
			(xy 91.149172 -398.856576) (xy 91.157212 -398.789757) (xy 91.17318 -398.724377) (xy 91.196847 -398.661374)
			(xy 91.227874 -398.601651) (xy 91.265816 -398.546065) (xy 91.2876 -398.520412) (xy 91.293416 -398.513281)
			(xy 91.299919 -398.49608) (xy 91.3003 -398.486884) (xy 91.3003 -397.993362) (xy 91.299908 -397.984173)
			(xy 91.293382 -397.966989) (xy 91.2876 -397.959834) (xy 91.265823 -397.934173) (xy 91.227877 -397.878587)
			(xy 91.196845 -397.818864) (xy 91.173174 -397.755861) (xy 91.157201 -397.69048) (xy 91.149157 -397.623659)
			(xy 91.149156 -397.556356) (xy 90.020411 -397.556356) (xy 90.022992 -397.561322) (xy 90.046667 -397.624323)
			(xy 90.062643 -397.689701) (xy 90.07069 -397.75652) (xy 90.070693 -397.823822) (xy 90.062653 -397.890643)
			(xy 90.046684 -397.956023) (xy 90.023015 -398.019026) (xy 89.991986 -398.078748) (xy 89.954041 -398.134334)
			(xy 89.932256 -398.159986) (xy 89.926435 -398.167114) (xy 89.919936 -398.184318) (xy 89.919556 -398.193514)
			(xy 89.919556 -398.351502) (xy 89.919138 -398.361674) (xy 89.911351 -398.38047) (xy 89.896964 -398.394855)
			(xy 89.878167 -398.402639) (xy 89.867994 -398.403064) (xy 89.151714 -398.403064) (xy 89.141544 -398.402625)
			(xy 89.122749 -398.394845) (xy 89.108364 -398.380464) (xy 89.100578 -398.361672) (xy 89.100152 -398.351502)
			(xy 89.100152 -398.193514) (xy 89.099724 -398.184329) (xy 89.093221 -398.167145) (xy 89.087452 -398.159986)
			(xy 89.065626 -398.134365) (xy 89.027678 -398.078774) (xy 88.996645 -398.019047) (xy 88.972974 -397.956038)
			(xy 88.957004 -397.890652) (xy 88.948962 -397.823826) (xy 87.820827 -397.823826) (xy 87.792062 -397.879042)
			(xy 87.753972 -397.934677) (xy 87.732108 -397.960342) (xy 87.726312 -397.967488) (xy 87.719797 -397.984678)
			(xy 87.719408 -397.99387) (xy 87.719408 -398.486376) (xy 87.719828 -398.495562) (xy 87.726335 -398.512747)
			(xy 87.732108 -398.519904) (xy 87.754007 -398.54554) (xy 87.792094 -398.601179) (xy 87.823243 -398.660979)
			(xy 87.847005 -398.72408) (xy 87.863037 -398.789573) (xy 87.87111 -398.856514) (xy 87.871107 -398.92394)
			(xy 87.863028 -398.990881) (xy 87.846989 -399.056372) (xy 87.823221 -399.11947) (xy 87.792066 -399.179267)
			(xy 87.753974 -399.234903) (xy 87.732108 -399.260568) (xy 87.726301 -399.267706) (xy 87.719792 -399.284902)
			(xy 87.719408 -399.294096) (xy 87.719408 -399.451576) (xy 87.718965 -399.461696) (xy 87.711226 -399.480398)
			(xy 87.696918 -399.494712) (xy 87.67822 -399.50246) (xy 87.6681 -399.502884) (xy 86.95182 -399.502884)
			(xy 86.941697 -399.502467) (xy 86.922991 -399.494723) (xy 86.908675 -399.480406) (xy 86.900932 -399.461699)
			(xy 86.900512 -399.451576) (xy 86.900512 -399.294096) (xy 86.900101 -399.284909) (xy 86.893587 -399.267725)
			(xy 86.887812 -399.260568) (xy 86.865983 -399.234874) (xy 86.827892 -399.179244) (xy 86.796739 -399.119452)
			(xy 86.772973 -399.056358) (xy 86.756934 -398.990873) (xy 86.748855 -398.923938) (xy 86.748852 -398.856516)
			(xy 86.756925 -398.78958) (xy 86.772957 -398.724093) (xy 86.796717 -398.660998) (xy 86.827865 -398.601203)
			(xy 86.86595 -398.545569) (xy 86.887812 -398.519904) (xy 86.893591 -398.512746) (xy 86.900116 -398.495565)
			(xy 86.900512 -398.486376) (xy 86.900512 -397.99387) (xy 86.900114 -397.984682) (xy 86.893592 -397.967497)
			(xy 86.887812 -397.960342) (xy 86.865957 -397.934669) (xy 86.827868 -397.879036) (xy 86.796716 -397.819241)
			(xy 86.772951 -397.756145) (xy 86.756914 -397.690657) (xy 86.748837 -397.623719) (xy 86.748836 -397.556296)
			(xy 85.620612 -397.556296) (xy 85.623035 -397.560946) (xy 85.646803 -397.624039) (xy 85.662842 -397.689525)
			(xy 85.670922 -397.756461) (xy 85.670925 -397.823882) (xy 85.662853 -397.890819) (xy 85.64682 -397.956306)
			(xy 85.623058 -398.019402) (xy 85.59191 -398.079196) (xy 85.553823 -398.134829) (xy 85.53196 -398.160494)
			(xy 85.526178 -398.16765) (xy 85.519656 -398.184832) (xy 85.51926 -398.194022) (xy 85.51926 -398.351502)
			(xy 85.518775 -398.361629) (xy 85.511047 -398.38035) (xy 85.49676 -398.394706) (xy 85.478076 -398.402525)
			(xy 85.467952 -398.403064) (xy 84.751672 -398.403064) (xy 84.741512 -398.402701) (xy 84.722752 -398.394889)
			(xy 84.708428 -398.380474) (xy 84.700736 -398.361665) (xy 84.700364 -398.351502) (xy 84.700364 -398.194022)
			(xy 84.699929 -398.184838) (xy 84.693431 -398.167654) (xy 84.687664 -398.160494) (xy 84.665764 -398.134859)
			(xy 84.627679 -398.079219) (xy 84.596532 -398.019419) (xy 84.572771 -397.956318) (xy 84.55674 -397.890825)
			(xy 84.548667 -397.823884) (xy 83.420495 -397.823884) (xy 83.392062 -397.878597) (xy 83.35411 -397.934182)
			(xy 83.33232 -397.959834) (xy 83.326529 -397.966983) (xy 83.32001 -397.984171) (xy 83.31962 -397.993362)
			(xy 83.31962 -398.486884) (xy 83.320033 -398.496071) (xy 83.326544 -398.513256) (xy 83.33232 -398.520412)
			(xy 83.354144 -398.546035) (xy 83.392095 -398.601624) (xy 83.423129 -398.661352) (xy 83.446801 -398.72436)
			(xy 83.462773 -398.789746) (xy 83.470815 -398.856573) (xy 83.470812 -398.923881) (xy 83.462763 -398.990707)
			(xy 83.446785 -399.056092) (xy 83.423107 -399.119098) (xy 83.392067 -399.178822) (xy 83.354111 -399.234408)
			(xy 83.33232 -399.26006) (xy 83.326518 -399.267201) (xy 83.320006 -399.284395) (xy 83.31962 -399.293588)
			(xy 83.31962 -399.451576) (xy 83.319159 -399.461726) (xy 83.311375 -399.480474) (xy 83.296991 -399.494798)
			(xy 83.27821 -399.502502) (xy 83.268058 -399.502884) (xy 82.551778 -399.502884) (xy 82.541653 -399.502392)
			(xy 82.522936 -399.494662) (xy 82.508581 -399.480378) (xy 82.500758 -399.461699) (xy 82.500216 -399.451576)
			(xy 82.500216 -399.293588) (xy 82.499808 -399.284401) (xy 82.493293 -399.267216) (xy 82.487516 -399.26006)
			(xy 82.465765 -399.234378) (xy 82.427816 -399.178795) (xy 82.396783 -399.119076) (xy 82.373109 -399.056075)
			(xy 82.357134 -398.990697) (xy 82.349088 -398.923878) (xy 82.349084 -398.856576) (xy 82.357125 -398.789756)
			(xy 82.373093 -398.724377) (xy 82.396761 -398.661374) (xy 82.427788 -398.601651) (xy 82.465731 -398.546065)
			(xy 82.487516 -398.520412) (xy 82.493334 -398.513282) (xy 82.499835 -398.49608) (xy 82.500216 -398.486884)
			(xy 82.500216 -397.993362) (xy 82.499821 -397.984173) (xy 82.493296 -397.966989) (xy 82.487516 -397.959834)
			(xy 82.465739 -397.934174) (xy 82.427791 -397.878588) (xy 82.396759 -397.818865) (xy 82.373086 -397.755862)
			(xy 82.357113 -397.690481) (xy 82.349069 -397.623659) (xy 82.349068 -397.556356) (xy 81.220853 -397.556356)
			(xy 81.223245 -397.560947) (xy 81.247013 -397.62404) (xy 81.263052 -397.689525) (xy 81.271131 -397.756461)
			(xy 81.271135 -397.823882) (xy 81.263062 -397.890818) (xy 81.24703 -397.956306) (xy 81.223269 -398.019401)
			(xy 81.192121 -398.079196) (xy 81.154035 -398.134829) (xy 81.132172 -398.160494) (xy 81.126392 -398.167651)
			(xy 81.119868 -398.184832) (xy 81.119472 -398.194022) (xy 81.119472 -398.351502) (xy 81.118975 -398.361627)
			(xy 81.111249 -398.380346) (xy 81.096966 -398.394702) (xy 81.078287 -398.402523) (xy 81.068164 -398.403064)
			(xy 80.351884 -398.403064) (xy 80.341724 -398.402691) (xy 80.322965 -398.394883) (xy 80.30864 -398.380471)
			(xy 80.300948 -398.361664) (xy 80.300576 -398.351502) (xy 80.300576 -398.194022) (xy 80.300161 -398.184835)
			(xy 80.293651 -398.16765) (xy 80.287876 -398.160494) (xy 80.265976 -398.134859) (xy 80.22789 -398.07922)
			(xy 80.196742 -398.019419) (xy 80.172981 -397.956318) (xy 80.156949 -397.890826) (xy 80.148876 -397.823885)
			(xy 79.02071 -397.823885) (xy 78.991976 -397.879041) (xy 78.953888 -397.934676) (xy 78.932024 -397.960342)
			(xy 78.92623 -397.967489) (xy 78.919713 -397.984678) (xy 78.919324 -397.99387) (xy 78.919324 -398.486376)
			(xy 78.91974 -398.495563) (xy 78.926249 -398.512747) (xy 78.932024 -398.519904) (xy 78.953922 -398.54554)
			(xy 78.992009 -398.60118) (xy 79.023156 -398.66098) (xy 79.046917 -398.724081) (xy 79.06295 -398.789573)
			(xy 79.071022 -398.856514) (xy 79.071019 -398.92394) (xy 79.06294 -398.99088) (xy 79.046901 -399.056371)
			(xy 79.023134 -399.119469) (xy 78.991981 -399.179267) (xy 78.953889 -399.234902) (xy 78.932024 -399.260568)
			(xy 78.926219 -399.267707) (xy 78.919709 -399.284902) (xy 78.919324 -399.294096) (xy 78.919324 -399.451576)
			(xy 78.918865 -399.461694) (xy 78.911129 -399.480393) (xy 78.896826 -399.494707) (xy 78.878134 -399.502457)
			(xy 78.868016 -399.502884) (xy 78.151736 -399.502884) (xy 78.141614 -399.502454) (xy 78.122908 -399.494715)
			(xy 78.108592 -399.480402) (xy 78.100848 -399.461698) (xy 78.100428 -399.451576) (xy 78.100428 -399.294096)
			(xy 78.100014 -399.284909) (xy 78.093502 -399.267725) (xy 78.087728 -399.260568) (xy 78.065898 -399.234874)
			(xy 78.027807 -399.179244) (xy 77.996653 -399.119452) (xy 77.972886 -399.056359) (xy 77.956847 -398.990873)
			(xy 77.948768 -398.923938) (xy 77.948764 -398.856516) (xy 77.956837 -398.78958) (xy 77.972869 -398.724093)
			(xy 77.996631 -398.660997) (xy 78.027779 -398.601202) (xy 78.065865 -398.545569) (xy 78.087728 -398.519904)
			(xy 78.093509 -398.512748) (xy 78.100032 -398.495566) (xy 78.100428 -398.486376) (xy 78.100428 -397.99387)
			(xy 78.100026 -397.984682) (xy 78.093506 -397.967498) (xy 78.087728 -397.960342) (xy 78.065873 -397.934669)
			(xy 78.027782 -397.879036) (xy 77.996629 -397.819241) (xy 77.972863 -397.756146) (xy 77.956826 -397.690657)
			(xy 77.948749 -397.623719) (xy 77.948748 -397.556296) (xy 76.820503 -397.556296) (xy 76.823115 -397.561323)
			(xy 76.846789 -397.624324) (xy 76.862764 -397.689702) (xy 76.870811 -397.756521) (xy 76.870814 -397.823822)
			(xy 76.862774 -397.890642) (xy 76.846806 -397.956022) (xy 76.823139 -398.019024) (xy 76.792111 -398.078747)
			(xy 76.754168 -398.134333) (xy 76.732384 -398.159986) (xy 76.726567 -398.167116) (xy 76.720065 -398.184318)
			(xy 76.719684 -398.193514) (xy 76.719684 -398.351502) (xy 76.719169 -398.361657) (xy 76.711398 -398.380422)
			(xy 76.697039 -398.394787) (xy 76.678277 -398.402565) (xy 76.668122 -398.403064) (xy 75.951842 -398.403064)
			(xy 75.941673 -398.402602) (xy 75.92288 -398.394831) (xy 75.908494 -398.380457) (xy 75.900707 -398.36167)
			(xy 75.90028 -398.351502) (xy 75.90028 -398.193514) (xy 75.899868 -398.184327) (xy 75.893356 -398.167142)
			(xy 75.88758 -398.159986) (xy 75.865754 -398.134365) (xy 75.827803 -398.078775) (xy 75.79677 -398.019048)
			(xy 75.773097 -397.956039) (xy 75.757126 -397.890653) (xy 75.749084 -397.823826) (xy 74.620438 -397.823826)
			(xy 74.591977 -397.878596) (xy 74.554025 -397.934182) (xy 74.532236 -397.959834) (xy 74.526435 -397.966975)
			(xy 74.519925 -397.984169) (xy 74.519536 -397.993362) (xy 74.519536 -398.486884) (xy 74.519968 -398.496069)
			(xy 74.526468 -398.513252) (xy 74.532236 -398.520412) (xy 74.55406 -398.546035) (xy 74.592009 -398.601625)
			(xy 74.623043 -398.661352) (xy 74.646714 -398.724361) (xy 74.662686 -398.789747) (xy 74.670727 -398.856573)
			(xy 74.670724 -398.923881) (xy 74.662676 -398.990707) (xy 74.646698 -399.056091) (xy 74.623021 -399.119097)
			(xy 74.591982 -399.178822) (xy 74.554027 -399.234408) (xy 74.532236 -399.26006) (xy 74.526424 -399.267194)
			(xy 74.51992 -399.284393) (xy 74.519536 -399.293588) (xy 74.519536 -399.451576) (xy 74.51906 -399.461724)
			(xy 74.511279 -399.480469) (xy 74.496899 -399.494792) (xy 74.478124 -399.502499) (xy 74.467974 -399.502884)
			(xy 73.751694 -399.502884) (xy 73.74157 -399.502379) (xy 73.722853 -399.494654) (xy 73.708498 -399.480373)
			(xy 73.700675 -399.461697) (xy 73.700132 -399.451576) (xy 73.700132 -399.293588) (xy 73.699721 -399.284401)
			(xy 73.693207 -399.267217) (xy 73.687432 -399.26006) (xy 73.66568 -399.234378) (xy 73.627731 -399.178796)
			(xy 73.596696 -399.119077) (xy 73.573022 -399.056076) (xy 73.557047 -398.990697) (xy 73.549 -398.923878)
			(xy 73.548996 -398.856576) (xy 73.557037 -398.789756) (xy 73.573006 -398.724376) (xy 73.596674 -398.661373)
			(xy 73.627703 -398.60165) (xy 73.665647 -398.546064) (xy 73.687432 -398.520412) (xy 73.693253 -398.513284)
			(xy 73.699752 -398.49608) (xy 73.700132 -398.486884) (xy 73.700132 -397.993362) (xy 73.699733 -397.984174)
			(xy 73.693211 -397.96699) (xy 73.687432 -397.959834) (xy 73.665654 -397.934174) (xy 73.627705 -397.878588)
			(xy 73.596672 -397.818866) (xy 73.572999 -397.755862) (xy 73.557026 -397.690481) (xy 73.548981 -397.62366)
			(xy 73.54898 -397.556355) (xy 72.420766 -397.556355) (xy 72.423159 -397.560948) (xy 72.446926 -397.62404)
			(xy 72.462964 -397.689526) (xy 72.471043 -397.756461) (xy 72.471047 -397.823882) (xy 72.462974 -397.890818)
			(xy 72.446942 -397.956305) (xy 72.423182 -398.0194) (xy 72.392035 -398.079195) (xy 72.35395 -398.134829)
			(xy 72.332088 -398.160494) (xy 72.32631 -398.167652) (xy 72.319785 -398.184833) (xy 72.319388 -398.194022)
			(xy 72.319388 -398.351502) (xy 72.318876 -398.361625) (xy 72.311153 -398.380341) (xy 72.296875 -398.394696)
			(xy 72.278201 -398.40252) (xy 72.26808 -398.403064) (xy 71.5518 -398.403064) (xy 71.541641 -398.402678)
			(xy 71.522882 -398.394875) (xy 71.508557 -398.380467) (xy 71.500864 -398.361663) (xy 71.500492 -398.351502)
			(xy 71.500492 -398.194022) (xy 71.500073 -398.184836) (xy 71.493566 -398.167651) (xy 71.487792 -398.160494)
			(xy 71.465891 -398.134859) (xy 71.427804 -398.07922) (xy 71.396655 -398.01942) (xy 71.372894 -397.956319)
			(xy 71.356861 -397.890826) (xy 71.348788 -397.823885) (xy 66.525648 -397.823885) (xy 66.525648 -401.723796)
			(xy 71.3488 -401.723796) (xy 71.348802 -401.656371) (xy 71.35688 -401.589431) (xy 71.372917 -401.523941)
			(xy 71.396683 -401.460843) (xy 71.427836 -401.401046) (xy 71.465927 -401.345411) (xy 71.487792 -401.319746)
			(xy 71.493593 -401.312604) (xy 71.500105 -401.295411) (xy 71.500492 -401.286218) (xy 71.500492 -400.793966)
			(xy 71.5001 -400.784777) (xy 71.493574 -400.767592) (xy 71.487792 -400.760438) (xy 71.465934 -400.734768)
			(xy 71.427846 -400.679134) (xy 71.396695 -400.619338) (xy 71.372931 -400.556242) (xy 71.356896 -400.490754)
			(xy 71.348819 -400.423816) (xy 71.348819 -400.356393) (xy 71.356894 -400.289455) (xy 71.372928 -400.223967)
			(xy 71.396692 -400.16087) (xy 71.427841 -400.101074) (xy 71.465929 -400.045439) (xy 71.487792 -400.019774)
			(xy 71.493581 -400.012623) (xy 71.500101 -399.995437) (xy 71.500492 -399.986246) (xy 71.500492 -399.828766)
			(xy 71.500997 -399.818643) (xy 71.508727 -399.79993) (xy 71.523007 -399.785577) (xy 71.54168 -399.77775)
			(xy 71.5518 -399.777204) (xy 72.26808 -399.777204) (xy 72.278233 -399.777638) (xy 72.296986 -399.785428)
			(xy 72.31131 -399.799821) (xy 72.31901 -399.818611) (xy 72.319388 -399.828766) (xy 72.319388 -399.986246)
			(xy 72.319827 -399.99543) (xy 72.326321 -400.012615) (xy 72.332088 -400.019774) (xy 72.353958 -400.045434)
			(xy 72.392048 -400.101069) (xy 72.423199 -400.160866) (xy 72.446963 -400.223963) (xy 72.462999 -400.289453)
			(xy 72.471074 -400.356392) (xy 72.471074 -400.423817) (xy 72.462997 -400.490756) (xy 72.44696 -400.556245)
			(xy 72.423195 -400.619342) (xy 72.392043 -400.679139) (xy 72.353953 -400.734773) (xy 72.332088 -400.760438)
			(xy 72.326291 -400.767583) (xy 72.319777 -400.784774) (xy 72.319388 -400.793966) (xy 72.319388 -401.286218)
			(xy 72.319792 -401.295406) (xy 72.32631 -401.31259) (xy 72.332088 -401.319746) (xy 72.353931 -401.345429)
			(xy 72.392021 -401.401061) (xy 72.423173 -401.460854) (xy 72.446939 -401.523949) (xy 72.462977 -401.589436)
			(xy 72.471054 -401.656372) (xy 72.471056 -401.723795) (xy 72.462982 -401.790732) (xy 72.446949 -401.85622)
			(xy 72.423187 -401.919316) (xy 72.392038 -401.979111) (xy 72.353951 -402.034745) (xy 72.332088 -402.06041)
			(xy 72.326303 -402.067564) (xy 72.319782 -402.084748) (xy 72.319388 -402.093938) (xy 72.319388 -402.251418)
			(xy 72.318889 -402.261542) (xy 72.311161 -402.280259) (xy 72.296879 -402.294614) (xy 72.278202 -402.302437)
			(xy 72.26808 -402.30298) (xy 71.5518 -402.30298) (xy 71.541643 -402.302578) (xy 71.522887 -402.294779)
			(xy 71.508563 -402.280376) (xy 71.500867 -402.261577) (xy 71.500492 -402.251418) (xy 71.500492 -402.093938)
			(xy 71.500065 -402.084753) (xy 71.493563 -402.067568) (xy 71.487792 -402.06041) (xy 71.465907 -402.034762)
			(xy 71.427819 -401.979125) (xy 71.39667 -401.919326) (xy 71.372907 -401.856227) (xy 71.356874 -401.790736)
			(xy 71.3488 -401.723796) (xy 66.525648 -401.723796) (xy 66.525648 -402.823818) (xy 73.54894 -402.823818)
			(xy 73.548944 -402.75651) (xy 73.556993 -402.689684) (xy 73.572971 -402.624299) (xy 73.596649 -402.561293)
			(xy 73.627687 -402.501568) (xy 73.665642 -402.44598) (xy 73.687432 -402.420328) (xy 73.693246 -402.413195)
			(xy 73.699749 -402.395995) (xy 73.700132 -402.3868) (xy 73.700132 -401.893532) (xy 73.699699 -401.884347)
			(xy 73.6932 -401.867163) (xy 73.687432 -401.860004) (xy 73.665625 -401.834368) (xy 73.627677 -401.778779)
			(xy 73.596645 -401.719053) (xy 73.572974 -401.656047) (xy 73.557002 -401.590662) (xy 73.54896 -401.523838)
			(xy 73.548962 -401.456532) (xy 73.557008 -401.389708) (xy 73.572982 -401.324325) (xy 73.596657 -401.261319)
			(xy 73.627692 -401.201595) (xy 73.665643 -401.146008) (xy 73.687432 -401.120356) (xy 73.693234 -401.113215)
			(xy 73.699745 -401.096021) (xy 73.700132 -401.086828) (xy 73.700132 -400.92884) (xy 73.700555 -400.918685)
			(xy 73.708343 -400.899927) (xy 73.722741 -400.885601) (xy 73.741537 -400.877906) (xy 73.751694 -400.877532)
			(xy 74.467974 -400.877532) (xy 74.478098 -400.878047) (xy 74.496817 -400.885765) (xy 74.511174 -400.900043)
			(xy 74.518996 -400.918719) (xy 74.519536 -400.92884) (xy 74.519536 -401.086828) (xy 74.519947 -401.096015)
			(xy 74.526462 -401.113198) (xy 74.532236 -401.120356) (xy 74.554005 -401.146024) (xy 74.591956 -401.201608)
			(xy 74.622991 -401.261329) (xy 74.646666 -401.324331) (xy 74.662641 -401.389712) (xy 74.670687 -401.456533)
			(xy 74.670689 -401.523837) (xy 74.662647 -401.590659) (xy 74.646675 -401.65604) (xy 74.623004 -401.719044)
			(xy 74.620565 -401.723737) (xy 75.749095 -401.723737) (xy 75.749097 -401.65643) (xy 75.757144 -401.589605)
			(xy 75.773121 -401.524221) (xy 75.796798 -401.461215) (xy 75.827836 -401.401492) (xy 75.86579 -401.345906)
			(xy 75.88758 -401.320254) (xy 75.893376 -401.313108) (xy 75.899892 -401.295918) (xy 75.90028 -401.286726)
			(xy 75.90028 -400.793458) (xy 75.899895 -400.784268) (xy 75.893364 -400.767084) (xy 75.88758 -400.75993)
			(xy 75.865797 -400.734274) (xy 75.827845 -400.678689) (xy 75.79681 -400.618966) (xy 75.773135 -400.555962)
			(xy 75.75716 -400.49058) (xy 75.749115 -400.423757) (xy 75.749114 -400.356452) (xy 75.757158 -400.289629)
			(xy 75.773132 -400.224247) (xy 75.796806 -400.161242) (xy 75.827841 -400.101519) (xy 75.865791 -400.045934)
			(xy 75.88758 -400.020282) (xy 75.893364 -400.013128) (xy 75.899887 -399.995944) (xy 75.90028 -399.986754)
			(xy 75.90028 -399.828766) (xy 75.900637 -399.818587) (xy 75.908441 -399.799783) (xy 75.922847 -399.785398)
			(xy 75.941662 -399.777622) (xy 75.951842 -399.777204) (xy 76.668122 -399.777204) (xy 76.678277 -399.777714)
			(xy 76.69704 -399.78549) (xy 76.711404 -399.79985) (xy 76.719183 -399.818611) (xy 76.719684 -399.828766)
			(xy 76.719684 -399.986754) (xy 76.72012 -399.995938) (xy 76.726616 -400.013123) (xy 76.732384 -400.020282)
			(xy 76.754177 -400.04593) (xy 76.792124 -400.101517) (xy 76.823156 -400.161242) (xy 76.846827 -400.224247)
			(xy 76.862799 -400.289629) (xy 76.870842 -400.356452) (xy 76.870842 -400.423757) (xy 76.862798 -400.49058)
			(xy 76.846825 -400.555962) (xy 76.823152 -400.618967) (xy 76.792119 -400.678691) (xy 76.754171 -400.734278)
			(xy 76.732384 -400.75993) (xy 76.72659 -400.767077) (xy 76.720074 -400.784266) (xy 76.719684 -400.793458)
			(xy 76.719684 -401.286726) (xy 76.720085 -401.295914) (xy 76.726605 -401.313098) (xy 76.732384 -401.320254)
			(xy 76.754149 -401.345924) (xy 76.792097 -401.401509) (xy 76.82313 -401.46123) (xy 76.846803 -401.524232)
			(xy 76.862777 -401.589612) (xy 76.870823 -401.656432) (xy 76.870825 -401.723735) (xy 76.862783 -401.790556)
			(xy 76.846813 -401.855936) (xy 76.823144 -401.91894) (xy 76.792114 -401.978663) (xy 76.75417 -402.03425)
			(xy 76.732384 -402.059902) (xy 76.726602 -402.067058) (xy 76.720079 -402.08424) (xy 76.719684 -402.09343)
			(xy 76.719684 -402.251418) (xy 76.719182 -402.261574) (xy 76.711406 -402.28034) (xy 76.697043 -402.294704)
			(xy 76.678278 -402.302481) (xy 76.668122 -402.30298) (xy 75.951842 -402.30298) (xy 75.941675 -402.302502)
			(xy 75.922885 -402.294734) (xy 75.908499 -402.280365) (xy 75.90071 -402.261584) (xy 75.90028 -402.251418)
			(xy 75.90028 -402.09343) (xy 75.89986 -402.084244) (xy 75.893354 -402.067059) (xy 75.88758 -402.059902)
			(xy 75.865769 -402.034268) (xy 75.827819 -401.97868) (xy 75.796784 -401.918954) (xy 75.773111 -401.855947)
			(xy 75.757138 -401.790562) (xy 75.749095 -401.723737) (xy 74.620565 -401.723737) (xy 74.591971 -401.778767)
			(xy 74.554023 -401.834352) (xy 74.532236 -401.860004) (xy 74.526447 -401.867155) (xy 74.51993 -401.884341)
			(xy 74.519536 -401.893532) (xy 74.519536 -402.3868) (xy 74.519961 -402.395985) (xy 74.526466 -402.413169)
			(xy 74.532236 -402.420328) (xy 74.553977 -402.446019) (xy 74.591929 -402.501599) (xy 74.622966 -402.561317)
			(xy 74.646642 -402.624317) (xy 74.662619 -402.689694) (xy 74.670668 -402.756513) (xy 74.670672 -402.823815)
			(xy 74.670664 -402.823878) (xy 77.948708 -402.823878) (xy 77.948713 -402.75645) (xy 77.956794 -402.689508)
			(xy 77.972835 -402.624016) (xy 77.996606 -402.560917) (xy 78.027764 -402.501119) (xy 78.06586 -402.445485)
			(xy 78.087728 -402.41982) (xy 78.093545 -402.412689) (xy 78.100047 -402.395488) (xy 78.100428 -402.386292)
			(xy 78.100428 -401.89404) (xy 78.099992 -401.884856) (xy 78.093496 -401.867671) (xy 78.087728 -401.860512)
			(xy 78.065843 -401.834863) (xy 78.027753 -401.779227) (xy 77.996602 -401.719429) (xy 77.972838 -401.65633)
			(xy 77.956803 -401.590838) (xy 77.948728 -401.523898) (xy 77.94873 -401.456472) (xy 77.956808 -401.389532)
			(xy 77.972847 -401.324041) (xy 77.996614 -401.260944) (xy 78.027769 -401.201147) (xy 78.065862 -401.145513)
			(xy 78.087728 -401.119848) (xy 78.093533 -401.112709) (xy 78.100042 -401.095514) (xy 78.100428 -401.08632)
			(xy 78.100428 -400.92884) (xy 78.10085 -400.918717) (xy 78.10859 -400.900009) (xy 78.122905 -400.885692)
			(xy 78.141613 -400.87795) (xy 78.151736 -400.877532) (xy 78.868016 -400.877532) (xy 78.878144 -400.877903)
			(xy 78.896854 -400.885663) (xy 78.911169 -400.899993) (xy 78.918908 -400.918712) (xy 78.919324 -400.92884)
			(xy 78.919324 -401.08632) (xy 78.919719 -401.095509) (xy 78.926243 -401.112693) (xy 78.932024 -401.119848)
			(xy 78.953867 -401.14553) (xy 78.991955 -401.201163) (xy 79.023105 -401.260957) (xy 79.04687 -401.324051)
			(xy 79.062906 -401.389538) (xy 79.070983 -401.456474) (xy 79.070985 -401.523896) (xy 79.062911 -401.590832)
			(xy 79.046879 -401.65632) (xy 79.023118 -401.719416) (xy 79.020837 -401.723796) (xy 80.148888 -401.723796)
			(xy 80.14889 -401.656371) (xy 80.156967 -401.589432) (xy 80.173004 -401.523942) (xy 80.19677 -401.460844)
			(xy 80.227922 -401.401047) (xy 80.266012 -401.345412) (xy 80.287876 -401.319746) (xy 80.293675 -401.312603)
			(xy 80.300189 -401.295411) (xy 80.300576 -401.286218) (xy 80.300576 -400.793966) (xy 80.300187 -400.784776)
			(xy 80.293659 -400.767592) (xy 80.287876 -400.760438) (xy 80.266019 -400.734767) (xy 80.227931 -400.679133)
			(xy 80.196782 -400.619337) (xy 80.173018 -400.556241) (xy 80.156983 -400.490753) (xy 80.148907 -400.423816)
			(xy 80.148907 -400.356393) (xy 80.156982 -400.289456) (xy 80.173016 -400.223967) (xy 80.196778 -400.160871)
			(xy 80.227927 -400.101075) (xy 80.266013 -400.04544) (xy 80.287876 -400.019774) (xy 80.293663 -400.012622)
			(xy 80.300184 -399.995437) (xy 80.300576 -399.986246) (xy 80.300576 -399.828766) (xy 80.301 -399.818633)
			(xy 80.308745 -399.799904) (xy 80.323051 -399.785548) (xy 80.341753 -399.777736) (xy 80.351884 -399.777204)
			(xy 81.068164 -399.777204) (xy 81.078316 -399.777651) (xy 81.097069 -399.785436) (xy 81.111393 -399.799825)
			(xy 81.119094 -399.818612) (xy 81.119472 -399.828766) (xy 81.119472 -399.986246) (xy 81.119914 -399.99543)
			(xy 81.126406 -400.012614) (xy 81.132172 -400.019774) (xy 81.154043 -400.045434) (xy 81.192133 -400.101069)
			(xy 81.223285 -400.160865) (xy 81.24705 -400.223963) (xy 81.263086 -400.289453) (xy 81.271162 -400.356392)
			(xy 81.271161 -400.423817) (xy 81.263085 -400.490756) (xy 81.247048 -400.556246) (xy 81.223282 -400.619343)
			(xy 81.192129 -400.679139) (xy 81.154037 -400.734773) (xy 81.132172 -400.760438) (xy 81.126373 -400.767581)
			(xy 81.11986 -400.784773) (xy 81.119472 -400.793966) (xy 81.119472 -401.286218) (xy 81.11988 -401.295405)
			(xy 81.126396 -401.312589) (xy 81.132172 -401.319746) (xy 81.154015 -401.345429) (xy 81.192107 -401.40106)
			(xy 81.22326 -401.460854) (xy 81.247026 -401.523948) (xy 81.263064 -401.589435) (xy 81.271142 -401.656372)
			(xy 81.271144 -401.723795) (xy 81.26307 -401.790732) (xy 81.247036 -401.85622) (xy 81.223273 -401.919316)
			(xy 81.192124 -401.979112) (xy 81.154036 -402.034745) (xy 81.132172 -402.06041) (xy 81.126385 -402.067562)
			(xy 81.119865 -402.084747) (xy 81.119472 -402.093938) (xy 81.119472 -402.251418) (xy 81.118989 -402.261544)
			(xy 81.111257 -402.280264) (xy 81.09697 -402.294619) (xy 81.078288 -402.30244) (xy 81.068164 -402.30298)
			(xy 80.351884 -402.30298) (xy 80.341726 -402.302591) (xy 80.32297 -402.294787) (xy 80.308646 -402.28038)
			(xy 80.30095 -402.261578) (xy 80.300576 -402.251418) (xy 80.300576 -402.093938) (xy 80.300153 -402.084752)
			(xy 80.293649 -402.067567) (xy 80.287876 -402.06041) (xy 80.265991 -402.034762) (xy 80.227905 -401.979125)
			(xy 80.196756 -401.919326) (xy 80.172994 -401.856227) (xy 80.156961 -401.790736) (xy 80.148888 -401.723796)
			(xy 79.020837 -401.723796) (xy 78.991971 -401.779212) (xy 78.953886 -401.834846) (xy 78.932024 -401.860512)
			(xy 78.926243 -401.867668) (xy 78.919718 -401.88485) (xy 78.919324 -401.89404) (xy 78.919324 -402.386292)
			(xy 78.919733 -402.395479) (xy 78.926247 -402.412664) (xy 78.932024 -402.41982) (xy 78.95384 -402.445525)
			(xy 78.991929 -402.501154) (xy 79.02308 -402.560945) (xy 79.046846 -402.624037) (xy 79.062884 -402.689521)
			(xy 79.070963 -402.756454) (xy 79.070968 -402.823818) (xy 82.349028 -402.823818) (xy 82.349032 -402.75651)
			(xy 82.357081 -402.689684) (xy 82.373058 -402.6243) (xy 82.396735 -402.561293) (xy 82.427773 -402.501568)
			(xy 82.465726 -402.44598) (xy 82.487516 -402.420328) (xy 82.493327 -402.413193) (xy 82.499833 -402.395995)
			(xy 82.500216 -402.3868) (xy 82.500216 -401.893532) (xy 82.499787 -401.884347) (xy 82.493286 -401.867163)
			(xy 82.487516 -401.860004) (xy 82.465709 -401.834368) (xy 82.427763 -401.778778) (xy 82.396731 -401.719052)
			(xy 82.373061 -401.656046) (xy 82.35709 -401.590662) (xy 82.349048 -401.523838) (xy 82.34905 -401.456532)
			(xy 82.357095 -401.389708) (xy 82.37307 -401.324325) (xy 82.396744 -401.26132) (xy 82.427778 -401.201596)
			(xy 82.465728 -401.146008) (xy 82.487516 -401.120356) (xy 82.493316 -401.113213) (xy 82.499828 -401.096021)
			(xy 82.500216 -401.086828) (xy 82.500216 -400.92884) (xy 82.500655 -400.918687) (xy 82.50844 -400.899932)
			(xy 82.522832 -400.885607) (xy 82.541623 -400.877908) (xy 82.551778 -400.877532) (xy 83.268058 -400.877532)
			(xy 83.278181 -400.878061) (xy 83.2969 -400.885773) (xy 83.311257 -400.900047) (xy 83.319079 -400.91872)
			(xy 83.31962 -400.92884) (xy 83.31962 -401.086828) (xy 83.320012 -401.096017) (xy 83.326538 -401.113202)
			(xy 83.33232 -401.120356) (xy 83.354089 -401.146024) (xy 83.392041 -401.201607) (xy 83.423078 -401.261328)
			(xy 83.446753 -401.324331) (xy 83.462729 -401.389711) (xy 83.470775 -401.456533) (xy 83.470777 -401.523837)
			(xy 83.462734 -401.590659) (xy 83.446762 -401.656041) (xy 83.42309 -401.719044) (xy 83.420621 -401.723796)
			(xy 84.548678 -401.723796) (xy 84.54868 -401.656371) (xy 84.556758 -401.589432) (xy 84.572795 -401.523942)
			(xy 84.59656 -401.460845) (xy 84.627711 -401.401047) (xy 84.6658 -401.345412) (xy 84.687664 -401.319746)
			(xy 84.693474 -401.312611) (xy 84.699979 -401.295412) (xy 84.700364 -401.286218) (xy 84.700364 -400.793966)
			(xy 84.699956 -400.784779) (xy 84.693439 -400.767595) (xy 84.687664 -400.760438) (xy 84.665807 -400.734767)
			(xy 84.627721 -400.679133) (xy 84.596572 -400.619337) (xy 84.572809 -400.556241) (xy 84.556774 -400.490753)
			(xy 84.548698 -400.423816) (xy 84.548698 -400.356393) (xy 84.556772 -400.289456) (xy 84.572806 -400.223968)
			(xy 84.596568 -400.160871) (xy 84.627716 -400.101075) (xy 84.665802 -400.04544) (xy 84.687664 -400.019774)
			(xy 84.693462 -400.01263) (xy 84.699974 -399.995438) (xy 84.700364 -399.986246) (xy 84.700364 -399.828766)
			(xy 84.700799 -399.818634) (xy 84.708543 -399.799908) (xy 84.722845 -399.785552) (xy 84.741542 -399.777738)
			(xy 84.751672 -399.777204) (xy 85.467952 -399.777204) (xy 85.478104 -399.777661) (xy 85.496856 -399.785442)
			(xy 85.511181 -399.799828) (xy 85.518881 -399.818613) (xy 85.51926 -399.828766) (xy 85.51926 -399.986246)
			(xy 85.519705 -399.995429) (xy 85.526196 -400.012613) (xy 85.53196 -400.019774) (xy 85.553831 -400.045434)
			(xy 85.591922 -400.101068) (xy 85.623075 -400.160865) (xy 85.646841 -400.223962) (xy 85.662877 -400.289453)
			(xy 85.670953 -400.356392) (xy 85.670952 -400.423817) (xy 85.662875 -400.490756) (xy 85.646838 -400.556246)
			(xy 85.623071 -400.619344) (xy 85.591918 -400.67914) (xy 85.553826 -400.734773) (xy 85.53196 -400.760438)
			(xy 85.52616 -400.76758) (xy 85.519648 -400.784773) (xy 85.51926 -400.793966) (xy 85.51926 -401.286218)
			(xy 85.51967 -401.295405) (xy 85.526185 -401.312589) (xy 85.53196 -401.319746) (xy 85.553804 -401.345428)
			(xy 85.591896 -401.40106) (xy 85.62305 -401.460853) (xy 85.646817 -401.523948) (xy 85.662855 -401.589435)
			(xy 85.670933 -401.656372) (xy 85.670935 -401.723795) (xy 85.662861 -401.790732) (xy 85.646827 -401.856221)
			(xy 85.623063 -401.919317) (xy 85.591913 -401.979112) (xy 85.553824 -402.034745) (xy 85.53196 -402.06041)
			(xy 85.526172 -402.067561) (xy 85.519653 -402.084747) (xy 85.51926 -402.093938) (xy 85.51926 -402.251418)
			(xy 85.518788 -402.261546) (xy 85.511055 -402.280268) (xy 85.496764 -402.294623) (xy 85.478078 -402.302442)
			(xy 85.467952 -402.30298) (xy 84.751672 -402.30298) (xy 84.741514 -402.302601) (xy 84.722757 -402.294792)
			(xy 84.708434 -402.280383) (xy 84.700738 -402.261579) (xy 84.700364 -402.251418) (xy 84.700364 -402.093938)
			(xy 84.699921 -402.084755) (xy 84.693429 -402.067571) (xy 84.687664 -402.06041) (xy 84.66578 -402.034762)
			(xy 84.627694 -401.979124) (xy 84.596546 -401.919325) (xy 84.572785 -401.856226) (xy 84.556752 -401.790735)
			(xy 84.548678 -401.723796) (xy 83.420621 -401.723796) (xy 83.392057 -401.778767) (xy 83.354108 -401.834352)
			(xy 83.33232 -401.860004) (xy 83.326542 -401.867162) (xy 83.320015 -401.884343) (xy 83.31962 -401.893532)
			(xy 83.31962 -402.3868) (xy 83.320026 -402.395988) (xy 83.326542 -402.413172) (xy 83.33232 -402.420328)
			(xy 83.354062 -402.446018) (xy 83.392015 -402.501598) (xy 83.423052 -402.561316) (xy 83.44673 -402.624316)
			(xy 83.462707 -402.689694) (xy 83.470756 -402.756513) (xy 83.47076 -402.823815) (xy 83.470752 -402.823878)
			(xy 86.748796 -402.823878) (xy 86.748801 -402.75645) (xy 86.756882 -402.689508) (xy 86.772922 -402.624016)
			(xy 86.796693 -402.560918) (xy 86.82785 -402.50112) (xy 86.865945 -402.445485) (xy 86.887812 -402.41982)
			(xy 86.893626 -402.412687) (xy 86.90013 -402.395487) (xy 86.900512 -402.386292) (xy 86.900512 -401.89404)
			(xy 86.90008 -401.884855) (xy 86.893581 -401.867671) (xy 86.887812 -401.860512) (xy 86.865928 -401.834863)
			(xy 86.827839 -401.779227) (xy 86.796689 -401.719428) (xy 86.772925 -401.656329) (xy 86.756891 -401.590838)
			(xy 86.748816 -401.523898) (xy 86.748818 -401.456472) (xy 86.756896 -401.389532) (xy 86.772934 -401.324042)
			(xy 86.796701 -401.260944) (xy 86.827855 -401.201148) (xy 86.865946 -401.145513) (xy 86.887812 -401.119848)
			(xy 86.893615 -401.112707) (xy 86.900125 -401.095513) (xy 86.900512 -401.08632) (xy 86.900512 -400.92884)
			(xy 86.900949 -400.918719) (xy 86.908686 -400.900014) (xy 86.922997 -400.885698) (xy 86.941699 -400.877953)
			(xy 86.95182 -400.877532) (xy 87.6681 -400.877532) (xy 87.678226 -400.877917) (xy 87.696936 -400.885671)
			(xy 87.711252 -400.899997) (xy 87.718991 -400.918713) (xy 87.719408 -400.92884) (xy 87.719408 -401.08632)
			(xy 87.719807 -401.095508) (xy 87.726328 -401.112693) (xy 87.732108 -401.119848) (xy 87.753952 -401.14553)
			(xy 87.792041 -401.201162) (xy 87.823192 -401.260956) (xy 87.846957 -401.324051) (xy 87.862994 -401.389538)
			(xy 87.871071 -401.456474) (xy 87.871073 -401.523896) (xy 87.862999 -401.590833) (xy 87.846966 -401.656321)
			(xy 87.823204 -401.719417) (xy 87.820954 -401.723737) (xy 115.349237 -401.723737) (xy 115.349239 -401.65643)
			(xy 115.357285 -401.589607) (xy 115.373259 -401.524224) (xy 115.396933 -401.461219) (xy 115.427967 -401.401494)
			(xy 115.465916 -401.345907) (xy 115.487704 -401.320254) (xy 115.493503 -401.313111) (xy 115.500016 -401.295919)
			(xy 115.500404 -401.286726) (xy 115.500404 -400.793458) (xy 115.500013 -400.784269) (xy 115.493486 -400.767085)
			(xy 115.487704 -400.75993) (xy 115.465923 -400.734273) (xy 115.427977 -400.678686) (xy 115.396945 -400.618963)
			(xy 115.373273 -400.555959) (xy 115.357301 -400.490578) (xy 115.349257 -400.423756) (xy 115.349256 -400.356453)
			(xy 115.357299 -400.289631) (xy 115.373271 -400.22425) (xy 115.396941 -400.161245) (xy 115.427972 -400.101522)
			(xy 115.465918 -400.045935) (xy 115.487704 -400.020282) (xy 115.493491 -400.01313) (xy 115.500011 -399.995945)
			(xy 115.500404 -399.986754) (xy 115.500404 -399.828766) (xy 115.500905 -399.81861) (xy 115.508684 -399.799847)
			(xy 115.523047 -399.785484) (xy 115.54181 -399.777705) (xy 115.551966 -399.777204) (xy 116.268246 -399.777204)
			(xy 116.278403 -399.777695) (xy 116.297166 -399.785478) (xy 116.311529 -399.799844) (xy 116.319307 -399.818609)
			(xy 116.319808 -399.828766) (xy 116.319808 -399.986754) (xy 116.320238 -399.995939) (xy 116.326738 -400.013124)
			(xy 116.332508 -400.020282) (xy 116.354303 -400.045929) (xy 116.392255 -400.101515) (xy 116.423291 -400.161238)
			(xy 116.446966 -400.224244) (xy 116.46294 -400.289627) (xy 116.470985 -400.356451) (xy 116.470984 -400.423758)
			(xy 116.462939 -400.490582) (xy 116.446963 -400.555965) (xy 116.423288 -400.61897) (xy 116.392251 -400.678693)
			(xy 116.354298 -400.734279) (xy 116.332508 -400.75993) (xy 116.326717 -400.767079) (xy 116.320199 -400.784267)
			(xy 116.319808 -400.793458) (xy 116.319808 -401.286726) (xy 116.320204 -401.295915) (xy 116.326727 -401.313099)
			(xy 116.332508 -401.320254) (xy 116.354276 -401.345923) (xy 116.392229 -401.401506) (xy 116.423266 -401.461227)
			(xy 116.446942 -401.524229) (xy 116.462918 -401.58961) (xy 116.470965 -401.656431) (xy 116.470967 -401.723736)
			(xy 116.462924 -401.790558) (xy 116.446952 -401.855939) (xy 116.423279 -401.918943) (xy 116.392246 -401.978666)
			(xy 116.354296 -402.034251) (xy 116.332508 -402.059902) (xy 116.326729 -402.06706) (xy 116.320204 -402.084241)
			(xy 116.319808 -402.09343) (xy 116.319808 -402.251418) (xy 116.319283 -402.261571) (xy 116.311511 -402.280332)
			(xy 116.297156 -402.294695) (xy 116.278399 -402.302477) (xy 116.268246 -402.30298) (xy 115.551966 -402.30298)
			(xy 115.541808 -402.302495) (xy 115.523042 -402.294713) (xy 115.508678 -402.280345) (xy 115.500902 -402.261576)
			(xy 115.500404 -402.251418) (xy 115.500404 -402.09343) (xy 115.499978 -402.084244) (xy 115.493475 -402.06706)
			(xy 115.487704 -402.059902) (xy 115.465896 -402.034267) (xy 115.42795 -401.978677) (xy 115.396919 -401.918951)
			(xy 115.373249 -401.855944) (xy 115.357279 -401.79056) (xy 115.349237 -401.723737) (xy 87.820954 -401.723737)
			(xy 87.792056 -401.779212) (xy 87.75397 -401.834847) (xy 87.732108 -401.860512) (xy 87.726325 -401.867667)
			(xy 87.719802 -401.88485) (xy 87.719408 -401.89404) (xy 87.719408 -402.386292) (xy 87.71982 -402.395479)
			(xy 87.726332 -402.412663) (xy 87.732108 -402.41982) (xy 87.753925 -402.445524) (xy 87.792014 -402.501153)
			(xy 87.823166 -402.560944) (xy 87.846933 -402.624036) (xy 87.862972 -402.68952) (xy 87.871051 -402.756454)
			(xy 87.871055 -402.823874) (xy 87.871055 -402.823878) (xy 117.548826 -402.823878) (xy 117.548831 -402.75645)
			(xy 117.556912 -402.689507) (xy 117.572954 -402.624015) (xy 117.596726 -402.560916) (xy 117.627885 -402.501119)
			(xy 117.665983 -402.445484) (xy 117.687852 -402.41982) (xy 117.693671 -402.412691) (xy 117.700171 -402.395488)
			(xy 117.700552 -402.386292) (xy 117.700552 -401.89404) (xy 117.700111 -401.884856) (xy 117.693618 -401.867672)
			(xy 117.687852 -401.860512) (xy 117.665967 -401.834864) (xy 117.627875 -401.779228) (xy 117.596722 -401.71943)
			(xy 117.572957 -401.656331) (xy 117.556921 -401.590839) (xy 117.548846 -401.523898) (xy 117.548848 -401.456472)
			(xy 117.556927 -401.389531) (xy 117.572966 -401.32404) (xy 117.596735 -401.260943) (xy 117.627891 -401.201146)
			(xy 117.665985 -401.145512) (xy 117.687852 -401.119848) (xy 117.69366 -401.112711) (xy 117.700166 -401.095514)
			(xy 117.700552 -401.08632) (xy 117.700552 -400.92884) (xy 117.701117 -400.91874) (xy 117.708832 -400.900072)
			(xy 117.723105 -400.885777) (xy 117.741761 -400.878033) (xy 117.75186 -400.877532) (xy 118.46814 -400.877532)
			(xy 118.478255 -400.877953) (xy 118.49694 -400.88571) (xy 118.511235 -400.900027) (xy 118.518963 -400.918724)
			(xy 118.519448 -400.92884) (xy 118.519448 -401.08632) (xy 118.51986 -401.095507) (xy 118.526374 -401.11269)
			(xy 118.532148 -401.119848) (xy 118.553994 -401.145529) (xy 118.592087 -401.20116) (xy 118.623241 -401.260953)
			(xy 118.647009 -401.324048) (xy 118.663047 -401.389536) (xy 118.671126 -401.456473) (xy 118.671127 -401.523897)
			(xy 118.663053 -401.590834) (xy 118.647018 -401.656323) (xy 118.623254 -401.719419) (xy 118.620974 -401.723796)
			(xy 119.749006 -401.723796) (xy 119.749008 -401.656371) (xy 119.757086 -401.589431) (xy 119.773123 -401.523941)
			(xy 119.79689 -401.460843) (xy 119.828043 -401.401046) (xy 119.866135 -401.345411) (xy 119.888 -401.319746)
			(xy 119.893802 -401.312605) (xy 119.900313 -401.295411) (xy 119.9007 -401.286218) (xy 119.9007 -400.793966)
			(xy 119.900306 -400.784777) (xy 119.893781 -400.767593) (xy 119.888 -400.760438) (xy 119.866142 -400.734768)
			(xy 119.828053 -400.679134) (xy 119.796902 -400.619339) (xy 119.773138 -400.556242) (xy 119.757102 -400.490754)
			(xy 119.749025 -400.423816) (xy 119.749025 -400.356393) (xy 119.7571 -400.289455) (xy 119.773135 -400.223966)
			(xy 119.796898 -400.16087) (xy 119.828048 -400.101074) (xy 119.866136 -400.045439) (xy 119.888 -400.019774)
			(xy 119.89379 -400.012624) (xy 119.900309 -399.995437) (xy 119.9007 -399.986246) (xy 119.9007 -399.828766)
			(xy 119.901197 -399.818642) (xy 119.908929 -399.799928) (xy 119.923211 -399.785574) (xy 119.941887 -399.777749)
			(xy 119.952008 -399.777204) (xy 120.668288 -399.777204) (xy 120.67841 -399.777626) (xy 120.697114 -399.785371)
			(xy 120.711429 -399.799686) (xy 120.719174 -399.81839) (xy 120.719596 -399.828512) (xy 120.719596 -399.986246)
			(xy 120.720033 -399.99543) (xy 120.726528 -400.012615) (xy 120.732296 -400.019774) (xy 120.754166 -400.045434)
			(xy 120.792255 -400.101069) (xy 120.823405 -400.160866) (xy 120.847169 -400.223964) (xy 120.863205 -400.289454)
			(xy 120.87128 -400.356392) (xy 120.87128 -400.423817) (xy 120.863203 -400.490755) (xy 120.847167 -400.556245)
			(xy 120.823402 -400.619342) (xy 120.79225 -400.679138) (xy 120.75416 -400.734773) (xy 120.732296 -400.760438)
			(xy 120.7265 -400.767584) (xy 120.719985 -400.784774) (xy 120.719596 -400.793966) (xy 120.719596 -401.286218)
			(xy 120.719998 -401.295406) (xy 120.726517 -401.31259) (xy 120.732296 -401.319746) (xy 120.754138 -401.345429)
			(xy 120.792228 -401.401061) (xy 120.82338 -401.460855) (xy 120.847146 -401.523949) (xy 120.863183 -401.589436)
			(xy 120.87126 -401.656372) (xy 120.871262 -401.723794) (xy 120.863189 -401.790731) (xy 120.847155 -401.856219)
			(xy 120.823394 -401.919315) (xy 120.792245 -401.979111) (xy 120.754159 -402.034745) (xy 120.732296 -402.06041)
			(xy 120.726512 -402.067564) (xy 120.71999 -402.084748) (xy 120.719596 -402.093938) (xy 120.719596 -402.251418)
			(xy 120.719089 -402.261541) (xy 120.711362 -402.280256) (xy 120.697083 -402.294611) (xy 120.678409 -402.302436)
			(xy 120.668288 -402.30298) (xy 119.952008 -402.30298) (xy 119.941884 -402.302577) (xy 119.923176 -402.294828)
			(xy 119.908861 -402.280507) (xy 119.901119 -402.261797) (xy 119.9007 -402.251672) (xy 119.9007 -402.093938)
			(xy 119.900272 -402.084753) (xy 119.893771 -402.067568) (xy 119.888 -402.06041) (xy 119.866114 -402.034763)
			(xy 119.828026 -401.979126) (xy 119.796877 -401.919327) (xy 119.773114 -401.856228) (xy 119.75708 -401.790736)
			(xy 119.749006 -401.723796) (xy 118.620974 -401.723796) (xy 118.592102 -401.779215) (xy 118.554013 -401.834848)
			(xy 118.532148 -401.860512) (xy 118.526357 -401.867661) (xy 118.519841 -401.884849) (xy 118.519448 -401.89404)
			(xy 118.519448 -402.386292) (xy 118.519874 -402.395477) (xy 118.526378 -402.412661) (xy 118.532148 -402.41982)
			(xy 118.553967 -402.445523) (xy 118.59206 -402.501151) (xy 118.623216 -402.560942) (xy 118.646985 -402.624034)
			(xy 118.663025 -402.689519) (xy 118.671106 -402.756454) (xy 118.67111 -402.823818) (xy 121.949146 -402.823818)
			(xy 121.94915 -402.756509) (xy 121.957199 -402.689684) (xy 121.973177 -402.624299) (xy 121.996856 -402.561292)
			(xy 122.027895 -402.501567) (xy 122.065849 -402.44598) (xy 122.08764 -402.420328) (xy 122.093455 -402.413196)
			(xy 122.099958 -402.395995) (xy 122.10034 -402.3868) (xy 122.10034 -401.893532) (xy 122.099905 -401.884348)
			(xy 122.093408 -401.867164) (xy 122.08764 -401.860004) (xy 122.065832 -401.834368) (xy 122.027884 -401.778779)
			(xy 121.996852 -401.719054) (xy 121.97318 -401.656047) (xy 121.957208 -401.590663) (xy 121.949166 -401.523838)
			(xy 121.949168 -401.456532) (xy 121.957214 -401.389708) (xy 121.973189 -401.324324) (xy 121.996864 -401.261319)
			(xy 122.0279 -401.201595) (xy 122.065851 -401.146008) (xy 122.08764 -401.120356) (xy 122.093443 -401.113215)
			(xy 122.099953 -401.096021) (xy 122.10034 -401.086828) (xy 122.10034 -400.92884) (xy 122.10075 -400.918715)
			(xy 122.108492 -400.900005) (xy 122.122812 -400.885688) (xy 122.141523 -400.877948) (xy 122.151648 -400.877532)
			(xy 122.868182 -400.877532) (xy 122.878307 -400.878041) (xy 122.897026 -400.885761) (xy 122.911383 -400.900041)
			(xy 122.919204 -400.918718) (xy 122.919744 -400.92884) (xy 122.919744 -401.086828) (xy 122.920153 -401.096015)
			(xy 122.926669 -401.113199) (xy 122.932444 -401.120356) (xy 122.954212 -401.146024) (xy 122.992163 -401.201608)
			(xy 123.023198 -401.261329) (xy 123.046873 -401.324332) (xy 123.062848 -401.389712) (xy 123.070894 -401.456533)
			(xy 123.070895 -401.523837) (xy 123.062853 -401.590658) (xy 123.046882 -401.65604) (xy 123.02321 -401.719043)
			(xy 123.020771 -401.723737) (xy 124.149301 -401.723737) (xy 124.149303 -401.65643) (xy 124.15735 -401.589605)
			(xy 124.173327 -401.524221) (xy 124.197004 -401.461215) (xy 124.228043 -401.401491) (xy 124.265997 -401.345906)
			(xy 124.287788 -401.320254) (xy 124.293585 -401.313109) (xy 124.3001 -401.295918) (xy 124.300488 -401.286726)
			(xy 124.300488 -400.793458) (xy 124.300101 -400.784268) (xy 124.293572 -400.767084) (xy 124.287788 -400.75993)
			(xy 124.266005 -400.734274) (xy 124.228052 -400.678689) (xy 124.197016 -400.618966) (xy 124.173341 -400.555962)
			(xy 124.157366 -400.49058) (xy 124.149321 -400.423757) (xy 124.14932 -400.356452) (xy 124.157365 -400.289629)
			(xy 124.173338 -400.224246) (xy 124.197013 -400.161242) (xy 124.228048 -400.101519) (xy 124.265999 -400.045933)
			(xy 124.287788 -400.020282) (xy 124.293573 -400.013129) (xy 124.300095 -399.995944) (xy 124.300488 -399.986754)
			(xy 124.300488 -399.828766) (xy 124.300837 -399.818586) (xy 124.308643 -399.799781) (xy 124.323052 -399.785395)
			(xy 124.341869 -399.777621) (xy 124.35205 -399.777204) (xy 125.06833 -399.777204) (xy 125.078486 -399.777708)
			(xy 125.097249 -399.785486) (xy 125.111612 -399.799848) (xy 125.119391 -399.818611) (xy 125.119892 -399.828766)
			(xy 125.119892 -399.986754) (xy 125.120326 -399.995939) (xy 125.126823 -400.013123) (xy 125.132592 -400.020282)
			(xy 125.154385 -400.04593) (xy 125.192331 -400.101518) (xy 125.223363 -400.161242) (xy 125.247034 -400.224247)
			(xy 125.263005 -400.289629) (xy 125.271049 -400.356452) (xy 125.271048 -400.423757) (xy 125.263004 -400.490579)
			(xy 125.247031 -400.555962) (xy 125.223359 -400.618966) (xy 125.192327 -400.67869) (xy 125.154379 -400.734277)
			(xy 125.132592 -400.75993) (xy 125.126799 -400.767078) (xy 125.120283 -400.784266) (xy 125.119892 -400.793458)
			(xy 125.119892 -401.286726) (xy 125.120291 -401.295914) (xy 125.126813 -401.313099) (xy 125.132592 -401.320254)
			(xy 125.154357 -401.345924) (xy 125.192305 -401.401509) (xy 125.223337 -401.46123) (xy 125.24701 -401.524232)
			(xy 125.262983 -401.589612) (xy 125.271029 -401.656432) (xy 125.271031 -401.723735) (xy 125.262989 -401.790555)
			(xy 125.24702 -401.855936) (xy 125.223351 -401.918939) (xy 125.192322 -401.978663) (xy 125.154377 -402.034249)
			(xy 125.132592 -402.059902) (xy 125.126811 -402.067058) (xy 125.120287 -402.08424) (xy 125.119892 -402.09343)
			(xy 125.119892 -402.251418) (xy 125.119382 -402.261573) (xy 125.111608 -402.280337) (xy 125.097247 -402.294701)
			(xy 125.078485 -402.30248) (xy 125.06833 -402.30298) (xy 124.35205 -402.30298) (xy 124.341884 -402.302496)
			(xy 124.323094 -402.29473) (xy 124.308708 -402.280363) (xy 124.300918 -402.261584) (xy 124.300488 -402.251418)
			(xy 124.300488 -402.09343) (xy 124.300066 -402.084244) (xy 124.293561 -402.067059) (xy 124.287788 -402.059902)
			(xy 124.265977 -402.034268) (xy 124.228026 -401.97868) (xy 124.196991 -401.918955) (xy 124.173317 -401.855948)
			(xy 124.157344 -401.790563) (xy 124.149301 -401.723737) (xy 123.020771 -401.723737) (xy 122.992178 -401.778766)
			(xy 122.954231 -401.834352) (xy 122.932444 -401.860004) (xy 122.926656 -401.867155) (xy 122.920138 -401.884341)
			(xy 122.919744 -401.893532) (xy 122.919744 -402.3868) (xy 122.920167 -402.395986) (xy 122.926673 -402.413169)
			(xy 122.932444 -402.420328) (xy 122.954185 -402.446019) (xy 122.992136 -402.501599) (xy 123.023173 -402.561317)
			(xy 123.046849 -402.624317) (xy 123.062826 -402.689695) (xy 123.070874 -402.756513) (xy 123.070878 -402.823815)
			(xy 123.07087 -402.823878) (xy 126.348914 -402.823878) (xy 126.348919 -402.75645) (xy 126.357 -402.689508)
			(xy 126.373042 -402.624016) (xy 126.396813 -402.560916) (xy 126.427971 -402.501119) (xy 126.466068 -402.445485)
			(xy 126.487936 -402.41982) (xy 126.493754 -402.41269) (xy 126.500255 -402.395488) (xy 126.500636 -402.386292)
			(xy 126.500636 -401.89404) (xy 126.500198 -401.884856) (xy 126.493703 -401.867672) (xy 126.487936 -401.860512)
			(xy 126.466051 -401.834864) (xy 126.427961 -401.779227) (xy 126.396809 -401.719429) (xy 126.373044 -401.65633)
			(xy 126.357009 -401.590839) (xy 126.348934 -401.523898) (xy 126.348936 -401.456472) (xy 126.357014 -401.389532)
			(xy 126.373053 -401.324041) (xy 126.396821 -401.260943) (xy 126.427976 -401.201147) (xy 126.46607 -401.145513)
			(xy 126.487936 -401.119848) (xy 126.493742 -401.112709) (xy 126.50025 -401.095514) (xy 126.500636 -401.08632)
			(xy 126.500636 -400.92884) (xy 126.50105 -400.918716) (xy 126.508791 -400.900006) (xy 126.523109 -400.885689)
			(xy 126.54182 -400.877949) (xy 126.551944 -400.877532) (xy 127.268224 -400.877532) (xy 127.278352 -400.877897)
			(xy 127.297062 -400.885659) (xy 127.311377 -400.899991) (xy 127.319116 -400.918711) (xy 127.319532 -400.92884)
			(xy 127.319532 -401.08632) (xy 127.319948 -401.095506) (xy 127.326459 -401.11269) (xy 127.332232 -401.119848)
			(xy 127.354075 -401.14553) (xy 127.392162 -401.201163) (xy 127.423312 -401.260957) (xy 127.447076 -401.324052)
			(xy 127.463112 -401.389538) (xy 127.471189 -401.456474) (xy 127.471191 -401.523896) (xy 127.463117 -401.590832)
			(xy 127.447085 -401.65632) (xy 127.423324 -401.719415) (xy 127.421073 -401.723737) (xy 128.549092 -401.723737)
			(xy 128.549094 -401.65643) (xy 128.557141 -401.589605) (xy 128.573117 -401.524221) (xy 128.596794 -401.461216)
			(xy 128.627832 -401.401492) (xy 128.665786 -401.345906) (xy 128.687576 -401.320254) (xy 128.693372 -401.313108)
			(xy 128.699888 -401.295918) (xy 128.700276 -401.286726) (xy 128.700276 -400.793458) (xy 128.699891 -400.784268)
			(xy 128.69336 -400.767084) (xy 128.687576 -400.75993) (xy 128.665793 -400.734273) (xy 128.627842 -400.678688)
			(xy 128.596806 -400.618966) (xy 128.573131 -400.555962) (xy 128.557157 -400.49058) (xy 128.549112 -400.423757)
			(xy 128.549111 -400.356452) (xy 128.557155 -400.289629) (xy 128.573129 -400.224247) (xy 128.596802 -400.161242)
			(xy 128.627837 -400.101519) (xy 128.665788 -400.045934) (xy 128.687576 -400.020282) (xy 128.69336 -400.013128)
			(xy 128.699883 -399.995944) (xy 128.700276 -399.986754) (xy 128.700276 -399.828766) (xy 128.700637 -399.818587)
			(xy 128.70844 -399.799785) (xy 128.722845 -399.7854) (xy 128.741659 -399.777623) (xy 128.751838 -399.777204)
			(xy 129.468118 -399.777204) (xy 129.478273 -399.777718) (xy 129.497036 -399.785492) (xy 129.511399 -399.799851)
			(xy 129.519179 -399.818611) (xy 129.51968 -399.828766) (xy 129.51968 -399.986754) (xy 129.520117 -399.995938)
			(xy 129.526612 -400.013123) (xy 129.53238 -400.020282) (xy 129.554173 -400.045929) (xy 129.592121 -400.101517)
			(xy 129.623152 -400.161241) (xy 129.646824 -400.224247) (xy 129.662796 -400.289629) (xy 129.670839 -400.356452)
			(xy 129.670839 -400.423757) (xy 129.662794 -400.49058) (xy 129.646821 -400.555962) (xy 129.623149 -400.618967)
			(xy 129.592116 -400.678691) (xy 129.554168 -400.734278) (xy 129.53238 -400.75993) (xy 129.526586 -400.767077)
			(xy 129.52007 -400.784266) (xy 129.51968 -400.793458) (xy 129.51968 -401.286726) (xy 129.520082 -401.295914)
			(xy 129.526602 -401.313098) (xy 129.53238 -401.320254) (xy 129.554146 -401.345924) (xy 129.592094 -401.401508)
			(xy 129.623127 -401.46123) (xy 129.6468 -401.524232) (xy 129.662774 -401.589612) (xy 129.67082 -401.656432)
			(xy 129.670822 -401.723735) (xy 129.66278 -401.790556) (xy 129.64681 -401.855937) (xy 129.623141 -401.91894)
			(xy 129.592111 -401.978663) (xy 129.554166 -402.03425) (xy 129.53238 -402.059902) (xy 129.526598 -402.067057)
			(xy 129.520075 -402.08424) (xy 129.51968 -402.09343) (xy 129.51968 -402.251418) (xy 129.519182 -402.261575)
			(xy 129.511405 -402.280341) (xy 129.497041 -402.294705) (xy 129.478275 -402.302482) (xy 129.468118 -402.30298)
			(xy 128.751838 -402.30298) (xy 128.741671 -402.302505) (xy 128.722881 -402.294736) (xy 128.708495 -402.280366)
			(xy 128.700706 -402.261584) (xy 128.700276 -402.251418) (xy 128.700276 -402.09343) (xy 128.699857 -402.084244)
			(xy 128.69335 -402.067059) (xy 128.687576 -402.059902) (xy 128.665766 -402.034268) (xy 128.627815 -401.97868)
			(xy 128.596781 -401.918954) (xy 128.573108 -401.855947) (xy 128.557135 -401.790562) (xy 128.549092 -401.723737)
			(xy 127.421073 -401.723737) (xy 127.392178 -401.779211) (xy 127.354094 -401.834846) (xy 127.332232 -401.860512)
			(xy 127.32644 -401.86766) (xy 127.319924 -401.884849) (xy 127.319532 -401.89404) (xy 127.319532 -402.386292)
			(xy 127.319961 -402.395477) (xy 127.326463 -402.412661) (xy 127.332232 -402.41982) (xy 127.354048 -402.445525)
			(xy 127.392136 -402.501154) (xy 127.423287 -402.560945) (xy 127.447052 -402.624037) (xy 127.46309 -402.689521)
			(xy 127.471169 -402.756454) (xy 127.471174 -402.823818) (xy 130.749234 -402.823818) (xy 130.749238 -402.75651)
			(xy 130.757287 -402.689684) (xy 130.773265 -402.624299) (xy 130.796942 -402.561293) (xy 130.82798 -402.501568)
			(xy 130.865934 -402.44598) (xy 130.887724 -402.420328) (xy 130.893536 -402.413194) (xy 130.900041 -402.395995)
			(xy 130.900424 -402.3868) (xy 130.900424 -401.893532) (xy 130.899993 -401.884347) (xy 130.893493 -401.867163)
			(xy 130.887724 -401.860004) (xy 130.865917 -401.834368) (xy 130.82797 -401.778779) (xy 130.796938 -401.719053)
			(xy 130.773267 -401.656046) (xy 130.757296 -401.590662) (xy 130.749254 -401.523838) (xy 130.749256 -401.456532)
			(xy 130.757301 -401.389708) (xy 130.773276 -401.324325) (xy 130.79695 -401.26132) (xy 130.827985 -401.201595)
			(xy 130.865935 -401.146008) (xy 130.887724 -401.120356) (xy 130.893525 -401.113214) (xy 130.900036 -401.096021)
			(xy 130.900424 -401.086828) (xy 130.900424 -400.92884) (xy 130.900855 -400.918686) (xy 130.908642 -400.899929)
			(xy 130.923036 -400.885604) (xy 130.94183 -400.877907) (xy 130.951986 -400.877532) (xy 131.668266 -400.877532)
			(xy 131.67839 -400.878054) (xy 131.697108 -400.88577) (xy 131.711465 -400.900045) (xy 131.719287 -400.918719)
			(xy 131.719828 -400.92884) (xy 131.719828 -401.086828) (xy 131.720218 -401.096017) (xy 131.726745 -401.113202)
			(xy 131.732528 -401.120356) (xy 131.754297 -401.146024) (xy 131.792249 -401.201607) (xy 131.823285 -401.261328)
			(xy 131.84696 -401.324331) (xy 131.862935 -401.389712) (xy 131.870981 -401.456533) (xy 131.870983 -401.523837)
			(xy 131.862941 -401.590659) (xy 131.846969 -401.65604) (xy 131.823297 -401.719044) (xy 131.792264 -401.778767)
			(xy 131.754315 -401.834352) (xy 131.732528 -401.860004) (xy 131.726738 -401.867154) (xy 131.720222 -401.884341)
			(xy 131.719828 -401.893532) (xy 131.719828 -402.3868) (xy 131.720232 -402.395988) (xy 131.726749 -402.413173)
			(xy 131.732528 -402.420328) (xy 131.75427 -402.446019) (xy 131.792222 -402.501599) (xy 131.823259 -402.561317)
			(xy 131.846936 -402.624316) (xy 131.862913 -402.689694) (xy 131.870962 -402.756513) (xy 131.870966 -402.823815)
			(xy 131.862926 -402.890635) (xy 131.846957 -402.956015) (xy 131.823289 -403.019017) (xy 131.792259 -403.078739)
			(xy 131.754314 -403.134324) (xy 131.732528 -403.159976) (xy 131.726708 -403.167104) (xy 131.720209 -403.184308)
			(xy 131.719828 -403.193504) (xy 131.719828 -403.351492) (xy 131.719372 -403.361642) (xy 131.711585 -403.380389)
			(xy 131.697199 -403.394712) (xy 131.678418 -403.402417) (xy 131.668266 -403.4028) (xy 130.951986 -403.4028)
			(xy 130.941863 -403.402286) (xy 130.92315 -403.394561) (xy 130.908795 -403.380284) (xy 130.90097 -403.361612)
			(xy 130.900424 -403.351492) (xy 130.900424 -403.193504) (xy 130.900007 -403.184318) (xy 130.893498 -403.167133)
			(xy 130.887724 -403.159976) (xy 130.86589 -403.134362) (xy 130.827943 -403.07877) (xy 130.796913 -403.019041)
			(xy 130.773243 -402.956032) (xy 130.757274 -402.890645) (xy 130.749234 -402.823818) (xy 127.471174 -402.823818)
			(xy 127.471174 -402.823874) (xy 127.463103 -402.890808) (xy 127.447074 -402.956294) (xy 127.423316 -403.019389)
			(xy 127.392173 -403.079184) (xy 127.354092 -403.134818) (xy 127.332232 -403.160484) (xy 127.326409 -403.16761)
			(xy 127.319912 -403.184816) (xy 127.319532 -403.194012) (xy 127.319532 -403.351492) (xy 127.319009 -403.361596)
			(xy 127.31128 -403.380268) (xy 127.296995 -403.394562) (xy 127.278328 -403.402303) (xy 127.268224 -403.4028)
			(xy 126.551944 -403.4028) (xy 126.541824 -403.402348) (xy 126.523122 -403.394614) (xy 126.508806 -403.380308)
			(xy 126.501059 -403.361611) (xy 126.500636 -403.351492) (xy 126.500636 -403.194012) (xy 126.500212 -403.184826)
			(xy 126.493707 -403.167642) (xy 126.487936 -403.160484) (xy 126.466024 -403.134858) (xy 126.427934 -403.079219)
			(xy 126.396783 -403.019418) (xy 126.37302 -402.956315) (xy 126.356987 -402.890821) (xy 126.348914 -402.823878)
			(xy 123.07087 -402.823878) (xy 123.062839 -402.890634) (xy 123.04687 -402.956014) (xy 123.023202 -403.019017)
			(xy 122.992173 -403.078739) (xy 122.954229 -403.134324) (xy 122.932444 -403.159976) (xy 122.926626 -403.167106)
			(xy 122.920126 -403.184308) (xy 122.919744 -403.193504) (xy 122.919744 -403.351492) (xy 122.919209 -403.361595)
			(xy 122.911483 -403.380264) (xy 122.897201 -403.394558) (xy 122.878538 -403.402301) (xy 122.868436 -403.4028)
			(xy 122.151902 -403.4028) (xy 122.14178 -403.402273) (xy 122.123067 -403.394553) (xy 122.108712 -403.38028)
			(xy 122.100886 -403.361611) (xy 122.10034 -403.351492) (xy 122.10034 -403.193504) (xy 122.099919 -403.184318)
			(xy 122.093412 -403.167134) (xy 122.08764 -403.159976) (xy 122.065805 -403.134363) (xy 122.027857 -403.078771)
			(xy 121.996826 -403.019042) (xy 121.973156 -402.956032) (xy 121.957186 -402.890645) (xy 121.949146 -402.823818)
			(xy 118.67111 -402.823818) (xy 118.67111 -402.823874) (xy 118.663038 -402.89081) (xy 118.647006 -402.956297)
			(xy 118.623245 -403.019392) (xy 118.592097 -403.079187) (xy 118.554011 -403.13482) (xy 118.532148 -403.160484)
			(xy 118.526327 -403.167612) (xy 118.519828 -403.184816) (xy 118.519448 -403.194012) (xy 118.519448 -403.351492)
			(xy 118.51891 -403.361594) (xy 118.511183 -403.380263) (xy 118.496903 -403.394557) (xy 118.478242 -403.4023)
			(xy 118.46814 -403.4028) (xy 117.75186 -403.4028) (xy 117.741749 -403.402348) (xy 117.72307 -403.394597)
			(xy 117.708776 -403.38029) (xy 117.701043 -403.361604) (xy 117.700552 -403.351492) (xy 117.700552 -403.194012)
			(xy 117.700125 -403.184827) (xy 117.693622 -403.167643) (xy 117.687852 -403.160484) (xy 117.665939 -403.134859)
			(xy 117.627848 -403.07922) (xy 117.596697 -403.019418) (xy 117.572933 -402.956316) (xy 117.556899 -402.890822)
			(xy 117.548826 -402.823878) (xy 87.871055 -402.823878) (xy 87.862984 -402.890809) (xy 87.846954 -402.956295)
			(xy 87.823196 -403.01939) (xy 87.792051 -403.079185) (xy 87.753969 -403.134819) (xy 87.732108 -403.160484)
			(xy 87.726294 -403.167617) (xy 87.71979 -403.184817) (xy 87.719408 -403.194012) (xy 87.719408 -403.351492)
			(xy 87.718978 -403.361613) (xy 87.711234 -403.380315) (xy 87.696922 -403.394629) (xy 87.678221 -403.402376)
			(xy 87.6681 -403.4028) (xy 86.95182 -403.4028) (xy 86.941699 -403.402368) (xy 86.922996 -403.394626)
			(xy 86.908681 -403.380315) (xy 86.900935 -403.361613) (xy 86.900512 -403.351492) (xy 86.900512 -403.194012)
			(xy 86.900093 -403.184826) (xy 86.893585 -403.167642) (xy 86.887812 -403.160484) (xy 86.8659 -403.134858)
			(xy 86.827812 -403.079218) (xy 86.796663 -403.019417) (xy 86.772901 -402.956315) (xy 86.756869 -402.890821)
			(xy 86.748796 -402.823878) (xy 83.470752 -402.823878) (xy 83.46272 -402.890635) (xy 83.446751 -402.956015)
			(xy 83.423082 -403.019018) (xy 83.392052 -403.07874) (xy 83.354106 -403.134324) (xy 83.33232 -403.159976)
			(xy 83.326511 -403.167113) (xy 83.320003 -403.18431) (xy 83.31962 -403.193504) (xy 83.31962 -403.351492)
			(xy 83.319172 -403.361643) (xy 83.311383 -403.380391) (xy 83.296995 -403.394714) (xy 83.278211 -403.402418)
			(xy 83.268058 -403.4028) (xy 82.551778 -403.4028) (xy 82.541655 -403.402293) (xy 82.522941 -403.394565)
			(xy 82.508586 -403.380286) (xy 82.500761 -403.361613) (xy 82.500216 -403.351492) (xy 82.500216 -403.193504)
			(xy 82.4998 -403.184318) (xy 82.49329 -403.167133) (xy 82.487516 -403.159976) (xy 82.465682 -403.134362)
			(xy 82.427736 -403.07877) (xy 82.396706 -403.019041) (xy 82.373037 -402.956031) (xy 82.357068 -402.890645)
			(xy 82.349028 -402.823818) (xy 79.070968 -402.823818) (xy 79.070968 -402.823874) (xy 79.062897 -402.890808)
			(xy 79.046867 -402.956294) (xy 79.023109 -403.019389) (xy 78.991966 -403.079184) (xy 78.953884 -403.134818)
			(xy 78.932024 -403.160484) (xy 78.926212 -403.167618) (xy 78.919706 -403.184817) (xy 78.919324 -403.194012)
			(xy 78.919324 -403.351492) (xy 78.918809 -403.361597) (xy 78.911078 -403.380271) (xy 78.896791 -403.394565)
			(xy 78.878121 -403.402304) (xy 78.868016 -403.4028) (xy 78.151736 -403.4028) (xy 78.141616 -403.402354)
			(xy 78.122913 -403.394618) (xy 78.108598 -403.38031) (xy 78.100851 -403.361612) (xy 78.100428 -403.351492)
			(xy 78.100428 -403.194012) (xy 78.100006 -403.184826) (xy 78.0935 -403.167642) (xy 78.087728 -403.160484)
			(xy 78.065816 -403.134858) (xy 78.027727 -403.079219) (xy 77.996577 -403.019417) (xy 77.972814 -402.956315)
			(xy 77.956781 -402.890821) (xy 77.948708 -402.823878) (xy 74.670664 -402.823878) (xy 74.662632 -402.890635)
			(xy 74.646664 -402.956014) (xy 74.622995 -403.019017) (xy 74.591966 -403.078739) (xy 74.554022 -403.134324)
			(xy 74.532236 -403.159976) (xy 74.526417 -403.167105) (xy 74.519917 -403.184308) (xy 74.519536 -403.193504)
			(xy 74.519536 -403.351492) (xy 74.519073 -403.361641) (xy 74.511286 -403.380386) (xy 74.496903 -403.394709)
			(xy 74.478125 -403.402415) (xy 74.467974 -403.4028) (xy 73.751694 -403.4028) (xy 73.741572 -403.402279)
			(xy 73.722858 -403.394557) (xy 73.708504 -403.380282) (xy 73.700678 -403.361611) (xy 73.700132 -403.351492)
			(xy 73.700132 -403.193504) (xy 73.699713 -403.184318) (xy 73.693205 -403.167134) (xy 73.687432 -403.159976)
			(xy 73.665597 -403.134363) (xy 73.62765 -403.07877) (xy 73.59662 -403.019041) (xy 73.57295 -402.956032)
			(xy 73.55698 -402.890645) (xy 73.54894 -402.823818) (xy 66.525648 -402.823818) (xy 66.525648 -405.623707)
			(xy 71.348811 -405.623707) (xy 71.348811 -405.556283) (xy 71.356888 -405.489345) (xy 71.372924 -405.423856)
			(xy 71.396688 -405.360759) (xy 71.427839 -405.300962) (xy 71.465928 -405.245327) (xy 71.487792 -405.219662)
			(xy 71.493586 -405.212515) (xy 71.500103 -405.195326) (xy 71.500492 -405.186134) (xy 71.500492 -404.693882)
			(xy 71.500092 -404.684694) (xy 71.493571 -404.667509) (xy 71.487792 -404.660354) (xy 71.46595 -404.634671)
			(xy 71.427861 -404.579039) (xy 71.39671 -404.519245) (xy 71.372945 -404.45615) (xy 71.356908 -404.390664)
			(xy 71.348831 -404.323727) (xy 71.348829 -404.256306) (xy 71.356902 -404.189369) (xy 71.372935 -404.123881)
			(xy 71.396696 -404.060785) (xy 71.427844 -404.00099) (xy 71.46593 -403.945355) (xy 71.487792 -403.91969)
			(xy 71.493574 -403.912535) (xy 71.500098 -403.895352) (xy 71.500492 -403.886162) (xy 71.500492 -403.728682)
			(xy 71.50101 -403.71856) (xy 71.508735 -403.699847) (xy 71.523011 -403.685493) (xy 71.541681 -403.677666)
			(xy 71.5518 -403.67712) (xy 72.26808 -403.67712) (xy 72.278235 -403.677538) (xy 72.296991 -403.685331)
			(xy 72.311316 -403.699729) (xy 72.319013 -403.718525) (xy 72.319388 -403.728682) (xy 72.319388 -403.886162)
			(xy 72.319819 -403.895347) (xy 72.326319 -403.912531) (xy 72.332088 -403.91969) (xy 72.353974 -403.945337)
			(xy 72.392063 -404.000974) (xy 72.423213 -404.060773) (xy 72.446977 -404.123872) (xy 72.463011 -404.189363)
			(xy 72.471085 -404.256304) (xy 72.471083 -404.323729) (xy 72.463005 -404.390669) (xy 72.446967 -404.45616)
			(xy 72.4232 -404.519258) (xy 72.392046 -404.579054) (xy 72.353954 -404.634689) (xy 72.332088 -404.660354)
			(xy 72.326285 -404.667494) (xy 72.319774 -404.684689) (xy 72.319388 -404.693882) (xy 72.319388 -405.186134)
			(xy 72.319784 -405.195323) (xy 72.326308 -405.212507) (xy 72.332088 -405.219662) (xy 72.353946 -405.245332)
			(xy 72.392036 -405.300965) (xy 72.423188 -405.360761) (xy 72.446953 -405.423857) (xy 72.462989 -405.489346)
			(xy 72.471066 -405.556284) (xy 72.471066 -405.623707) (xy 72.462991 -405.690645) (xy 72.446956 -405.756134)
			(xy 72.423191 -405.819231) (xy 72.392041 -405.879027) (xy 72.353952 -405.934661) (xy 72.332088 -405.960326)
			(xy 72.326297 -405.967475) (xy 72.319779 -405.984663) (xy 72.319388 -405.993854) (xy 72.319388 -406.151334)
			(xy 72.318902 -406.161459) (xy 72.311168 -406.180176) (xy 72.296883 -406.19453) (xy 72.278203 -406.202353)
			(xy 72.26808 -406.202896) (xy 71.5518 -406.202896) (xy 71.541645 -406.202478) (xy 71.522892 -406.194682)
			(xy 71.508569 -406.180284) (xy 71.50087 -406.161491) (xy 71.500492 -406.151334) (xy 71.500492 -405.993854)
			(xy 71.500058 -405.984669) (xy 71.493561 -405.967485) (xy 71.487792 -405.960326) (xy 71.465922 -405.934665)
			(xy 71.427834 -405.87903) (xy 71.396684 -405.819233) (xy 71.372921 -405.756136) (xy 71.356886 -405.690646)
			(xy 71.348811 -405.623707) (xy 66.525648 -405.623707) (xy 66.525648 -406.72373) (xy 73.548951 -406.72373)
			(xy 73.548954 -406.656422) (xy 73.557001 -406.589598) (xy 73.572978 -406.524214) (xy 73.596654 -406.461208)
			(xy 73.62769 -406.401483) (xy 73.665642 -406.345896) (xy 73.687432 -406.320244) (xy 73.693239 -406.313106)
			(xy 73.699747 -406.29591) (xy 73.700132 -406.286716) (xy 73.700132 -405.793448) (xy 73.699691 -405.784264)
			(xy 73.693198 -405.76708) (xy 73.687432 -405.75992) (xy 73.66564 -405.734271) (xy 73.627692 -405.678684)
			(xy 73.596659 -405.61896) (xy 73.572987 -405.555955) (xy 73.557015 -405.490572) (xy 73.548971 -405.42375)
			(xy 73.548971 -405.356444) (xy 73.557016 -405.289622) (xy 73.572989 -405.224239) (xy 73.596662 -405.161235)
			(xy 73.627695 -405.101511) (xy 73.665644 -405.045924) (xy 73.687432 -405.020272) (xy 73.693227 -405.013126)
			(xy 73.699742 -404.995936) (xy 73.700132 -404.986744) (xy 73.700132 -404.828756) (xy 73.700486 -404.818595)
			(xy 73.708302 -404.799836) (xy 73.72272 -404.785513) (xy 73.74153 -404.77782) (xy 73.751694 -404.777448)
			(xy 74.467974 -404.777448) (xy 74.4781 -404.777948) (xy 74.496822 -404.785669) (xy 74.51118 -404.799951)
			(xy 74.518998 -404.818633) (xy 74.519536 -404.828756) (xy 74.519536 -404.986744) (xy 74.519939 -404.995932)
			(xy 74.526459 -405.013115) (xy 74.532236 -405.020272) (xy 74.55402 -405.045927) (xy 74.591971 -405.101513)
			(xy 74.623006 -405.161235) (xy 74.64668 -405.22424) (xy 74.662654 -405.289622) (xy 74.670699 -405.356444)
			(xy 74.670699 -405.42375) (xy 74.662655 -405.490572) (xy 74.646682 -405.555955) (xy 74.623008 -405.618959)
			(xy 74.620571 -405.623649) (xy 75.749106 -405.623649) (xy 75.749107 -405.556342) (xy 75.757152 -405.489519)
			(xy 75.773127 -405.424136) (xy 75.796802 -405.361131) (xy 75.827839 -405.301407) (xy 75.865791 -405.245822)
			(xy 75.88758 -405.22017) (xy 75.893369 -405.21302) (xy 75.899889 -405.195833) (xy 75.90028 -405.186642)
			(xy 75.90028 -404.693374) (xy 75.899887 -404.684185) (xy 75.893362 -404.667001) (xy 75.88758 -404.659846)
			(xy 75.865813 -404.634177) (xy 75.827861 -404.578594) (xy 75.796824 -404.518873) (xy 75.773148 -404.45587)
			(xy 75.757173 -404.39049) (xy 75.749126 -404.323669) (xy 75.749124 -404.256365) (xy 75.757167 -404.189543)
			(xy 75.773138 -404.124161) (xy 75.796811 -404.061157) (xy 75.827844 -404.001435) (xy 75.865792 -403.94585)
			(xy 75.88758 -403.920198) (xy 75.893358 -403.913039) (xy 75.899884 -403.895859) (xy 75.90028 -403.88667)
			(xy 75.90028 -403.728682) (xy 75.90065 -403.718504) (xy 75.908449 -403.699701) (xy 75.922851 -403.685315)
			(xy 75.941664 -403.677538) (xy 75.951842 -403.67712) (xy 76.668122 -403.67712) (xy 76.678279 -403.677615)
			(xy 76.697045 -403.685393) (xy 76.711409 -403.699758) (xy 76.719186 -403.718525) (xy 76.719684 -403.728682)
			(xy 76.719684 -403.88667) (xy 76.720112 -403.895855) (xy 76.726614 -403.91304) (xy 76.732384 -403.920198)
			(xy 76.754193 -403.945833) (xy 76.792139 -404.001422) (xy 76.82317 -404.061148) (xy 76.846841 -404.124155)
			(xy 76.862812 -404.189539) (xy 76.870854 -404.256363) (xy 76.870852 -404.32367) (xy 76.862806 -404.390493)
			(xy 76.846831 -404.455877) (xy 76.823157 -404.518882) (xy 76.792122 -404.578606) (xy 76.754172 -404.634194)
			(xy 76.732384 -404.659846) (xy 76.726584 -404.666988) (xy 76.720072 -404.684181) (xy 76.719684 -404.693374)
			(xy 76.719684 -405.186642) (xy 76.720077 -405.195831) (xy 76.726603 -405.213015) (xy 76.732384 -405.22017)
			(xy 76.754165 -405.245827) (xy 76.792113 -405.301414) (xy 76.823145 -405.361137) (xy 76.846817 -405.42414)
			(xy 76.86279 -405.489522) (xy 76.870834 -405.556343) (xy 76.870835 -405.623648) (xy 76.862791 -405.690469)
			(xy 76.84682 -405.755851) (xy 76.823149 -405.818855) (xy 76.792117 -405.878579) (xy 76.754171 -405.934166)
			(xy 76.732384 -405.959818) (xy 76.726595 -405.966969) (xy 76.720077 -405.984155) (xy 76.719684 -405.993346)
			(xy 76.719684 -406.151334) (xy 76.719195 -406.161491) (xy 76.711414 -406.180257) (xy 76.697047 -406.19462)
			(xy 76.678279 -406.202397) (xy 76.668122 -406.202896) (xy 75.951842 -406.202896) (xy 75.941677 -406.202403)
			(xy 75.92289 -406.194638) (xy 75.908505 -406.180274) (xy 75.900712 -406.161498) (xy 75.90028 -406.151334)
			(xy 75.90028 -405.993346) (xy 75.899852 -405.984161) (xy 75.893351 -405.966976) (xy 75.88758 -405.959818)
			(xy 75.865785 -405.934171) (xy 75.827834 -405.878585) (xy 75.796799 -405.818861) (xy 75.773124 -405.755856)
			(xy 75.757151 -405.690472) (xy 75.749106 -405.623649) (xy 74.620571 -405.623649) (xy 74.591974 -405.678682)
			(xy 74.554024 -405.734268) (xy 74.532236 -405.75992) (xy 74.526441 -405.767066) (xy 74.519927 -405.784256)
			(xy 74.519536 -405.793448) (xy 74.519536 -406.286716) (xy 74.519953 -406.295902) (xy 74.526464 -406.313086)
			(xy 74.532236 -406.320244) (xy 74.553993 -406.345922) (xy 74.591944 -406.401504) (xy 74.62298 -406.461224)
			(xy 74.646656 -406.524225) (xy 74.662632 -406.589604) (xy 74.670679 -406.656424) (xy 74.670682 -406.723727)
			(xy 74.670675 -406.723789) (xy 77.94872 -406.723789) (xy 77.948723 -406.656363) (xy 77.956802 -406.589422)
			(xy 77.972842 -406.52393) (xy 77.996611 -406.460832) (xy 78.027767 -406.401035) (xy 78.065861 -406.345401)
			(xy 78.087728 -406.319736) (xy 78.093538 -406.3126) (xy 78.100044 -406.295402) (xy 78.100428 -406.286208)
			(xy 78.100428 -405.793956) (xy 78.100033 -405.784767) (xy 78.093508 -405.767584) (xy 78.087728 -405.760428)
			(xy 78.065859 -405.734766) (xy 78.027769 -405.679132) (xy 77.996617 -405.619336) (xy 77.972851 -405.556238)
			(xy 77.956815 -405.490748) (xy 77.948739 -405.423809) (xy 77.94874 -405.356385) (xy 77.956816 -405.289446)
			(xy 77.972853 -405.223956) (xy 77.996619 -405.160859) (xy 78.027772 -405.101063) (xy 78.065863 -405.045429)
			(xy 78.087728 -405.019764) (xy 78.093526 -405.01262) (xy 78.100039 -404.995428) (xy 78.100428 -404.986236)
			(xy 78.100428 -404.828756) (xy 78.10085 -404.818641) (xy 78.108607 -404.799956) (xy 78.122924 -404.785662)
			(xy 78.14162 -404.777934) (xy 78.151736 -404.777448) (xy 78.868016 -404.777448) (xy 78.878119 -404.777971)
			(xy 78.896788 -404.785704) (xy 78.91108 -404.799989) (xy 78.918823 -404.818653) (xy 78.919324 -404.828756)
			(xy 78.919324 -404.986236) (xy 78.919712 -404.995426) (xy 78.92624 -405.01261) (xy 78.932024 -405.019764)
			(xy 78.953883 -405.045433) (xy 78.99197 -405.101067) (xy 79.02312 -405.160863) (xy 79.046883 -405.22396)
			(xy 79.062918 -405.289448) (xy 79.070994 -405.356386) (xy 79.070995 -405.423808) (xy 79.062919 -405.490746)
			(xy 79.046885 -405.556235) (xy 79.023122 -405.619331) (xy 79.020843 -405.623707) (xy 80.148899 -405.623707)
			(xy 80.148899 -405.556284) (xy 80.156975 -405.489345) (xy 80.173011 -405.423856) (xy 80.196775 -405.360759)
			(xy 80.227925 -405.300963) (xy 80.266013 -405.245328) (xy 80.287876 -405.219662) (xy 80.293668 -405.212514)
			(xy 80.300186 -405.195326) (xy 80.300576 -405.186134) (xy 80.300576 -404.693882) (xy 80.30018 -404.684693)
			(xy 80.293657 -404.667509) (xy 80.287876 -404.660354) (xy 80.266034 -404.634671) (xy 80.227947 -404.579038)
			(xy 80.196796 -404.519244) (xy 80.173032 -404.45615) (xy 80.156996 -404.390663) (xy 80.148918 -404.323727)
			(xy 80.148917 -404.256306) (xy 80.15699 -404.189369) (xy 80.173022 -404.123882) (xy 80.196783 -404.060786)
			(xy 80.22793 -404.00099) (xy 80.266014 -403.945356) (xy 80.287876 -403.91969) (xy 80.293657 -403.912533)
			(xy 80.300182 -403.895352) (xy 80.300576 -403.886162) (xy 80.300576 -403.728682) (xy 80.301013 -403.71855)
			(xy 80.308753 -403.699821) (xy 80.323055 -403.685464) (xy 80.341754 -403.677652) (xy 80.351884 -403.67712)
			(xy 81.068164 -403.67712) (xy 81.078318 -403.677552) (xy 81.097074 -403.685339) (xy 81.111399 -403.699733)
			(xy 81.119096 -403.718526) (xy 81.119472 -403.728682) (xy 81.119472 -403.886162) (xy 81.119907 -403.895346)
			(xy 81.126404 -403.912531) (xy 81.132172 -403.91969) (xy 81.154059 -403.945337) (xy 81.192148 -404.000973)
			(xy 81.2233 -404.060772) (xy 81.247064 -404.123871) (xy 81.263099 -404.189363) (xy 81.271173 -404.256304)
			(xy 81.271171 -404.32373) (xy 81.263093 -404.39067) (xy 81.247054 -404.45616) (xy 81.223286 -404.519258)
			(xy 81.192131 -404.579055) (xy 81.154038 -404.634689) (xy 81.132172 -404.660354) (xy 81.126366 -404.667493)
			(xy 81.119858 -404.684688) (xy 81.119472 -404.693882) (xy 81.119472 -405.186134) (xy 81.119872 -405.195322)
			(xy 81.126393 -405.212506) (xy 81.132172 -405.219662) (xy 81.154031 -405.245332) (xy 81.192122 -405.300965)
			(xy 81.223274 -405.36076) (xy 81.24704 -405.423857) (xy 81.263077 -405.489345) (xy 81.271154 -405.556284)
			(xy 81.271154 -405.623707) (xy 81.263078 -405.690646) (xy 81.247043 -405.756135) (xy 81.223278 -405.819232)
			(xy 81.192126 -405.879027) (xy 81.154037 -405.934661) (xy 81.132172 -405.960326) (xy 81.126378 -405.967473)
			(xy 81.119862 -405.984662) (xy 81.119472 -405.993854) (xy 81.119472 -406.151334) (xy 81.119002 -406.161461)
			(xy 81.111265 -406.180181) (xy 81.096974 -406.194536) (xy 81.078289 -406.202356) (xy 81.068164 -406.202896)
			(xy 80.351884 -406.202896) (xy 80.341728 -406.202492) (xy 80.322975 -406.19469) (xy 80.308652 -406.180288)
			(xy 80.300953 -406.161492) (xy 80.300576 -406.151334) (xy 80.300576 -405.993854) (xy 80.300145 -405.984669)
			(xy 80.293646 -405.967484) (xy 80.287876 -405.960326) (xy 80.266007 -405.934665) (xy 80.22792 -405.879029)
			(xy 80.196771 -405.819232) (xy 80.173008 -405.756135) (xy 80.156974 -405.690646) (xy 80.148899 -405.623707)
			(xy 79.020843 -405.623707) (xy 78.991974 -405.679127) (xy 78.953887 -405.734762) (xy 78.932024 -405.760428)
			(xy 78.926236 -405.767579) (xy 78.919715 -405.784765) (xy 78.919324 -405.793956) (xy 78.919324 -406.286208)
			(xy 78.919725 -406.295396) (xy 78.926244 -406.312581) (xy 78.932024 -406.319736) (xy 78.953856 -406.345428)
			(xy 78.991944 -406.401059) (xy 79.023095 -406.460852) (xy 79.046859 -406.523945) (xy 79.062896 -406.589431)
			(xy 79.070974 -406.656366) (xy 79.070977 -406.72373) (xy 82.349039 -406.72373) (xy 82.349042 -406.656422)
			(xy 82.357089 -406.589598) (xy 82.373065 -406.524214) (xy 82.39674 -406.461209) (xy 82.427776 -406.401484)
			(xy 82.465727 -406.345896) (xy 82.487516 -406.320244) (xy 82.493321 -406.313105) (xy 82.49983 -406.29591)
			(xy 82.500216 -406.286716) (xy 82.500216 -405.793448) (xy 82.499779 -405.784264) (xy 82.493284 -405.767079)
			(xy 82.487516 -405.75992) (xy 82.465725 -405.734271) (xy 82.427778 -405.678683) (xy 82.396746 -405.618959)
			(xy 82.373074 -405.555954) (xy 82.357102 -405.490572) (xy 82.349059 -405.423749) (xy 82.349059 -405.356445)
			(xy 82.357103 -405.289622) (xy 82.373076 -405.22424) (xy 82.396748 -405.161235) (xy 82.427781 -405.101511)
			(xy 82.465729 -405.045924) (xy 82.487516 -405.020272) (xy 82.493309 -405.013124) (xy 82.499825 -404.995936)
			(xy 82.500216 -404.986744) (xy 82.500216 -404.828756) (xy 82.500586 -404.818597) (xy 82.508399 -404.799841)
			(xy 82.522811 -404.785518) (xy 82.541617 -404.777823) (xy 82.551778 -404.777448) (xy 83.268058 -404.777448)
			(xy 83.278183 -404.777961) (xy 83.296905 -404.785677) (xy 83.311263 -404.799955) (xy 83.319082 -404.818634)
			(xy 83.31962 -404.828756) (xy 83.31962 -404.986744) (xy 83.320004 -404.995934) (xy 83.326535 -405.013118)
			(xy 83.33232 -405.020272) (xy 83.354105 -405.045927) (xy 83.392057 -405.101512) (xy 83.423092 -405.161235)
			(xy 83.446767 -405.224239) (xy 83.462742 -405.289621) (xy 83.470787 -405.356444) (xy 83.470787 -405.42375)
			(xy 83.462743 -405.490573) (xy 83.446769 -405.555955) (xy 83.423095 -405.61896) (xy 83.420628 -405.623707)
			(xy 84.54869 -405.623707) (xy 84.54869 -405.556284) (xy 84.556766 -405.489346) (xy 84.572801 -405.423857)
			(xy 84.596564 -405.36076) (xy 84.627714 -405.300963) (xy 84.665801 -405.245328) (xy 84.687664 -405.219662)
			(xy 84.693467 -405.212522) (xy 84.699976 -405.195327) (xy 84.700364 -405.186134) (xy 84.700364 -404.693882)
			(xy 84.699948 -404.684696) (xy 84.693437 -404.667512) (xy 84.687664 -404.660354) (xy 84.665823 -404.63467)
			(xy 84.627736 -404.579038) (xy 84.596586 -404.519244) (xy 84.572822 -404.456149) (xy 84.556787 -404.390663)
			(xy 84.548709 -404.323727) (xy 84.548707 -404.256306) (xy 84.556781 -404.18937) (xy 84.572813 -404.123882)
			(xy 84.596573 -404.060787) (xy 84.627719 -404.000991) (xy 84.665803 -403.945356) (xy 84.687664 -403.91969)
			(xy 84.693455 -403.912541) (xy 84.699971 -403.895353) (xy 84.700364 -403.886162) (xy 84.700364 -403.728682)
			(xy 84.700812 -403.718551) (xy 84.70855 -403.699825) (xy 84.722849 -403.685468) (xy 84.741543 -403.677654)
			(xy 84.751672 -403.67712) (xy 85.467952 -403.67712) (xy 85.478105 -403.677561) (xy 85.496861 -403.685345)
			(xy 85.511186 -403.699736) (xy 85.518884 -403.718527) (xy 85.51926 -403.728682) (xy 85.51926 -403.886162)
			(xy 85.519698 -403.895346) (xy 85.526193 -403.91253) (xy 85.53196 -403.91969) (xy 85.553847 -403.945337)
			(xy 85.591938 -404.000973) (xy 85.62309 -404.060771) (xy 85.646854 -404.123871) (xy 85.66289 -404.189362)
			(xy 85.670964 -404.256303) (xy 85.670962 -404.32373) (xy 85.662884 -404.39067) (xy 85.646845 -404.456161)
			(xy 85.623076 -404.519259) (xy 85.591921 -404.579055) (xy 85.553827 -404.634689) (xy 85.53196 -404.660354)
			(xy 85.526153 -404.667492) (xy 85.519646 -404.684688) (xy 85.51926 -404.693882) (xy 85.51926 -405.186134)
			(xy 85.519663 -405.195322) (xy 85.526183 -405.212506) (xy 85.53196 -405.219662) (xy 85.553819 -405.245331)
			(xy 85.591911 -405.300964) (xy 85.623064 -405.36076) (xy 85.64683 -405.423856) (xy 85.662868 -405.489345)
			(xy 85.670945 -405.556284) (xy 85.670945 -405.623707) (xy 85.662869 -405.690646) (xy 85.646833 -405.756135)
			(xy 85.623068 -405.819232) (xy 85.591916 -405.879028) (xy 85.553825 -405.934661) (xy 85.53196 -405.960326)
			(xy 85.526165 -405.967472) (xy 85.51965 -405.984662) (xy 85.51926 -405.993854) (xy 85.51926 -406.151334)
			(xy 85.518801 -406.161463) (xy 85.511062 -406.180185) (xy 85.496768 -406.19454) (xy 85.478079 -406.202358)
			(xy 85.467952 -406.202896) (xy 84.751672 -406.202896) (xy 84.741516 -406.202501) (xy 84.722762 -406.194696)
			(xy 84.708439 -406.180291) (xy 84.700741 -406.161493) (xy 84.700364 -406.151334) (xy 84.700364 -405.993854)
			(xy 84.699914 -405.984671) (xy 84.693426 -405.967487) (xy 84.687664 -405.960326) (xy 84.665795 -405.934665)
			(xy 84.627709 -405.879029) (xy 84.596561 -405.819232) (xy 84.572799 -405.756135) (xy 84.556765 -405.690645)
			(xy 84.54869 -405.623707) (xy 83.420628 -405.623707) (xy 83.39206 -405.678683) (xy 83.354109 -405.734268)
			(xy 83.33232 -405.75992) (xy 83.326535 -405.767073) (xy 83.320013 -405.784258) (xy 83.31962 -405.793448)
			(xy 83.31962 -406.286716) (xy 83.320018 -406.295905) (xy 83.32654 -406.313089) (xy 83.33232 -406.320244)
			(xy 83.354077 -406.345921) (xy 83.39203 -406.401503) (xy 83.423067 -406.461223) (xy 83.446743 -406.524224)
			(xy 83.46272 -406.589604) (xy 83.470767 -406.656424) (xy 83.47077 -406.723728) (xy 83.470763 -406.723789)
			(xy 86.748808 -406.723789) (xy 86.748811 -406.656363) (xy 86.75689 -406.589422) (xy 86.772929 -406.523931)
			(xy 86.796697 -406.460833) (xy 86.827852 -406.401036) (xy 86.865946 -406.345401) (xy 86.887812 -406.319736)
			(xy 86.89362 -406.312599) (xy 86.900127 -406.295402) (xy 86.900512 -406.286208) (xy 86.900512 -405.793956)
			(xy 86.90012 -405.784767) (xy 86.893594 -405.767583) (xy 86.887812 -405.760428) (xy 86.865944 -405.734766)
			(xy 86.827854 -405.679131) (xy 86.796703 -405.619335) (xy 86.772939 -405.556238) (xy 86.756903 -405.490748)
			(xy 86.748827 -405.423809) (xy 86.748828 -405.356385) (xy 86.756904 -405.289446) (xy 86.77294 -405.223957)
			(xy 86.796706 -405.16086) (xy 86.827857 -405.101063) (xy 86.865947 -405.045429) (xy 86.887812 -405.019764)
			(xy 86.893608 -405.012618) (xy 86.900123 -404.995428) (xy 86.900512 -404.986236) (xy 86.900512 -404.828756)
			(xy 86.900949 -404.818643) (xy 86.908704 -404.799961) (xy 86.923015 -404.785668) (xy 86.941706 -404.777937)
			(xy 86.95182 -404.777448) (xy 87.6681 -404.777448) (xy 87.678202 -404.777984) (xy 87.696871 -404.785712)
			(xy 87.711163 -404.799993) (xy 87.718907 -404.818654) (xy 87.719408 -404.828756) (xy 87.719408 -404.986236)
			(xy 87.719799 -404.995425) (xy 87.726326 -405.01261) (xy 87.732108 -405.019764) (xy 87.753968 -405.045433)
			(xy 87.792056 -405.101067) (xy 87.823206 -405.160863) (xy 87.846971 -405.223959) (xy 87.863006 -405.289448)
			(xy 87.871082 -405.356385) (xy 87.871082 -405.423809) (xy 87.863007 -405.490746) (xy 87.846972 -405.556235)
			(xy 87.823209 -405.619332) (xy 87.792059 -405.679128) (xy 87.753971 -405.734763) (xy 87.732108 -405.760428)
			(xy 87.726318 -405.767578) (xy 87.719799 -405.784765) (xy 87.719408 -405.793956) (xy 87.719408 -406.286208)
			(xy 87.719813 -406.295396) (xy 87.72633 -406.31258) (xy 87.732108 -406.319736) (xy 87.75394 -406.345427)
			(xy 87.792029 -406.401058) (xy 87.823181 -406.460851) (xy 87.846947 -406.523944) (xy 87.862984 -406.58943)
			(xy 87.871062 -406.656365) (xy 87.871065 -406.723729) (xy 91.149127 -406.723729) (xy 91.14913 -406.656423)
			(xy 91.157177 -406.589598) (xy 91.173152 -406.524215) (xy 91.196827 -406.461209) (xy 91.227861 -406.401484)
			(xy 91.265812 -406.345897) (xy 91.2876 -406.320244) (xy 91.293403 -406.313103) (xy 91.299914 -406.295909)
			(xy 91.3003 -406.286716) (xy 91.3003 -405.793448) (xy 91.299867 -405.784263) (xy 91.293369 -405.767079)
			(xy 91.2876 -405.75992) (xy 91.26581 -405.734271) (xy 91.227863 -405.678683) (xy 91.196832 -405.618958)
			(xy 91.173162 -405.555954) (xy 91.15719 -405.490572) (xy 91.149147 -405.423749) (xy 91.149147 -405.356445)
			(xy 91.157191 -405.289622) (xy 91.173163 -405.224241) (xy 91.196835 -405.161236) (xy 91.227866 -405.101512)
			(xy 91.265813 -405.045925) (xy 91.2876 -405.020272) (xy 91.293391 -405.013123) (xy 91.299909 -404.995935)
			(xy 91.3003 -404.986744) (xy 91.3003 -404.828756) (xy 91.300686 -404.818599) (xy 91.308496 -404.799846)
			(xy 91.322903 -404.785524) (xy 91.341703 -404.777826) (xy 91.351862 -404.777448) (xy 92.068142 -404.777448)
			(xy 92.078272 -404.777892) (xy 92.096996 -404.785635) (xy 92.111351 -404.799934) (xy 92.119167 -404.818628)
			(xy 92.119704 -404.828756) (xy 92.119704 -404.986744) (xy 92.120092 -404.995934) (xy 92.126621 -405.013118)
			(xy 92.132404 -405.020272) (xy 92.154186 -405.045928) (xy 92.192133 -405.101515) (xy 92.223164 -405.161238)
			(xy 92.246835 -405.224242) (xy 92.262807 -405.289624) (xy 92.270851 -405.356445) (xy 92.270851 -405.423749)
			(xy 92.262808 -405.490571) (xy 92.246837 -405.555952) (xy 92.223166 -405.618956) (xy 92.220728 -405.623648)
			(xy 115.349248 -405.623648) (xy 115.349249 -405.556343) (xy 115.357293 -405.489521) (xy 115.373266 -405.424139)
			(xy 115.396938 -405.361134) (xy 115.42797 -405.30141) (xy 115.465917 -405.245823) (xy 115.487704 -405.22017)
			(xy 115.493496 -405.213022) (xy 115.500013 -405.195834) (xy 115.500404 -405.186642) (xy 115.500404 -404.693374)
			(xy 115.500006 -404.684186) (xy 115.493484 -404.667001) (xy 115.487704 -404.659846) (xy 115.465939 -404.634176)
			(xy 115.427992 -404.578591) (xy 115.396959 -404.51887) (xy 115.373287 -404.455868) (xy 115.357314 -404.390488)
			(xy 115.349268 -404.323668) (xy 115.349266 -404.256365) (xy 115.357308 -404.189545) (xy 115.373277 -404.124164)
			(xy 115.396946 -404.061161) (xy 115.427975 -404.001437) (xy 115.465919 -403.945851) (xy 115.487704 -403.920198)
			(xy 115.493484 -403.913041) (xy 115.500009 -403.89586) (xy 115.500404 -403.88667) (xy 115.500404 -403.728682)
			(xy 115.500918 -403.718527) (xy 115.508692 -403.699764) (xy 115.523051 -403.685401) (xy 115.541811 -403.677621)
			(xy 115.551966 -403.67712) (xy 116.268246 -403.67712) (xy 116.278404 -403.677595) (xy 116.297171 -403.685382)
			(xy 116.311534 -403.699752) (xy 116.31931 -403.718523) (xy 116.319808 -403.728682) (xy 116.319808 -403.88667)
			(xy 116.320231 -403.895856) (xy 116.326735 -403.91304) (xy 116.332508 -403.920198) (xy 116.354319 -403.945832)
			(xy 116.392271 -404.00142) (xy 116.423306 -404.061145) (xy 116.44698 -404.124152) (xy 116.462953 -404.189537)
			(xy 116.470996 -404.256363) (xy 116.470994 -404.32367) (xy 116.462947 -404.390495) (xy 116.44697 -404.455879)
			(xy 116.423292 -404.518885) (xy 116.392254 -404.578609) (xy 116.354299 -404.634195) (xy 116.332508 -404.659846)
			(xy 116.32671 -404.66699) (xy 116.320196 -404.684181) (xy 116.319808 -404.693374) (xy 116.319808 -405.186642)
			(xy 116.320196 -405.195832) (xy 116.326725 -405.213016) (xy 116.332508 -405.22017) (xy 116.354291 -405.245826)
			(xy 116.392244 -405.301411) (xy 116.42328 -405.361133) (xy 116.446956 -405.424137) (xy 116.462931 -405.48952)
			(xy 116.470976 -405.556343) (xy 116.470977 -405.623648) (xy 116.462932 -405.690471) (xy 116.446958 -405.755854)
			(xy 116.423284 -405.818858) (xy 116.392249 -405.878581) (xy 116.354297 -405.934167) (xy 116.332508 -405.959818)
			(xy 116.326722 -405.966971) (xy 116.320201 -405.984155) (xy 116.319808 -405.993346) (xy 116.319808 -406.151334)
			(xy 116.319296 -406.161488) (xy 116.311519 -406.180249) (xy 116.297159 -406.194612) (xy 116.2784 -406.202393)
			(xy 116.268246 -406.202896) (xy 115.551966 -406.202896) (xy 115.54181 -406.202395) (xy 115.523047 -406.194616)
			(xy 115.508684 -406.180253) (xy 115.500905 -406.16149) (xy 115.500404 -406.151334) (xy 115.500404 -405.993346)
			(xy 115.499971 -405.984161) (xy 115.493473 -405.966977) (xy 115.487704 -405.959818) (xy 115.465911 -405.93417)
			(xy 115.427965 -405.878582) (xy 115.396934 -405.818858) (xy 115.373263 -405.755853) (xy 115.357292 -405.69047)
			(xy 115.349248 -405.623648) (xy 92.220728 -405.623648) (xy 92.192136 -405.67868) (xy 92.15419 -405.734267)
			(xy 92.132404 -405.75992) (xy 92.126617 -405.767072) (xy 92.120096 -405.784257) (xy 92.119704 -405.793448)
			(xy 92.119704 -406.286716) (xy 92.120106 -406.295904) (xy 92.126625 -406.313088) (xy 92.132404 -406.320244)
			(xy 92.154159 -406.345923) (xy 92.192106 -406.401506) (xy 92.223138 -406.461227) (xy 92.246811 -406.524228)
			(xy 92.262785 -406.589606) (xy 92.270831 -406.656425) (xy 92.270834 -406.723727) (xy 92.270826 -406.72379)
			(xy 117.548838 -406.72379) (xy 117.548841 -406.656362) (xy 117.55692 -406.589421) (xy 117.572961 -406.523929)
			(xy 117.596731 -406.460831) (xy 117.627888 -406.401034) (xy 117.665984 -406.3454) (xy 117.687852 -406.319736)
			(xy 117.693665 -406.312602) (xy 117.700168 -406.295403) (xy 117.700552 -406.286208) (xy 117.700552 -405.793956)
			(xy 117.700151 -405.784768) (xy 117.69363 -405.767585) (xy 117.687852 -405.760428) (xy 117.665982 -405.734767)
			(xy 117.62789 -405.679133) (xy 117.596737 -405.619337) (xy 117.572971 -405.556239) (xy 117.556934 -405.490749)
			(xy 117.548857 -405.42381) (xy 117.548858 -405.356384) (xy 117.556935 -405.289445) (xy 117.572972 -405.223955)
			(xy 117.596739 -405.160858) (xy 117.627893 -405.101062) (xy 117.665986 -405.045428) (xy 117.687852 -405.019764)
			(xy 117.693653 -405.012622) (xy 117.700164 -404.995429) (xy 117.700552 -404.986236) (xy 117.700552 -404.828756)
			(xy 117.701048 -404.81865) (xy 117.708791 -404.79998) (xy 117.723084 -404.785689) (xy 117.741754 -404.777947)
			(xy 117.75186 -404.777448) (xy 118.46814 -404.777448) (xy 118.478245 -404.777951) (xy 118.496914 -404.785692)
			(xy 118.511206 -404.799983) (xy 118.518948 -404.818651) (xy 118.519448 -404.828756) (xy 118.519448 -404.986236)
			(xy 118.519853 -404.995424) (xy 118.526372 -405.012607) (xy 118.532148 -405.019764) (xy 118.55401 -405.045432)
			(xy 118.592102 -405.101065) (xy 118.623256 -405.16086) (xy 118.647023 -405.223957) (xy 118.66306 -405.289446)
			(xy 118.671137 -405.356385) (xy 118.671137 -405.423809) (xy 118.663061 -405.490748) (xy 118.647024 -405.556238)
			(xy 118.623258 -405.619335) (xy 118.62098 -405.623708) (xy 119.749017 -405.623708) (xy 119.749017 -405.556283)
			(xy 119.757094 -405.489345) (xy 119.77313 -405.423855) (xy 119.796895 -405.360758) (xy 119.828046 -405.300962)
			(xy 119.866136 -405.245327) (xy 119.888 -405.219662) (xy 119.893795 -405.212516) (xy 119.900311 -405.195326)
			(xy 119.9007 -405.186134) (xy 119.9007 -404.693882) (xy 119.900298 -404.684694) (xy 119.893779 -404.66751)
			(xy 119.888 -404.660354) (xy 119.866158 -404.634671) (xy 119.828068 -404.579039) (xy 119.796917 -404.519245)
			(xy 119.773151 -404.456151) (xy 119.757114 -404.390664) (xy 119.749037 -404.323727) (xy 119.749035 -404.256306)
			(xy 119.757108 -404.189369) (xy 119.773141 -404.123881) (xy 119.796903 -404.060785) (xy 119.828051 -404.000989)
			(xy 119.866137 -403.945355) (xy 119.888 -403.91969) (xy 119.893783 -403.912535) (xy 119.900306 -403.895352)
			(xy 119.9007 -403.886162) (xy 119.9007 -403.728682) (xy 119.90121 -403.718559) (xy 119.908937 -403.699845)
			(xy 119.923215 -403.685491) (xy 119.941888 -403.677665) (xy 119.952008 -403.67712) (xy 120.668288 -403.67712)
			(xy 120.678412 -403.677526) (xy 120.697119 -403.685274) (xy 120.711435 -403.699594) (xy 120.719177 -403.718304)
			(xy 120.719596 -403.728428) (xy 120.719596 -403.886162) (xy 120.720025 -403.895347) (xy 120.726526 -403.912532)
			(xy 120.732296 -403.91969) (xy 120.754182 -403.945337) (xy 120.79227 -404.000974) (xy 120.82342 -404.060773)
			(xy 120.847183 -404.123872) (xy 120.863217 -404.189363) (xy 120.871291 -404.256304) (xy 120.871289 -404.323729)
			(xy 120.863211 -404.390669) (xy 120.847173 -404.456159) (xy 120.823407 -404.519257) (xy 120.792253 -404.579054)
			(xy 120.754161 -404.634689) (xy 120.732296 -404.660354) (xy 120.726494 -404.667495) (xy 120.719983 -404.684689)
			(xy 120.719596 -404.693882) (xy 120.719596 -405.186134) (xy 120.719991 -405.195323) (xy 120.726515 -405.212507)
			(xy 120.732296 -405.219662) (xy 120.754154 -405.245332) (xy 120.792243 -405.300966) (xy 120.823395 -405.360761)
			(xy 120.847159 -405.423858) (xy 120.863195 -405.489346) (xy 120.871272 -405.556284) (xy 120.871272 -405.623707)
			(xy 120.863197 -405.690645) (xy 120.847162 -405.756134) (xy 120.823398 -405.81923) (xy 120.792248 -405.879026)
			(xy 120.75416 -405.934661) (xy 120.732296 -405.960326) (xy 120.726505 -405.967475) (xy 120.719987 -405.984663)
			(xy 120.719596 -405.993854) (xy 120.719596 -406.151334) (xy 120.719102 -406.161458) (xy 120.71137 -406.180174)
			(xy 120.697087 -406.194527) (xy 120.67841 -406.202352) (xy 120.668288 -406.202896) (xy 119.952008 -406.202896)
			(xy 119.941886 -406.202477) (xy 119.923181 -406.194731) (xy 119.908867 -406.180415) (xy 119.901122 -406.16171)
			(xy 119.9007 -406.151588) (xy 119.9007 -405.993854) (xy 119.900264 -405.98467) (xy 119.893768 -405.967485)
			(xy 119.888 -405.960326) (xy 119.86613 -405.934666) (xy 119.828042 -405.87903) (xy 119.796891 -405.819234)
			(xy 119.773127 -405.756136) (xy 119.757092 -405.690646) (xy 119.749017 -405.623708) (xy 118.62098 -405.623708)
			(xy 118.592105 -405.67913) (xy 118.554014 -405.734764) (xy 118.532148 -405.760428) (xy 118.526351 -405.767572)
			(xy 118.519838 -405.784764) (xy 118.519448 -405.793956) (xy 118.519448 -406.286208) (xy 118.519866 -406.295394)
			(xy 118.526375 -406.312578) (xy 118.532148 -406.319736) (xy 118.553982 -406.345426) (xy 118.592075 -406.401056)
			(xy 118.62323 -406.460848) (xy 118.646999 -406.523942) (xy 118.663038 -406.589429) (xy 118.671117 -406.656365)
			(xy 118.67112 -406.72373) (xy 121.949157 -406.72373) (xy 121.94916 -406.656422) (xy 121.957208 -406.589597)
			(xy 121.973184 -406.524213) (xy 121.99686 -406.461207) (xy 122.027897 -406.401483) (xy 122.06585 -406.345896)
			(xy 122.08764 -406.320244) (xy 122.093448 -406.313107) (xy 122.099955 -406.29591) (xy 122.10034 -406.286716)
			(xy 122.10034 -405.793448) (xy 122.099898 -405.784264) (xy 122.093405 -405.76708) (xy 122.08764 -405.75992)
			(xy 122.065848 -405.734271) (xy 122.027899 -405.678684) (xy 121.996866 -405.61896) (xy 121.973194 -405.555955)
			(xy 121.957221 -405.490573) (xy 121.949177 -405.42375) (xy 121.949177 -405.356444) (xy 121.957222 -405.289621)
			(xy 121.973195 -405.224239) (xy 121.996869 -405.161234) (xy 122.027902 -405.101511) (xy 122.065852 -405.045924)
			(xy 122.08764 -405.020272) (xy 122.093436 -405.013127) (xy 122.09995 -404.995936) (xy 122.10034 -404.986744)
			(xy 122.10034 -404.828756) (xy 122.100681 -404.818626) (xy 122.108451 -404.799913) (xy 122.122791 -404.785599)
			(xy 122.141517 -404.777863) (xy 122.151648 -404.777448) (xy 122.868182 -404.777448) (xy 122.878309 -404.777941)
			(xy 122.897031 -404.785665) (xy 122.911388 -404.799949) (xy 122.919207 -404.818632) (xy 122.919744 -404.828756)
			(xy 122.919744 -404.986744) (xy 122.920145 -404.995932) (xy 122.926666 -405.013116) (xy 122.932444 -405.020272)
			(xy 122.954228 -405.045927) (xy 122.992178 -405.101513) (xy 123.023213 -405.161236) (xy 123.046886 -405.22424)
			(xy 123.06286 -405.289622) (xy 123.070905 -405.356444) (xy 123.070905 -405.42375) (xy 123.062861 -405.490572)
			(xy 123.046888 -405.555954) (xy 123.023215 -405.618959) (xy 123.020778 -405.623649) (xy 124.149312 -405.623649)
			(xy 124.149313 -405.556342) (xy 124.157358 -405.489518) (xy 124.173333 -405.424135) (xy 124.197009 -405.36113)
			(xy 124.228046 -405.301407) (xy 124.265998 -405.245822) (xy 124.287788 -405.22017) (xy 124.293578 -405.21302)
			(xy 124.300097 -405.195833) (xy 124.300488 -405.186642) (xy 124.300488 -404.693374) (xy 124.300093 -404.684185)
			(xy 124.293569 -404.667001) (xy 124.287788 -404.659846) (xy 124.26602 -404.634177) (xy 124.228068 -404.578594)
			(xy 124.197031 -404.518873) (xy 124.173355 -404.455871) (xy 124.157379 -404.39049) (xy 124.149332 -404.323669)
			(xy 124.14933 -404.256364) (xy 124.157373 -404.189542) (xy 124.173345 -404.124161) (xy 124.197017 -404.061157)
			(xy 124.228051 -404.001435) (xy 124.266 -403.945849) (xy 124.287788 -403.920198) (xy 124.293567 -403.91304)
			(xy 124.300092 -403.895859) (xy 124.300488 -403.88667) (xy 124.300488 -403.728682) (xy 124.30085 -403.718503)
			(xy 124.308651 -403.699698) (xy 124.323056 -403.685313) (xy 124.34187 -403.677537) (xy 124.35205 -403.67712)
			(xy 125.06833 -403.67712) (xy 125.078487 -403.677608) (xy 125.097254 -403.685389) (xy 125.111617 -403.699756)
			(xy 125.119394 -403.718524) (xy 125.119892 -403.728682) (xy 125.119892 -403.88667) (xy 125.120318 -403.895855)
			(xy 125.126821 -403.91304) (xy 125.132592 -403.920198) (xy 125.1544 -403.945833) (xy 125.192347 -404.001422)
			(xy 125.223377 -404.061149) (xy 125.247047 -404.124155) (xy 125.263018 -404.189539) (xy 125.27106 -404.256363)
			(xy 125.271058 -404.32367) (xy 125.263012 -404.390493) (xy 125.247038 -404.455876) (xy 125.223364 -404.518882)
			(xy 125.19233 -404.578606) (xy 125.15438 -404.634193) (xy 125.132592 -404.659846) (xy 125.126792 -404.666989)
			(xy 125.12028 -404.684181) (xy 125.119892 -404.693374) (xy 125.119892 -405.186642) (xy 125.120284 -405.195831)
			(xy 125.12681 -405.213015) (xy 125.132592 -405.22017) (xy 125.154373 -405.245827) (xy 125.19232 -405.301414)
			(xy 125.223352 -405.361137) (xy 125.247023 -405.424141) (xy 125.262996 -405.489522) (xy 125.27104 -405.556343)
			(xy 125.271041 -405.623647) (xy 125.262998 -405.690469) (xy 125.247026 -405.755851) (xy 125.223355 -405.818855)
			(xy 125.192325 -405.878578) (xy 125.154378 -405.934165) (xy 125.132592 -405.959818) (xy 125.126804 -405.96697)
			(xy 125.120285 -405.984155) (xy 125.119892 -405.993346) (xy 125.119892 -406.151334) (xy 125.119395 -406.16149)
			(xy 125.111615 -406.180254) (xy 125.097251 -406.194617) (xy 125.078486 -406.202396) (xy 125.06833 -406.202896)
			(xy 124.35205 -406.202896) (xy 124.341886 -406.202396) (xy 124.323099 -406.194634) (xy 124.308713 -406.180272)
			(xy 124.30092 -406.161497) (xy 124.300488 -406.151334) (xy 124.300488 -405.993346) (xy 124.300059 -405.984161)
			(xy 124.293559 -405.966976) (xy 124.287788 -405.959818) (xy 124.265993 -405.934171) (xy 124.228041 -405.878585)
			(xy 124.197005 -405.818861) (xy 124.173331 -405.755856) (xy 124.157357 -405.690473) (xy 124.149312 -405.623649)
			(xy 123.020778 -405.623649) (xy 122.992181 -405.678682) (xy 122.954232 -405.734268) (xy 122.932444 -405.75992)
			(xy 122.92665 -405.767066) (xy 122.920135 -405.784256) (xy 122.919744 -405.793448) (xy 122.919744 -406.286716)
			(xy 122.920159 -406.295902) (xy 122.926671 -406.313086) (xy 122.932444 -406.320244) (xy 122.954201 -406.345922)
			(xy 122.992152 -406.401504) (xy 123.023187 -406.461224) (xy 123.046862 -406.524225) (xy 123.062838 -406.589605)
			(xy 123.070885 -406.656425) (xy 123.070888 -406.723727) (xy 123.070881 -406.723789) (xy 126.348926 -406.723789)
			(xy 126.348929 -406.656363) (xy 126.357008 -406.589421) (xy 126.373048 -406.52393) (xy 126.396818 -406.460832)
			(xy 126.427974 -406.401035) (xy 126.466069 -406.345401) (xy 126.487936 -406.319736) (xy 126.493747 -406.312601)
			(xy 126.500252 -406.295403) (xy 126.500636 -406.286208) (xy 126.500636 -405.793956) (xy 126.500239 -405.784768)
			(xy 126.493715 -405.767584) (xy 126.487936 -405.760428) (xy 126.466067 -405.734767) (xy 126.427976 -405.679132)
			(xy 126.396823 -405.619336) (xy 126.373058 -405.556239) (xy 126.357022 -405.490749) (xy 126.348945 -405.423809)
			(xy 126.348946 -405.356385) (xy 126.357023 -405.289445) (xy 126.37306 -405.223956) (xy 126.396826 -405.160859)
			(xy 126.427979 -405.101062) (xy 126.466071 -405.045429) (xy 126.487936 -405.019764) (xy 126.493735 -405.012621)
			(xy 126.500247 -404.995429) (xy 126.500636 -404.986236) (xy 126.500636 -404.828756) (xy 126.50105 -404.81864)
			(xy 126.508809 -404.799954) (xy 126.523128 -404.785659) (xy 126.541827 -404.777933) (xy 126.551944 -404.777448)
			(xy 127.268224 -404.777448) (xy 127.278328 -404.777964) (xy 127.296997 -404.7857) (xy 127.311289 -404.799986)
			(xy 127.319032 -404.818652) (xy 127.319532 -404.828756) (xy 127.319532 -404.986236) (xy 127.31994 -404.995423)
			(xy 127.326457 -405.012607) (xy 127.332232 -405.019764) (xy 127.354091 -405.045433) (xy 127.392178 -405.101068)
			(xy 127.423327 -405.160864) (xy 127.44709 -405.22396) (xy 127.463125 -405.289448) (xy 127.4712 -405.356386)
			(xy 127.471201 -405.423808) (xy 127.463126 -405.490746) (xy 127.447092 -405.556234) (xy 127.423329 -405.619331)
			(xy 127.42108 -405.623649) (xy 128.549103 -405.623649) (xy 128.549104 -405.556342) (xy 128.557149 -405.489519)
			(xy 128.573124 -405.424136) (xy 128.596799 -405.361131) (xy 128.627835 -405.301407) (xy 128.665787 -405.245822)
			(xy 128.687576 -405.22017) (xy 128.693365 -405.213019) (xy 128.699885 -405.195833) (xy 128.700276 -405.186642)
			(xy 128.700276 -404.693374) (xy 128.699884 -404.684185) (xy 128.693358 -404.667) (xy 128.687576 -404.659846)
			(xy 128.665809 -404.634177) (xy 128.627857 -404.578593) (xy 128.596821 -404.518873) (xy 128.573145 -404.45587)
			(xy 128.557169 -404.39049) (xy 128.549123 -404.323669) (xy 128.549121 -404.256365) (xy 128.557164 -404.189543)
			(xy 128.573135 -404.124161) (xy 128.596807 -404.061158) (xy 128.62784 -404.001435) (xy 128.665789 -403.94585)
			(xy 128.687576 -403.920198) (xy 128.693353 -403.913039) (xy 128.69988 -403.895859) (xy 128.700276 -403.88667)
			(xy 128.700276 -403.728682) (xy 128.70065 -403.718505) (xy 128.708448 -403.699702) (xy 128.722849 -403.685317)
			(xy 128.74166 -403.677539) (xy 128.751838 -403.67712) (xy 129.468118 -403.67712) (xy 129.478275 -403.677618)
			(xy 129.497041 -403.685395) (xy 129.511405 -403.699759) (xy 129.519182 -403.718525) (xy 129.51968 -403.728682)
			(xy 129.51968 -403.88667) (xy 129.520109 -403.895855) (xy 129.52661 -403.913039) (xy 129.53238 -403.920198)
			(xy 129.554189 -403.945833) (xy 129.592136 -404.001422) (xy 129.623167 -404.061148) (xy 129.646838 -404.124155)
			(xy 129.662809 -404.189539) (xy 129.670851 -404.256363) (xy 129.670849 -404.32367) (xy 129.662803 -404.390494)
			(xy 129.646828 -404.455877) (xy 129.623154 -404.518882) (xy 129.592119 -404.578606) (xy 129.554169 -404.634194)
			(xy 129.53238 -404.659846) (xy 129.526579 -404.666988) (xy 129.520068 -404.684181) (xy 129.51968 -404.693374)
			(xy 129.51968 -405.186642) (xy 129.520074 -405.195831) (xy 129.5266 -405.213015) (xy 129.53238 -405.22017)
			(xy 129.554161 -405.245827) (xy 129.592109 -405.301413) (xy 129.623142 -405.361136) (xy 129.646814 -405.42414)
			(xy 129.662787 -405.489522) (xy 129.670831 -405.556343) (xy 129.670832 -405.623648) (xy 129.662788 -405.690469)
			(xy 129.646817 -405.755851) (xy 129.623145 -405.818855) (xy 129.592114 -405.878579) (xy 129.554167 -405.934166)
			(xy 129.53238 -405.959818) (xy 129.526591 -405.966968) (xy 129.520072 -405.984155) (xy 129.51968 -405.993346)
			(xy 129.51968 -406.151334) (xy 129.519195 -406.161492) (xy 129.511413 -406.180258) (xy 129.497045 -406.194622)
			(xy 129.478276 -406.202398) (xy 129.468118 -406.202896) (xy 128.751838 -406.202896) (xy 128.741673 -406.202406)
			(xy 128.722886 -406.19464) (xy 128.708501 -406.180275) (xy 128.700708 -406.161498) (xy 128.700276 -406.151334)
			(xy 128.700276 -405.993346) (xy 128.699849 -405.984161) (xy 128.693347 -405.966976) (xy 128.687576 -405.959818)
			(xy 128.665781 -405.934171) (xy 128.62783 -405.878585) (xy 128.596795 -405.818861) (xy 128.573121 -405.755856)
			(xy 128.557148 -405.690472) (xy 128.549103 -405.623649) (xy 127.42108 -405.623649) (xy 127.392181 -405.679127)
			(xy 127.354095 -405.734762) (xy 127.332232 -405.760428) (xy 127.326433 -405.767571) (xy 127.319922 -405.784763)
			(xy 127.319532 -405.793956) (xy 127.319532 -406.286208) (xy 127.319954 -406.295394) (xy 127.326461 -406.312577)
			(xy 127.332232 -406.319736) (xy 127.354063 -406.345428) (xy 127.392151 -406.401059) (xy 127.423301 -406.460852)
			(xy 127.447066 -406.523945) (xy 127.463103 -406.589431) (xy 127.471181 -406.656366) (xy 127.471183 -406.72373)
			(xy 130.749245 -406.72373) (xy 130.749248 -406.656422) (xy 130.757295 -406.589598) (xy 130.773271 -406.524214)
			(xy 130.796947 -406.461208) (xy 130.827983 -406.401484) (xy 130.865935 -406.345896) (xy 130.887724 -406.320244)
			(xy 130.89353 -406.313105) (xy 130.900038 -406.29591) (xy 130.900424 -406.286716) (xy 130.900424 -405.793448)
			(xy 130.899985 -405.784264) (xy 130.893491 -405.76708) (xy 130.887724 -405.75992) (xy 130.865933 -405.734271)
			(xy 130.827985 -405.678684) (xy 130.796953 -405.61896) (xy 130.773281 -405.555955) (xy 130.757309 -405.490572)
			(xy 130.749265 -405.42375) (xy 130.749265 -405.356444) (xy 130.75731 -405.289622) (xy 130.773283 -405.22424)
			(xy 130.796955 -405.161235) (xy 130.827988 -405.101511) (xy 130.865936 -405.045924) (xy 130.887724 -405.020272)
			(xy 130.893518 -405.013125) (xy 130.900033 -404.995936) (xy 130.900424 -404.986744) (xy 130.900424 -404.828756)
			(xy 130.900786 -404.818596) (xy 130.908601 -404.799838) (xy 130.923016 -404.785515) (xy 130.941823 -404.777822)
			(xy 130.951986 -404.777448) (xy 131.668266 -404.777448) (xy 131.678391 -404.777955) (xy 131.697113 -404.785673)
			(xy 131.711471 -404.799953) (xy 131.71929 -404.818633) (xy 131.719828 -404.828756) (xy 131.719828 -404.986744)
			(xy 131.720211 -404.995934) (xy 131.726743 -405.013119) (xy 131.732528 -405.020272) (xy 131.754313 -405.045927)
			(xy 131.792264 -405.101512) (xy 131.823299 -405.161235) (xy 131.846974 -405.224239) (xy 131.862948 -405.289622)
			(xy 131.870993 -405.356444) (xy 131.870993 -405.42375) (xy 131.862949 -405.490573) (xy 131.846975 -405.555955)
			(xy 131.823302 -405.618959) (xy 131.792267 -405.678683) (xy 131.754316 -405.734268) (xy 131.732528 -405.75992)
			(xy 131.726732 -405.767065) (xy 131.720219 -405.784256) (xy 131.719828 -405.793448) (xy 131.719828 -406.286716)
			(xy 131.720224 -406.295905) (xy 131.726747 -406.313089) (xy 131.732528 -406.320244) (xy 131.754285 -406.345922)
			(xy 131.792237 -406.401504) (xy 131.823274 -406.461223) (xy 131.84695 -406.524225) (xy 131.862926 -406.589604)
			(xy 131.870973 -406.656424) (xy 131.870976 -406.723728) (xy 131.862934 -406.790548) (xy 131.846964 -406.855929)
			(xy 131.823293 -406.918933) (xy 131.792262 -406.978655) (xy 131.754315 -407.03424) (xy 131.732528 -407.059892)
			(xy 131.726744 -407.067045) (xy 131.720224 -407.08423) (xy 131.719828 -407.09342) (xy 131.719828 -407.251408)
			(xy 131.719385 -407.261559) (xy 131.711592 -407.280306) (xy 131.697203 -407.294628) (xy 131.678419 -407.302333)
			(xy 131.668266 -407.302716) (xy 130.951986 -407.302716) (xy 130.941853 -407.302283) (xy 130.923123 -407.294543)
			(xy 130.908766 -407.28024) (xy 130.900955 -407.261539) (xy 130.900424 -407.251408) (xy 130.900424 -407.09342)
			(xy 130.899999 -407.084235) (xy 130.893495 -407.06705) (xy 130.887724 -407.059892) (xy 130.865905 -407.034266)
			(xy 130.827958 -406.978675) (xy 130.796927 -406.918948) (xy 130.773257 -406.85594) (xy 130.757287 -406.790555)
			(xy 130.749245 -406.72373) (xy 127.471183 -406.72373) (xy 127.471183 -406.723786) (xy 127.463111 -406.790722)
			(xy 127.44708 -406.856209) (xy 127.423321 -406.919304) (xy 127.392176 -406.9791) (xy 127.354093 -407.034734)
			(xy 127.332232 -407.0604) (xy 127.326445 -407.067551) (xy 127.319926 -407.084737) (xy 127.319532 -407.093928)
			(xy 127.319532 -407.251408) (xy 127.319022 -407.261513) (xy 127.311288 -407.280185) (xy 127.296999 -407.294479)
			(xy 127.278329 -407.302219) (xy 127.268224 -407.302716) (xy 126.551944 -407.302716) (xy 126.541826 -407.302248)
			(xy 126.523127 -407.294518) (xy 126.508812 -407.280217) (xy 126.501062 -407.261525) (xy 126.500636 -407.251408)
			(xy 126.500636 -407.093928) (xy 126.500204 -407.084743) (xy 126.493705 -407.067559) (xy 126.487936 -407.0604)
			(xy 126.466039 -407.034761) (xy 126.427949 -406.979124) (xy 126.396798 -406.919324) (xy 126.373034 -406.856224)
			(xy 126.357 -406.790731) (xy 126.348926 -406.723789) (xy 123.070881 -406.723789) (xy 123.062847 -406.790548)
			(xy 123.046877 -406.855929) (xy 123.023207 -406.918932) (xy 122.992176 -406.978654) (xy 122.95423 -407.03424)
			(xy 122.932444 -407.059892) (xy 122.926661 -407.067047) (xy 122.92014 -407.08423) (xy 122.919744 -407.09342)
			(xy 122.919744 -407.251408) (xy 122.919222 -407.261512) (xy 122.91149 -407.280182) (xy 122.897205 -407.294475)
			(xy 122.878539 -407.302217) (xy 122.868436 -407.302716) (xy 122.151902 -407.302716) (xy 122.14177 -407.30227)
			(xy 122.123041 -407.294535) (xy 122.108683 -407.280236) (xy 122.100871 -407.261538) (xy 122.10034 -407.251408)
			(xy 122.10034 -407.09342) (xy 122.099911 -407.084235) (xy 122.09341 -407.067051) (xy 122.08764 -407.059892)
			(xy 122.065821 -407.034266) (xy 122.027873 -406.978676) (xy 121.996841 -406.918949) (xy 121.97317 -406.855941)
			(xy 121.957199 -406.790555) (xy 121.949157 -406.72373) (xy 118.67112 -406.72373) (xy 118.67112 -406.723787)
			(xy 118.663047 -406.790724) (xy 118.647013 -406.856212) (xy 118.62325 -406.919308) (xy 118.5921 -406.979103)
			(xy 118.554012 -407.034736) (xy 118.532148 -407.0604) (xy 118.526362 -407.067553) (xy 118.519843 -407.084738)
			(xy 118.519448 -407.093928) (xy 118.519448 -407.251408) (xy 118.518922 -407.261511) (xy 118.511191 -407.28018)
			(xy 118.496907 -407.294473) (xy 118.478243 -407.302216) (xy 118.46814 -407.302716) (xy 117.75186 -407.302716)
			(xy 117.741751 -407.302248) (xy 117.723075 -407.2945) (xy 117.708782 -407.280198) (xy 117.701046 -407.261518)
			(xy 117.700552 -407.251408) (xy 117.700552 -407.093928) (xy 117.700117 -407.084744) (xy 117.693619 -407.06756)
			(xy 117.687852 -407.0604) (xy 117.665955 -407.034762) (xy 117.627864 -406.979124) (xy 117.596711 -406.919325)
			(xy 117.572947 -406.856225) (xy 117.556912 -406.790732) (xy 117.548838 -406.72379) (xy 92.270826 -406.72379)
			(xy 92.262793 -406.790546) (xy 92.246825 -406.855926) (xy 92.223158 -406.918929) (xy 92.192131 -406.978652)
			(xy 92.154188 -407.034239) (xy 92.132404 -407.059892) (xy 92.126629 -407.067052) (xy 92.120101 -407.084231)
			(xy 92.119704 -407.09342) (xy 92.119704 -407.251408) (xy 92.119285 -407.261562) (xy 92.111487 -407.280314)
			(xy 92.09709 -407.294637) (xy 92.078298 -407.302337) (xy 92.068142 -407.302716) (xy 91.351862 -407.302716)
			(xy 91.341727 -407.302303) (xy 91.322997 -407.294555) (xy 91.308641 -407.280246) (xy 91.30083 -407.261541)
			(xy 91.3003 -407.251408) (xy 91.3003 -407.09342) (xy 91.29988 -407.084234) (xy 91.293373 -407.067049)
			(xy 91.2876 -407.059892) (xy 91.265782 -407.034265) (xy 91.227837 -406.978674) (xy 91.196807 -406.918947)
			(xy 91.173138 -406.855939) (xy 91.157168 -406.790554) (xy 91.149127 -406.723729) (xy 87.871065 -406.723729)
			(xy 87.871065 -406.723786) (xy 87.862993 -406.790722) (xy 87.846961 -406.85621) (xy 87.823201 -406.919305)
			(xy 87.792054 -406.9791) (xy 87.75397 -407.034735) (xy 87.732108 -407.0604) (xy 87.72633 -407.067558)
			(xy 87.719804 -407.084739) (xy 87.719408 -407.093928) (xy 87.719408 -407.251408) (xy 87.718921 -407.261516)
			(xy 87.711183 -407.280193) (xy 87.696886 -407.294487) (xy 87.678208 -407.302223) (xy 87.6681 -407.302716)
			(xy 86.95182 -407.302716) (xy 86.941701 -407.302268) (xy 86.923001 -407.29453) (xy 86.908686 -407.280223)
			(xy 86.900937 -407.261527) (xy 86.900512 -407.251408) (xy 86.900512 -407.093928) (xy 86.900086 -407.084743)
			(xy 86.893583 -407.067558) (xy 86.887812 -407.0604) (xy 86.865916 -407.034761) (xy 86.827828 -406.979123)
			(xy 86.796678 -406.919323) (xy 86.772915 -406.856223) (xy 86.756881 -406.790731) (xy 86.748808 -406.723789)
			(xy 83.470763 -406.723789) (xy 83.462728 -406.790549) (xy 83.446757 -406.85593) (xy 83.423086 -406.918933)
			(xy 83.392055 -406.978655) (xy 83.354107 -407.03424) (xy 83.33232 -407.059892) (xy 83.326547 -407.067054)
			(xy 83.320017 -407.084231) (xy 83.31962 -407.09342) (xy 83.31962 -407.251408) (xy 83.319185 -407.26156)
			(xy 83.311391 -407.280309) (xy 83.296998 -407.294631) (xy 83.278212 -407.302334) (xy 83.268058 -407.302716)
			(xy 82.551778 -407.302716) (xy 82.541644 -407.30229) (xy 82.522914 -407.294547) (xy 82.508557 -407.280242)
			(xy 82.500747 -407.26154) (xy 82.500216 -407.251408) (xy 82.500216 -407.09342) (xy 82.499792 -407.084234)
			(xy 82.493288 -407.06705) (xy 82.487516 -407.059892) (xy 82.465698 -407.034265) (xy 82.427751 -406.978675)
			(xy 82.396721 -406.918947) (xy 82.373051 -406.85594) (xy 82.35708 -406.790555) (xy 82.349039 -406.72373)
			(xy 79.070977 -406.72373) (xy 79.070977 -406.723786) (xy 79.062905 -406.790722) (xy 79.046874 -406.856209)
			(xy 79.023114 -406.919304) (xy 78.991969 -406.9791) (xy 78.953885 -407.034734) (xy 78.932024 -407.0604)
			(xy 78.926248 -407.06756) (xy 78.91972 -407.084739) (xy 78.919324 -407.093928) (xy 78.919324 -407.251408)
			(xy 78.918822 -407.261514) (xy 78.911086 -407.280188) (xy 78.896795 -407.294482) (xy 78.878122 -407.30222)
			(xy 78.868016 -407.302716) (xy 78.151736 -407.302716) (xy 78.141618 -407.302255) (xy 78.122918 -407.294521)
			(xy 78.108603 -407.280219) (xy 78.100854 -407.261526) (xy 78.100428 -407.251408) (xy 78.100428 -407.093928)
			(xy 78.099998 -407.084743) (xy 78.093497 -407.067559) (xy 78.087728 -407.0604) (xy 78.065832 -407.034761)
			(xy 78.027742 -406.979124) (xy 77.996591 -406.919324) (xy 77.972828 -406.856224) (xy 77.956793 -406.790731)
			(xy 77.94872 -406.723789) (xy 74.670675 -406.723789) (xy 74.662641 -406.790548) (xy 74.64667 -406.855929)
			(xy 74.623 -406.918932) (xy 74.591969 -406.978655) (xy 74.554022 -407.03424) (xy 74.532236 -407.059892)
			(xy 74.526453 -407.067046) (xy 74.519932 -407.08423) (xy 74.519536 -407.09342) (xy 74.519536 -407.251408)
			(xy 74.519085 -407.261558) (xy 74.511294 -407.280304) (xy 74.496907 -407.294625) (xy 74.478126 -407.302331)
			(xy 74.467974 -407.302716) (xy 73.751694 -407.302716) (xy 73.741562 -407.302277) (xy 73.722832 -407.294539)
			(xy 73.708474 -407.280238) (xy 73.700663 -407.261538) (xy 73.700132 -407.251408) (xy 73.700132 -407.09342)
			(xy 73.699705 -407.084235) (xy 73.693202 -407.067051) (xy 73.687432 -407.059892) (xy 73.665613 -407.034266)
			(xy 73.627666 -406.978675) (xy 73.596634 -406.918948) (xy 73.572963 -406.85594) (xy 73.556993 -406.790555)
			(xy 73.548951 -406.72373) (xy 66.525648 -406.72373) (xy 66.525648 -409.523886) (xy 71.34879 -409.523886)
			(xy 71.348793 -409.45646) (xy 71.356872 -409.389519) (xy 71.372911 -409.324028) (xy 71.396679 -409.26093)
			(xy 71.427834 -409.201133) (xy 71.465926 -409.145497) (xy 71.487792 -409.119832) (xy 71.493599 -409.112694)
			(xy 71.500108 -409.095498) (xy 71.500492 -409.086304) (xy 71.500492 -408.594052) (xy 71.500059 -408.584867)
			(xy 71.493561 -408.567682) (xy 71.487792 -408.560524) (xy 71.46592 -408.534865) (xy 71.427833 -408.479229)
			(xy 71.396683 -408.419432) (xy 71.372919 -408.356335) (xy 71.356885 -408.290845) (xy 71.348809 -408.223906)
			(xy 71.34881 -408.156482) (xy 71.356887 -408.089543) (xy 71.372923 -408.024054) (xy 71.396688 -407.960957)
			(xy 71.427839 -407.90116) (xy 71.465928 -407.845525) (xy 71.487792 -407.81986) (xy 71.493587 -407.812714)
			(xy 71.500103 -407.795524) (xy 71.500492 -407.786332) (xy 71.500492 -407.628852) (xy 71.500946 -407.618741)
			(xy 71.508698 -407.600063) (xy 71.523004 -407.585771) (xy 71.541689 -407.578036) (xy 71.5518 -407.577544)
			(xy 72.26808 -407.577544) (xy 72.278181 -407.5781) (xy 72.296848 -407.585821) (xy 72.311141 -407.600095)
			(xy 72.318887 -407.618752) (xy 72.319388 -407.628852) (xy 72.319388 -407.786332) (xy 72.319785 -407.795521)
			(xy 72.326308 -407.812705) (xy 72.332088 -407.81986) (xy 72.353945 -407.845532) (xy 72.392034 -407.901165)
			(xy 72.423186 -407.96096) (xy 72.446951 -408.024056) (xy 72.462988 -408.089545) (xy 72.471064 -408.156482)
			(xy 72.471065 -408.223906) (xy 72.46299 -408.290844) (xy 72.446955 -408.356332) (xy 72.423191 -408.419429)
			(xy 72.39204 -408.479225) (xy 72.353952 -408.534859) (xy 72.332088 -408.560524) (xy 72.326297 -408.567673)
			(xy 72.31978 -408.584861) (xy 72.319388 -408.594052) (xy 72.319388 -409.086304) (xy 72.319799 -409.095491)
			(xy 72.326313 -409.112675) (xy 72.332088 -409.119832) (xy 72.353917 -409.145526) (xy 72.392008 -409.201156)
			(xy 72.423161 -409.260948) (xy 72.446927 -409.324042) (xy 72.462966 -409.389527) (xy 72.471045 -409.456462)
			(xy 72.471048 -409.523884) (xy 72.462975 -409.59082) (xy 72.446943 -409.656307) (xy 72.423183 -409.719402)
			(xy 72.392035 -409.779197) (xy 72.35395 -409.834831) (xy 72.332088 -409.860496) (xy 72.326309 -409.867654)
			(xy 72.319784 -409.884835) (xy 72.319388 -409.894024) (xy 72.319388 -410.051504) (xy 72.318987 -410.061628)
			(xy 72.311235 -410.080334) (xy 72.296914 -410.094649) (xy 72.278204 -410.102392) (xy 72.26808 -410.102812)
			(xy 71.5518 -410.102812) (xy 71.541693 -410.102315) (xy 71.523017 -410.09458) (xy 71.508723 -410.080286)
			(xy 71.500986 -410.061611) (xy 71.500492 -410.051504) (xy 71.500492 -409.894024) (xy 71.500072 -409.884838)
			(xy 71.493565 -409.867653) (xy 71.487792 -409.860496) (xy 71.465893 -409.83486) (xy 71.427806 -409.779221)
			(xy 71.396657 -409.719421) (xy 71.372895 -409.65632) (xy 71.356863 -409.590827) (xy 71.34879 -409.523886)
			(xy 66.525648 -409.523886) (xy 66.525648 -410.623641) (xy 73.548963 -410.623641) (xy 73.548964 -410.556335)
			(xy 73.55701 -410.489511) (xy 73.572984 -410.424128) (xy 73.596658 -410.361123) (xy 73.627693 -410.301399)
			(xy 73.665643 -410.245812) (xy 73.687432 -410.22016) (xy 73.693232 -410.213017) (xy 73.699744 -410.195825)
			(xy 73.700132 -410.186632) (xy 73.700132 -409.693364) (xy 73.699732 -409.684176) (xy 73.69321 -409.666992)
			(xy 73.687432 -409.659836) (xy 73.665656 -409.634174) (xy 73.627707 -409.578589) (xy 73.596674 -409.518867)
			(xy 73.573001 -409.455863) (xy 73.557027 -409.390482) (xy 73.548982 -409.323661) (xy 73.548981 -409.256357)
			(xy 73.557024 -409.189535) (xy 73.572995 -409.124154) (xy 73.596667 -409.06115) (xy 73.627698 -409.001427)
			(xy 73.665645 -408.94584) (xy 73.687432 -408.920188) (xy 73.69322 -408.913037) (xy 73.699739 -408.895851)
			(xy 73.700132 -408.88666) (xy 73.700132 -408.728672) (xy 73.700499 -408.718512) (xy 73.70831 -408.699753)
			(xy 73.722724 -408.685429) (xy 73.741532 -408.677736) (xy 73.751694 -408.677364) (xy 74.467974 -408.677364)
			(xy 74.478102 -408.677848) (xy 74.496827 -408.685572) (xy 74.511185 -408.69986) (xy 74.519001 -408.718546)
			(xy 74.519536 -408.728672) (xy 74.519536 -408.88666) (xy 74.51998 -408.895843) (xy 74.526472 -408.913027)
			(xy 74.532236 -408.920188) (xy 74.554036 -408.94583) (xy 74.591986 -409.001418) (xy 74.62302 -409.061142)
			(xy 74.646694 -409.124148) (xy 74.662666 -409.189532) (xy 74.67071 -409.256356) (xy 74.670709 -409.323662)
			(xy 74.662663 -409.390486) (xy 74.646688 -409.455869) (xy 74.623013 -409.518874) (xy 74.620439 -409.523827)
			(xy 75.749085 -409.523827) (xy 75.749088 -409.456519) (xy 75.757137 -409.389693) (xy 75.773115 -409.324308)
			(xy 75.796793 -409.261302) (xy 75.827833 -409.201578) (xy 75.865789 -409.145992) (xy 75.88758 -409.12034)
			(xy 75.893382 -409.113199) (xy 75.899894 -409.096005) (xy 75.90028 -409.086812) (xy 75.90028 -408.593544)
			(xy 75.899853 -408.584358) (xy 75.893352 -408.567174) (xy 75.88758 -408.560016) (xy 75.865783 -408.534371)
			(xy 75.827832 -408.478784) (xy 75.796797 -408.41906) (xy 75.773123 -408.356055) (xy 75.757149 -408.290671)
			(xy 75.749105 -408.223847) (xy 75.749106 -408.156541) (xy 75.757151 -408.089717) (xy 75.773126 -408.024334)
			(xy 75.796802 -407.961329) (xy 75.827838 -407.901605) (xy 75.865791 -407.84602) (xy 75.88758 -407.820368)
			(xy 75.89337 -407.813218) (xy 75.899889 -407.796031) (xy 75.90028 -407.78684) (xy 75.90028 -407.628852)
			(xy 75.900682 -407.618697) (xy 75.90849 -407.599948) (xy 75.922892 -407.585627) (xy 75.941685 -407.577925)
			(xy 75.951842 -407.577544) (xy 76.668122 -407.577544) (xy 76.678251 -407.578008) (xy 76.696973 -407.585744)
			(xy 76.711329 -407.600037) (xy 76.719147 -407.618726) (xy 76.719684 -407.628852) (xy 76.719684 -407.78684)
			(xy 76.720078 -407.796029) (xy 76.726603 -407.813213) (xy 76.732384 -407.820368) (xy 76.754163 -407.846027)
			(xy 76.792111 -407.901613) (xy 76.823143 -407.961336) (xy 76.846815 -408.024339) (xy 76.862788 -408.08972)
			(xy 76.870833 -408.156542) (xy 76.870833 -408.223846) (xy 76.86279 -408.290668) (xy 76.846819 -408.356049)
			(xy 76.823148 -408.419053) (xy 76.792117 -408.478777) (xy 76.754171 -408.534364) (xy 76.732384 -408.560016)
			(xy 76.726596 -408.567167) (xy 76.720077 -408.584353) (xy 76.719684 -408.593544) (xy 76.719684 -409.086812)
			(xy 76.720092 -409.095999) (xy 76.726607 -409.113184) (xy 76.732384 -409.12034) (xy 76.754135 -409.146022)
			(xy 76.792084 -409.201605) (xy 76.823117 -409.261324) (xy 76.846791 -409.324325) (xy 76.862766 -409.389703)
			(xy 76.870812 -409.456522) (xy 76.870816 -409.523824) (xy 76.862775 -409.590644) (xy 76.846807 -409.656023)
			(xy 76.823139 -409.719026) (xy 76.792112 -409.778749) (xy 76.754169 -409.834335) (xy 76.732384 -409.859988)
			(xy 76.726566 -409.867118) (xy 76.720065 -409.88432) (xy 76.719684 -409.893516) (xy 76.719684 -410.051504)
			(xy 76.719281 -410.06166) (xy 76.711481 -410.080416) (xy 76.697079 -410.09474) (xy 76.678281 -410.102436)
			(xy 76.668122 -410.102812) (xy 75.951842 -410.102812) (xy 75.941724 -410.10224) (xy 75.923014 -410.094536)
			(xy 75.908658 -410.080276) (xy 75.900828 -410.061618) (xy 75.90028 -410.051504) (xy 75.90028 -409.893516)
			(xy 75.899867 -409.884329) (xy 75.893356 -409.867144) (xy 75.88758 -409.859988) (xy 75.865756 -409.834365)
			(xy 75.827805 -409.778776) (xy 75.796771 -409.719048) (xy 75.773099 -409.65604) (xy 75.757127 -409.590654)
			(xy 75.749085 -409.523827) (xy 74.620439 -409.523827) (xy 74.591977 -409.578598) (xy 74.554025 -409.634184)
			(xy 74.532236 -409.659836) (xy 74.526434 -409.666977) (xy 74.519924 -409.684171) (xy 74.519536 -409.693364)
			(xy 74.519536 -410.186632) (xy 74.519945 -410.195819) (xy 74.526461 -410.213002) (xy 74.532236 -410.22016)
			(xy 74.554009 -410.245825) (xy 74.59196 -410.301409) (xy 74.622995 -410.36113) (xy 74.64667 -410.424133)
			(xy 74.662644 -410.489514) (xy 74.67069 -410.556336) (xy 74.670692 -410.62364) (xy 74.670685 -410.623701)
			(xy 77.948731 -410.623701) (xy 77.948732 -410.556275) (xy 77.95681 -410.489335) (xy 77.972848 -410.423845)
			(xy 77.996615 -410.360747) (xy 78.02777 -410.300951) (xy 78.065862 -410.245317) (xy 78.087728 -410.219652)
			(xy 78.093531 -410.212512) (xy 78.100041 -410.195317) (xy 78.100428 -410.186124) (xy 78.100428 -409.693872)
			(xy 78.100025 -409.684684) (xy 78.093506 -409.6675) (xy 78.087728 -409.660344) (xy 78.065875 -409.63467)
			(xy 78.027784 -409.579037) (xy 77.996631 -409.519242) (xy 77.972865 -409.456147) (xy 77.956828 -409.390658)
			(xy 77.948751 -409.323721) (xy 77.94875 -409.256297) (xy 77.956825 -409.189359) (xy 77.97286 -409.123871)
			(xy 77.996624 -409.060774) (xy 78.027775 -409.000979) (xy 78.065864 -408.945345) (xy 78.087728 -408.91968)
			(xy 78.093519 -408.912531) (xy 78.100036 -408.895343) (xy 78.100428 -408.886152) (xy 78.100428 -408.728672)
			(xy 78.100794 -408.718544) (xy 78.108556 -408.699835) (xy 78.122888 -408.68552) (xy 78.141608 -408.677781)
			(xy 78.151736 -408.677364) (xy 78.868016 -408.677364) (xy 78.878121 -408.677871) (xy 78.896793 -408.685608)
			(xy 78.911086 -408.699897) (xy 78.918826 -408.718567) (xy 78.919324 -408.728672) (xy 78.919324 -408.886152)
			(xy 78.919752 -408.895337) (xy 78.926253 -408.912522) (xy 78.932024 -408.91968) (xy 78.953899 -408.945336)
			(xy 78.991986 -409.000972) (xy 79.023135 -409.06077) (xy 79.046897 -409.123868) (xy 79.062931 -409.189358)
			(xy 79.071005 -409.256297) (xy 79.071004 -409.323721) (xy 79.062928 -409.39066) (xy 79.046892 -409.456149)
			(xy 79.023127 -409.519246) (xy 79.02071 -409.523886) (xy 80.148878 -409.523886) (xy 80.148881 -409.45646)
			(xy 80.15696 -409.38952) (xy 80.172999 -409.324029) (xy 80.196766 -409.260931) (xy 80.227919 -409.201133)
			(xy 80.266011 -409.145498) (xy 80.287876 -409.119832) (xy 80.293681 -409.112693) (xy 80.300191 -409.095498)
			(xy 80.300576 -409.086304) (xy 80.300576 -408.594052) (xy 80.300146 -408.584867) (xy 80.293647 -408.567682)
			(xy 80.287876 -408.560524) (xy 80.266005 -408.534865) (xy 80.227918 -408.479229) (xy 80.196769 -408.419432)
			(xy 80.173006 -408.356334) (xy 80.156972 -408.290844) (xy 80.148897 -408.223906) (xy 80.148898 -408.156482)
			(xy 80.156974 -408.089544) (xy 80.17301 -408.024055) (xy 80.196774 -407.960957) (xy 80.227924 -407.901161)
			(xy 80.266012 -407.845526) (xy 80.287876 -407.81986) (xy 80.293669 -407.812712) (xy 80.300187 -407.795524)
			(xy 80.300576 -407.786332) (xy 80.300576 -407.628852) (xy 80.301045 -407.618743) (xy 80.308794 -407.600069)
			(xy 80.323095 -407.585776) (xy 80.341775 -407.578039) (xy 80.351884 -407.577544) (xy 81.068164 -407.577544)
			(xy 81.078264 -407.578113) (xy 81.09693 -407.585829) (xy 81.111224 -407.600099) (xy 81.11897 -407.618753)
			(xy 81.119472 -407.628852) (xy 81.119472 -407.786332) (xy 81.119873 -407.79552) (xy 81.126394 -407.812704)
			(xy 81.132172 -407.81986) (xy 81.154029 -407.845531) (xy 81.19212 -407.901164) (xy 81.223273 -407.960959)
			(xy 81.247038 -408.024056) (xy 81.263075 -408.089544) (xy 81.271152 -408.156482) (xy 81.271153 -408.223906)
			(xy 81.263077 -408.290844) (xy 81.247042 -408.356333) (xy 81.223277 -408.41943) (xy 81.192126 -408.479225)
			(xy 81.154036 -408.534859) (xy 81.132172 -408.560524) (xy 81.126379 -408.567672) (xy 81.119863 -408.58486)
			(xy 81.119472 -408.594052) (xy 81.119472 -409.086304) (xy 81.119886 -409.095491) (xy 81.126398 -409.112675)
			(xy 81.132172 -409.119832) (xy 81.154002 -409.145526) (xy 81.192093 -409.201156) (xy 81.223247 -409.260948)
			(xy 81.247014 -409.324041) (xy 81.263053 -409.389527) (xy 81.271132 -409.456462) (xy 81.271136 -409.523884)
			(xy 81.263063 -409.59082) (xy 81.247031 -409.656307) (xy 81.223269 -409.719403) (xy 81.192121 -409.779198)
			(xy 81.154035 -409.834831) (xy 81.132172 -409.860496) (xy 81.126391 -409.867652) (xy 81.119868 -409.884834)
			(xy 81.119472 -409.894024) (xy 81.119472 -410.051504) (xy 81.119086 -410.06163) (xy 81.111332 -410.080339)
			(xy 81.097006 -410.094654) (xy 81.078291 -410.102394) (xy 81.068164 -410.102812) (xy 80.351884 -410.102812)
			(xy 80.341776 -410.102328) (xy 80.3231 -410.094587) (xy 80.308806 -410.08029) (xy 80.30107 -410.061612)
			(xy 80.300576 -410.051504) (xy 80.300576 -409.894024) (xy 80.30016 -409.884837) (xy 80.293651 -409.867653)
			(xy 80.287876 -409.860496) (xy 80.265978 -409.83486) (xy 80.227891 -409.77922) (xy 80.196744 -409.71942)
			(xy 80.172983 -409.656319) (xy 80.15695 -409.590827) (xy 80.148878 -409.523886) (xy 79.02071 -409.523886)
			(xy 78.991976 -409.579043) (xy 78.953888 -409.634678) (xy 78.932024 -409.660344) (xy 78.926229 -409.667491)
			(xy 78.919713 -409.68468) (xy 78.919324 -409.693872) (xy 78.919324 -410.186124) (xy 78.919717 -410.195313)
			(xy 78.926242 -410.212497) (xy 78.932024 -410.219652) (xy 78.953871 -410.245331) (xy 78.991959 -410.300964)
			(xy 79.023109 -410.360758) (xy 79.046873 -410.423853) (xy 79.062909 -410.489341) (xy 79.070986 -410.556277)
			(xy 79.070987 -410.623641) (xy 82.349051 -410.623641) (xy 82.349052 -410.556335) (xy 82.357097 -410.489512)
			(xy 82.373071 -410.424129) (xy 82.396745 -410.361124) (xy 82.427779 -410.3014) (xy 82.465728 -410.245812)
			(xy 82.487516 -410.22016) (xy 82.493314 -410.213016) (xy 82.499827 -410.195824) (xy 82.500216 -410.186632)
			(xy 82.500216 -409.693364) (xy 82.49982 -409.684175) (xy 82.493296 -409.666991) (xy 82.487516 -409.659836)
			(xy 82.465741 -409.634174) (xy 82.427793 -409.578588) (xy 82.39676 -409.518866) (xy 82.373088 -409.455863)
			(xy 82.357115 -409.390482) (xy 82.34907 -409.323661) (xy 82.349069 -409.256357) (xy 82.357112 -409.189536)
			(xy 82.373083 -409.124155) (xy 82.396753 -409.061151) (xy 82.427784 -409.001427) (xy 82.46573 -408.94584)
			(xy 82.487516 -408.920188) (xy 82.493302 -408.913035) (xy 82.499822 -408.89585) (xy 82.500216 -408.88666)
			(xy 82.500216 -408.728672) (xy 82.500599 -408.718514) (xy 82.508407 -408.699758) (xy 82.522815 -408.685435)
			(xy 82.541618 -408.677739) (xy 82.551778 -408.677364) (xy 83.268058 -408.677364) (xy 83.278185 -408.677862)
			(xy 83.29691 -408.68558) (xy 83.311268 -408.699864) (xy 83.319085 -408.718548) (xy 83.31962 -408.728672)
			(xy 83.31962 -408.88666) (xy 83.320045 -408.895846) (xy 83.326548 -408.913031) (xy 83.33232 -408.920188)
			(xy 83.354121 -408.94583) (xy 83.392072 -409.001417) (xy 83.423107 -409.061141) (xy 83.446781 -409.124147)
			(xy 83.462754 -409.189531) (xy 83.470798 -409.256356) (xy 83.470797 -409.323662) (xy 83.462751 -409.390487)
			(xy 83.446775 -409.45587) (xy 83.423099 -409.518875) (xy 83.420495 -409.523886) (xy 84.548669 -409.523886)
			(xy 84.548672 -409.45646) (xy 84.556751 -409.38952) (xy 84.572789 -409.324029) (xy 84.596556 -409.260931)
			(xy 84.627709 -409.201134) (xy 84.665799 -409.145498) (xy 84.687664 -409.119832) (xy 84.69348 -409.112701)
			(xy 84.699981 -409.095499) (xy 84.700364 -409.086304) (xy 84.700364 -408.594052) (xy 84.699915 -408.584869)
			(xy 84.693427 -408.567685) (xy 84.687664 -408.560524) (xy 84.665793 -408.534865) (xy 84.627707 -408.479228)
			(xy 84.596559 -408.419431) (xy 84.572797 -408.356334) (xy 84.556763 -408.290844) (xy 84.548688 -408.223906)
			(xy 84.548689 -408.156482) (xy 84.556765 -408.089544) (xy 84.5728 -408.024055) (xy 84.596564 -407.960958)
			(xy 84.627714 -407.901161) (xy 84.665801 -407.845526) (xy 84.687664 -407.81986) (xy 84.693468 -407.81272)
			(xy 84.699976 -407.795525) (xy 84.700364 -407.786332) (xy 84.700364 -407.628852) (xy 84.700845 -407.618745)
			(xy 84.708592 -407.600072) (xy 84.722889 -407.585781) (xy 84.741564 -407.578041) (xy 84.751672 -407.577544)
			(xy 85.467952 -407.577544) (xy 85.478051 -407.578123) (xy 85.496717 -407.585835) (xy 85.511012 -407.600102)
			(xy 85.518758 -407.618754) (xy 85.51926 -407.628852) (xy 85.51926 -407.786332) (xy 85.519664 -407.79552)
			(xy 85.526183 -407.812703) (xy 85.53196 -407.81986) (xy 85.553818 -407.845531) (xy 85.591909 -407.901164)
			(xy 85.623062 -407.960959) (xy 85.646829 -408.024055) (xy 85.662866 -408.089544) (xy 85.670943 -408.156482)
			(xy 85.670944 -408.223906) (xy 85.662868 -408.290844) (xy 85.646832 -408.356333) (xy 85.623067 -408.41943)
			(xy 85.591915 -408.479226) (xy 85.553825 -408.534859) (xy 85.53196 -408.560524) (xy 85.526166 -408.567671)
			(xy 85.519651 -408.58486) (xy 85.51926 -408.594052) (xy 85.51926 -409.086304) (xy 85.519677 -409.09549)
			(xy 85.526187 -409.112674) (xy 85.53196 -409.119832) (xy 85.55379 -409.145526) (xy 85.591882 -409.201155)
			(xy 85.623037 -409.260947) (xy 85.646805 -409.32404) (xy 85.662844 -409.389526) (xy 85.670923 -409.456462)
			(xy 85.670927 -409.523884) (xy 85.662854 -409.59082) (xy 85.646821 -409.656308) (xy 85.623059 -409.719403)
			(xy 85.59191 -409.779198) (xy 85.553823 -409.834831) (xy 85.53196 -409.860496) (xy 85.526178 -409.867651)
			(xy 85.519655 -409.884834) (xy 85.51926 -409.894024) (xy 85.51926 -410.051504) (xy 85.518886 -410.061632)
			(xy 85.511129 -410.080343) (xy 85.496799 -410.094659) (xy 85.47808 -410.102396) (xy 85.467952 -410.102812)
			(xy 84.751672 -410.102812) (xy 84.741563 -410.102338) (xy 84.722886 -410.094594) (xy 84.708593 -410.080293)
			(xy 84.700857 -410.061613) (xy 84.700364 -410.051504) (xy 84.700364 -409.894024) (xy 84.699928 -409.88484)
			(xy 84.693431 -409.867656) (xy 84.687664 -409.860496) (xy 84.665766 -409.834859) (xy 84.627681 -409.77922)
			(xy 84.596534 -409.719419) (xy 84.572773 -409.656319) (xy 84.556741 -409.590827) (xy 84.548669 -409.523886)
			(xy 83.420495 -409.523886) (xy 83.392063 -409.578599) (xy 83.35411 -409.634184) (xy 83.33232 -409.659836)
			(xy 83.326528 -409.666985) (xy 83.32001 -409.684172) (xy 83.31962 -409.693364) (xy 83.31962 -410.186632)
			(xy 83.32001 -410.195821) (xy 83.326537 -410.213006) (xy 83.33232 -410.22016) (xy 83.354093 -410.245825)
			(xy 83.392045 -410.301408) (xy 83.423081 -410.36113) (xy 83.446757 -410.424133) (xy 83.462732 -410.489514)
			(xy 83.470778 -410.556336) (xy 83.47078 -410.62364) (xy 83.470773 -410.623701) (xy 86.748819 -410.623701)
			(xy 86.74882 -410.556275) (xy 86.756898 -410.489336) (xy 86.772936 -410.423846) (xy 86.796702 -410.360748)
			(xy 86.827855 -410.300952) (xy 86.865947 -410.245317) (xy 86.887812 -410.219652) (xy 86.893613 -410.21251)
			(xy 86.900125 -410.195317) (xy 86.900512 -410.186124) (xy 86.900512 -409.693872) (xy 86.900113 -409.684684)
			(xy 86.893591 -409.6675) (xy 86.887812 -409.660344) (xy 86.865959 -409.634669) (xy 86.82787 -409.579036)
			(xy 86.796718 -409.519242) (xy 86.772952 -409.456146) (xy 86.756916 -409.390658) (xy 86.748839 -409.32372)
			(xy 86.748837 -409.256298) (xy 86.756912 -409.18936) (xy 86.772947 -409.123871) (xy 86.79671 -409.060775)
			(xy 86.82786 -409.000979) (xy 86.865948 -408.945345) (xy 86.887812 -408.91968) (xy 86.893601 -408.912529)
			(xy 86.90012 -408.895343) (xy 86.900512 -408.886152) (xy 86.900512 -408.728672) (xy 86.900962 -408.71856)
			(xy 86.908711 -408.699879) (xy 86.923019 -408.685585) (xy 86.941708 -408.677853) (xy 86.95182 -408.677364)
			(xy 87.6681 -408.677364) (xy 87.678204 -408.677884) (xy 87.696876 -408.685615) (xy 87.711169 -408.699901)
			(xy 87.71891 -408.718568) (xy 87.719408 -408.728672) (xy 87.719408 -408.886152) (xy 87.719839 -408.895337)
			(xy 87.726338 -408.912522) (xy 87.732108 -408.91968) (xy 87.753983 -408.945336) (xy 87.792071 -409.000972)
			(xy 87.823221 -409.060769) (xy 87.846984 -409.123867) (xy 87.863019 -409.189358) (xy 87.871093 -409.256297)
			(xy 87.871092 -409.323721) (xy 87.863015 -409.39066) (xy 87.846979 -409.45615) (xy 87.823214 -409.519247)
			(xy 87.792062 -409.579044) (xy 87.753972 -409.634679) (xy 87.732108 -409.660344) (xy 87.726311 -409.667489)
			(xy 87.719796 -409.68468) (xy 87.719408 -409.693872) (xy 87.719408 -410.186124) (xy 87.719805 -410.195313)
			(xy 87.726328 -410.212497) (xy 87.732108 -410.219652) (xy 87.753956 -410.24533) (xy 87.792045 -410.300963)
			(xy 87.823196 -410.360758) (xy 87.84696 -410.423853) (xy 87.862997 -410.48934) (xy 87.871074 -410.556277)
			(xy 87.871075 -410.623641) (xy 91.149138 -410.623641) (xy 91.14914 -410.556335) (xy 91.157185 -410.489512)
			(xy 91.173158 -410.42413) (xy 91.196831 -410.361125) (xy 91.227864 -410.3014) (xy 91.265813 -410.245813)
			(xy 91.2876 -410.22016) (xy 91.293396 -410.213014) (xy 91.299911 -410.195824) (xy 91.3003 -410.186632)
			(xy 91.3003 -409.693364) (xy 91.299907 -409.684175) (xy 91.293382 -409.666991) (xy 91.2876 -409.659836)
			(xy 91.265825 -409.634174) (xy 91.227879 -409.578588) (xy 91.196847 -409.518865) (xy 91.173175 -409.455862)
			(xy 91.157203 -409.390482) (xy 91.149158 -409.323661) (xy 91.149157 -409.256357) (xy 91.157199 -409.189536)
			(xy 91.17317 -409.124155) (xy 91.19684 -409.061151) (xy 91.227869 -409.001428) (xy 91.265814 -408.945841)
			(xy 91.2876 -408.920188) (xy 91.293384 -408.913034) (xy 91.299906 -408.89585) (xy 91.3003 -408.88666)
			(xy 91.3003 -408.728672) (xy 91.300699 -408.718516) (xy 91.308503 -408.699763) (xy 91.322907 -408.685441)
			(xy 91.341704 -408.677742) (xy 91.351862 -408.677364) (xy 92.068142 -408.677364) (xy 92.078274 -408.677793)
			(xy 92.097001 -408.685539) (xy 92.111357 -408.699843) (xy 92.11917 -408.718542) (xy 92.119704 -408.728672)
			(xy 92.119704 -408.88666) (xy 92.120132 -408.895845) (xy 92.126633 -408.91303) (xy 92.132404 -408.920188)
			(xy 92.154202 -408.945831) (xy 92.192148 -409.00142) (xy 92.223178 -409.061145) (xy 92.246848 -409.124151)
			(xy 92.262819 -409.189534) (xy 92.270862 -409.256356) (xy 92.270861 -409.323662) (xy 92.262816 -409.390484)
			(xy 92.246843 -409.455867) (xy 92.223171 -409.518871) (xy 92.220596 -409.523827) (xy 115.349227 -409.523827)
			(xy 115.349231 -409.456519) (xy 115.357278 -409.389695) (xy 115.373254 -409.324311) (xy 115.396929 -409.261305)
			(xy 115.427964 -409.20158) (xy 115.465915 -409.145993) (xy 115.487704 -409.12034) (xy 115.493509 -409.113201)
			(xy 115.500019 -409.096006) (xy 115.500404 -409.086812) (xy 115.500404 -408.593544) (xy 115.499972 -408.584359)
			(xy 115.493473 -408.567175) (xy 115.487704 -408.560016) (xy 115.465909 -408.53437) (xy 115.427963 -408.478782)
			(xy 115.396932 -408.419057) (xy 115.373261 -408.356052) (xy 115.35729 -408.290669) (xy 115.349247 -408.223846)
			(xy 115.349248 -408.156541) (xy 115.357292 -408.089719) (xy 115.373265 -408.024337) (xy 115.396937 -407.961332)
			(xy 115.427969 -407.901608) (xy 115.465917 -407.846021) (xy 115.487704 -407.820368) (xy 115.493497 -407.81322)
			(xy 115.500014 -407.796032) (xy 115.500404 -407.78684) (xy 115.500404 -407.628852) (xy 115.500846 -407.61874)
			(xy 115.5086 -407.60006) (xy 115.52291 -407.585767) (xy 115.541599 -407.578034) (xy 115.551712 -407.577544)
			(xy 116.268246 -407.577544) (xy 116.278376 -407.577989) (xy 116.297099 -407.585733) (xy 116.311454 -407.600031)
			(xy 116.319271 -407.618724) (xy 116.319808 -407.628852) (xy 116.319808 -407.78684) (xy 116.320197 -407.79603)
			(xy 116.326725 -407.813214) (xy 116.332508 -407.820368) (xy 116.354289 -407.846026) (xy 116.392242 -407.90161)
			(xy 116.423279 -407.961333) (xy 116.446954 -408.024336) (xy 116.462929 -408.089718) (xy 116.470975 -408.156541)
			(xy 116.470976 -408.223847) (xy 116.462931 -408.29067) (xy 116.446958 -408.356052) (xy 116.423283 -408.419056)
			(xy 116.392248 -408.478779) (xy 116.354297 -408.534365) (xy 116.332508 -408.560016) (xy 116.326723 -408.56717)
			(xy 116.320201 -408.584354) (xy 116.319808 -408.593544) (xy 116.319808 -409.086812) (xy 116.320211 -409.096)
			(xy 116.326729 -409.113184) (xy 116.332508 -409.12034) (xy 116.354262 -409.146021) (xy 116.392215 -409.201602)
			(xy 116.423253 -409.261321) (xy 116.44693 -409.324322) (xy 116.462907 -409.389701) (xy 116.470955 -409.456521)
			(xy 116.470958 -409.523825) (xy 116.462917 -409.590646) (xy 116.446946 -409.656026) (xy 116.423275 -409.71903)
			(xy 116.392243 -409.778752) (xy 116.354295 -409.834337) (xy 116.332508 -409.859988) (xy 116.326692 -409.86712)
			(xy 116.320189 -409.884321) (xy 116.319808 -409.893516) (xy 116.319808 -410.051504) (xy 116.319318 -410.061612)
			(xy 116.311581 -410.080289) (xy 116.297285 -410.094583) (xy 116.278608 -410.102319) (xy 116.2685 -410.102812)
			(xy 115.551966 -410.102812) (xy 115.541844 -410.102303) (xy 115.523131 -410.094574) (xy 115.508778 -410.080295)
			(xy 115.500951 -410.061624) (xy 115.500404 -410.051504) (xy 115.500404 -409.893516) (xy 115.499985 -409.88433)
			(xy 115.493477 -409.867145) (xy 115.487704 -409.859988) (xy 115.465882 -409.834364) (xy 115.427937 -409.778773)
			(xy 115.396907 -409.719045) (xy 115.373238 -409.656037) (xy 115.357268 -409.590652) (xy 115.349227 -409.523827)
			(xy 92.220596 -409.523827) (xy 92.192139 -409.578596) (xy 92.154191 -409.634183) (xy 92.132404 -409.659836)
			(xy 92.12661 -409.666983) (xy 92.120094 -409.684172) (xy 92.119704 -409.693364) (xy 92.119704 -410.186632)
			(xy 92.120098 -410.195821) (xy 92.126623 -410.213005) (xy 92.132404 -410.22016) (xy 92.154175 -410.245826)
			(xy 92.192121 -410.301411) (xy 92.223153 -410.361133) (xy 92.246825 -410.424136) (xy 92.262797 -410.489516)
			(xy 92.270842 -410.556336) (xy 92.270844 -410.623639) (xy 92.270837 -410.623701) (xy 117.548849 -410.623701)
			(xy 117.54885 -410.556275) (xy 117.556929 -410.489335) (xy 117.572967 -410.423844) (xy 117.596736 -410.360746)
			(xy 117.627891 -410.30095) (xy 117.665985 -410.245316) (xy 117.687852 -410.219652) (xy 117.693658 -410.212514)
			(xy 117.700166 -410.195318) (xy 117.700552 -410.186124) (xy 117.700552 -409.693872) (xy 117.700144 -409.684685)
			(xy 117.693627 -409.667501) (xy 117.687852 -409.660344) (xy 117.665998 -409.63467) (xy 117.627906 -409.579038)
			(xy 117.596751 -409.519243) (xy 117.572984 -409.456148) (xy 117.556946 -409.390659) (xy 117.548869 -409.323721)
			(xy 117.548868 -409.256297) (xy 117.556943 -409.189359) (xy 117.572979 -409.12387) (xy 117.596744 -409.060773)
			(xy 117.627896 -409.000978) (xy 117.665987 -408.945344) (xy 117.687852 -408.91968) (xy 117.693646 -408.912533)
			(xy 117.700161 -408.895344) (xy 117.700552 -408.886152) (xy 117.700552 -408.728672) (xy 117.701061 -408.718567)
			(xy 117.708799 -408.699898) (xy 117.723088 -408.685606) (xy 117.741756 -408.677863) (xy 117.75186 -408.677364)
			(xy 118.46814 -408.677364) (xy 118.478247 -408.677852) (xy 118.496919 -408.685596) (xy 118.511211 -408.699891)
			(xy 118.518951 -408.718565) (xy 118.519448 -408.728672) (xy 118.519448 -408.886152) (xy 118.519893 -408.895335)
			(xy 118.526384 -408.912519) (xy 118.532148 -408.91968) (xy 118.554026 -408.945335) (xy 118.592117 -409.000969)
			(xy 118.62327 -409.060767) (xy 118.647036 -409.123865) (xy 118.663072 -409.189356) (xy 118.671148 -409.256296)
			(xy 118.671147 -409.323722) (xy 118.663069 -409.390662) (xy 118.647031 -409.456152) (xy 118.623263 -409.51925)
			(xy 118.620848 -409.523886) (xy 119.748996 -409.523886) (xy 119.748999 -409.45646) (xy 119.757078 -409.389519)
			(xy 119.773118 -409.324028) (xy 119.796886 -409.26093) (xy 119.828041 -409.201132) (xy 119.866134 -409.145497)
			(xy 119.888 -409.119832) (xy 119.893808 -409.112695) (xy 119.900316 -409.095498) (xy 119.9007 -409.086304)
			(xy 119.9007 -408.594052) (xy 119.900265 -408.584867) (xy 119.893769 -408.567683) (xy 119.888 -408.560524)
			(xy 119.866128 -408.534865) (xy 119.82804 -408.47923) (xy 119.796889 -408.419433) (xy 119.773126 -408.356335)
			(xy 119.757091 -408.290845) (xy 119.749015 -408.223906) (xy 119.749016 -408.156482) (xy 119.757093 -408.089543)
			(xy 119.773129 -408.024054) (xy 119.796894 -407.960956) (xy 119.828046 -407.90116) (xy 119.866136 -407.845525)
			(xy 119.888 -407.81986) (xy 119.893796 -407.812714) (xy 119.900311 -407.795524) (xy 119.9007 -407.786332)
			(xy 119.9007 -407.628852) (xy 119.901146 -407.61874) (xy 119.908899 -407.600061) (xy 119.923208 -407.585768)
			(xy 119.941896 -407.578035) (xy 119.952008 -407.577544) (xy 120.668288 -407.577544) (xy 120.678389 -407.578094)
			(xy 120.697056 -407.585817) (xy 120.71135 -407.600093) (xy 120.719095 -407.618752) (xy 120.719596 -407.628852)
			(xy 120.719596 -407.786332) (xy 120.719991 -407.795521) (xy 120.726515 -407.812705) (xy 120.732296 -407.81986)
			(xy 120.754152 -407.845532) (xy 120.792241 -407.901165) (xy 120.823393 -407.96096) (xy 120.847158 -408.024056)
			(xy 120.863194 -408.089545) (xy 120.87127 -408.156482) (xy 120.871271 -408.223906) (xy 120.863196 -408.290843)
			(xy 120.847161 -408.356332) (xy 120.823398 -408.419429) (xy 120.792248 -408.479225) (xy 120.75416 -408.534859)
			(xy 120.732296 -408.560524) (xy 120.726506 -408.567674) (xy 120.719988 -408.584861) (xy 120.719596 -408.594052)
			(xy 120.719596 -409.086304) (xy 120.720005 -409.095491) (xy 120.72652 -409.112675) (xy 120.732296 -409.119832)
			(xy 120.754125 -409.145526) (xy 120.792215 -409.201157) (xy 120.823367 -409.260949) (xy 120.847134 -409.324042)
			(xy 120.863172 -409.389527) (xy 120.871251 -409.456463) (xy 120.871254 -409.523883) (xy 120.863181 -409.590819)
			(xy 120.84715 -409.656306) (xy 120.823389 -409.719402) (xy 120.792243 -409.779197) (xy 120.754158 -409.834831)
			(xy 120.732296 -409.860496) (xy 120.726518 -409.867654) (xy 120.719992 -409.884835) (xy 120.719596 -409.894024)
			(xy 120.719596 -410.051504) (xy 120.719187 -410.061627) (xy 120.711437 -410.080332) (xy 120.697118 -410.094646)
			(xy 120.678411 -410.10239) (xy 120.668288 -410.102812) (xy 119.952008 -410.102812) (xy 119.941888 -410.102378)
			(xy 119.923186 -410.094634) (xy 119.908872 -410.080324) (xy 119.901125 -410.061624) (xy 119.9007 -410.051504)
			(xy 119.9007 -409.894024) (xy 119.900278 -409.884838) (xy 119.893773 -409.867654) (xy 119.888 -409.860496)
			(xy 119.866101 -409.83486) (xy 119.828013 -409.779221) (xy 119.796864 -409.719421) (xy 119.773102 -409.65632)
			(xy 119.757069 -409.590828) (xy 119.748996 -409.523886) (xy 118.620848 -409.523886) (xy 118.592108 -409.579046)
			(xy 118.554015 -409.63468) (xy 118.532148 -409.660344) (xy 118.526344 -409.667484) (xy 118.519835 -409.684679)
			(xy 118.519448 -409.693872) (xy 118.519448 -410.186124) (xy 118.519858 -410.195311) (xy 118.526373 -410.212495)
			(xy 118.532148 -410.219652) (xy 118.553998 -410.245329) (xy 118.592091 -410.300961) (xy 118.623245 -410.360755)
			(xy 118.647012 -410.42385) (xy 118.663051 -410.489338) (xy 118.671128 -410.556276) (xy 118.67113 -410.623641)
			(xy 121.949169 -410.623641) (xy 121.94917 -410.556335) (xy 121.957216 -410.489511) (xy 121.97319 -410.424128)
			(xy 121.996865 -410.361123) (xy 122.0279 -410.301399) (xy 122.065851 -410.245812) (xy 122.08764 -410.22016)
			(xy 122.093441 -410.213018) (xy 122.099952 -410.195825) (xy 122.10034 -410.186632) (xy 122.10034 -409.693364)
			(xy 122.099938 -409.684176) (xy 122.093418 -409.666992) (xy 122.08764 -409.659836) (xy 122.065864 -409.634174)
			(xy 122.027915 -409.578589) (xy 121.996881 -409.518867) (xy 121.973208 -409.455864) (xy 121.957234 -409.390483)
			(xy 121.949189 -409.323661) (xy 121.949188 -409.256357) (xy 121.957231 -409.189535) (xy 121.973202 -409.124154)
			(xy 121.996874 -409.06115) (xy 122.027906 -409.001427) (xy 122.065853 -408.94584) (xy 122.08764 -408.920188)
			(xy 122.093429 -408.913038) (xy 122.099947 -408.895851) (xy 122.10034 -408.88666) (xy 122.10034 -408.728672)
			(xy 122.100694 -408.718543) (xy 122.108459 -408.699831) (xy 122.122795 -408.685516) (xy 122.141518 -408.677779)
			(xy 122.151648 -408.677364) (xy 122.868182 -408.677364) (xy 122.878311 -408.677842) (xy 122.897036 -408.685568)
			(xy 122.911394 -408.699858) (xy 122.919209 -408.718546) (xy 122.919744 -408.728672) (xy 122.919744 -408.88666)
			(xy 122.920186 -408.895844) (xy 122.926679 -408.913028) (xy 122.932444 -408.920188) (xy 122.954244 -408.94583)
			(xy 122.992193 -409.001418) (xy 123.023227 -409.061143) (xy 123.0469 -409.124148) (xy 123.062873 -409.189532)
			(xy 123.070916 -409.256356) (xy 123.070915 -409.323662) (xy 123.062869 -409.390486) (xy 123.046895 -409.455869)
			(xy 123.02322 -409.518874) (xy 123.020646 -409.523827) (xy 124.149291 -409.523827) (xy 124.149295 -409.456519)
			(xy 124.157343 -409.389693) (xy 124.173321 -409.324308) (xy 124.197 -409.261302) (xy 124.22804 -409.201577)
			(xy 124.265997 -409.145992) (xy 124.287788 -409.12034) (xy 124.293591 -409.113199) (xy 124.300102 -409.096005)
			(xy 124.300488 -409.086812) (xy 124.300488 -408.593544) (xy 124.300059 -408.584359) (xy 124.293559 -408.567174)
			(xy 124.287788 -408.560016) (xy 124.265991 -408.534371) (xy 124.228039 -408.478785) (xy 124.197004 -408.419061)
			(xy 124.173329 -408.356055) (xy 124.157355 -408.290671) (xy 124.149311 -408.223847) (xy 124.149312 -408.156541)
			(xy 124.157357 -408.089717) (xy 124.173333 -408.024333) (xy 124.197008 -407.961328) (xy 124.228045 -407.901605)
			(xy 124.265998 -407.84602) (xy 124.287788 -407.820368) (xy 124.293579 -407.813219) (xy 124.300097 -407.796031)
			(xy 124.300488 -407.78684) (xy 124.300488 -407.628852) (xy 124.300946 -407.618742) (xy 124.308697 -407.600065)
			(xy 124.323002 -407.585772) (xy 124.341685 -407.578037) (xy 124.351796 -407.577544) (xy 125.06833 -407.577544)
			(xy 125.078459 -407.578002) (xy 125.097182 -407.58574) (xy 125.111537 -407.600035) (xy 125.119355 -407.618725)
			(xy 125.119892 -407.628852) (xy 125.119892 -407.78684) (xy 125.120285 -407.796029) (xy 125.126811 -407.813213)
			(xy 125.132592 -407.820368) (xy 125.154371 -407.846027) (xy 125.192318 -407.901613) (xy 125.22335 -407.961336)
			(xy 125.247022 -408.02434) (xy 125.262994 -408.089721) (xy 125.271039 -408.156542) (xy 125.271039 -408.223846)
			(xy 125.262997 -408.290667) (xy 125.247025 -408.356049) (xy 125.223355 -408.419053) (xy 125.192324 -408.478776)
			(xy 125.154378 -408.534363) (xy 125.132592 -408.560016) (xy 125.126805 -408.567168) (xy 125.120285 -408.584353)
			(xy 125.119892 -408.593544) (xy 125.119892 -409.086812) (xy 125.120298 -409.096) (xy 125.126815 -409.113184)
			(xy 125.132592 -409.12034) (xy 125.154343 -409.146022) (xy 125.192291 -409.201605) (xy 125.223324 -409.261324)
			(xy 125.246998 -409.324325) (xy 125.262972 -409.389703) (xy 125.271019 -409.456522) (xy 125.271022 -409.523824)
			(xy 125.262982 -409.590643) (xy 125.247014 -409.656023) (xy 125.223347 -409.719026) (xy 125.192319 -409.778749)
			(xy 125.154377 -409.834336) (xy 125.132592 -409.859988) (xy 125.126775 -409.867118) (xy 125.120273 -409.88432)
			(xy 125.119892 -409.893516) (xy 125.119892 -410.051504) (xy 125.119487 -410.061628) (xy 125.111736 -410.080333)
			(xy 125.097416 -410.094647) (xy 125.078708 -410.102391) (xy 125.068584 -410.102812) (xy 124.35205 -410.102812)
			(xy 124.341933 -410.102234) (xy 124.323223 -410.094532) (xy 124.308867 -410.080274) (xy 124.301036 -410.061618)
			(xy 124.300488 -410.051504) (xy 124.300488 -409.893516) (xy 124.300073 -409.884329) (xy 124.293563 -409.867145)
			(xy 124.287788 -409.859988) (xy 124.265963 -409.834366) (xy 124.228013 -409.778776) (xy 124.196978 -409.719049)
			(xy 124.173305 -409.65604) (xy 124.157333 -409.590654) (xy 124.149291 -409.523827) (xy 123.020646 -409.523827)
			(xy 122.992184 -409.578598) (xy 122.954233 -409.634184) (xy 122.932444 -409.659836) (xy 122.926643 -409.666978)
			(xy 122.920132 -409.684171) (xy 122.919744 -409.693364) (xy 122.919744 -410.186632) (xy 122.920151 -410.195819)
			(xy 122.926668 -410.213003) (xy 122.932444 -410.22016) (xy 122.954216 -410.245825) (xy 122.992167 -410.301409)
			(xy 123.023202 -410.361131) (xy 123.046876 -410.424134) (xy 123.062851 -410.489514) (xy 123.070896 -410.556336)
			(xy 123.070898 -410.62364) (xy 123.070891 -410.623701) (xy 126.348937 -410.623701) (xy 126.348938 -410.556275)
			(xy 126.357016 -410.489335) (xy 126.373055 -410.423845) (xy 126.396822 -410.360747) (xy 126.427977 -410.300951)
			(xy 126.46607 -410.245317) (xy 126.487936 -410.219652) (xy 126.49374 -410.212512) (xy 126.500249 -410.195317)
			(xy 126.500636 -410.186124) (xy 126.500636 -409.693872) (xy 126.500231 -409.684684) (xy 126.493713 -409.667501)
			(xy 126.487936 -409.660344) (xy 126.466083 -409.63467) (xy 126.427991 -409.579037) (xy 126.396838 -409.519243)
			(xy 126.373071 -409.456147) (xy 126.357034 -409.390659) (xy 126.348957 -409.323721) (xy 126.348956 -409.256297)
			(xy 126.357031 -409.189359) (xy 126.373066 -409.12387) (xy 126.396831 -409.060774) (xy 126.427982 -409.000978)
			(xy 126.466071 -408.945345) (xy 126.487936 -408.91968) (xy 126.493728 -408.912532) (xy 126.500245 -408.895343)
			(xy 126.500636 -408.886152) (xy 126.500636 -408.728672) (xy 126.500994 -408.718543) (xy 126.508758 -408.699832)
			(xy 126.523093 -408.685517) (xy 126.541815 -408.67778) (xy 126.551944 -408.677364) (xy 127.268224 -408.677364)
			(xy 127.27833 -408.677864) (xy 127.297002 -408.685603) (xy 127.311294 -408.699895) (xy 127.319035 -408.718566)
			(xy 127.319532 -408.728672) (xy 127.319532 -408.886152) (xy 127.31998 -408.895335) (xy 127.326469 -408.912519)
			(xy 127.332232 -408.91968) (xy 127.354107 -408.945336) (xy 127.392193 -409.000973) (xy 127.423341 -409.06077)
			(xy 127.447103 -409.123868) (xy 127.463137 -409.189358) (xy 127.471211 -409.256297) (xy 127.47121 -409.323721)
			(xy 127.463134 -409.39066) (xy 127.447098 -409.456149) (xy 127.423334 -409.519246) (xy 127.420948 -409.523827)
			(xy 128.549082 -409.523827) (xy 128.549085 -409.456519) (xy 128.557133 -409.389693) (xy 128.573111 -409.324308)
			(xy 128.59679 -409.261302) (xy 128.627829 -409.201578) (xy 128.665785 -409.145991) (xy 128.687576 -409.12034)
			(xy 128.693378 -409.113198) (xy 128.69989 -409.096005) (xy 128.700276 -409.086812) (xy 128.700276 -408.593544)
			(xy 128.69985 -408.584358) (xy 128.693348 -408.567174) (xy 128.687576 -408.560016) (xy 128.665779 -408.534371)
			(xy 128.627828 -408.478784) (xy 128.596793 -408.41906) (xy 128.573119 -408.356055) (xy 128.557146 -408.290671)
			(xy 128.549102 -408.223847) (xy 128.549103 -408.156541) (xy 128.557148 -408.089717) (xy 128.573123 -408.024334)
			(xy 128.596798 -407.961329) (xy 128.627835 -407.901605) (xy 128.665787 -407.84602) (xy 128.687576 -407.820368)
			(xy 128.693366 -407.813218) (xy 128.699885 -407.796031) (xy 128.700276 -407.78684) (xy 128.700276 -407.628852)
			(xy 128.700745 -407.618743) (xy 128.708494 -407.600069) (xy 128.722795 -407.585776) (xy 128.741475 -407.578039)
			(xy 128.751584 -407.577544) (xy 129.468118 -407.577544) (xy 129.478246 -407.578012) (xy 129.496969 -407.585746)
			(xy 129.511325 -407.600038) (xy 129.519143 -407.618726) (xy 129.51968 -407.628852) (xy 129.51968 -407.78684)
			(xy 129.520075 -407.796029) (xy 129.5266 -407.813213) (xy 129.53238 -407.820368) (xy 129.554159 -407.846027)
			(xy 129.592107 -407.901613) (xy 129.62314 -407.961336) (xy 129.646812 -408.024339) (xy 129.662785 -408.08972)
			(xy 129.67083 -408.156542) (xy 129.67083 -408.223846) (xy 129.662787 -408.290668) (xy 129.646816 -408.356049)
			(xy 129.623145 -408.419053) (xy 129.592113 -408.478777) (xy 129.554167 -408.534364) (xy 129.53238 -408.560016)
			(xy 129.526592 -408.567167) (xy 129.520073 -408.584353) (xy 129.51968 -408.593544) (xy 129.51968 -409.086812)
			(xy 129.520089 -409.095999) (xy 129.526604 -409.113183) (xy 129.53238 -409.12034) (xy 129.554131 -409.146022)
			(xy 129.59208 -409.201604) (xy 129.623114 -409.261324) (xy 129.646788 -409.324325) (xy 129.662763 -409.389703)
			(xy 129.670809 -409.456522) (xy 129.670813 -409.523824) (xy 129.662772 -409.590644) (xy 129.646804 -409.656024)
			(xy 129.623136 -409.719026) (xy 129.592108 -409.778749) (xy 129.554165 -409.834335) (xy 129.53238 -409.859988)
			(xy 129.526561 -409.867117) (xy 129.52006 -409.88432) (xy 129.51968 -409.893516) (xy 129.51968 -410.051504)
			(xy 129.519287 -410.061629) (xy 129.511534 -410.080337) (xy 129.49721 -410.094651) (xy 129.478497 -410.102393)
			(xy 129.468372 -410.102812) (xy 128.751838 -410.102812) (xy 128.74172 -410.102244) (xy 128.72301 -410.094538)
			(xy 128.708654 -410.080277) (xy 128.700824 -410.061618) (xy 128.700276 -410.051504) (xy 128.700276 -409.893516)
			(xy 128.699864 -409.884329) (xy 128.693352 -409.867144) (xy 128.687576 -409.859988) (xy 128.665751 -409.834366)
			(xy 128.627801 -409.778776) (xy 128.596768 -409.719048) (xy 128.573095 -409.65604) (xy 128.557124 -409.590654)
			(xy 128.549082 -409.523827) (xy 127.420948 -409.523827) (xy 127.392184 -409.579043) (xy 127.354096 -409.634678)
			(xy 127.332232 -409.660344) (xy 127.326426 -409.667482) (xy 127.319919 -409.684678) (xy 127.319532 -409.693872)
			(xy 127.319532 -410.186124) (xy 127.319946 -410.19531) (xy 127.326459 -410.212494) (xy 127.332232 -410.219652)
			(xy 127.354079 -410.245331) (xy 127.392166 -410.300964) (xy 127.423316 -410.360759) (xy 127.44708 -410.423854)
			(xy 127.463115 -410.489341) (xy 127.471192 -410.556277) (xy 127.471193 -410.623641) (xy 130.749257 -410.623641)
			(xy 130.749258 -410.556335) (xy 130.757303 -410.489512) (xy 130.773278 -410.424129) (xy 130.796952 -410.361123)
			(xy 130.827986 -410.301399) (xy 130.865936 -410.245812) (xy 130.887724 -410.22016) (xy 130.893523 -410.213017)
			(xy 130.900035 -410.195825) (xy 130.900424 -410.186632) (xy 130.900424 -409.693364) (xy 130.900026 -409.684176)
			(xy 130.893503 -409.666992) (xy 130.887724 -409.659836) (xy 130.865948 -409.634174) (xy 130.828 -409.578589)
			(xy 130.796967 -409.518866) (xy 130.773294 -409.455863) (xy 130.757321 -409.390482) (xy 130.749276 -409.323661)
			(xy 130.749275 -409.256357) (xy 130.757318 -409.189536) (xy 130.773289 -409.124154) (xy 130.79696 -409.06115)
			(xy 130.827991 -409.001427) (xy 130.865937 -408.94584) (xy 130.887724 -408.920188) (xy 130.893511 -408.913036)
			(xy 130.900031 -408.895851) (xy 130.900424 -408.88666) (xy 130.900424 -408.728672) (xy 130.900799 -408.718513)
			(xy 130.908608 -408.699755) (xy 130.92302 -408.685432) (xy 130.941825 -408.677738) (xy 130.951986 -408.677364)
			(xy 131.668266 -408.677364) (xy 131.678393 -408.677855) (xy 131.697118 -408.685576) (xy 131.711477 -408.699862)
			(xy 131.719293 -408.718547) (xy 131.719828 -408.728672) (xy 131.719828 -408.88666) (xy 131.720251 -408.895846)
			(xy 131.726755 -408.913031) (xy 131.732528 -408.920188) (xy 131.754328 -408.94583) (xy 131.792279 -409.001417)
			(xy 131.823314 -409.061142) (xy 131.846987 -409.124148) (xy 131.86296 -409.189532) (xy 131.871004 -409.256356)
			(xy 131.871003 -409.323662) (xy 131.862957 -409.390486) (xy 131.846982 -409.45587) (xy 131.823306 -409.518875)
			(xy 131.79227 -409.578598) (xy 131.754317 -409.634184) (xy 131.732528 -409.659836) (xy 131.726725 -409.666976)
			(xy 131.720216 -409.684171) (xy 131.719828 -409.693364) (xy 131.719828 -410.186632) (xy 131.720217 -410.195822)
			(xy 131.726745 -410.213006) (xy 131.732528 -410.22016) (xy 131.754301 -410.245825) (xy 131.792252 -410.301409)
			(xy 131.823288 -410.36113) (xy 131.846963 -410.424133) (xy 131.862938 -410.489514) (xy 131.870984 -410.556336)
			(xy 131.870986 -410.62364) (xy 131.862943 -410.690462) (xy 131.84697 -410.755844) (xy 131.823298 -410.818848)
			(xy 131.792265 -410.878571) (xy 131.754316 -410.934156) (xy 131.732528 -410.959808) (xy 131.726737 -410.966957)
			(xy 131.720221 -410.984145) (xy 131.719828 -410.993336) (xy 131.719828 -411.151324) (xy 131.719399 -411.161476)
			(xy 131.7116 -411.180224) (xy 131.697207 -411.194545) (xy 131.67842 -411.202249) (xy 131.668266 -411.202632)
			(xy 130.951986 -411.202632) (xy 130.941855 -411.202184) (xy 130.923128 -411.194446) (xy 130.908772 -411.180148)
			(xy 130.900958 -411.161453) (xy 130.900424 -411.151324) (xy 130.900424 -410.993336) (xy 130.899991 -410.984151)
			(xy 130.893493 -410.966967) (xy 130.887724 -410.959808) (xy 130.865921 -410.934169) (xy 130.827974 -410.87858)
			(xy 130.796942 -410.818855) (xy 130.773271 -410.755848) (xy 130.757299 -410.690465) (xy 130.749257 -410.623641)
			(xy 127.471193 -410.623641) (xy 127.471193 -410.623699) (xy 127.463119 -410.690635) (xy 127.447087 -410.756123)
			(xy 127.423326 -410.819219) (xy 127.392179 -410.879015) (xy 127.354094 -410.93465) (xy 127.332232 -410.960316)
			(xy 127.326438 -410.967463) (xy 127.319924 -410.984652) (xy 127.319532 -410.993844) (xy 127.319532 -411.151324)
			(xy 127.319035 -411.16143) (xy 127.311296 -411.180103) (xy 127.297003 -411.194396) (xy 127.27833 -411.202135)
			(xy 127.268224 -411.202632) (xy 126.551944 -411.202632) (xy 126.541828 -411.202149) (xy 126.523132 -411.194421)
			(xy 126.508817 -411.180125) (xy 126.501065 -411.161439) (xy 126.500636 -411.151324) (xy 126.500636 -410.993844)
			(xy 126.500196 -410.98466) (xy 126.493702 -410.967476) (xy 126.487936 -410.960316) (xy 126.466055 -410.934664)
			(xy 126.427964 -410.879029) (xy 126.396812 -410.819231) (xy 126.373048 -410.756132) (xy 126.357012 -410.690641)
			(xy 126.348937 -410.623701) (xy 123.070891 -410.623701) (xy 123.062855 -410.690462) (xy 123.046883 -410.755843)
			(xy 123.023211 -410.818847) (xy 122.992179 -410.87857) (xy 122.954231 -410.934156) (xy 122.932444 -410.959808)
			(xy 122.926655 -410.966958) (xy 122.920137 -410.984145) (xy 122.919744 -410.993336) (xy 122.919744 -411.151324)
			(xy 122.919236 -411.161429) (xy 122.911498 -411.180099) (xy 122.897209 -411.194392) (xy 122.878541 -411.202133)
			(xy 122.868436 -411.202632) (xy 122.151902 -411.202632) (xy 122.141772 -411.202171) (xy 122.123046 -411.194439)
			(xy 122.108688 -411.180144) (xy 122.100874 -411.161452) (xy 122.10034 -411.151324) (xy 122.10034 -410.993336)
			(xy 122.099903 -410.984152) (xy 122.093407 -410.966968) (xy 122.08764 -410.959808) (xy 122.065836 -410.934169)
			(xy 122.027888 -410.878581) (xy 121.996855 -410.818855) (xy 121.973183 -410.755849) (xy 121.957211 -410.690465)
			(xy 121.949169 -410.623641) (xy 118.67113 -410.623641) (xy 118.67113 -410.6237) (xy 118.663055 -410.690638)
			(xy 118.647019 -410.756127) (xy 118.623255 -410.819223) (xy 118.592103 -410.879018) (xy 118.554013 -410.934652)
			(xy 118.532148 -410.960316) (xy 118.526356 -410.967464) (xy 118.51984 -410.984653) (xy 118.519448 -410.993844)
			(xy 118.519448 -411.151324) (xy 118.518936 -411.161428) (xy 118.511199 -411.180098) (xy 118.496911 -411.19439)
			(xy 118.478244 -411.202133) (xy 118.46814 -411.202632) (xy 117.75186 -411.202632) (xy 117.741753 -411.202148)
			(xy 117.72308 -411.194404) (xy 117.708787 -411.180107) (xy 117.701048 -411.161431) (xy 117.700552 -411.151324)
			(xy 117.700552 -410.993844) (xy 117.700109 -410.984661) (xy 117.693617 -410.967477) (xy 117.687852 -410.960316)
			(xy 117.66597 -410.934665) (xy 117.627879 -410.879029) (xy 117.596726 -410.819232) (xy 117.57296 -410.756133)
			(xy 117.556924 -410.690642) (xy 117.548849 -410.623701) (xy 92.270837 -410.623701) (xy 92.262802 -410.69046)
			(xy 92.246832 -410.755841) (xy 92.223163 -410.818845) (xy 92.192134 -410.878568) (xy 92.154189 -410.934155)
			(xy 92.132404 -410.959808) (xy 92.126622 -410.966964) (xy 92.120098 -410.984146) (xy 92.119704 -410.993336)
			(xy 92.119704 -411.151324) (xy 92.119298 -411.161479) (xy 92.111495 -411.180231) (xy 92.097094 -411.194554)
			(xy 92.078299 -411.202253) (xy 92.068142 -411.202632) (xy 91.351862 -411.202632) (xy 91.341729 -411.202204)
			(xy 91.323002 -411.194458) (xy 91.308646 -411.180154) (xy 91.300833 -411.161455) (xy 91.3003 -411.151324)
			(xy 91.3003 -410.993336) (xy 91.299873 -410.984151) (xy 91.293371 -410.966966) (xy 91.2876 -410.959808)
			(xy 91.265798 -410.934168) (xy 91.227852 -410.878579) (xy 91.196822 -410.818853) (xy 91.173151 -410.755847)
			(xy 91.157181 -410.690464) (xy 91.149138 -410.623641) (xy 87.871075 -410.623641) (xy 87.871075 -410.623699)
			(xy 87.863001 -410.690636) (xy 87.846967 -410.756124) (xy 87.823205 -410.81922) (xy 87.792057 -410.879016)
			(xy 87.753971 -410.934651) (xy 87.732108 -410.960316) (xy 87.726323 -410.96747) (xy 87.719801 -410.984654)
			(xy 87.719408 -410.993844) (xy 87.719408 -411.151324) (xy 87.718935 -411.161433) (xy 87.711191 -411.180111)
			(xy 87.69689 -411.194404) (xy 87.67821 -411.20214) (xy 87.6681 -411.202632) (xy 86.95182 -411.202632)
			(xy 86.941716 -411.202099) (xy 86.923045 -411.194374) (xy 86.90875 -411.180092) (xy 86.901009 -411.161427)
			(xy 86.900512 -411.151324) (xy 86.900512 -410.993844) (xy 86.900078 -410.984659) (xy 86.893581 -410.967475)
			(xy 86.887812 -410.960316) (xy 86.865932 -410.934664) (xy 86.827843 -410.879028) (xy 86.796692 -410.81923)
			(xy 86.772928 -410.756131) (xy 86.756894 -410.69064) (xy 86.748819 -410.623701) (xy 83.470773 -410.623701)
			(xy 83.462736 -410.690462) (xy 83.446764 -410.755844) (xy 83.423091 -410.818848) (xy 83.392058 -410.878571)
			(xy 83.354108 -410.934156) (xy 83.33232 -410.959808) (xy 83.32654 -410.966965) (xy 83.320015 -410.984146)
			(xy 83.31962 -410.993336) (xy 83.31962 -411.151324) (xy 83.319199 -411.161477) (xy 83.311399 -411.180226)
			(xy 83.297003 -411.194548) (xy 83.278213 -411.202251) (xy 83.268058 -411.202632) (xy 82.551778 -411.202632)
			(xy 82.541646 -411.202191) (xy 82.522919 -411.194451) (xy 82.508563 -411.18015) (xy 82.500749 -411.161454)
			(xy 82.500216 -411.151324) (xy 82.500216 -410.993336) (xy 82.499785 -410.984151) (xy 82.493285 -410.966967)
			(xy 82.487516 -410.959808) (xy 82.465713 -410.934169) (xy 82.427766 -410.87858) (xy 82.396735 -410.818854)
			(xy 82.373064 -410.755848) (xy 82.357093 -410.690465) (xy 82.349051 -410.623641) (xy 79.070987 -410.623641)
			(xy 79.070987 -410.623699) (xy 79.062913 -410.690636) (xy 79.04688 -410.756124) (xy 79.023119 -410.81922)
			(xy 78.991971 -410.879016) (xy 78.953886 -410.93465) (xy 78.932024 -410.960316) (xy 78.926241 -410.967471)
			(xy 78.919717 -410.984654) (xy 78.919324 -410.993844) (xy 78.919324 -411.151324) (xy 78.918835 -411.161431)
			(xy 78.911094 -411.180106) (xy 78.896799 -411.194399) (xy 78.878123 -411.202137) (xy 78.868016 -411.202632)
			(xy 78.151736 -411.202632) (xy 78.14162 -411.202155) (xy 78.122923 -411.194425) (xy 78.108609 -411.180127)
			(xy 78.100857 -411.16144) (xy 78.100428 -411.151324) (xy 78.100428 -410.993844) (xy 78.09999 -410.98466)
			(xy 78.093495 -410.967476) (xy 78.087728 -410.960316) (xy 78.065847 -410.934664) (xy 78.027757 -410.879028)
			(xy 77.996606 -410.819231) (xy 77.972841 -410.756132) (xy 77.956806 -410.690641) (xy 77.948731 -410.623701)
			(xy 74.670685 -410.623701) (xy 74.662649 -410.690462) (xy 74.646677 -410.755844) (xy 74.623005 -410.818848)
			(xy 74.591972 -410.87857) (xy 74.554023 -410.934156) (xy 74.532236 -410.959808) (xy 74.526446 -410.966957)
			(xy 74.519929 -410.984145) (xy 74.519536 -410.993336) (xy 74.519536 -411.151324) (xy 74.519099 -411.161475)
			(xy 74.511302 -411.180221) (xy 74.496911 -411.194542) (xy 74.478127 -411.202248) (xy 74.467974 -411.202632)
			(xy 73.751694 -411.202632) (xy 73.741563 -411.202177) (xy 73.722837 -411.194442) (xy 73.70848 -411.180146)
			(xy 73.700666 -411.161452) (xy 73.700132 -411.151324) (xy 73.700132 -410.993336) (xy 73.699697 -410.984152)
			(xy 73.6932 -410.966967) (xy 73.687432 -410.959808) (xy 73.665629 -410.934169) (xy 73.627681 -410.87858)
			(xy 73.596649 -410.818855) (xy 73.572977 -410.755849) (xy 73.557005 -410.690465) (xy 73.548963 -410.623641)
			(xy 66.525648 -410.623641) (xy 66.525648 -417.289488) (xy 66.525648 -417.371276) (xy 141.02334 -417.371276)
			(xy 141.02334 -394.305282) (xy 141.023796 -394.293166) (xy 141.031289 -394.270122) (xy 141.045535 -394.25052)
			(xy 141.06514 -394.23628) (xy 141.088186 -394.228793) (xy 141.100302 -394.22832) (xy 154.426158 -394.22832)
			(xy 154.57678 -394.378688) (xy 154.57678 -397.823825) (xy 159.349135 -397.823825) (xy 159.349138 -397.756518)
			(xy 159.357186 -397.689693) (xy 159.373162 -397.624309) (xy 159.396838 -397.561303) (xy 159.427875 -397.501578)
			(xy 159.465827 -397.44599) (xy 159.487616 -397.420338) (xy 159.493423 -397.4132) (xy 159.499931 -397.396004)
			(xy 159.500316 -397.38681) (xy 159.500316 -396.893542) (xy 159.499882 -396.884357) (xy 159.493384 -396.867173)
			(xy 159.487616 -396.860014) (xy 159.465819 -396.83437) (xy 159.427872 -396.778782) (xy 159.396841 -396.719057)
			(xy 159.373169 -396.656051) (xy 159.357198 -396.590668) (xy 159.349155 -396.523845) (xy 159.349156 -396.45654)
			(xy 159.3572 -396.389717) (xy 159.373174 -396.324334) (xy 159.396847 -396.26133) (xy 159.42788 -396.201606)
			(xy 159.465828 -396.146018) (xy 159.487616 -396.120366) (xy 159.493411 -396.11322) (xy 159.499926 -396.09603)
			(xy 159.500316 -396.086838) (xy 159.500316 -395.92885) (xy 159.500804 -395.918684) (xy 159.508569 -395.899895)
			(xy 159.522934 -395.885509) (xy 159.541713 -395.877718) (xy 159.551878 -395.877288) (xy 160.268158 -395.877288)
			(xy 160.278333 -395.877699) (xy 160.297136 -395.88548) (xy 160.311525 -395.89987) (xy 160.319302 -395.918675)
			(xy 160.31972 -395.92885) (xy 160.31972 -396.086838) (xy 160.320108 -396.096028) (xy 160.326637 -396.113212)
			(xy 160.33242 -396.120366) (xy 160.354199 -396.146026) (xy 160.392151 -396.20161) (xy 160.423187 -396.261332)
			(xy 160.446862 -396.324336) (xy 160.462837 -396.389718) (xy 160.470882 -396.45654) (xy 160.470883 -396.523845)
			(xy 160.46284 -396.590668) (xy 160.446866 -396.65605) (xy 160.423193 -396.719054) (xy 160.392159 -396.778777)
			(xy 160.354208 -396.834362) (xy 160.33242 -396.860014) (xy 160.326637 -396.867169) (xy 160.320114 -396.884352)
			(xy 160.31972 -396.893542) (xy 160.31972 -397.38681) (xy 160.320121 -397.395998) (xy 160.326641 -397.413183)
			(xy 160.33242 -397.420338) (xy 160.354172 -397.44602) (xy 160.392124 -397.501601) (xy 160.420549 -397.556296)
			(xy 161.5488 -397.556296) (xy 161.556874 -397.489359) (xy 161.572908 -397.423871) (xy 161.596669 -397.360775)
			(xy 161.627817 -397.300979) (xy 161.665902 -397.245344) (xy 161.687764 -397.219678) (xy 161.69356 -397.212533)
			(xy 161.700073 -397.195342) (xy 161.700464 -397.18615) (xy 161.700464 -397.028924) (xy 161.701004 -397.018821)
			(xy 161.708727 -397.00015) (xy 161.723007 -396.985856) (xy 161.74167 -396.978114) (xy 161.751772 -396.977616)
			(xy 162.468052 -396.977616) (xy 162.478173 -396.978056) (xy 162.496879 -396.985791) (xy 162.511195 -397.000101)
			(xy 162.51894 -397.018803) (xy 162.51936 -397.028924) (xy 162.51936 -397.18615) (xy 162.519803 -397.195333)
			(xy 162.526295 -397.212518) (xy 162.53206 -397.219678) (xy 162.553935 -397.245334) (xy 162.592026 -397.300969)
			(xy 162.623179 -397.360766) (xy 162.646944 -397.423864) (xy 162.66298 -397.489355) (xy 162.671056 -397.556295)
			(xy 162.671055 -397.62372) (xy 162.662977 -397.69066) (xy 162.64694 -397.75615) (xy 162.623173 -397.819247)
			(xy 162.620757 -397.823885) (xy 163.748903 -397.823885) (xy 163.748907 -397.756458) (xy 163.756987 -397.689517)
			(xy 163.773027 -397.624026) (xy 163.796796 -397.560927) (xy 163.827951 -397.50113) (xy 163.866045 -397.445495)
			(xy 163.887912 -397.41983) (xy 163.893722 -397.412694) (xy 163.900228 -397.395497) (xy 163.900612 -397.386302)
			(xy 163.900612 -396.89405) (xy 163.900175 -396.884866) (xy 163.89368 -396.867681) (xy 163.887912 -396.860522)
			(xy 163.866038 -396.834865) (xy 163.827949 -396.77923) (xy 163.796798 -396.719432) (xy 163.773034 -396.656334)
			(xy 163.756998 -396.590844) (xy 163.748923 -396.523905) (xy 163.748924 -396.45648) (xy 163.757001 -396.389541)
			(xy 163.773038 -396.324051) (xy 163.796804 -396.260954) (xy 163.827956 -396.201157) (xy 163.866047 -396.145523)
			(xy 163.887912 -396.119858) (xy 163.89371 -396.112714) (xy 163.900224 -396.095523) (xy 163.900612 -396.08633)
			(xy 163.900612 -395.92885) (xy 163.901167 -395.91873) (xy 163.908873 -395.900015) (xy 163.923138 -395.885658)
			(xy 163.941803 -395.877832) (xy 163.95192 -395.877288) (xy 164.6682 -395.877288) (xy 164.678353 -395.877721)
			(xy 164.697103 -395.885515) (xy 164.711426 -395.899908) (xy 164.719127 -395.918695) (xy 164.719508 -395.92885)
			(xy 164.719508 -396.08633) (xy 164.719902 -396.095519) (xy 164.726426 -396.112703) (xy 164.732208 -396.119858)
			(xy 164.754062 -396.145531) (xy 164.79215 -396.201165) (xy 164.823301 -396.26096) (xy 164.847065 -396.324056)
			(xy 164.863101 -396.389544) (xy 164.871178 -396.456481) (xy 164.871179 -396.523904) (xy 164.863104 -396.590841)
			(xy 164.84707 -396.65633) (xy 164.823307 -396.719426) (xy 164.792158 -396.779222) (xy 164.754071 -396.834857)
			(xy 164.732208 -396.860522) (xy 164.726421 -396.867674) (xy 164.7199 -396.884859) (xy 164.719508 -396.89405)
			(xy 164.719508 -397.386302) (xy 164.719915 -397.395489) (xy 164.726431 -397.412674) (xy 164.732208 -397.41983)
			(xy 164.754034 -397.445526) (xy 164.792124 -397.501156) (xy 164.823276 -397.560948) (xy 164.846898 -397.62366)
			(xy 165.949096 -397.62366) (xy 165.949096 -397.556355) (xy 165.957139 -397.489533) (xy 165.973111 -397.424151)
			(xy 165.996783 -397.361147) (xy 166.027816 -397.301424) (xy 166.065765 -397.245838) (xy 166.087552 -397.220186)
			(xy 166.093343 -397.213037) (xy 166.09986 -397.195849) (xy 166.100252 -397.186658) (xy 166.100252 -397.028924)
			(xy 166.10074 -397.018777) (xy 166.108519 -397.000035) (xy 166.122895 -396.985712) (xy 166.141666 -396.978003)
			(xy 166.151814 -396.977616) (xy 166.868094 -396.977616) (xy 166.878217 -396.978131) (xy 166.896934 -396.985852)
			(xy 166.911289 -397.000129) (xy 166.919113 -397.018803) (xy 166.919656 -397.028924) (xy 166.919656 -397.186658)
			(xy 166.920096 -397.195842) (xy 166.92659 -397.213026) (xy 166.932356 -397.220186) (xy 166.954154 -397.24583)
			(xy 166.992103 -397.301417) (xy 167.023136 -397.361142) (xy 167.046808 -397.424148) (xy 167.062781 -397.489531)
			(xy 167.070824 -397.556355) (xy 167.070823 -397.62366) (xy 167.062778 -397.690484) (xy 167.046804 -397.755867)
			(xy 167.02313 -397.818872) (xy 167.020556 -397.823825) (xy 168.149223 -397.823825) (xy 168.149226 -397.756518)
			(xy 168.157274 -397.689693) (xy 168.17325 -397.624309) (xy 168.196925 -397.561304) (xy 168.22796 -397.501579)
			(xy 168.265911 -397.445991) (xy 168.2877 -397.420338) (xy 168.293505 -397.413199) (xy 168.300015 -397.396004)
			(xy 168.3004 -397.38681) (xy 168.3004 -396.893542) (xy 168.29997 -396.884357) (xy 168.29347 -396.867172)
			(xy 168.2877 -396.860014) (xy 168.265904 -396.834369) (xy 168.227958 -396.778781) (xy 168.196927 -396.719056)
			(xy 168.173256 -396.656051) (xy 168.157285 -396.590668) (xy 168.149243 -396.523845) (xy 168.149244 -396.45654)
			(xy 168.157288 -396.389717) (xy 168.173261 -396.324335) (xy 168.196933 -396.26133) (xy 168.227965 -396.201606)
			(xy 168.265913 -396.146019) (xy 168.2877 -396.120366) (xy 168.293494 -396.113219) (xy 168.30001 -396.09603)
			(xy 168.3004 -396.086838) (xy 168.3004 -395.92885) (xy 168.300904 -395.918686) (xy 168.308665 -395.8999)
			(xy 168.323026 -395.885515) (xy 168.341799 -395.877721) (xy 168.351962 -395.877288) (xy 169.068242 -395.877288)
			(xy 169.078423 -395.877631) (xy 169.097228 -395.885439) (xy 169.111613 -395.89985) (xy 169.119388 -395.918669)
			(xy 169.119804 -395.92885) (xy 169.119804 -396.086838) (xy 169.120195 -396.096027) (xy 169.126722 -396.113212)
			(xy 169.132504 -396.120366) (xy 169.154281 -396.146027) (xy 169.192227 -396.201613) (xy 169.223258 -396.261336)
			(xy 169.24693 -396.324339) (xy 169.262902 -396.38972) (xy 169.270946 -396.456541) (xy 169.270947 -396.523844)
			(xy 169.262905 -396.590665) (xy 169.246934 -396.656047) (xy 169.223264 -396.71905) (xy 169.192235 -396.778774)
			(xy 169.15429 -396.834361) (xy 169.132504 -396.860014) (xy 169.126719 -396.867168) (xy 169.120197 -396.884352)
			(xy 169.119804 -396.893542) (xy 169.119804 -397.38681) (xy 169.120209 -397.395998) (xy 169.126726 -397.413182)
			(xy 169.132504 -397.420338) (xy 169.154253 -397.446021) (xy 169.1922 -397.501604) (xy 169.22062 -397.556296)
			(xy 170.348863 -397.556296) (xy 170.356939 -397.489357) (xy 170.372975 -397.423868) (xy 170.39674 -397.360771)
			(xy 170.427892 -397.300976) (xy 170.465983 -397.245342) (xy 170.487848 -397.219678) (xy 170.493642 -397.212531)
			(xy 170.500157 -397.195342) (xy 170.500548 -397.18615) (xy 170.500548 -397.028924) (xy 170.501103 -397.018823)
			(xy 170.508823 -397.000155) (xy 170.523098 -396.985862) (xy 170.541756 -396.978117) (xy 170.551856 -396.977616)
			(xy 171.268136 -396.977616) (xy 171.278249 -396.978056) (xy 171.296931 -396.985808) (xy 171.311225 -397.000119)
			(xy 171.318956 -397.01881) (xy 171.319444 -397.028924) (xy 171.319444 -397.18615) (xy 171.319891 -397.195333)
			(xy 171.326381 -397.212517) (xy 171.332144 -397.219678) (xy 171.35402 -397.245334) (xy 171.392112 -397.300969)
			(xy 171.423265 -397.360766) (xy 171.447031 -397.423864) (xy 171.463068 -397.489355) (xy 171.471144 -397.556295)
			(xy 171.471143 -397.62372) (xy 171.463065 -397.69066) (xy 171.447027 -397.756151) (xy 171.423259 -397.819248)
			(xy 171.420874 -397.823826) (xy 172.54899 -397.823826) (xy 172.548993 -397.756517) (xy 172.557042 -397.689691)
			(xy 172.57302 -397.624306) (xy 172.5967 -397.5613) (xy 172.62774 -397.501575) (xy 172.665697 -397.44599)
			(xy 172.687488 -397.420338) (xy 172.693292 -397.413198) (xy 172.699803 -397.396004) (xy 172.700188 -397.38681)
			(xy 172.700188 -396.893542) (xy 172.69976 -396.884357) (xy 172.693259 -396.867172) (xy 172.687488 -396.860014)
			(xy 172.665689 -396.834371) (xy 172.627737 -396.778784) (xy 172.596702 -396.71906) (xy 172.573027 -396.656054)
			(xy 172.557054 -396.59067) (xy 172.54901 -396.523846) (xy 172.54901 -396.456539) (xy 172.557056 -396.389715)
			(xy 172.573032 -396.324332) (xy 172.596708 -396.261327) (xy 172.627745 -396.201603) (xy 172.665698 -396.146018)
			(xy 172.687488 -396.120366) (xy 172.69328 -396.113218) (xy 172.699798 -396.09603) (xy 172.700188 -396.086838)
			(xy 172.700188 -395.92885) (xy 172.700606 -395.918675) (xy 172.708384 -395.899872) (xy 172.722772 -395.885484)
			(xy 172.741575 -395.877706) (xy 172.75175 -395.877288) (xy 173.46803 -395.877288) (xy 173.47821 -395.87764)
			(xy 173.497015 -395.885445) (xy 173.5114 -395.899852) (xy 173.519175 -395.91867) (xy 173.519592 -395.92885)
			(xy 173.519592 -396.086838) (xy 173.519986 -396.096027) (xy 173.526511 -396.113211) (xy 173.532292 -396.120366)
			(xy 173.554069 -396.146027) (xy 173.592016 -396.201613) (xy 173.623048 -396.261335) (xy 173.64672 -396.324339)
			(xy 173.662693 -396.389719) (xy 173.670737 -396.456541) (xy 173.670738 -396.523844) (xy 173.662695 -396.590666)
			(xy 173.646725 -396.656047) (xy 173.623054 -396.719051) (xy 173.592024 -396.778774) (xy 173.554078 -396.834361)
			(xy 173.532292 -396.860014) (xy 173.526506 -396.867167) (xy 173.519985 -396.884351) (xy 173.519592 -396.893542)
			(xy 173.519592 -397.38681) (xy 173.519999 -397.395998) (xy 173.526515 -397.413182) (xy 173.532292 -397.420338)
			(xy 173.554041 -397.446021) (xy 173.591989 -397.501604) (xy 173.620441 -397.556355) (xy 174.749183 -397.556355)
			(xy 174.757226 -397.489534) (xy 174.773198 -397.424152) (xy 174.796869 -397.361148) (xy 174.827901 -397.301424)
			(xy 174.865849 -397.245838) (xy 174.887636 -397.220186) (xy 174.893426 -397.213036) (xy 174.899944 -397.195849)
			(xy 174.900336 -397.186658) (xy 174.900336 -397.028924) (xy 174.900742 -397.018767) (xy 174.908536 -397.000008)
			(xy 174.922939 -396.985682) (xy 174.941739 -396.977988) (xy 174.951898 -396.977616) (xy 175.668178 -396.977616)
			(xy 175.6783 -396.978144) (xy 175.697017 -396.98586) (xy 175.711373 -397.000133) (xy 175.719197 -397.018805)
			(xy 175.71974 -397.028924) (xy 175.71974 -397.186658) (xy 175.720184 -397.195841) (xy 175.726675 -397.213025)
			(xy 175.73244 -397.220186) (xy 175.754238 -397.24583) (xy 175.792188 -397.301417) (xy 175.823222 -397.361142)
			(xy 175.846895 -397.424147) (xy 175.862868 -397.489531) (xy 175.870912 -397.556354) (xy 175.870911 -397.623661)
			(xy 175.862865 -397.690484) (xy 175.846891 -397.755867) (xy 175.823216 -397.818872) (xy 175.79218 -397.878596)
			(xy 175.754229 -397.934182) (xy 175.73244 -397.959834) (xy 175.726639 -397.966976) (xy 175.720129 -397.984169)
			(xy 175.71974 -397.993362) (xy 175.71974 -398.486884) (xy 175.720171 -398.496069) (xy 175.726672 -398.513253)
			(xy 175.73244 -398.520412) (xy 175.754264 -398.546035) (xy 175.792213 -398.601625) (xy 175.823246 -398.661352)
			(xy 175.846918 -398.724361) (xy 175.862889 -398.789747) (xy 175.87093 -398.856573) (xy 175.870927 -398.923881)
			(xy 175.862879 -398.990707) (xy 175.846902 -399.056091) (xy 175.823224 -399.119097) (xy 175.792185 -399.178822)
			(xy 175.754231 -399.234408) (xy 175.73244 -399.26006) (xy 175.726628 -399.267194) (xy 175.720124 -399.284393)
			(xy 175.71974 -399.293588) (xy 175.71974 -399.451576) (xy 175.71926 -399.461724) (xy 175.71148 -399.480468)
			(xy 175.697101 -399.494791) (xy 175.678327 -399.502498) (xy 175.668178 -399.502884) (xy 174.951898 -399.502884)
			(xy 174.941774 -399.502376) (xy 174.923058 -399.494652) (xy 174.908702 -399.480372) (xy 174.900879 -399.461697)
			(xy 174.900336 -399.451576) (xy 174.900336 -399.293588) (xy 174.899924 -399.284401) (xy 174.893411 -399.267217)
			(xy 174.887636 -399.26006) (xy 174.865884 -399.234379) (xy 174.827934 -399.178796) (xy 174.7969 -399.119077)
			(xy 174.773225 -399.056076) (xy 174.75725 -398.990697) (xy 174.749203 -398.923878) (xy 174.749199 -398.856576)
			(xy 174.75724 -398.789756) (xy 174.773209 -398.724376) (xy 174.796878 -398.661373) (xy 174.827906 -398.60165)
			(xy 174.865851 -398.546064) (xy 174.887636 -398.520412) (xy 174.893457 -398.513284) (xy 174.899956 -398.49608)
			(xy 174.900336 -398.486884) (xy 174.900336 -397.993362) (xy 174.899936 -397.984174) (xy 174.893414 -397.96699)
			(xy 174.887636 -397.959834) (xy 174.865858 -397.934174) (xy 174.827909 -397.878588) (xy 174.796876 -397.818866)
			(xy 174.773202 -397.755863) (xy 174.757229 -397.690481) (xy 174.749184 -397.62366) (xy 174.749183 -397.556355)
			(xy 173.620441 -397.556355) (xy 173.623023 -397.561324) (xy 173.646696 -397.624324) (xy 173.662671 -397.689702)
			(xy 173.670718 -397.756521) (xy 173.670721 -397.823822) (xy 173.662681 -397.890642) (xy 173.646713 -397.956021)
			(xy 173.623046 -398.019024) (xy 173.592019 -398.078747) (xy 173.554077 -398.134334) (xy 173.532292 -398.159986)
			(xy 173.526475 -398.167117) (xy 173.519973 -398.184318) (xy 173.519592 -398.193514) (xy 173.519592 -398.351502)
			(xy 173.519069 -398.361656) (xy 173.511299 -398.38042) (xy 173.496943 -398.394784) (xy 173.478184 -398.402563)
			(xy 173.46803 -398.403064) (xy 172.75175 -398.403064) (xy 172.741582 -398.402595) (xy 172.722789 -398.394827)
			(xy 172.708402 -398.380455) (xy 172.700615 -398.36167) (xy 172.700188 -398.351502) (xy 172.700188 -398.193514)
			(xy 172.699774 -398.184327) (xy 172.693263 -398.167143) (xy 172.687488 -398.159986) (xy 172.665661 -398.134365)
			(xy 172.627711 -398.078775) (xy 172.596676 -398.019048) (xy 172.573004 -397.956039) (xy 172.557032 -397.890653)
			(xy 172.54899 -397.823826) (xy 171.420874 -397.823826) (xy 171.392104 -397.879044) (xy 171.354011 -397.934678)
			(xy 171.332144 -397.960342) (xy 171.32634 -397.967482) (xy 171.319831 -397.984677) (xy 171.319444 -397.99387)
			(xy 171.319444 -398.486376) (xy 171.319878 -398.49556) (xy 171.326376 -398.512744) (xy 171.332144 -398.519904)
			(xy 171.354045 -398.545539) (xy 171.392137 -398.601177) (xy 171.423289 -398.660976) (xy 171.447054 -398.724077)
			(xy 171.463088 -398.789571) (xy 171.471162 -398.856513) (xy 171.471159 -398.923941) (xy 171.463078 -398.990883)
			(xy 171.447037 -399.056374) (xy 171.423267 -399.119473) (xy 171.392109 -399.17927) (xy 171.354012 -399.234904)
			(xy 171.332144 -399.260568) (xy 171.326329 -399.2677) (xy 171.319827 -399.284901) (xy 171.319444 -399.294096)
			(xy 171.319444 -399.451576) (xy 171.318896 -399.461678) (xy 171.311175 -399.480347) (xy 171.296897 -399.494641)
			(xy 171.278237 -399.502385) (xy 171.268136 -399.502884) (xy 170.551856 -399.502884) (xy 170.541742 -399.50245)
			(xy 170.52306 -399.494695) (xy 170.508766 -399.480383) (xy 170.501036 -399.46169) (xy 170.500548 -399.451576)
			(xy 170.500548 -399.294096) (xy 170.500129 -399.28491) (xy 170.49362 -399.267726) (xy 170.487848 -399.260568)
			(xy 170.466018 -399.234874) (xy 170.427925 -399.179245) (xy 170.39677 -399.119453) (xy 170.373001 -399.05636)
			(xy 170.356962 -398.990874) (xy 170.348883 -398.923938) (xy 170.348879 -398.856516) (xy 170.356952 -398.789579)
			(xy 170.372985 -398.724092) (xy 170.396748 -398.660996) (xy 170.427897 -398.601201) (xy 170.465984 -398.545568)
			(xy 170.487848 -398.519904) (xy 170.493631 -398.51275) (xy 170.500153 -398.495566) (xy 170.500548 -398.486376)
			(xy 170.500548 -397.99387) (xy 170.500141 -397.984683) (xy 170.493624 -397.967499) (xy 170.487848 -397.960342)
			(xy 170.465992 -397.934669) (xy 170.4279 -397.879037) (xy 170.396746 -397.819242) (xy 170.372979 -397.756146)
			(xy 170.356942 -397.690658) (xy 170.348864 -397.623719) (xy 170.348863 -397.556296) (xy 169.22062 -397.556296)
			(xy 169.223233 -397.561324) (xy 169.246906 -397.624324) (xy 169.26288 -397.689702) (xy 169.270927 -397.756521)
			(xy 169.27093 -397.823822) (xy 169.26289 -397.890641) (xy 169.246923 -397.956021) (xy 169.223256 -398.019024)
			(xy 169.19223 -398.078746) (xy 169.154288 -398.134333) (xy 169.132504 -398.159986) (xy 169.126689 -398.167118)
			(xy 169.120185 -398.184319) (xy 169.119804 -398.193514) (xy 169.119804 -398.351502) (xy 169.119269 -398.361655)
			(xy 169.111502 -398.380416) (xy 169.097149 -398.394779) (xy 169.078394 -398.402561) (xy 169.068242 -398.403064)
			(xy 168.351962 -398.403064) (xy 168.341802 -398.402598) (xy 168.323032 -398.394811) (xy 168.308669 -398.380437)
			(xy 168.300895 -398.361662) (xy 168.3004 -398.351502) (xy 168.3004 -398.193514) (xy 168.299983 -398.184328)
			(xy 168.293474 -398.167143) (xy 168.2877 -398.159986) (xy 168.265876 -398.134364) (xy 168.227931 -398.078772)
			(xy 168.196902 -398.019044) (xy 168.173233 -397.956036) (xy 168.157263 -397.89065) (xy 168.149223 -397.823825)
			(xy 167.020556 -397.823825) (xy 166.992095 -397.878596) (xy 166.954145 -397.934182) (xy 166.932356 -397.959834)
			(xy 166.926557 -397.966977) (xy 166.920045 -397.984169) (xy 166.919656 -397.993362) (xy 166.919656 -398.486884)
			(xy 166.920084 -398.496069) (xy 166.926586 -398.513253) (xy 166.932356 -398.520412) (xy 166.954179 -398.546035)
			(xy 166.992127 -398.601625) (xy 167.023159 -398.661353) (xy 167.04683 -398.724361) (xy 167.062801 -398.789747)
			(xy 167.070842 -398.856573) (xy 167.070839 -398.923881) (xy 167.062791 -398.990706) (xy 167.046814 -399.05609)
			(xy 167.023137 -399.119097) (xy 166.9921 -399.178821) (xy 166.954146 -399.234408) (xy 166.932356 -399.26006)
			(xy 166.926546 -399.267195) (xy 166.92004 -399.284394) (xy 166.919656 -399.293588) (xy 166.919656 -399.451576)
			(xy 166.91916 -399.461722) (xy 166.911383 -399.480463) (xy 166.89701 -399.494785) (xy 166.878241 -399.502496)
			(xy 166.868094 -399.502884) (xy 166.151814 -399.502884) (xy 166.141691 -399.502363) (xy 166.122975 -399.494644)
			(xy 166.108619 -399.480369) (xy 166.100795 -399.461696) (xy 166.100252 -399.451576) (xy 166.100252 -399.293588)
			(xy 166.099836 -399.284402) (xy 166.093325 -399.267218) (xy 166.087552 -399.26006) (xy 166.065799 -399.234379)
			(xy 166.027849 -399.178797) (xy 165.996813 -399.119077) (xy 165.973138 -399.056077) (xy 165.957162 -398.990698)
			(xy 165.949115 -398.923878) (xy 165.949111 -398.856576) (xy 165.957152 -398.789755) (xy 165.973122 -398.724375)
			(xy 165.996791 -398.661372) (xy 166.027821 -398.60165) (xy 166.065766 -398.546064) (xy 166.087552 -398.520412)
			(xy 166.093375 -398.513286) (xy 166.099872 -398.49608) (xy 166.100252 -398.486884) (xy 166.100252 -397.993362)
			(xy 166.099848 -397.984174) (xy 166.093329 -397.966991) (xy 166.087552 -397.959834) (xy 166.065774 -397.934174)
			(xy 166.027824 -397.878589) (xy 165.99679 -397.818866) (xy 165.973116 -397.755863) (xy 165.957142 -397.690482)
			(xy 165.949096 -397.62366) (xy 164.846898 -397.62366) (xy 164.847042 -397.624041) (xy 164.863079 -397.689526)
			(xy 164.871158 -397.756461) (xy 164.871162 -397.823882) (xy 164.86309 -397.890817) (xy 164.847058 -397.956304)
			(xy 164.823299 -398.019399) (xy 164.792153 -398.079195) (xy 164.754069 -398.134829) (xy 164.732208 -398.160494)
			(xy 164.726432 -398.167654) (xy 164.719905 -398.184833) (xy 164.719508 -398.194022) (xy 164.719508 -398.351502)
			(xy 164.718976 -398.361623) (xy 164.711257 -398.380335) (xy 164.696985 -398.394689) (xy 164.678318 -398.402517)
			(xy 164.6682 -398.403064) (xy 163.95192 -398.403064) (xy 163.941763 -398.402661) (xy 163.923004 -398.394866)
			(xy 163.908678 -398.380462) (xy 163.900984 -398.361662) (xy 163.900612 -398.351502) (xy 163.900612 -398.194022)
			(xy 163.900188 -398.184836) (xy 163.893684 -398.167652) (xy 163.887912 -398.160494) (xy 163.86601 -398.13486)
			(xy 163.827922 -398.079221) (xy 163.796772 -398.019421) (xy 163.77301 -397.95632) (xy 163.756976 -397.890827)
			(xy 163.748903 -397.823885) (xy 162.620757 -397.823885) (xy 162.592019 -397.879044) (xy 162.553926 -397.934677)
			(xy 162.53206 -397.960342) (xy 162.526258 -397.967483) (xy 162.519748 -397.984677) (xy 162.51936 -397.99387)
			(xy 162.51936 -398.486376) (xy 162.51979 -398.495561) (xy 162.526291 -398.512745) (xy 162.53206 -398.519904)
			(xy 162.553961 -398.545539) (xy 162.592051 -398.601177) (xy 162.623202 -398.660977) (xy 162.646966 -398.724078)
			(xy 162.663 -398.789571) (xy 162.671074 -398.856513) (xy 162.671071 -398.923941) (xy 162.662991 -398.990882)
			(xy 162.64695 -399.056374) (xy 162.62318 -399.119472) (xy 162.592023 -399.179269) (xy 162.553928 -399.234903)
			(xy 162.53206 -399.260568) (xy 162.526247 -399.267701) (xy 162.519743 -399.284901) (xy 162.51936 -399.294096)
			(xy 162.51936 -399.451576) (xy 162.518964 -399.461702) (xy 162.511216 -399.480413) (xy 162.496893 -399.494729)
			(xy 162.478178 -399.502468) (xy 162.468052 -399.502884) (xy 161.751772 -399.502884) (xy 161.741659 -399.502438)
			(xy 161.722978 -399.494688) (xy 161.708683 -399.480379) (xy 161.700952 -399.461689) (xy 161.700464 -399.451576)
			(xy 161.700464 -399.294096) (xy 161.700041 -399.28491) (xy 161.693535 -399.267727) (xy 161.687764 -399.260568)
			(xy 161.665937 -399.234873) (xy 161.627849 -399.179242) (xy 161.596699 -399.119449) (xy 161.572934 -399.056357)
			(xy 161.556897 -398.990871) (xy 161.548819 -398.923937) (xy 161.548816 -398.856517) (xy 161.556888 -398.789582)
			(xy 161.572918 -398.724095) (xy 161.596677 -398.661) (xy 161.627821 -398.601205) (xy 161.665903 -398.54557)
			(xy 161.687764 -398.519904) (xy 161.693549 -398.512751) (xy 161.700069 -398.495566) (xy 161.700464 -398.486376)
			(xy 161.700464 -397.99387) (xy 161.700054 -397.984683) (xy 161.693538 -397.9675) (xy 161.687764 -397.960342)
			(xy 161.665911 -397.934668) (xy 161.627824 -397.879034) (xy 161.596675 -397.819239) (xy 161.572912 -397.756143)
			(xy 161.556877 -397.690655) (xy 161.548801 -397.623719) (xy 161.5488 -397.556296) (xy 160.420549 -397.556296)
			(xy 160.423161 -397.561321) (xy 160.446838 -397.624321) (xy 160.462815 -397.6897) (xy 160.470863 -397.75652)
			(xy 160.470866 -397.823823) (xy 160.462825 -397.890644) (xy 160.446855 -397.956024) (xy 160.423185 -398.019027)
			(xy 160.392154 -398.078749) (xy 160.354207 -398.134334) (xy 160.33242 -398.159986) (xy 160.326607 -398.16712)
			(xy 160.320101 -398.184319) (xy 160.31972 -398.193514) (xy 160.31972 -398.351502) (xy 160.319337 -398.361679)
			(xy 160.311543 -398.380482) (xy 160.297145 -398.394868) (xy 160.278335 -398.402645) (xy 160.268158 -398.403064)
			(xy 159.551878 -398.403064) (xy 159.541719 -398.402585) (xy 159.52295 -398.394804) (xy 159.508585 -398.380433)
			(xy 159.500811 -398.361661) (xy 159.500316 -398.351502) (xy 159.500316 -398.193514) (xy 159.499895 -398.184328)
			(xy 159.493388 -398.167144) (xy 159.487616 -398.159986) (xy 159.465792 -398.134364) (xy 159.427845 -398.078773)
			(xy 159.396815 -398.019045) (xy 159.373145 -397.956036) (xy 159.357176 -397.890651) (xy 159.349135 -397.823825)
			(xy 154.57678 -397.823825) (xy 154.57678 -401.723737) (xy 159.349146 -401.723737) (xy 159.349148 -401.65643)
			(xy 159.357194 -401.589607) (xy 159.373169 -401.524223) (xy 159.396843 -401.461218) (xy 159.427878 -401.401494)
			(xy 159.465828 -401.345906) (xy 159.487616 -401.320254) (xy 159.493416 -401.313112) (xy 159.499928 -401.295919)
			(xy 159.500316 -401.286726) (xy 159.500316 -400.793458) (xy 159.499923 -400.784269) (xy 159.493397 -400.767085)
			(xy 159.487616 -400.75993) (xy 159.465835 -400.734273) (xy 159.427887 -400.678686) (xy 159.396855 -400.618963)
			(xy 159.373183 -400.55596) (xy 159.35721 -400.490578) (xy 159.349166 -400.423757) (xy 159.349165 -400.356452)
			(xy 159.357209 -400.289631) (xy 159.37318 -400.224249) (xy 159.396851 -400.161245) (xy 159.427883 -400.101521)
			(xy 159.465829 -400.045934) (xy 159.487616 -400.020282) (xy 159.493405 -400.013131) (xy 159.499923 -399.995945)
			(xy 159.500316 -399.986754) (xy 159.500316 -399.828766) (xy 159.500805 -399.818609) (xy 159.508586 -399.799843)
			(xy 159.522953 -399.78548) (xy 159.541721 -399.777703) (xy 159.551878 -399.777204) (xy 160.268158 -399.777204)
			(xy 160.278323 -399.777697) (xy 160.29711 -399.785462) (xy 160.311495 -399.799826) (xy 160.319288 -399.818602)
			(xy 160.31972 -399.828766) (xy 160.31972 -399.986754) (xy 160.320148 -399.995939) (xy 160.326649 -400.013124)
			(xy 160.33242 -400.020282) (xy 160.354215 -400.045929) (xy 160.392166 -400.101515) (xy 160.423201 -400.161239)
			(xy 160.446876 -400.224244) (xy 160.462849 -400.289628) (xy 160.470894 -400.356451) (xy 160.470893 -400.423758)
			(xy 160.462848 -400.490581) (xy 160.446873 -400.555964) (xy 160.423198 -400.618969) (xy 160.392161 -400.678693)
			(xy 160.354209 -400.734278) (xy 160.33242 -400.75993) (xy 160.326631 -400.76708) (xy 160.320111 -400.784267)
			(xy 160.31972 -400.793458) (xy 160.31972 -401.286726) (xy 160.320113 -401.295915) (xy 160.326638 -401.313099)
			(xy 160.33242 -401.320254) (xy 160.354187 -401.345923) (xy 160.392139 -401.401506) (xy 160.423176 -401.461227)
			(xy 160.446852 -401.52423) (xy 160.462827 -401.58961) (xy 160.470874 -401.656431) (xy 160.470876 -401.723735)
			(xy 160.462833 -401.790557) (xy 160.446862 -401.855939) (xy 160.423189 -401.918943) (xy 160.392156 -401.978665)
			(xy 160.354208 -402.03425) (xy 160.33242 -402.059902) (xy 160.326642 -402.067061) (xy 160.320116 -402.084241)
			(xy 160.31972 -402.09343) (xy 160.31972 -402.251418) (xy 160.31935 -402.261596) (xy 160.311551 -402.280399)
			(xy 160.297149 -402.294785) (xy 160.278336 -402.302562) (xy 160.268158 -402.30298) (xy 159.551878 -402.30298)
			(xy 159.541721 -402.302485) (xy 159.522955 -402.294707) (xy 159.508591 -402.280342) (xy 159.500814 -402.261575)
			(xy 159.500316 -402.251418) (xy 159.500316 -402.09343) (xy 159.499888 -402.084245) (xy 159.493386 -402.06706)
			(xy 159.487616 -402.059902) (xy 159.465807 -402.034267) (xy 159.427861 -401.978678) (xy 159.39683 -401.918952)
			(xy 159.373159 -401.855945) (xy 159.357188 -401.790561) (xy 159.349146 -401.723737) (xy 154.57678 -401.723737)
			(xy 154.57678 -402.823877) (xy 161.54876 -402.823877) (xy 161.548765 -402.756451) (xy 161.556845 -402.68951)
			(xy 161.572884 -402.624018) (xy 161.596652 -402.56092) (xy 161.627806 -402.501122) (xy 161.665898 -402.445486)
			(xy 161.687764 -402.41982) (xy 161.693585 -402.412692) (xy 161.700083 -402.395488) (xy 161.700464 -402.386292)
			(xy 161.700464 -401.89404) (xy 161.70002 -401.884857) (xy 161.693528 -401.867673) (xy 161.687764 -401.860512)
			(xy 161.665882 -401.834862) (xy 161.627796 -401.779225) (xy 161.596648 -401.719426) (xy 161.572887 -401.656327)
			(xy 161.556854 -401.590837) (xy 161.54878 -401.523897) (xy 161.548782 -401.456473) (xy 161.556859 -401.389534)
			(xy 161.572896 -401.324044) (xy 161.59666 -401.260946) (xy 161.627811 -401.201149) (xy 161.6659 -401.145514)
			(xy 161.687764 -401.119848) (xy 161.693573 -401.112712) (xy 161.700078 -401.095514) (xy 161.700464 -401.08632)
			(xy 161.700464 -400.92884) (xy 161.700948 -400.918725) (xy 161.708676 -400.900029) (xy 161.722972 -400.885714)
			(xy 161.741657 -400.877961) (xy 161.751772 -400.877532) (xy 162.468052 -400.877532) (xy 162.478175 -400.877956)
			(xy 162.496884 -400.885694) (xy 162.511201 -400.900009) (xy 162.518942 -400.918717) (xy 162.51936 -400.92884)
			(xy 162.51936 -401.08632) (xy 162.519769 -401.095507) (xy 162.526285 -401.112691) (xy 162.53206 -401.119848)
			(xy 162.553906 -401.145529) (xy 162.591998 -401.20116) (xy 162.623151 -401.260954) (xy 162.646919 -401.324049)
			(xy 162.662957 -401.389536) (xy 162.671035 -401.456474) (xy 162.671037 -401.523896) (xy 162.662962 -401.590834)
			(xy 162.646927 -401.656323) (xy 162.623164 -401.719419) (xy 162.620884 -401.723796) (xy 163.748915 -401.723796)
			(xy 163.748917 -401.656371) (xy 163.756995 -401.589431) (xy 163.773033 -401.52394) (xy 163.7968 -401.460842)
			(xy 163.827954 -401.401046) (xy 163.866046 -401.345411) (xy 163.887912 -401.319746) (xy 163.893715 -401.312606)
			(xy 163.900226 -401.295411) (xy 163.900612 -401.286218) (xy 163.900612 -400.793966) (xy 163.900216 -400.784777)
			(xy 163.893692 -400.767593) (xy 163.887912 -400.760438) (xy 163.866054 -400.734768) (xy 163.827964 -400.679135)
			(xy 163.796812 -400.619339) (xy 163.773047 -400.556243) (xy 163.757011 -400.490754) (xy 163.748934 -400.423816)
			(xy 163.748934 -400.356393) (xy 163.757009 -400.289455) (xy 163.773044 -400.223966) (xy 163.796809 -400.160869)
			(xy 163.827959 -400.101073) (xy 163.866048 -400.045439) (xy 163.887912 -400.019774) (xy 163.893703 -400.012625)
			(xy 163.900221 -399.995437) (xy 163.900612 -399.986246) (xy 163.900612 -399.828766) (xy 163.901098 -399.818641)
			(xy 163.908832 -399.799924) (xy 163.923117 -399.78557) (xy 163.941797 -399.777747) (xy 163.95192 -399.777204)
			(xy 164.6682 -399.777204) (xy 164.678355 -399.777622) (xy 164.697108 -399.785418) (xy 164.711431 -399.799816)
			(xy 164.71913 -399.818609) (xy 164.719508 -399.828766) (xy 164.719508 -399.986246) (xy 164.719942 -399.995431)
			(xy 164.726439 -400.012615) (xy 164.732208 -400.019774) (xy 164.754078 -400.045435) (xy 164.792166 -400.10107)
			(xy 164.823316 -400.160867) (xy 164.847079 -400.223964) (xy 164.863114 -400.289454) (xy 164.871189 -400.356393)
			(xy 164.871189 -400.423817) (xy 164.863112 -400.490755) (xy 164.847076 -400.556244) (xy 164.823312 -400.619341)
			(xy 164.792161 -400.679138) (xy 164.754072 -400.734773) (xy 164.732208 -400.760438) (xy 164.726414 -400.767585)
			(xy 164.719897 -400.784774) (xy 164.719508 -400.793966) (xy 164.719508 -401.286218) (xy 164.719908 -401.295406)
			(xy 164.726429 -401.312591) (xy 164.732208 -401.319746) (xy 164.75405 -401.345429) (xy 164.792139 -401.401061)
			(xy 164.82329 -401.460855) (xy 164.847055 -401.52395) (xy 164.863092 -401.589436) (xy 164.871169 -401.656373)
			(xy 164.871171 -401.723794) (xy 164.863098 -401.790731) (xy 164.847065 -401.856219) (xy 164.823304 -401.919315)
			(xy 164.792156 -401.97911) (xy 164.75407 -402.034745) (xy 164.732208 -402.06041) (xy 164.726426 -402.067565)
			(xy 164.719902 -402.084748) (xy 164.719508 -402.093938) (xy 164.719508 -402.251418) (xy 164.71899 -402.26154)
			(xy 164.711265 -402.280253) (xy 164.696989 -402.294607) (xy 164.678319 -402.302434) (xy 164.6682 -402.30298)
			(xy 163.95192 -402.30298) (xy 163.941765 -402.302562) (xy 163.923009 -402.294769) (xy 163.908684 -402.280371)
			(xy 163.900987 -402.261575) (xy 163.900612 -402.251418) (xy 163.900612 -402.093938) (xy 163.900181 -402.084753)
			(xy 163.893681 -402.067569) (xy 163.887912 -402.06041) (xy 163.866026 -402.034763) (xy 163.827937 -401.979126)
			(xy 163.796787 -401.919327) (xy 163.773023 -401.856228) (xy 163.756989 -401.790737) (xy 163.748915 -401.723796)
			(xy 162.620884 -401.723796) (xy 162.592013 -401.779214) (xy 162.553924 -401.834847) (xy 162.53206 -401.860512)
			(xy 162.526271 -401.867662) (xy 162.519753 -401.884849) (xy 162.51936 -401.89404) (xy 162.51936 -402.386292)
			(xy 162.519783 -402.395478) (xy 162.526289 -402.412662) (xy 162.53206 -402.41982) (xy 162.553878 -402.445523)
			(xy 162.591971 -402.501152) (xy 162.623126 -402.560942) (xy 162.646895 -402.624034) (xy 162.662935 -402.689519)
			(xy 162.671015 -402.756454) (xy 162.671019 -402.823818) (xy 165.949055 -402.823818) (xy 165.94906 -402.756509)
			(xy 165.957109 -402.689683) (xy 165.973087 -402.624298) (xy 165.996766 -402.561292) (xy 166.027805 -402.501567)
			(xy 166.065761 -402.44598) (xy 166.087552 -402.420328) (xy 166.093368 -402.413197) (xy 166.09987 -402.395995)
			(xy 166.100252 -402.3868) (xy 166.100252 -401.893532) (xy 166.099815 -401.884348) (xy 166.093319 -401.867164)
			(xy 166.087552 -401.860004) (xy 166.065744 -401.834368) (xy 166.027795 -401.77878) (xy 165.996762 -401.719054)
			(xy 165.97309 -401.656047) (xy 165.957118 -401.590663) (xy 165.949075 -401.523838) (xy 165.949077 -401.456532)
			(xy 165.957123 -401.389707) (xy 165.973098 -401.324324) (xy 165.996774 -401.261318) (xy 166.02781 -401.201594)
			(xy 166.065762 -401.146008) (xy 166.087552 -401.120356) (xy 166.093356 -401.113216) (xy 166.099865 -401.096021)
			(xy 166.100252 -401.086828) (xy 166.100252 -400.92884) (xy 166.100754 -400.918694) (xy 166.108527 -400.899952)
			(xy 166.122899 -400.885629) (xy 166.141667 -400.87792) (xy 166.151814 -400.877532) (xy 166.868094 -400.877532)
			(xy 166.878219 -400.878031) (xy 166.896939 -400.885756) (xy 166.911295 -400.900038) (xy 166.919116 -400.918717)
			(xy 166.919656 -400.92884) (xy 166.919656 -401.086828) (xy 166.920063 -401.096015) (xy 166.92658 -401.113199)
			(xy 166.932356 -401.120356) (xy 166.954124 -401.146024) (xy 166.992074 -401.201608) (xy 167.023108 -401.26133)
			(xy 167.046782 -401.324332) (xy 167.062757 -401.389712) (xy 167.070803 -401.456533) (xy 167.070804 -401.523837)
			(xy 167.062762 -401.590658) (xy 167.046791 -401.656039) (xy 167.02312 -401.719043) (xy 167.020682 -401.723736)
			(xy 168.149234 -401.723736) (xy 168.149236 -401.65643) (xy 168.157282 -401.589607) (xy 168.173256 -401.524224)
			(xy 168.19693 -401.461219) (xy 168.227963 -401.401494) (xy 168.265912 -401.345907) (xy 168.2877 -401.320254)
			(xy 168.293499 -401.31311) (xy 168.300012 -401.295919) (xy 168.3004 -401.286726) (xy 168.3004 -400.793458)
			(xy 168.30001 -400.784269) (xy 168.293482 -400.767084) (xy 168.2877 -400.75993) (xy 168.265919 -400.734272)
			(xy 168.227973 -400.678686) (xy 168.196942 -400.618963) (xy 168.17327 -400.555959) (xy 168.157298 -400.490578)
			(xy 168.149254 -400.423756) (xy 168.149253 -400.356453) (xy 168.157296 -400.289631) (xy 168.173267 -400.22425)
			(xy 168.196938 -400.161246) (xy 168.227968 -400.101522) (xy 168.265914 -400.045935) (xy 168.2877 -400.020282)
			(xy 168.293487 -400.01313) (xy 168.300007 -399.995945) (xy 168.3004 -399.986754) (xy 168.3004 -399.828766)
			(xy 168.300905 -399.818611) (xy 168.308683 -399.799848) (xy 168.323045 -399.785485) (xy 168.341807 -399.777705)
			(xy 168.351962 -399.777204) (xy 169.068242 -399.777204) (xy 169.078398 -399.777698) (xy 169.097162 -399.78548)
			(xy 169.111524 -399.799845) (xy 169.119303 -399.81861) (xy 169.119804 -399.828766) (xy 169.119804 -399.986754)
			(xy 169.120235 -399.995939) (xy 169.126734 -400.013124) (xy 169.132504 -400.020282) (xy 169.154296 -400.04593)
			(xy 169.192242 -400.101518) (xy 169.223273 -400.161243) (xy 169.246943 -400.224248) (xy 169.262915 -400.28963)
			(xy 169.270958 -400.356452) (xy 169.270957 -400.423757) (xy 169.262913 -400.490579) (xy 169.246941 -400.555961)
			(xy 169.223269 -400.618966) (xy 169.192237 -400.67869) (xy 169.154291 -400.734277) (xy 169.132504 -400.75993)
			(xy 169.126713 -400.767079) (xy 169.120195 -400.784267) (xy 169.119804 -400.793458) (xy 169.119804 -401.286726)
			(xy 169.1202 -401.295915) (xy 169.126723 -401.313099) (xy 169.132504 -401.320254) (xy 169.154269 -401.345925)
			(xy 169.192215 -401.401509) (xy 169.223247 -401.461231) (xy 169.246919 -401.524233) (xy 169.262893 -401.589612)
			(xy 169.270938 -401.656432) (xy 169.27094 -401.723735) (xy 169.262899 -401.790555) (xy 169.246929 -401.855936)
			(xy 169.223261 -401.918939) (xy 169.192232 -401.978662) (xy 169.154289 -402.034249) (xy 169.132504 -402.059902)
			(xy 169.126725 -402.067059) (xy 169.1202 -402.084241) (xy 169.119804 -402.09343) (xy 169.119804 -402.251418)
			(xy 169.119283 -402.261572) (xy 169.11151 -402.280333) (xy 169.097154 -402.294697) (xy 169.078396 -402.302478)
			(xy 169.068242 -402.30298) (xy 168.351962 -402.30298) (xy 168.341804 -402.302498) (xy 168.323037 -402.294715)
			(xy 168.308674 -402.280346) (xy 168.300898 -402.261576) (xy 168.3004 -402.251418) (xy 168.3004 -402.09343)
			(xy 168.299975 -402.084244) (xy 168.293472 -402.06706) (xy 168.2877 -402.059902) (xy 168.265892 -402.034267)
			(xy 168.227946 -401.978677) (xy 168.196916 -401.918951) (xy 168.173246 -401.855944) (xy 168.157276 -401.79056)
			(xy 168.149234 -401.723736) (xy 167.020682 -401.723736) (xy 166.992089 -401.778766) (xy 166.954142 -401.834352)
			(xy 166.932356 -401.860004) (xy 166.92657 -401.867156) (xy 166.92005 -401.884342) (xy 166.919656 -401.893532)
			(xy 166.919656 -402.3868) (xy 166.920076 -402.395986) (xy 166.926584 -402.41317) (xy 166.932356 -402.420328)
			(xy 166.954097 -402.446019) (xy 166.992047 -402.5016) (xy 167.023083 -402.561318) (xy 167.046758 -402.624317)
			(xy 167.062735 -402.689695) (xy 167.070783 -402.756513) (xy 167.070787 -402.823815) (xy 167.070779 -402.823878)
			(xy 170.348823 -402.823878) (xy 170.348828 -402.75645) (xy 170.356909 -402.689507) (xy 170.372951 -402.624015)
			(xy 170.396723 -402.560916) (xy 170.427882 -402.501119) (xy 170.465979 -402.445484) (xy 170.487848 -402.41982)
			(xy 170.493667 -402.412691) (xy 170.500167 -402.395488) (xy 170.500548 -402.386292) (xy 170.500548 -401.89404)
			(xy 170.500108 -401.884856) (xy 170.493614 -401.867672) (xy 170.487848 -401.860512) (xy 170.465963 -401.834864)
			(xy 170.427871 -401.779228) (xy 170.396719 -401.71943) (xy 170.372954 -401.656331) (xy 170.356918 -401.590839)
			(xy 170.348843 -401.523898) (xy 170.348845 -401.456472) (xy 170.356924 -401.389531) (xy 170.372963 -401.324041)
			(xy 170.396731 -401.260943) (xy 170.427887 -401.201146) (xy 170.465981 -401.145512) (xy 170.487848 -401.119848)
			(xy 170.493655 -401.112711) (xy 170.500162 -401.095514) (xy 170.500548 -401.08632) (xy 170.500548 -400.92884)
			(xy 170.501117 -400.91874) (xy 170.508832 -400.900073) (xy 170.523102 -400.885779) (xy 170.541757 -400.878033)
			(xy 170.551856 -400.877532) (xy 171.268136 -400.877532) (xy 171.278265 -400.877887) (xy 171.296975 -400.885653)
			(xy 171.311289 -400.899989) (xy 171.319028 -400.918711) (xy 171.319444 -400.92884) (xy 171.319444 -401.08632)
			(xy 171.319857 -401.095507) (xy 171.32637 -401.11269) (xy 171.332144 -401.119848) (xy 171.35399 -401.145528)
			(xy 171.392083 -401.20116) (xy 171.423238 -401.260953) (xy 171.447006 -401.324048) (xy 171.463044 -401.389536)
			(xy 171.471123 -401.456473) (xy 171.471124 -401.523897) (xy 171.46305 -401.590834) (xy 171.447015 -401.656323)
			(xy 171.42325 -401.719419) (xy 171.421001 -401.723737) (xy 172.549001 -401.723737) (xy 172.549003 -401.65643)
			(xy 172.55705 -401.589605) (xy 172.573027 -401.524221) (xy 172.596704 -401.461215) (xy 172.627743 -401.401491)
			(xy 172.665697 -401.345906) (xy 172.687488 -401.320254) (xy 172.693285 -401.313109) (xy 172.6998 -401.295918)
			(xy 172.700188 -401.286726) (xy 172.700188 -400.793458) (xy 172.699801 -400.784268) (xy 172.693272 -400.767084)
			(xy 172.687488 -400.75993) (xy 172.665705 -400.734274) (xy 172.627752 -400.678689) (xy 172.596716 -400.618966)
			(xy 172.573041 -400.555962) (xy 172.557066 -400.49058) (xy 172.549021 -400.423757) (xy 172.54902 -400.356452)
			(xy 172.557065 -400.289629) (xy 172.573038 -400.224246) (xy 172.596713 -400.161242) (xy 172.627748 -400.101519)
			(xy 172.665699 -400.045933) (xy 172.687488 -400.020282) (xy 172.693273 -400.013129) (xy 172.699795 -399.995944)
			(xy 172.700188 -399.986754) (xy 172.700188 -399.828766) (xy 172.700537 -399.818586) (xy 172.708343 -399.799781)
			(xy 172.722752 -399.785395) (xy 172.741569 -399.777621) (xy 172.75175 -399.777204) (xy 173.46803 -399.777204)
			(xy 173.478186 -399.777708) (xy 173.496949 -399.785486) (xy 173.511312 -399.799848) (xy 173.519091 -399.818611)
			(xy 173.519592 -399.828766) (xy 173.519592 -399.986754) (xy 173.520026 -399.995939) (xy 173.526523 -400.013123)
			(xy 173.532292 -400.020282) (xy 173.554085 -400.04593) (xy 173.592031 -400.101518) (xy 173.623063 -400.161242)
			(xy 173.646734 -400.224247) (xy 173.662705 -400.289629) (xy 173.670749 -400.356452) (xy 173.670748 -400.423757)
			(xy 173.662704 -400.490579) (xy 173.646731 -400.555962) (xy 173.623059 -400.618966) (xy 173.592027 -400.67869)
			(xy 173.554079 -400.734277) (xy 173.532292 -400.75993) (xy 173.526499 -400.767078) (xy 173.519983 -400.784266)
			(xy 173.519592 -400.793458) (xy 173.519592 -401.286726) (xy 173.519991 -401.295914) (xy 173.526513 -401.313099)
			(xy 173.532292 -401.320254) (xy 173.554057 -401.345924) (xy 173.592005 -401.401509) (xy 173.623037 -401.46123)
			(xy 173.64671 -401.524232) (xy 173.662683 -401.589612) (xy 173.670729 -401.656432) (xy 173.670731 -401.723735)
			(xy 173.662689 -401.790555) (xy 173.64672 -401.855936) (xy 173.623051 -401.918939) (xy 173.592022 -401.978663)
			(xy 173.554077 -402.034249) (xy 173.532292 -402.059902) (xy 173.526511 -402.067058) (xy 173.519987 -402.08424)
			(xy 173.519592 -402.09343) (xy 173.519592 -402.251418) (xy 173.519082 -402.261573) (xy 173.511308 -402.280337)
			(xy 173.496947 -402.294701) (xy 173.478185 -402.30248) (xy 173.46803 -402.30298) (xy 172.75175 -402.30298)
			(xy 172.741584 -402.302496) (xy 172.722794 -402.29473) (xy 172.708408 -402.280363) (xy 172.700618 -402.261584)
			(xy 172.700188 -402.251418) (xy 172.700188 -402.09343) (xy 172.699766 -402.084244) (xy 172.693261 -402.067059)
			(xy 172.687488 -402.059902) (xy 172.665677 -402.034268) (xy 172.627726 -401.97868) (xy 172.596691 -401.918955)
			(xy 172.573017 -401.855948) (xy 172.557044 -401.790563) (xy 172.549001 -401.723737) (xy 171.421001 -401.723737)
			(xy 171.392099 -401.779215) (xy 171.354009 -401.834848) (xy 171.332144 -401.860512) (xy 171.326353 -401.867661)
			(xy 171.319836 -401.884849) (xy 171.319444 -401.89404) (xy 171.319444 -402.386292) (xy 171.31987 -402.395477)
			(xy 171.326374 -402.412661) (xy 171.332144 -402.41982) (xy 171.353963 -402.445523) (xy 171.392057 -402.501151)
			(xy 171.423213 -402.560941) (xy 171.446982 -402.624033) (xy 171.463022 -402.689518) (xy 171.471103 -402.756453)
			(xy 171.471107 -402.823818) (xy 174.749143 -402.823818) (xy 174.749147 -402.75651) (xy 174.757196 -402.689684)
			(xy 174.773174 -402.624299) (xy 174.796852 -402.561292) (xy 174.827891 -402.501567) (xy 174.865845 -402.44598)
			(xy 174.887636 -402.420328) (xy 174.89345 -402.413195) (xy 174.899953 -402.395995) (xy 174.900336 -402.3868)
			(xy 174.900336 -401.893532) (xy 174.899902 -401.884348) (xy 174.893404 -401.867163) (xy 174.887636 -401.860004)
			(xy 174.865829 -401.834368) (xy 174.827881 -401.778779) (xy 174.796848 -401.719053) (xy 174.773177 -401.656047)
			(xy 174.757205 -401.590663) (xy 174.749163 -401.523838) (xy 174.749165 -401.456532) (xy 174.757211 -401.389708)
			(xy 174.773186 -401.324324) (xy 174.796861 -401.261319) (xy 174.827896 -401.201595) (xy 174.865847 -401.146008)
			(xy 174.887636 -401.120356) (xy 174.893438 -401.113215) (xy 174.899949 -401.096021) (xy 174.900336 -401.086828)
			(xy 174.900336 -400.92884) (xy 174.900755 -400.918684) (xy 174.908544 -400.899926) (xy 174.922943 -400.8856)
			(xy 174.94174 -400.877905) (xy 174.951898 -400.877532) (xy 175.668178 -400.877532) (xy 175.678302 -400.878044)
			(xy 175.697022 -400.885763) (xy 175.711378 -400.900042) (xy 175.7192 -400.918718) (xy 175.71974 -400.92884)
			(xy 175.71974 -401.086828) (xy 175.72015 -401.096015) (xy 175.726665 -401.113198) (xy 175.73244 -401.120356)
			(xy 175.754209 -401.146024) (xy 175.792159 -401.201608) (xy 175.823195 -401.261329) (xy 175.846869 -401.324331)
			(xy 175.862844 -401.389712) (xy 175.870891 -401.456533) (xy 175.870892 -401.523837) (xy 175.86285 -401.590658)
			(xy 175.846878 -401.65604) (xy 175.823207 -401.719044) (xy 175.792175 -401.778766) (xy 175.754227 -401.834352)
			(xy 175.73244 -401.860004) (xy 175.726652 -401.867155) (xy 175.720134 -401.884341) (xy 175.71974 -401.893532)
			(xy 175.71974 -402.3868) (xy 175.720164 -402.395985) (xy 175.726669 -402.413169) (xy 175.73244 -402.420328)
			(xy 175.754181 -402.446019) (xy 175.792133 -402.501599) (xy 175.823169 -402.561317) (xy 175.846846 -402.624317)
			(xy 175.862823 -402.689694) (xy 175.870871 -402.756513) (xy 175.870875 -402.823815) (xy 175.862835 -402.890634)
			(xy 175.846867 -402.956014) (xy 175.823199 -403.019017) (xy 175.79217 -403.078739) (xy 175.754225 -403.134324)
			(xy 175.73244 -403.159976) (xy 175.726621 -403.167105) (xy 175.720122 -403.184308) (xy 175.71974 -403.193504)
			(xy 175.71974 -403.351492) (xy 175.719273 -403.361641) (xy 175.711487 -403.380385) (xy 175.697105 -403.394707)
			(xy 175.678328 -403.402415) (xy 175.668178 -403.4028) (xy 174.951898 -403.4028) (xy 174.941776 -403.402276)
			(xy 174.923063 -403.394555) (xy 174.908708 -403.380281) (xy 174.900882 -403.361611) (xy 174.900336 -403.351492)
			(xy 174.900336 -403.193504) (xy 174.899916 -403.184318) (xy 174.893408 -403.167134) (xy 174.887636 -403.159976)
			(xy 174.865801 -403.134363) (xy 174.827854 -403.078771) (xy 174.796823 -403.019042) (xy 174.773153 -402.956032)
			(xy 174.757183 -402.890645) (xy 174.749143 -402.823818) (xy 171.471107 -402.823818) (xy 171.471107 -402.823874)
			(xy 171.463035 -402.89081) (xy 171.447003 -402.956298) (xy 171.423242 -403.019393) (xy 171.392094 -403.079187)
			(xy 171.354007 -403.13482) (xy 171.332144 -403.160484) (xy 171.326322 -403.167611) (xy 171.319824 -403.184816)
			(xy 171.319444 -403.194012) (xy 171.319444 -403.351492) (xy 171.318909 -403.361595) (xy 171.311183 -403.380264)
			(xy 171.296901 -403.394558) (xy 171.278238 -403.402301) (xy 171.268136 -403.4028) (xy 170.551856 -403.4028)
			(xy 170.541744 -403.402351) (xy 170.523065 -403.394599) (xy 170.508772 -403.380291) (xy 170.501039 -403.361604)
			(xy 170.500548 -403.351492) (xy 170.500548 -403.194012) (xy 170.500121 -403.184827) (xy 170.493618 -403.167643)
			(xy 170.487848 -403.160484) (xy 170.465935 -403.134858) (xy 170.427845 -403.079219) (xy 170.396693 -403.019418)
			(xy 170.37293 -402.956316) (xy 170.356896 -402.890822) (xy 170.348823 -402.823878) (xy 167.070779 -402.823878)
			(xy 167.062748 -402.890634) (xy 167.04678 -402.956014) (xy 167.023112 -403.019016) (xy 166.992084 -403.078738)
			(xy 166.954141 -403.134324) (xy 166.932356 -403.159976) (xy 166.926539 -403.167107) (xy 166.920038 -403.184308)
			(xy 166.919656 -403.193504) (xy 166.919656 -403.351492) (xy 166.919173 -403.361639) (xy 166.911391 -403.38038)
			(xy 166.897014 -403.394702) (xy 166.878242 -403.402412) (xy 166.868094 -403.4028) (xy 166.151814 -403.4028)
			(xy 166.141693 -403.402263) (xy 166.12298 -403.394547) (xy 166.108624 -403.380277) (xy 166.100798 -403.36161)
			(xy 166.100252 -403.351492) (xy 166.100252 -403.193504) (xy 166.099828 -403.184318) (xy 166.093323 -403.167135)
			(xy 166.087552 -403.159976) (xy 166.065717 -403.134363) (xy 166.027768 -403.078771) (xy 165.996736 -403.019042)
			(xy 165.973066 -402.956033) (xy 165.957096 -402.890646) (xy 165.949055 -402.823818) (xy 162.671019 -402.823818)
			(xy 162.671019 -402.823874) (xy 162.662948 -402.89081) (xy 162.646916 -402.956297) (xy 162.623155 -403.019392)
			(xy 162.592008 -403.079187) (xy 162.553923 -403.13482) (xy 162.53206 -403.160484) (xy 162.52624 -403.167613)
			(xy 162.51974 -403.184816) (xy 162.51936 -403.194012) (xy 162.51936 -403.351492) (xy 162.518976 -403.361619)
			(xy 162.511224 -403.38033) (xy 162.496896 -403.394646) (xy 162.478179 -403.402384) (xy 162.468052 -403.4028)
			(xy 161.751772 -403.4028) (xy 161.741661 -403.402338) (xy 161.722983 -403.394591) (xy 161.708689 -403.380287)
			(xy 161.700955 -403.361603) (xy 161.700464 -403.351492) (xy 161.700464 -403.194012) (xy 161.700034 -403.184827)
			(xy 161.693532 -403.167643) (xy 161.687764 -403.160484) (xy 161.665854 -403.134857) (xy 161.627769 -403.079216)
			(xy 161.596623 -403.019414) (xy 161.572863 -402.956313) (xy 161.556832 -402.890819) (xy 161.54876 -402.823877)
			(xy 154.57678 -402.823877) (xy 154.57678 -405.623648) (xy 159.349158 -405.623648) (xy 159.349158 -405.556343)
			(xy 159.357202 -405.48952) (xy 159.373175 -405.424138) (xy 159.396848 -405.361133) (xy 159.427881 -405.301409)
			(xy 159.465829 -405.245822) (xy 159.487616 -405.22017) (xy 159.49341 -405.213023) (xy 159.499926 -405.195834)
			(xy 159.500316 -405.186642) (xy 159.500316 -404.693374) (xy 159.499915 -404.684186) (xy 159.493395 -404.667002)
			(xy 159.487616 -404.659846) (xy 159.465851 -404.634176) (xy 159.427903 -404.578591) (xy 159.39687 -404.51887)
			(xy 159.373197 -404.455868) (xy 159.357223 -404.390488) (xy 159.349177 -404.323668) (xy 159.349175 -404.256365)
			(xy 159.357217 -404.189544) (xy 159.373187 -404.124164) (xy 159.396856 -404.06116) (xy 159.427886 -404.001437)
			(xy 159.46583 -403.94585) (xy 159.487616 -403.920198) (xy 159.493398 -403.913042) (xy 159.499921 -403.89586)
			(xy 159.500316 -403.88667) (xy 159.500316 -403.728682) (xy 159.500818 -403.718526) (xy 159.508594 -403.69976)
			(xy 159.522957 -403.685396) (xy 159.541722 -403.677619) (xy 159.551878 -403.67712) (xy 160.268158 -403.67712)
			(xy 160.278325 -403.677598) (xy 160.297115 -403.685366) (xy 160.311501 -403.699735) (xy 160.31929 -403.718516)
			(xy 160.31972 -403.728682) (xy 160.31972 -403.88667) (xy 160.32014 -403.895856) (xy 160.326646 -403.913041)
			(xy 160.33242 -403.920198) (xy 160.354231 -403.945832) (xy 160.392181 -404.00142) (xy 160.423216 -404.061146)
			(xy 160.446889 -404.124153) (xy 160.462862 -404.189538) (xy 160.470905 -404.256363) (xy 160.470903 -404.32367)
			(xy 160.462856 -404.390495) (xy 160.446879 -404.455879) (xy 160.423202 -404.518885) (xy 160.392164 -404.578608)
			(xy 160.35421 -404.634194) (xy 160.33242 -404.659846) (xy 160.326624 -404.666992) (xy 160.320108 -404.684182)
			(xy 160.31972 -404.693374) (xy 160.31972 -405.186642) (xy 160.320105 -405.195832) (xy 160.326636 -405.213016)
			(xy 160.33242 -405.22017) (xy 160.354203 -405.245826) (xy 160.392155 -405.301411) (xy 160.42319 -405.361134)
			(xy 160.446865 -405.424138) (xy 160.46284 -405.48952) (xy 160.470885 -405.556343) (xy 160.470886 -405.623648)
			(xy 160.462842 -405.690471) (xy 160.446868 -405.755853) (xy 160.423194 -405.818858) (xy 160.392159 -405.878581)
			(xy 160.354209 -405.934166) (xy 160.33242 -405.959818) (xy 160.326636 -405.966972) (xy 160.320113 -405.984156)
			(xy 160.31972 -405.993346) (xy 160.31972 -406.151334) (xy 160.319363 -406.161513) (xy 160.311559 -406.180317)
			(xy 160.297153 -406.194702) (xy 160.278338 -406.202478) (xy 160.268158 -406.202896) (xy 159.551878 -406.202896)
			(xy 159.541723 -406.202386) (xy 159.52296 -406.19461) (xy 159.508596 -406.18025) (xy 159.500817 -406.161489)
			(xy 159.500316 -406.151334) (xy 159.500316 -405.993346) (xy 159.49988 -405.984162) (xy 159.493384 -405.966977)
			(xy 159.487616 -405.959818) (xy 159.465823 -405.93417) (xy 159.427876 -405.878583) (xy 159.396844 -405.818858)
			(xy 159.373173 -405.755853) (xy 159.357201 -405.690471) (xy 159.349158 -405.623648) (xy 154.57678 -405.623648)
			(xy 154.57678 -406.723789) (xy 161.548771 -406.723789) (xy 161.548774 -406.656363) (xy 161.556853 -406.589423)
			(xy 161.572891 -406.523933) (xy 161.596657 -406.460835) (xy 161.627809 -406.401038) (xy 161.665899 -406.345402)
			(xy 161.687764 -406.319736) (xy 161.693578 -406.312604) (xy 161.70008 -406.295403) (xy 161.700464 -406.286208)
			(xy 161.700464 -405.793956) (xy 161.700061 -405.784768) (xy 161.693541 -405.767585) (xy 161.687764 -405.760428)
			(xy 161.665897 -405.734765) (xy 161.627811 -405.67913) (xy 161.596663 -405.619333) (xy 161.5729 -405.556236)
			(xy 161.556866 -405.490747) (xy 161.548791 -405.423809) (xy 161.548792 -405.356385) (xy 161.556867 -405.289447)
			(xy 161.572902 -405.223959) (xy 161.596665 -405.160862) (xy 161.627814 -405.101065) (xy 161.665901 -405.04543)
			(xy 161.687764 -405.019764) (xy 161.693566 -405.012623) (xy 161.700076 -404.995429) (xy 161.700464 -404.986236)
			(xy 161.700464 -404.828756) (xy 161.700948 -404.818649) (xy 161.708694 -404.799977) (xy 161.72299 -404.785685)
			(xy 161.741665 -404.777945) (xy 161.751772 -404.777448) (xy 162.468052 -404.777448) (xy 162.478165 -404.777954)
			(xy 162.496858 -404.785677) (xy 162.511172 -404.799965) (xy 162.518928 -404.818644) (xy 162.51936 -404.828756)
			(xy 162.51936 -404.986236) (xy 162.519762 -404.995424) (xy 162.526282 -405.012608) (xy 162.53206 -405.019764)
			(xy 162.553921 -405.045432) (xy 162.592013 -405.101065) (xy 162.623166 -405.16086) (xy 162.646932 -405.223957)
			(xy 162.662969 -405.289446) (xy 162.671046 -405.356385) (xy 162.671046 -405.423809) (xy 162.66297 -405.490748)
			(xy 162.646934 -405.556237) (xy 162.623168 -405.619334) (xy 162.620889 -405.623708) (xy 163.748926 -405.623708)
			(xy 163.748926 -405.556283) (xy 163.757003 -405.489344) (xy 163.77304 -405.423855) (xy 163.796805 -405.360758)
			(xy 163.827957 -405.300961) (xy 163.866047 -405.245327) (xy 163.887912 -405.219662) (xy 163.893709 -405.212517)
			(xy 163.900223 -405.195326) (xy 163.900612 -405.186134) (xy 163.900612 -404.693882) (xy 163.900208 -404.684694)
			(xy 163.89369 -404.66751) (xy 163.887912 -404.660354) (xy 163.866069 -404.634671) (xy 163.827979 -404.579039)
			(xy 163.796827 -404.519246) (xy 163.773061 -404.456151) (xy 163.757023 -404.390664) (xy 163.748946 -404.323728)
			(xy 163.748944 -404.256305) (xy 163.757018 -404.189368) (xy 163.773051 -404.12388) (xy 163.796813 -404.060784)
			(xy 163.827962 -404.000989) (xy 163.866049 -403.945355) (xy 163.887912 -403.91969) (xy 163.893697 -403.912536)
			(xy 163.900218 -403.895352) (xy 163.900612 -403.886162) (xy 163.900612 -403.728682) (xy 163.901111 -403.718558)
			(xy 163.908839 -403.699841) (xy 163.923121 -403.685486) (xy 163.941798 -403.677663) (xy 163.95192 -403.67712)
			(xy 164.6682 -403.67712) (xy 164.678357 -403.677522) (xy 164.697113 -403.685321) (xy 164.711437 -403.699724)
			(xy 164.719133 -403.718523) (xy 164.719508 -403.728682) (xy 164.719508 -403.886162) (xy 164.719935 -403.895347)
			(xy 164.726437 -403.912532) (xy 164.732208 -403.91969) (xy 164.754093 -403.945338) (xy 164.792181 -404.000975)
			(xy 164.82333 -404.060774) (xy 164.847093 -404.123873) (xy 164.863126 -404.189364) (xy 164.8712 -404.256304)
			(xy 164.871198 -404.323729) (xy 164.86312 -404.390669) (xy 164.847083 -404.456159) (xy 164.823317 -404.519257)
			(xy 164.792164 -404.579054) (xy 164.754073 -404.634689) (xy 164.732208 -404.660354) (xy 164.726407 -404.667496)
			(xy 164.719895 -404.684689) (xy 164.719508 -404.693882) (xy 164.719508 -405.186134) (xy 164.7199 -405.195323)
			(xy 164.726426 -405.212508) (xy 164.732208 -405.219662) (xy 164.754066 -405.245332) (xy 164.792154 -405.300966)
			(xy 164.823305 -405.360762) (xy 164.847069 -405.423858) (xy 164.863104 -405.489346) (xy 164.871181 -405.556284)
			(xy 164.871181 -405.623707) (xy 164.863106 -405.690645) (xy 164.847072 -405.756133) (xy 164.823308 -405.81923)
			(xy 164.792159 -405.879026) (xy 164.754071 -405.934661) (xy 164.732208 -405.960326) (xy 164.726419 -405.967477)
			(xy 164.719899 -405.984663) (xy 164.719508 -405.993854) (xy 164.719508 -406.151334) (xy 164.719003 -406.161457)
			(xy 164.711273 -406.18017) (xy 164.696993 -406.194523) (xy 164.67832 -406.20235) (xy 164.6682 -406.202896)
			(xy 163.95192 -406.202896) (xy 163.941767 -406.202462) (xy 163.923014 -406.194672) (xy 163.90869 -406.180279)
			(xy 163.90099 -406.161489) (xy 163.900612 -406.151334) (xy 163.900612 -405.993854) (xy 163.900173 -405.98467)
			(xy 163.893679 -405.967485) (xy 163.887912 -405.960326) (xy 163.866042 -405.934666) (xy 163.827952 -405.879031)
			(xy 163.796801 -405.819234) (xy 163.773037 -405.756137) (xy 163.757001 -405.690647) (xy 163.748926 -405.623708)
			(xy 162.620889 -405.623708) (xy 162.592016 -405.67913) (xy 162.553925 -405.734763) (xy 162.53206 -405.760428)
			(xy 162.526264 -405.767573) (xy 162.51975 -405.784764) (xy 162.51936 -405.793956) (xy 162.51936 -406.286208)
			(xy 162.519775 -406.295394) (xy 162.526286 -406.312578) (xy 162.53206 -406.319736) (xy 162.553894 -406.345426)
			(xy 162.591986 -406.401056) (xy 162.623141 -406.460849) (xy 162.646908 -406.523942) (xy 162.662947 -406.589429)
			(xy 162.671026 -406.656365) (xy 162.671029 -406.72373) (xy 165.949066 -406.72373) (xy 165.949069 -406.656422)
			(xy 165.957117 -406.589597) (xy 165.973094 -406.524213) (xy 165.996771 -406.461207) (xy 166.027808 -406.401483)
			(xy 166.065762 -406.345896) (xy 166.087552 -406.320244) (xy 166.093361 -406.313108) (xy 166.099867 -406.29591)
			(xy 166.100252 -406.286716) (xy 166.100252 -405.793448) (xy 166.099807 -405.784265) (xy 166.093316 -405.767081)
			(xy 166.087552 -405.75992) (xy 166.06576 -405.734271) (xy 166.027811 -405.678685) (xy 165.996777 -405.618961)
			(xy 165.973104 -405.555956) (xy 165.957131 -405.490573) (xy 165.949087 -405.42375) (xy 165.949087 -405.356444)
			(xy 165.957132 -405.289621) (xy 165.973105 -405.224239) (xy 165.996779 -405.161234) (xy 166.027814 -405.10151)
			(xy 166.065764 -405.045924) (xy 166.087552 -405.020272) (xy 166.093349 -405.013128) (xy 166.099862 -404.995936)
			(xy 166.100252 -404.986744) (xy 166.100252 -404.828756) (xy 166.100685 -404.818605) (xy 166.108486 -404.799861)
			(xy 166.122878 -404.785541) (xy 166.141661 -404.777834) (xy 166.151814 -404.777448) (xy 166.868094 -404.777448)
			(xy 166.878221 -404.777932) (xy 166.896944 -404.785659) (xy 166.911301 -404.799946) (xy 166.919119 -404.818631)
			(xy 166.919656 -404.828756) (xy 166.919656 -404.986744) (xy 166.920055 -404.995932) (xy 166.926578 -405.013116)
			(xy 166.932356 -405.020272) (xy 166.95414 -405.045927) (xy 166.992089 -405.101513) (xy 167.023123 -405.161236)
			(xy 167.046796 -405.22424) (xy 167.062769 -405.289622) (xy 167.070814 -405.356445) (xy 167.070814 -405.423749)
			(xy 167.06277 -405.490572) (xy 167.046798 -405.555954) (xy 167.023125 -405.618958) (xy 167.020688 -405.623648)
			(xy 168.149245 -405.623648) (xy 168.149246 -405.556343) (xy 168.15729 -405.489521) (xy 168.173263 -405.424139)
			(xy 168.196934 -405.361134) (xy 168.227966 -405.30141) (xy 168.265913 -405.245823) (xy 168.2877 -405.22017)
			(xy 168.293492 -405.213021) (xy 168.300009 -405.195834) (xy 168.3004 -405.186642) (xy 168.3004 -404.693374)
			(xy 168.300003 -404.684185) (xy 168.29348 -404.667001) (xy 168.2877 -404.659846) (xy 168.265935 -404.634176)
			(xy 168.227988 -404.578591) (xy 168.196956 -404.518869) (xy 168.173284 -404.455867) (xy 168.15731 -404.390488)
			(xy 168.149265 -404.323668) (xy 168.149263 -404.256365) (xy 168.157305 -404.189545) (xy 168.173274 -404.124164)
			(xy 168.196943 -404.061161) (xy 168.227971 -404.001438) (xy 168.265915 -403.945851) (xy 168.2877 -403.920198)
			(xy 168.29348 -403.913041) (xy 168.300005 -403.89586) (xy 168.3004 -403.88667) (xy 168.3004 -403.728682)
			(xy 168.300917 -403.718528) (xy 168.308691 -403.699765) (xy 168.323049 -403.685402) (xy 168.341808 -403.677621)
			(xy 168.351962 -403.67712) (xy 169.068242 -403.67712) (xy 169.0784 -403.677599) (xy 169.097167 -403.685383)
			(xy 169.11153 -403.699753) (xy 169.119306 -403.718524) (xy 169.119804 -403.728682) (xy 169.119804 -403.88667)
			(xy 169.120228 -403.895856) (xy 169.126732 -403.91304) (xy 169.132504 -403.920198) (xy 169.154312 -403.945833)
			(xy 169.192257 -404.001423) (xy 169.223287 -404.061149) (xy 169.246957 -404.124156) (xy 169.262927 -404.18954)
			(xy 169.270969 -404.256364) (xy 169.270967 -404.32367) (xy 169.262921 -404.390493) (xy 169.246947 -404.455876)
			(xy 169.223274 -404.518881) (xy 169.19224 -404.578606) (xy 169.154292 -404.634193) (xy 169.132504 -404.659846)
			(xy 169.126706 -404.66699) (xy 169.120192 -404.684181) (xy 169.119804 -404.693374) (xy 169.119804 -405.186642)
			(xy 169.120193 -405.195832) (xy 169.126721 -405.213016) (xy 169.132504 -405.22017) (xy 169.154284 -405.245828)
			(xy 169.192231 -405.301414) (xy 169.223262 -405.361137) (xy 169.246933 -405.424141) (xy 169.262905 -405.489522)
			(xy 169.270949 -405.556344) (xy 169.27095 -405.623647) (xy 169.262907 -405.690469) (xy 169.246936 -405.75585)
			(xy 169.223266 -405.818854) (xy 169.192235 -405.878578) (xy 169.15429 -405.934165) (xy 169.132504 -405.959818)
			(xy 169.126718 -405.966971) (xy 169.120197 -405.984155) (xy 169.119804 -405.993346) (xy 169.119804 -406.151334)
			(xy 169.119296 -406.161489) (xy 169.111518 -406.180251) (xy 169.097157 -406.194613) (xy 169.078397 -406.202394)
			(xy 169.068242 -406.202896) (xy 168.351962 -406.202896) (xy 168.341806 -406.202399) (xy 168.323042 -406.194618)
			(xy 168.30868 -406.180254) (xy 168.300901 -406.16149) (xy 168.3004 -406.151334) (xy 168.3004 -405.993346)
			(xy 168.299968 -405.984161) (xy 168.293469 -405.966977) (xy 168.2877 -405.959818) (xy 168.265908 -405.93417)
			(xy 168.227961 -405.878582) (xy 168.196931 -405.818858) (xy 168.17326 -405.755853) (xy 168.157289 -405.69047)
			(xy 168.149245 -405.623648) (xy 167.020688 -405.623648) (xy 166.992092 -405.678681) (xy 166.954143 -405.734268)
			(xy 166.932356 -405.75992) (xy 166.926563 -405.767067) (xy 166.920047 -405.784256) (xy 166.919656 -405.793448)
			(xy 166.919656 -406.286716) (xy 166.920068 -406.295903) (xy 166.926582 -406.313087) (xy 166.932356 -406.320244)
			(xy 166.954112 -406.345922) (xy 166.992062 -406.401505) (xy 167.023097 -406.461225) (xy 167.046772 -406.524226)
			(xy 167.062747 -406.589605) (xy 167.070794 -406.656425) (xy 167.070797 -406.723727) (xy 167.070789 -406.72379)
			(xy 170.348835 -406.72379) (xy 170.348838 -406.656362) (xy 170.356917 -406.589421) (xy 170.372958 -406.52393)
			(xy 170.396728 -406.460831) (xy 170.427885 -406.401034) (xy 170.46598 -406.3454) (xy 170.487848 -406.319736)
			(xy 170.49366 -406.312602) (xy 170.500164 -406.295403) (xy 170.500548 -406.286208) (xy 170.500548 -405.793956)
			(xy 170.500148 -405.784768) (xy 170.493626 -405.767584) (xy 170.487848 -405.760428) (xy 170.465978 -405.734767)
			(xy 170.427887 -405.679133) (xy 170.396733 -405.619337) (xy 170.372967 -405.556239) (xy 170.356931 -405.490749)
			(xy 170.348854 -405.423809) (xy 170.348855 -405.356385) (xy 170.356932 -405.289445) (xy 170.372969 -405.223955)
			(xy 170.396736 -405.160858) (xy 170.42789 -405.101062) (xy 170.465982 -405.045428) (xy 170.487848 -405.019764)
			(xy 170.493648 -405.012622) (xy 170.500159 -404.995429) (xy 170.500548 -404.986236) (xy 170.500548 -404.828756)
			(xy 170.501048 -404.818651) (xy 170.50879 -404.799982) (xy 170.523082 -404.78569) (xy 170.541751 -404.777948)
			(xy 170.551856 -404.777448) (xy 171.268136 -404.777448) (xy 171.278241 -404.777954) (xy 171.29691 -404.785694)
			(xy 171.311201 -404.799984) (xy 171.318944 -404.818651) (xy 171.319444 -404.828756) (xy 171.319444 -404.986236)
			(xy 171.31985 -404.995423) (xy 171.326368 -405.012607) (xy 171.332144 -405.019764) (xy 171.354006 -405.045432)
			(xy 171.392099 -405.101064) (xy 171.423253 -405.16086) (xy 171.447019 -405.223956) (xy 171.463057 -405.289446)
			(xy 171.471134 -405.356385) (xy 171.471134 -405.423809) (xy 171.463058 -405.490748) (xy 171.447021 -405.556238)
			(xy 171.423255 -405.619335) (xy 171.421007 -405.623649) (xy 172.549012 -405.623649) (xy 172.549013 -405.556342)
			(xy 172.557058 -405.489518) (xy 172.573033 -405.424135) (xy 172.596709 -405.36113) (xy 172.627746 -405.301407)
			(xy 172.665698 -405.245822) (xy 172.687488 -405.22017) (xy 172.693278 -405.21302) (xy 172.699797 -405.195833)
			(xy 172.700188 -405.186642) (xy 172.700188 -404.693374) (xy 172.699793 -404.684185) (xy 172.693269 -404.667001)
			(xy 172.687488 -404.659846) (xy 172.66572 -404.634177) (xy 172.627768 -404.578594) (xy 172.596731 -404.518873)
			(xy 172.573055 -404.455871) (xy 172.557079 -404.39049) (xy 172.549032 -404.323669) (xy 172.54903 -404.256364)
			(xy 172.557073 -404.189542) (xy 172.573045 -404.124161) (xy 172.596717 -404.061157) (xy 172.627751 -404.001435)
			(xy 172.6657 -403.945849) (xy 172.687488 -403.920198) (xy 172.693267 -403.91304) (xy 172.699792 -403.895859)
			(xy 172.700188 -403.88667) (xy 172.700188 -403.728682) (xy 172.70055 -403.718503) (xy 172.708351 -403.699698)
			(xy 172.722756 -403.685313) (xy 172.74157 -403.677537) (xy 172.75175 -403.67712) (xy 173.46803 -403.67712)
			(xy 173.478187 -403.677608) (xy 173.496954 -403.685389) (xy 173.511317 -403.699756) (xy 173.519094 -403.718524)
			(xy 173.519592 -403.728682) (xy 173.519592 -403.88667) (xy 173.520018 -403.895855) (xy 173.526521 -403.91304)
			(xy 173.532292 -403.920198) (xy 173.5541 -403.945833) (xy 173.592047 -404.001422) (xy 173.623077 -404.061149)
			(xy 173.646747 -404.124155) (xy 173.662718 -404.189539) (xy 173.67076 -404.256363) (xy 173.670758 -404.32367)
			(xy 173.662712 -404.390493) (xy 173.646738 -404.455876) (xy 173.623064 -404.518882) (xy 173.59203 -404.578606)
			(xy 173.55408 -404.634193) (xy 173.532292 -404.659846) (xy 173.526492 -404.666989) (xy 173.51998 -404.684181)
			(xy 173.519592 -404.693374) (xy 173.519592 -405.186642) (xy 173.519984 -405.195831) (xy 173.52651 -405.213015)
			(xy 173.532292 -405.22017) (xy 173.554073 -405.245827) (xy 173.59202 -405.301414) (xy 173.623052 -405.361137)
			(xy 173.646723 -405.424141) (xy 173.662696 -405.489522) (xy 173.67074 -405.556343) (xy 173.670741 -405.623647)
			(xy 173.662698 -405.690469) (xy 173.646726 -405.755851) (xy 173.623055 -405.818855) (xy 173.592025 -405.878578)
			(xy 173.554078 -405.934165) (xy 173.532292 -405.959818) (xy 173.526504 -405.96697) (xy 173.519985 -405.984155)
			(xy 173.519592 -405.993346) (xy 173.519592 -406.151334) (xy 173.519095 -406.16149) (xy 173.511315 -406.180254)
			(xy 173.496951 -406.194617) (xy 173.478186 -406.202396) (xy 173.46803 -406.202896) (xy 172.75175 -406.202896)
			(xy 172.741586 -406.202396) (xy 172.722799 -406.194634) (xy 172.708413 -406.180272) (xy 172.70062 -406.161497)
			(xy 172.700188 -406.151334) (xy 172.700188 -405.993346) (xy 172.699759 -405.984161) (xy 172.693259 -405.966976)
			(xy 172.687488 -405.959818) (xy 172.665693 -405.934171) (xy 172.627741 -405.878585) (xy 172.596705 -405.818861)
			(xy 172.573031 -405.755856) (xy 172.557057 -405.690473) (xy 172.549012 -405.623649) (xy 171.421007 -405.623649)
			(xy 171.392102 -405.67913) (xy 171.35401 -405.734764) (xy 171.332144 -405.760428) (xy 171.326346 -405.767572)
			(xy 171.319834 -405.784764) (xy 171.319444 -405.793956) (xy 171.319444 -406.286208) (xy 171.319863 -406.295394)
			(xy 171.326372 -406.312578) (xy 171.332144 -406.319736) (xy 171.353978 -406.345426) (xy 171.392072 -406.401056)
			(xy 171.423227 -406.460848) (xy 171.446996 -406.523942) (xy 171.463035 -406.589428) (xy 171.471114 -406.656365)
			(xy 171.471117 -406.72373) (xy 174.749154 -406.72373) (xy 174.749157 -406.656422) (xy 174.757205 -406.589597)
			(xy 174.773181 -406.524213) (xy 174.796857 -406.461208) (xy 174.827894 -406.401483) (xy 174.865846 -406.345896)
			(xy 174.887636 -406.320244) (xy 174.893443 -406.313107) (xy 174.899951 -406.29591) (xy 174.900336 -406.286716)
			(xy 174.900336 -405.793448) (xy 174.899895 -405.784264) (xy 174.893402 -405.76708) (xy 174.887636 -405.75992)
			(xy 174.865844 -405.734271) (xy 174.827896 -405.678684) (xy 174.796863 -405.61896) (xy 174.77319 -405.555955)
			(xy 174.757218 -405.490573) (xy 174.749174 -405.42375) (xy 174.749174 -405.356444) (xy 174.757219 -405.289621)
			(xy 174.773192 -405.224239) (xy 174.796865 -405.161234) (xy 174.827899 -405.101511) (xy 174.865848 -405.045924)
			(xy 174.887636 -405.020272) (xy 174.893432 -405.013126) (xy 174.899946 -404.995936) (xy 174.900336 -404.986744)
			(xy 174.900336 -404.828756) (xy 174.900686 -404.818594) (xy 174.908503 -404.799834) (xy 174.922922 -404.785511)
			(xy 174.941734 -404.77782) (xy 174.951898 -404.777448) (xy 175.668178 -404.777448) (xy 175.678304 -404.777945)
			(xy 175.697027 -404.785667) (xy 175.711384 -404.79995) (xy 175.719202 -404.818632) (xy 175.71974 -404.828756)
			(xy 175.71974 -404.986744) (xy 175.720142 -404.995932) (xy 175.726663 -405.013115) (xy 175.73244 -405.020272)
			(xy 175.754224 -405.045927) (xy 175.792175 -405.101513) (xy 175.823209 -405.161236) (xy 175.846883 -405.22424)
			(xy 175.862857 -405.289622) (xy 175.870902 -405.356444) (xy 175.870902 -405.42375) (xy 175.862858 -405.490572)
			(xy 175.846885 -405.555954) (xy 175.823212 -405.618959) (xy 175.792178 -405.678682) (xy 175.754228 -405.734268)
			(xy 175.73244 -405.75992) (xy 175.726645 -405.767066) (xy 175.720131 -405.784256) (xy 175.71974 -405.793448)
			(xy 175.71974 -406.286716) (xy 175.720156 -406.295902) (xy 175.726667 -406.313086) (xy 175.73244 -406.320244)
			(xy 175.754197 -406.345922) (xy 175.792148 -406.401504) (xy 175.823184 -406.461224) (xy 175.846859 -406.524225)
			(xy 175.862835 -406.589604) (xy 175.870882 -406.656424) (xy 175.870885 -406.723727) (xy 175.862844 -406.790548)
			(xy 175.846873 -406.855929) (xy 175.823203 -406.918932) (xy 175.792173 -406.978655) (xy 175.754226 -407.03424)
			(xy 175.73244 -407.059892) (xy 175.726657 -407.067046) (xy 175.720136 -407.08423) (xy 175.71974 -407.09342)
			(xy 175.71974 -407.251408) (xy 175.719286 -407.261558) (xy 175.711495 -407.280302) (xy 175.697109 -407.294624)
			(xy 175.678329 -407.302331) (xy 175.668178 -407.302716) (xy 174.951898 -407.302716) (xy 174.941766 -407.302274)
			(xy 174.923036 -407.294537) (xy 174.908679 -407.280237) (xy 174.900867 -407.261538) (xy 174.900336 -407.251408)
			(xy 174.900336 -407.09342) (xy 174.899908 -407.084235) (xy 174.893406 -407.067051) (xy 174.887636 -407.059892)
			(xy 174.865817 -407.034266) (xy 174.827869 -406.978676) (xy 174.796837 -406.918948) (xy 174.773167 -406.85594)
			(xy 174.757196 -406.790555) (xy 174.749154 -406.72373) (xy 171.471117 -406.72373) (xy 171.471117 -406.723787)
			(xy 171.463044 -406.790724) (xy 171.44701 -406.856212) (xy 171.423247 -406.919308) (xy 171.392097 -406.979103)
			(xy 171.354008 -407.034736) (xy 171.332144 -407.0604) (xy 171.326358 -407.067552) (xy 171.319839 -407.084738)
			(xy 171.319444 -407.093928) (xy 171.319444 -407.251408) (xy 171.318922 -407.261512) (xy 171.31119 -407.280182)
			(xy 171.296905 -407.294475) (xy 171.278239 -407.302217) (xy 171.268136 -407.302716) (xy 170.551856 -407.302716)
			(xy 170.541746 -407.302251) (xy 170.52307 -407.294502) (xy 170.508778 -407.280199) (xy 170.501042 -407.261518)
			(xy 170.500548 -407.251408) (xy 170.500548 -407.093928) (xy 170.500114 -407.084744) (xy 170.493616 -407.067559)
			(xy 170.487848 -407.0604) (xy 170.465951 -407.034762) (xy 170.42786 -406.979124) (xy 170.396708 -406.919325)
			(xy 170.372944 -406.856224) (xy 170.356909 -406.790732) (xy 170.348835 -406.72379) (xy 167.070789 -406.72379)
			(xy 167.062756 -406.790548) (xy 167.046786 -406.855928) (xy 167.023117 -406.918931) (xy 166.992087 -406.978654)
			(xy 166.954142 -407.03424) (xy 166.932356 -407.059892) (xy 166.926575 -407.067048) (xy 166.920052 -407.08423)
			(xy 166.919656 -407.09342) (xy 166.919656 -407.251408) (xy 166.919186 -407.261556) (xy 166.911398 -407.280297)
			(xy 166.897017 -407.294618) (xy 166.878243 -407.302328) (xy 166.868094 -407.302716) (xy 166.151814 -407.302716)
			(xy 166.141683 -407.302261) (xy 166.122954 -407.294529) (xy 166.108595 -407.280233) (xy 166.100783 -407.261537)
			(xy 166.100252 -407.251408) (xy 166.100252 -407.09342) (xy 166.099821 -407.084235) (xy 166.093321 -407.067051)
			(xy 166.087552 -407.059892) (xy 166.065732 -407.034266) (xy 166.027784 -406.978676) (xy 165.996751 -406.918949)
			(xy 165.973079 -406.855941) (xy 165.957108 -406.790556) (xy 165.949066 -406.72373) (xy 162.671029 -406.72373)
			(xy 162.671029 -406.723787) (xy 162.662956 -406.790724) (xy 162.646923 -406.856212) (xy 162.62316 -406.919307)
			(xy 162.592011 -406.979102) (xy 162.553923 -407.034735) (xy 162.53206 -407.0604) (xy 162.526276 -407.067554)
			(xy 162.519755 -407.084738) (xy 162.51936 -407.093928) (xy 162.51936 -407.251408) (xy 162.518989 -407.261536)
			(xy 162.511231 -407.280247) (xy 162.4969 -407.294563) (xy 162.47818 -407.3023) (xy 162.468052 -407.302716)
			(xy 161.751772 -407.302716) (xy 161.741663 -407.302238) (xy 161.722988 -407.294494) (xy 161.708694 -407.280196)
			(xy 161.700958 -407.261517) (xy 161.700464 -407.251408) (xy 161.700464 -407.093928) (xy 161.700026 -407.084744)
			(xy 161.69353 -407.06756) (xy 161.687764 -407.0604) (xy 161.66587 -407.03476) (xy 161.627784 -406.979121)
			(xy 161.596637 -406.919321) (xy 161.572876 -406.856221) (xy 161.556844 -406.790729) (xy 161.548771 -406.723789)
			(xy 154.57678 -406.723789) (xy 154.57678 -409.523827) (xy 159.349136 -409.523827) (xy 159.34914 -409.456519)
			(xy 159.357187 -409.389695) (xy 159.373163 -409.324311) (xy 159.396839 -409.261305) (xy 159.427875 -409.20158)
			(xy 159.465827 -409.145992) (xy 159.487616 -409.12034) (xy 159.493422 -409.113202) (xy 159.499931 -409.096006)
			(xy 159.500316 -409.086812) (xy 159.500316 -408.593544) (xy 159.499881 -408.58436) (xy 159.493384 -408.567175)
			(xy 159.487616 -408.560016) (xy 159.465821 -408.53437) (xy 159.427874 -408.478782) (xy 159.396842 -408.419058)
			(xy 159.373171 -408.356052) (xy 159.357199 -408.29067) (xy 159.349156 -408.223847) (xy 159.349157 -408.156541)
			(xy 159.357201 -408.089719) (xy 159.373175 -408.024336) (xy 159.396847 -407.961331) (xy 159.42788 -407.901607)
			(xy 159.465828 -407.84602) (xy 159.487616 -407.820368) (xy 159.49341 -407.813221) (xy 159.499926 -407.796032)
			(xy 159.500316 -407.78684) (xy 159.500316 -407.628852) (xy 159.500683 -407.618693) (xy 159.508497 -407.599936)
			(xy 159.522911 -407.585614) (xy 159.541716 -407.577919) (xy 159.551878 -407.577544) (xy 160.268158 -407.577544)
			(xy 160.278283 -407.578061) (xy 160.297003 -407.585776) (xy 160.311361 -407.600053) (xy 160.319181 -407.61873)
			(xy 160.31972 -407.628852) (xy 160.31972 -407.78684) (xy 160.320107 -407.79603) (xy 160.326636 -407.813214)
			(xy 160.33242 -407.820368) (xy 160.354201 -407.846026) (xy 160.392153 -407.901611) (xy 160.423189 -407.961333)
			(xy 160.446864 -408.024337) (xy 160.462838 -408.089719) (xy 160.470884 -408.156541) (xy 160.470885 -408.223847)
			(xy 160.462841 -408.290669) (xy 160.446867 -408.356052) (xy 160.423194 -408.419056) (xy 160.392159 -408.478779)
			(xy 160.354208 -408.534364) (xy 160.33242 -408.560016) (xy 160.326636 -408.567171) (xy 160.320113 -408.584354)
			(xy 160.31972 -408.593544) (xy 160.31972 -409.086812) (xy 160.32012 -409.096) (xy 160.32664 -409.113185)
			(xy 160.33242 -409.12034) (xy 160.354174 -409.146021) (xy 160.392126 -409.201602) (xy 160.423163 -409.261321)
			(xy 160.44684 -409.324322) (xy 160.462817 -409.389701) (xy 160.470864 -409.456521) (xy 160.470867 -409.523824)
			(xy 160.462826 -409.590645) (xy 160.446856 -409.656026) (xy 160.423185 -409.719029) (xy 160.392154 -409.778751)
			(xy 160.354207 -409.834336) (xy 160.33242 -409.859988) (xy 160.326606 -409.867121) (xy 160.320101 -409.884321)
			(xy 160.31972 -409.893516) (xy 160.31972 -410.051504) (xy 160.319282 -410.061656) (xy 160.311489 -410.080404)
			(xy 160.297098 -410.094727) (xy 160.278312 -410.10243) (xy 160.268158 -410.102812) (xy 159.551878 -410.102812)
			(xy 159.541756 -410.102293) (xy 159.523044 -410.094568) (xy 159.508691 -410.080292) (xy 159.500863 -410.061623)
			(xy 159.500316 -410.051504) (xy 159.500316 -409.893516) (xy 159.499894 -409.88433) (xy 159.493388 -409.867146)
			(xy 159.487616 -409.859988) (xy 159.465794 -409.834365) (xy 159.427847 -409.778774) (xy 159.396817 -409.719046)
			(xy 159.373147 -409.656038) (xy 159.357177 -409.590652) (xy 159.349136 -409.523827) (xy 154.57678 -409.523827)
			(xy 154.57678 -410.6237) (xy 161.548783 -410.6237) (xy 161.548784 -410.556276) (xy 161.556861 -410.489337)
			(xy 161.572897 -410.423848) (xy 161.596662 -410.36075) (xy 161.627812 -410.300953) (xy 161.6659 -410.245318)
			(xy 161.687764 -410.219652) (xy 161.693571 -410.212515) (xy 161.700078 -410.195318) (xy 161.700464 -410.186124)
			(xy 161.700464 -409.693872) (xy 161.700053 -409.684685) (xy 161.693538 -409.667502) (xy 161.687764 -409.660344)
			(xy 161.665913 -409.634668) (xy 161.627826 -409.579035) (xy 161.596677 -409.519239) (xy 161.572914 -409.456144)
			(xy 161.556879 -409.390657) (xy 161.548802 -409.32372) (xy 161.548801 -409.256298) (xy 161.556875 -409.189361)
			(xy 161.572909 -409.123873) (xy 161.59667 -409.060777) (xy 161.627817 -409.000981) (xy 161.665902 -408.945346)
			(xy 161.687764 -408.91968) (xy 161.693559 -408.912534) (xy 161.700073 -408.895344) (xy 161.700464 -408.886152)
			(xy 161.700464 -408.728672) (xy 161.700961 -408.718566) (xy 161.708701 -408.699894) (xy 161.722994 -408.685601)
			(xy 161.741666 -408.677861) (xy 161.751772 -408.677364) (xy 162.468052 -408.677364) (xy 162.478167 -408.677854)
			(xy 162.496863 -408.68558) (xy 162.511177 -408.699874) (xy 162.518931 -408.718558) (xy 162.51936 -408.728672)
			(xy 162.51936 -408.886152) (xy 162.519802 -408.895336) (xy 162.526295 -408.91252) (xy 162.53206 -408.91968)
			(xy 162.553937 -408.945335) (xy 162.592028 -409.00097) (xy 162.623181 -409.060767) (xy 162.646946 -409.123866)
			(xy 162.662982 -409.189356) (xy 162.671057 -409.256296) (xy 162.671056 -409.323722) (xy 162.662978 -409.390662)
			(xy 162.64694 -409.456152) (xy 162.623173 -409.519249) (xy 162.620757 -409.523886) (xy 163.748905 -409.523886)
			(xy 163.748908 -409.45646) (xy 163.756988 -409.389519) (xy 163.773027 -409.324027) (xy 163.796796 -409.260929)
			(xy 163.827952 -409.201132) (xy 163.866045 -409.145497) (xy 163.887912 -409.119832) (xy 163.893721 -409.112696)
			(xy 163.900228 -409.095498) (xy 163.900612 -409.086304) (xy 163.900612 -408.594052) (xy 163.900174 -408.584868)
			(xy 163.893679 -408.567683) (xy 163.887912 -408.560524) (xy 163.86604 -408.534865) (xy 163.82795 -408.47923)
			(xy 163.796799 -408.419433) (xy 163.773035 -408.356335) (xy 163.757 -408.290845) (xy 163.748925 -408.223906)
			(xy 163.748925 -408.156482) (xy 163.757002 -408.089543) (xy 163.773039 -408.024053) (xy 163.796804 -407.960956)
			(xy 163.827957 -407.901159) (xy 163.866047 -407.845525) (xy 163.887912 -407.81986) (xy 163.893709 -407.812715)
			(xy 163.900223 -407.795524) (xy 163.900612 -407.786332) (xy 163.900612 -407.628852) (xy 163.901046 -407.618739)
			(xy 163.908802 -407.600057) (xy 163.923114 -407.585764) (xy 163.941806 -407.578033) (xy 163.95192 -407.577544)
			(xy 164.6682 -407.577544) (xy 164.678302 -407.578084) (xy 164.696969 -407.585811) (xy 164.711262 -407.60009)
			(xy 164.719007 -407.618751) (xy 164.719508 -407.628852) (xy 164.719508 -407.786332) (xy 164.719901 -407.795521)
			(xy 164.726426 -407.812705) (xy 164.732208 -407.81986) (xy 164.754064 -407.845532) (xy 164.792152 -407.901166)
			(xy 164.823303 -407.960961) (xy 164.847067 -408.024057) (xy 164.863103 -408.089545) (xy 164.871179 -408.156483)
			(xy 164.87118 -408.223905) (xy 164.863105 -408.290843) (xy 164.847071 -408.356332) (xy 164.823308 -408.419428)
			(xy 164.792158 -408.479224) (xy 164.754071 -408.534859) (xy 164.732208 -408.560524) (xy 164.72642 -408.567675)
			(xy 164.7199 -408.584861) (xy 164.719508 -408.594052) (xy 164.719508 -409.086304) (xy 164.719915 -409.095492)
			(xy 164.726431 -409.112676) (xy 164.732208 -409.119832) (xy 164.754036 -409.145527) (xy 164.792126 -409.201157)
			(xy 164.823277 -409.260949) (xy 164.847043 -409.324042) (xy 164.863081 -409.389528) (xy 164.87116 -409.456463)
			(xy 164.871163 -409.523883) (xy 164.863091 -409.590819) (xy 164.847059 -409.656306) (xy 164.8233 -409.719401)
			(xy 164.792153 -409.779196) (xy 164.75407 -409.834831) (xy 164.732208 -409.860496) (xy 164.726432 -409.867656)
			(xy 164.719905 -409.884835) (xy 164.719508 -409.894024) (xy 164.719508 -410.051504) (xy 164.719018 -410.061612)
			(xy 164.711281 -410.080289) (xy 164.696985 -410.094583) (xy 164.678308 -410.102319) (xy 164.6682 -410.102812)
			(xy 163.95192 -410.102812) (xy 163.9418 -410.102368) (xy 163.923099 -410.094629) (xy 163.908785 -410.080321)
			(xy 163.901037 -410.061624) (xy 163.900612 -410.051504) (xy 163.900612 -409.894024) (xy 163.900188 -409.884838)
			(xy 163.893683 -409.867654) (xy 163.887912 -409.860496) (xy 163.866012 -409.83486) (xy 163.827924 -409.779222)
			(xy 163.796774 -409.719422) (xy 163.773011 -409.656321) (xy 163.756978 -409.590828) (xy 163.748905 -409.523886)
			(xy 162.620757 -409.523886) (xy 162.592019 -409.579046) (xy 162.553926 -409.634679) (xy 162.53206 -409.660344)
			(xy 162.526257 -409.667485) (xy 162.519747 -409.684679) (xy 162.51936 -409.693872) (xy 162.51936 -410.186124)
			(xy 162.519768 -410.195311) (xy 162.526284 -410.212495) (xy 162.53206 -410.219652) (xy 162.55391 -410.24533)
			(xy 162.592001 -410.300961) (xy 162.623155 -410.360755) (xy 162.646922 -410.423851) (xy 162.66296 -410.489339)
			(xy 162.671038 -410.556276) (xy 162.671039 -410.623641) (xy 165.949078 -410.623641) (xy 165.949079 -410.556335)
			(xy 165.957125 -410.489511) (xy 165.9731 -410.424127) (xy 165.996775 -410.361122) (xy 166.027811 -410.301398)
			(xy 166.065763 -410.245812) (xy 166.087552 -410.22016) (xy 166.093354 -410.213019) (xy 166.099864 -410.195825)
			(xy 166.100252 -410.186632) (xy 166.100252 -409.693364) (xy 166.099847 -409.684176) (xy 166.093328 -409.666993)
			(xy 166.087552 -409.659836) (xy 166.065776 -409.634174) (xy 166.027826 -409.578589) (xy 165.996791 -409.518867)
			(xy 165.973117 -409.455864) (xy 165.957143 -409.390483) (xy 165.949098 -409.323661) (xy 165.949097 -409.256357)
			(xy 165.95714 -409.189535) (xy 165.973112 -409.124153) (xy 165.996784 -409.061149) (xy 166.027817 -409.001426)
			(xy 166.065765 -408.94584) (xy 166.087552 -408.920188) (xy 166.093343 -408.913039) (xy 166.099859 -408.895851)
			(xy 166.100252 -408.88666) (xy 166.100252 -408.728672) (xy 166.100698 -408.718522) (xy 166.108493 -408.699778)
			(xy 166.122882 -408.685458) (xy 166.141662 -408.67775) (xy 166.151814 -408.677364) (xy 166.868094 -408.677364)
			(xy 166.878223 -408.677832) (xy 166.896949 -408.685562) (xy 166.911306 -408.699855) (xy 166.919121 -408.718545)
			(xy 166.919656 -408.728672) (xy 166.919656 -408.88666) (xy 166.920095 -408.895844) (xy 166.92659 -408.913028)
			(xy 166.932356 -408.920188) (xy 166.954156 -408.94583) (xy 166.992105 -409.001418) (xy 167.023138 -409.061143)
			(xy 167.04681 -409.124149) (xy 167.062782 -409.189532) (xy 167.070826 -409.256356) (xy 167.070824 -409.323662)
			(xy 167.062779 -409.390486) (xy 167.046805 -409.455869) (xy 167.02313 -409.518874) (xy 167.020557 -409.523826)
			(xy 168.149224 -409.523826) (xy 168.149228 -409.456519) (xy 168.157275 -409.389695) (xy 168.17325 -409.324311)
			(xy 168.196925 -409.261305) (xy 168.227961 -409.201581) (xy 168.265911 -409.145993) (xy 168.2877 -409.12034)
			(xy 168.293505 -409.1132) (xy 168.300014 -409.096006) (xy 168.3004 -409.086812) (xy 168.3004 -408.593544)
			(xy 168.299969 -408.584359) (xy 168.29347 -408.567174) (xy 168.2877 -408.560016) (xy 168.265906 -408.53437)
			(xy 168.22796 -408.478782) (xy 168.196929 -408.419057) (xy 168.173258 -408.356052) (xy 168.157287 -408.290669)
			(xy 168.149244 -408.223846) (xy 168.149245 -408.156542) (xy 168.157289 -408.089719) (xy 168.173262 -408.024337)
			(xy 168.196934 -407.961332) (xy 168.227966 -407.901608) (xy 168.265913 -407.846021) (xy 168.2877 -407.820368)
			(xy 168.293493 -407.81322) (xy 168.30001 -407.796032) (xy 168.3004 -407.78684) (xy 168.3004 -407.628852)
			(xy 168.300782 -407.618695) (xy 168.308594 -407.599941) (xy 168.323002 -407.58562) (xy 168.341802 -407.577922)
			(xy 168.351962 -407.577544) (xy 169.068242 -407.577544) (xy 169.078372 -407.577992) (xy 169.097095 -407.585735)
			(xy 169.11145 -407.600032) (xy 169.119267 -407.618724) (xy 169.119804 -407.628852) (xy 169.119804 -407.78684)
			(xy 169.120194 -407.796029) (xy 169.126721 -407.813214) (xy 169.132504 -407.820368) (xy 169.154283 -407.846027)
			(xy 169.192229 -407.901614) (xy 169.22326 -407.961337) (xy 169.246931 -408.02434) (xy 169.262904 -408.089721)
			(xy 169.270948 -408.156542) (xy 169.270948 -408.223846) (xy 169.262906 -408.290667) (xy 169.246935 -408.356048)
			(xy 169.223265 -408.419052) (xy 169.192235 -408.478776) (xy 169.15429 -408.534363) (xy 169.132504 -408.560016)
			(xy 169.126719 -408.567169) (xy 169.120197 -408.584354) (xy 169.119804 -408.593544) (xy 169.119804 -409.086812)
			(xy 169.120208 -409.096) (xy 169.126726 -409.113184) (xy 169.132504 -409.12034) (xy 169.154255 -409.146022)
			(xy 169.192202 -409.201605) (xy 169.223235 -409.261325) (xy 169.246908 -409.324325) (xy 169.262882 -409.389704)
			(xy 169.270928 -409.456522) (xy 169.270931 -409.523824) (xy 169.262891 -409.590643) (xy 169.246924 -409.656023)
			(xy 169.223257 -409.719026) (xy 169.19223 -409.778748) (xy 169.154288 -409.834335) (xy 169.132504 -409.859988)
			(xy 169.126688 -409.86712) (xy 169.120185 -409.88432) (xy 169.119804 -409.893516) (xy 169.119804 -410.051504)
			(xy 169.119382 -410.061658) (xy 169.111586 -410.08041) (xy 169.097189 -410.094733) (xy 169.078398 -410.102433)
			(xy 169.068242 -410.102812) (xy 168.351962 -410.102812) (xy 168.341839 -410.102306) (xy 168.323127 -410.094575)
			(xy 168.308774 -410.080296) (xy 168.300947 -410.061624) (xy 168.3004 -410.051504) (xy 168.3004 -409.893516)
			(xy 168.299982 -409.88433) (xy 168.293474 -409.867145) (xy 168.2877 -409.859988) (xy 168.265878 -409.834364)
			(xy 168.227933 -409.778773) (xy 168.196903 -409.719045) (xy 168.173234 -409.656037) (xy 168.157265 -409.590652)
			(xy 168.149224 -409.523826) (xy 167.020557 -409.523826) (xy 166.992095 -409.578598) (xy 166.954145 -409.634184)
			(xy 166.932356 -409.659836) (xy 166.926556 -409.666979) (xy 166.920045 -409.684171) (xy 166.919656 -409.693364)
			(xy 166.919656 -410.186632) (xy 166.920061 -410.19582) (xy 166.926579 -410.213003) (xy 166.932356 -410.22016)
			(xy 166.954128 -410.245825) (xy 166.992078 -410.30141) (xy 167.023112 -410.361131) (xy 167.046786 -410.424134)
			(xy 167.06276 -410.489515) (xy 167.070805 -410.556336) (xy 167.070807 -410.62364) (xy 167.0708 -410.623701)
			(xy 170.348846 -410.623701) (xy 170.348847 -410.556275) (xy 170.356926 -410.489335) (xy 170.372964 -410.423844)
			(xy 170.396732 -410.360747) (xy 170.427888 -410.30095) (xy 170.465981 -410.245316) (xy 170.487848 -410.219652)
			(xy 170.493653 -410.212513) (xy 170.500162 -410.195318) (xy 170.500548 -410.186124) (xy 170.500548 -409.693872)
			(xy 170.50014 -409.684685) (xy 170.493624 -409.667501) (xy 170.487848 -409.660344) (xy 170.465994 -409.63467)
			(xy 170.427902 -409.579038) (xy 170.396748 -409.519243) (xy 170.372981 -409.456147) (xy 170.356943 -409.390659)
			(xy 170.348866 -409.323721) (xy 170.348865 -409.256297) (xy 170.35694 -409.189359) (xy 170.372976 -409.12387)
			(xy 170.396741 -409.060773) (xy 170.427893 -409.000978) (xy 170.465983 -408.945344) (xy 170.487848 -408.91968)
			(xy 170.493642 -408.912533) (xy 170.500157 -408.895344) (xy 170.500548 -408.886152) (xy 170.500548 -408.728672)
			(xy 170.501061 -408.718568) (xy 170.508798 -408.699899) (xy 170.523086 -408.685607) (xy 170.541752 -408.677864)
			(xy 170.551856 -408.677364) (xy 171.268136 -408.677364) (xy 171.278243 -408.677855) (xy 171.296915 -408.685598)
			(xy 171.311207 -408.699892) (xy 171.318947 -408.718565) (xy 171.319444 -408.728672) (xy 171.319444 -408.886152)
			(xy 171.31989 -408.895335) (xy 171.32638 -408.912519) (xy 171.332144 -408.91968) (xy 171.354022 -408.945335)
			(xy 171.392114 -409.000969) (xy 171.423267 -409.060766) (xy 171.447033 -409.123865) (xy 171.463069 -409.189356)
			(xy 171.471145 -409.256296) (xy 171.471144 -409.323722) (xy 171.463066 -409.390662) (xy 171.447028 -409.456152)
			(xy 171.42326 -409.51925) (xy 171.420875 -409.523827) (xy 172.548991 -409.523827) (xy 172.548995 -409.456519)
			(xy 172.557043 -409.389693) (xy 172.573021 -409.324308) (xy 172.5967 -409.261302) (xy 172.62774 -409.201577)
			(xy 172.665697 -409.145992) (xy 172.687488 -409.12034) (xy 172.693291 -409.113199) (xy 172.699802 -409.096005)
			(xy 172.700188 -409.086812) (xy 172.700188 -408.593544) (xy 172.699759 -408.584359) (xy 172.693259 -408.567174)
			(xy 172.687488 -408.560016) (xy 172.665691 -408.534371) (xy 172.627739 -408.478785) (xy 172.596704 -408.419061)
			(xy 172.573029 -408.356055) (xy 172.557055 -408.290671) (xy 172.549011 -408.223847) (xy 172.549012 -408.156541)
			(xy 172.557057 -408.089717) (xy 172.573033 -408.024333) (xy 172.596708 -407.961328) (xy 172.627745 -407.901605)
			(xy 172.665698 -407.84602) (xy 172.687488 -407.820368) (xy 172.693279 -407.813219) (xy 172.699797 -407.796031)
			(xy 172.700188 -407.78684) (xy 172.700188 -407.628852) (xy 172.700582 -407.618696) (xy 172.708391 -407.599945)
			(xy 172.722796 -407.585624) (xy 172.741592 -407.577924) (xy 172.75175 -407.577544) (xy 173.46803 -407.577544)
			(xy 173.478159 -407.578002) (xy 173.496882 -407.58574) (xy 173.511237 -407.600035) (xy 173.519055 -407.618725)
			(xy 173.519592 -407.628852) (xy 173.519592 -407.78684) (xy 173.519985 -407.796029) (xy 173.526511 -407.813213)
			(xy 173.532292 -407.820368) (xy 173.554071 -407.846027) (xy 173.592018 -407.901613) (xy 173.62305 -407.961336)
			(xy 173.646722 -408.02434) (xy 173.662694 -408.089721) (xy 173.670739 -408.156542) (xy 173.670739 -408.223846)
			(xy 173.662697 -408.290667) (xy 173.646725 -408.356049) (xy 173.623055 -408.419053) (xy 173.592024 -408.478776)
			(xy 173.554078 -408.534363) (xy 173.532292 -408.560016) (xy 173.526505 -408.567168) (xy 173.519985 -408.584353)
			(xy 173.519592 -408.593544) (xy 173.519592 -409.086812) (xy 173.519998 -409.096) (xy 173.526515 -409.113184)
			(xy 173.532292 -409.12034) (xy 173.554043 -409.146022) (xy 173.591991 -409.201605) (xy 173.623024 -409.261324)
			(xy 173.646698 -409.324325) (xy 173.662672 -409.389703) (xy 173.670719 -409.456522) (xy 173.670722 -409.523824)
			(xy 173.662682 -409.590643) (xy 173.646714 -409.656023) (xy 173.623047 -409.719026) (xy 173.592019 -409.778749)
			(xy 173.554077 -409.834336) (xy 173.532292 -409.859988) (xy 173.526475 -409.867118) (xy 173.519973 -409.88432)
			(xy 173.519592 -409.893516) (xy 173.519592 -410.051504) (xy 173.519181 -410.061659) (xy 173.511383 -410.080413)
			(xy 173.496983 -410.094737) (xy 173.478187 -410.102435) (xy 173.46803 -410.102812) (xy 172.75175 -410.102812)
			(xy 172.741633 -410.102234) (xy 172.722923 -410.094532) (xy 172.708567 -410.080274) (xy 172.700736 -410.061618)
			(xy 172.700188 -410.051504) (xy 172.700188 -409.893516) (xy 172.699773 -409.884329) (xy 172.693263 -409.867145)
			(xy 172.687488 -409.859988) (xy 172.665663 -409.834366) (xy 172.627713 -409.778776) (xy 172.596678 -409.719049)
			(xy 172.573005 -409.65604) (xy 172.557033 -409.590654) (xy 172.548991 -409.523827) (xy 171.420875 -409.523827)
			(xy 171.392104 -409.579046) (xy 171.354011 -409.63468) (xy 171.332144 -409.660344) (xy 171.326339 -409.667483)
			(xy 171.319831 -409.684679) (xy 171.319444 -409.693872) (xy 171.319444 -410.186124) (xy 171.319855 -410.195311)
			(xy 171.32637 -410.212494) (xy 171.332144 -410.219652) (xy 171.353994 -410.245329) (xy 171.392087 -410.300961)
			(xy 171.423242 -410.360755) (xy 171.447009 -410.42385) (xy 171.463047 -410.489338) (xy 171.471125 -410.556276)
			(xy 171.471127 -410.623641) (xy 174.749166 -410.623641) (xy 174.749167 -410.556335) (xy 174.757213 -410.489511)
			(xy 174.773187 -410.424128) (xy 174.796862 -410.361123) (xy 174.827897 -410.301399) (xy 174.865847 -410.245812)
			(xy 174.887636 -410.22016) (xy 174.893437 -410.213018) (xy 174.899948 -410.195825) (xy 174.900336 -410.186632)
			(xy 174.900336 -409.693364) (xy 174.899935 -409.684176) (xy 174.893414 -409.666992) (xy 174.887636 -409.659836)
			(xy 174.86586 -409.634174) (xy 174.827911 -409.578589) (xy 174.796878 -409.518867) (xy 174.773205 -409.455863)
			(xy 174.757231 -409.390482) (xy 174.749186 -409.323661) (xy 174.749185 -409.256357) (xy 174.757228 -409.189535)
			(xy 174.773199 -409.124154) (xy 174.79687 -409.06115) (xy 174.827902 -409.001427) (xy 174.865849 -408.94584)
			(xy 174.887636 -408.920188) (xy 174.893425 -408.913037) (xy 174.899943 -408.895851) (xy 174.900336 -408.88666)
			(xy 174.900336 -408.728672) (xy 174.900699 -408.718512) (xy 174.908511 -408.699752) (xy 174.922926 -408.685428)
			(xy 174.941735 -408.677736) (xy 174.951898 -408.677364) (xy 175.668178 -408.677364) (xy 175.678306 -408.677845)
			(xy 175.697032 -408.68557) (xy 175.711389 -408.699859) (xy 175.719205 -408.718546) (xy 175.71974 -408.728672)
			(xy 175.71974 -408.88666) (xy 175.720183 -408.895843) (xy 175.726675 -408.913028) (xy 175.73244 -408.920188)
			(xy 175.75424 -408.94583) (xy 175.79219 -409.001418) (xy 175.823224 -409.061142) (xy 175.846897 -409.124148)
			(xy 175.862869 -409.189532) (xy 175.870913 -409.256356) (xy 175.870912 -409.323662) (xy 175.862866 -409.390486)
			(xy 175.846891 -409.455869) (xy 175.823216 -409.518874) (xy 175.792181 -409.578598) (xy 175.754229 -409.634184)
			(xy 175.73244 -409.659836) (xy 175.726638 -409.666977) (xy 175.720128 -409.684171) (xy 175.71974 -409.693364)
			(xy 175.71974 -410.186632) (xy 175.720148 -410.195819) (xy 175.726665 -410.213003) (xy 175.73244 -410.22016)
			(xy 175.754213 -410.245825) (xy 175.792163 -410.301409) (xy 175.823198 -410.361131) (xy 175.846873 -410.424134)
			(xy 175.862848 -410.489514) (xy 175.870893 -410.556336) (xy 175.870895 -410.62364) (xy 175.862852 -410.690462)
			(xy 175.84688 -410.755843) (xy 175.823208 -410.818847) (xy 175.792176 -410.87857) (xy 175.754227 -410.934156)
			(xy 175.73244 -410.959808) (xy 175.72665 -410.966958) (xy 175.720133 -410.984145) (xy 175.71974 -410.993336)
			(xy 175.71974 -411.151324) (xy 175.719299 -411.161475) (xy 175.711503 -411.18022) (xy 175.697113 -411.194541)
			(xy 175.678331 -411.202247) (xy 175.668178 -411.202632) (xy 174.951898 -411.202632) (xy 174.941768 -411.202174)
			(xy 174.923041 -411.194441) (xy 174.908684 -411.180145) (xy 174.90087 -411.161452) (xy 174.900336 -411.151324)
			(xy 174.900336 -410.993336) (xy 174.8999 -410.984152) (xy 174.893403 -410.966968) (xy 174.887636 -410.959808)
			(xy 174.865833 -410.934169) (xy 174.827884 -410.87858) (xy 174.796852 -410.818855) (xy 174.77318 -410.755849)
			(xy 174.757208 -410.690465) (xy 174.749166 -410.623641) (xy 171.471127 -410.623641) (xy 171.471127 -410.6237)
			(xy 171.463052 -410.690638) (xy 171.447016 -410.756127) (xy 171.423251 -410.819223) (xy 171.392099 -410.879019)
			(xy 171.354009 -410.934652) (xy 171.332144 -410.960316) (xy 171.326351 -410.967464) (xy 171.319836 -410.984653)
			(xy 171.319444 -410.993844) (xy 171.319444 -411.151324) (xy 171.318936 -411.161429) (xy 171.311198 -411.180099)
			(xy 171.296909 -411.194392) (xy 171.278241 -411.202133) (xy 171.268136 -411.202632) (xy 170.551856 -411.202632)
			(xy 170.541748 -411.202152) (xy 170.523075 -411.194405) (xy 170.508783 -411.180108) (xy 170.501044 -411.161432)
			(xy 170.500548 -411.151324) (xy 170.500548 -410.993844) (xy 170.500106 -410.98466) (xy 170.493613 -410.967476)
			(xy 170.487848 -410.960316) (xy 170.465967 -410.934665) (xy 170.427875 -410.879029) (xy 170.396723 -410.819232)
			(xy 170.372957 -410.756133) (xy 170.356921 -410.690641) (xy 170.348846 -410.623701) (xy 167.0708 -410.623701)
			(xy 167.062764 -410.690461) (xy 167.046793 -410.755843) (xy 167.023122 -410.818847) (xy 166.99209 -410.87857)
			(xy 166.954143 -410.934156) (xy 166.932356 -410.959808) (xy 166.926568 -410.966959) (xy 166.920049 -410.984145)
			(xy 166.919656 -410.993336) (xy 166.919656 -411.151324) (xy 166.919199 -411.161473) (xy 166.911406 -411.180215)
			(xy 166.897021 -411.194535) (xy 166.878245 -411.202244) (xy 166.868094 -411.202632) (xy 166.151814 -411.202632)
			(xy 166.141685 -411.202161) (xy 166.122959 -411.194433) (xy 166.108601 -411.180141) (xy 166.100786 -411.161451)
			(xy 166.100252 -411.151324) (xy 166.100252 -410.993336) (xy 166.099813 -410.984152) (xy 166.093318 -410.966968)
			(xy 166.087552 -410.959808) (xy 166.065748 -410.934169) (xy 166.027799 -410.878581) (xy 165.996765 -410.818856)
			(xy 165.973093 -410.75585) (xy 165.957121 -410.690466) (xy 165.949078 -410.623641) (xy 162.671039 -410.623641)
			(xy 162.671039 -410.6237) (xy 162.662964 -410.690637) (xy 162.646929 -410.756126) (xy 162.623165 -410.819223)
			(xy 162.592014 -410.879018) (xy 162.553924 -410.934651) (xy 162.53206 -410.960316) (xy 162.526269 -410.967465)
			(xy 162.519752 -410.984653) (xy 162.51936 -410.993844) (xy 162.51936 -411.151324) (xy 162.519003 -411.161453)
			(xy 162.511239 -411.180165) (xy 162.496904 -411.19448) (xy 162.478182 -411.202217) (xy 162.468052 -411.202632)
			(xy 161.751772 -411.202632) (xy 161.741665 -411.202139) (xy 161.722993 -411.194398) (xy 161.7087 -411.180104)
			(xy 161.700961 -411.161431) (xy 161.700464 -411.151324) (xy 161.700464 -410.993844) (xy 161.700019 -410.984661)
			(xy 161.693528 -410.967477) (xy 161.687764 -410.960316) (xy 161.665886 -410.934663) (xy 161.6278 -410.879026)
			(xy 161.596652 -410.819228) (xy 161.57289 -410.756129) (xy 161.556857 -410.690639) (xy 161.548783 -410.6237)
			(xy 154.57678 -410.6237) (xy 154.57678 -417.371276) (xy 154.576371 -417.383441) (xy 154.568857 -417.406581)
			(xy 154.554556 -417.426265) (xy 154.53487 -417.440562) (xy 154.511729 -417.448073) (xy 154.499564 -417.448492)
			(xy 141.100302 -417.448492) (xy 141.088157 -417.448035) (xy 141.06506 -417.440516) (xy 141.045426 -417.426216)
			(xy 141.031183 -417.406541) (xy 141.02373 -417.383422) (xy 141.02334 -417.371276) (xy 66.525648 -417.371276)
			(xy 66.525648 -417.533836) (xy 66.525172 -417.545883) (xy 66.517735 -417.568802) (xy 66.503597 -417.588313)
			(xy 66.484133 -417.602517) (xy 66.46124 -417.610031) (xy 66.449194 -417.610544) (xy 53.151024 -417.610544)
			(xy 53.138954 -417.610016) (xy 53.115994 -417.602564) (xy 53.09646 -417.588383) (xy 53.082263 -417.56886)
			(xy 53.074793 -417.545905) (xy 53.074316 -417.533836) (xy 53.074316 -417.289488) (xy 53.073808 -417.289488)
			(xy 0.681656 -417.289488) (xy 0.736245 -417.384039) (xy 0.79912 -417.476259) (xy 0.86871 -417.563523)
			(xy 0.944627 -417.645342) (xy 1.026446 -417.721259) (xy 1.113709 -417.790849) (xy 1.205929 -417.853724)
			(xy 1.302589 -417.909531) (xy 1.40315 -417.957958) (xy 1.507049 -417.998736) (xy 1.613704 -418.031635)
			(xy 1.72252 -418.056471) (xy 1.832887 -418.073107) (xy 1.944189 -418.081448) (xy 1.999996 -418.081968)
		)
		(stroke
			(width 0)
			(type solid)
		)
		(fill yes)
		(layer "In8.Cu")
		(net "GND")
	)
	(gr_circle
		(center 43.499786 -312.049922)
		(end 43.753786 -312.049922)
		(stroke
			(width 0.1016)
			(type default)
		)
		(fill no)
		(layer "In8.Cu")
	)
	(gr_circle
		(center 43.499786 -311.099962)
		(end 43.753786 -311.099962)
		(stroke
			(width 0.1016)
			(type default)
		)
		(fill no)
		(layer "In8.Cu")
	)
	(gr_circle
		(center 44.449746 -313.949842)
		(end 44.703746 -313.949842)
		(stroke
			(width 0.1016)
			(type default)
		)
		(fill no)
		(layer "In8.Cu")
	)
	(gr_circle
		(center 44.449746 -312.999882)
		(end 44.703746 -312.999882)
		(stroke
			(width 0.1016)
			(type default)
		)
		(fill no)
		(layer "In8.Cu")
	)
	(gr_circle
		(center 44.449746 -278.799798)
		(end 44.703746 -278.799798)
		(stroke
			(width 0.1016)
			(type default)
		)
		(fill no)
		(layer "In8.Cu")
	)
	(gr_circle
		(center 44.449746 -277.849838)
		(end 44.703746 -277.849838)
		(stroke
			(width 0.1016)
			(type default)
		)
		(fill no)
		(layer "In8.Cu")
	)
	(gr_circle
		(center 45.39996 -312.049922)
		(end 45.65396 -312.049922)
		(stroke
			(width 0.1016)
			(type default)
		)
		(fill no)
		(layer "In8.Cu")
	)
	(gr_circle
		(center 45.39996 -311.099962)
		(end 45.65396 -311.099962)
		(stroke
			(width 0.1016)
			(type default)
		)
		(fill no)
		(layer "In8.Cu")
	)
	(gr_circle
		(center 45.39996 -280.699464)
		(end 45.65396 -280.699464)
		(stroke
			(width 0.1016)
			(type default)
		)
		(fill no)
		(layer "In8.Cu")
	)
	(gr_circle
		(center 45.39996 -279.749504)
		(end 45.65396 -279.749504)
		(stroke
			(width 0.1016)
			(type default)
		)
		(fill no)
		(layer "In8.Cu")
	)
	(gr_circle
		(center 46.34992 -313.949842)
		(end 46.60392 -313.949842)
		(stroke
			(width 0.1016)
			(type default)
		)
		(fill no)
		(layer "In8.Cu")
	)
	(gr_circle
		(center 46.34992 -312.999882)
		(end 46.60392 -312.999882)
		(stroke
			(width 0.1016)
			(type default)
		)
		(fill no)
		(layer "In8.Cu")
	)
	(gr_circle
		(center 46.34992 -278.799798)
		(end 46.60392 -278.799798)
		(stroke
			(width 0.1016)
			(type default)
		)
		(fill no)
		(layer "In8.Cu")
	)
	(gr_circle
		(center 46.34992 -277.849838)
		(end 46.60392 -277.849838)
		(stroke
			(width 0.1016)
			(type default)
		)
		(fill no)
		(layer "In8.Cu")
	)
	(gr_circle
		(center 47.29988 -312.049922)
		(end 47.55388 -312.049922)
		(stroke
			(width 0.1016)
			(type default)
		)
		(fill no)
		(layer "In8.Cu")
	)
	(gr_circle
		(center 47.29988 -311.099962)
		(end 47.55388 -311.099962)
		(stroke
			(width 0.1016)
			(type default)
		)
		(fill no)
		(layer "In8.Cu")
	)
	(gr_circle
		(center 47.29988 -280.699464)
		(end 47.55388 -280.699464)
		(stroke
			(width 0.1016)
			(type default)
		)
		(fill no)
		(layer "In8.Cu")
	)
	(gr_circle
		(center 47.29988 -279.749504)
		(end 47.55388 -279.749504)
		(stroke
			(width 0.1016)
			(type default)
		)
		(fill no)
		(layer "In8.Cu")
	)
	(gr_circle
		(center 48.24984 -313.949842)
		(end 48.50384 -313.949842)
		(stroke
			(width 0.1016)
			(type default)
		)
		(fill no)
		(layer "In8.Cu")
	)
	(gr_circle
		(center 48.24984 -312.999882)
		(end 48.50384 -312.999882)
		(stroke
			(width 0.1016)
			(type default)
		)
		(fill no)
		(layer "In8.Cu")
	)
	(gr_circle
		(center 48.24984 -278.799798)
		(end 48.50384 -278.799798)
		(stroke
			(width 0.1016)
			(type default)
		)
		(fill no)
		(layer "In8.Cu")
	)
	(gr_circle
		(center 48.24984 -277.849838)
		(end 48.50384 -277.849838)
		(stroke
			(width 0.1016)
			(type default)
		)
		(fill no)
		(layer "In8.Cu")
	)
	(gr_circle
		(center 49.1998 -312.049922)
		(end 49.4538 -312.049922)
		(stroke
			(width 0.1016)
			(type default)
		)
		(fill no)
		(layer "In8.Cu")
	)
	(gr_circle
		(center 49.1998 -311.099962)
		(end 49.4538 -311.099962)
		(stroke
			(width 0.1016)
			(type default)
		)
		(fill no)
		(layer "In8.Cu")
	)
	(gr_circle
		(center 49.1998 -280.699464)
		(end 49.4538 -280.699464)
		(stroke
			(width 0.1016)
			(type default)
		)
		(fill no)
		(layer "In8.Cu")
	)
	(gr_circle
		(center 49.1998 -279.749504)
		(end 49.4538 -279.749504)
		(stroke
			(width 0.1016)
			(type default)
		)
		(fill no)
		(layer "In8.Cu")
	)
	(gr_circle
		(center 50.14976 -313.949842)
		(end 50.40376 -313.949842)
		(stroke
			(width 0.1016)
			(type default)
		)
		(fill no)
		(layer "In8.Cu")
	)
	(gr_circle
		(center 50.14976 -312.999882)
		(end 50.40376 -312.999882)
		(stroke
			(width 0.1016)
			(type default)
		)
		(fill no)
		(layer "In8.Cu")
	)
	(gr_circle
		(center 50.14976 -278.799798)
		(end 50.40376 -278.799798)
		(stroke
			(width 0.1016)
			(type default)
		)
		(fill no)
		(layer "In8.Cu")
	)
	(gr_circle
		(center 50.14976 -277.849838)
		(end 50.40376 -277.849838)
		(stroke
			(width 0.1016)
			(type default)
		)
		(fill no)
		(layer "In8.Cu")
	)
	(gr_circle
		(center 51.099974 -316.799722)
		(end 51.353974 -316.799722)
		(stroke
			(width 0.1016)
			(type default)
		)
		(fill no)
		(layer "In8.Cu")
	)
	(gr_circle
		(center 51.099974 -315.849762)
		(end 51.353974 -315.849762)
		(stroke
			(width 0.1016)
			(type default)
		)
		(fill no)
		(layer "In8.Cu")
	)
	(gr_circle
		(center 51.099974 -312.049922)
		(end 51.353974 -312.049922)
		(stroke
			(width 0.1016)
			(type default)
		)
		(fill no)
		(layer "In8.Cu")
	)
	(gr_circle
		(center 51.099974 -311.099962)
		(end 51.353974 -311.099962)
		(stroke
			(width 0.1016)
			(type default)
		)
		(fill no)
		(layer "In8.Cu")
	)
	(gr_circle
		(center 51.099974 -280.699464)
		(end 51.353974 -280.699464)
		(stroke
			(width 0.1016)
			(type default)
		)
		(fill no)
		(layer "In8.Cu")
	)
	(gr_circle
		(center 51.099974 -279.749504)
		(end 51.353974 -279.749504)
		(stroke
			(width 0.1016)
			(type default)
		)
		(fill no)
		(layer "In8.Cu")
	)
	(gr_circle
		(center 52.049934 -318.699896)
		(end 52.303934 -318.699896)
		(stroke
			(width 0.1016)
			(type default)
		)
		(fill no)
		(layer "In8.Cu")
	)
	(gr_circle
		(center 52.049934 -317.749936)
		(end 52.303934 -317.749936)
		(stroke
			(width 0.1016)
			(type default)
		)
		(fill no)
		(layer "In8.Cu")
	)
	(gr_circle
		(center 52.049934 -313.949842)
		(end 52.303934 -313.949842)
		(stroke
			(width 0.1016)
			(type default)
		)
		(fill no)
		(layer "In8.Cu")
	)
	(gr_circle
		(center 52.049934 -312.999882)
		(end 52.303934 -312.999882)
		(stroke
			(width 0.1016)
			(type default)
		)
		(fill no)
		(layer "In8.Cu")
	)
	(gr_circle
		(center 52.049934 -278.799798)
		(end 52.303934 -278.799798)
		(stroke
			(width 0.1016)
			(type default)
		)
		(fill no)
		(layer "In8.Cu")
	)
	(gr_circle
		(center 52.049934 -277.849838)
		(end 52.303934 -277.849838)
		(stroke
			(width 0.1016)
			(type default)
		)
		(fill no)
		(layer "In8.Cu")
	)
	(gr_circle
		(center 52.999894 -316.799722)
		(end 53.253894 -316.799722)
		(stroke
			(width 0.1016)
			(type default)
		)
		(fill no)
		(layer "In8.Cu")
	)
	(gr_circle
		(center 52.999894 -315.849762)
		(end 53.253894 -315.849762)
		(stroke
			(width 0.1016)
			(type default)
		)
		(fill no)
		(layer "In8.Cu")
	)
	(gr_circle
		(center 52.999894 -312.049922)
		(end 53.253894 -312.049922)
		(stroke
			(width 0.1016)
			(type default)
		)
		(fill no)
		(layer "In8.Cu")
	)
	(gr_circle
		(center 52.999894 -311.099962)
		(end 53.253894 -311.099962)
		(stroke
			(width 0.1016)
			(type default)
		)
		(fill no)
		(layer "In8.Cu")
	)
	(gr_circle
		(center 52.999894 -280.699464)
		(end 53.253894 -280.699464)
		(stroke
			(width 0.1016)
			(type default)
		)
		(fill no)
		(layer "In8.Cu")
	)
	(gr_circle
		(center 52.999894 -279.749504)
		(end 53.253894 -279.749504)
		(stroke
			(width 0.1016)
			(type default)
		)
		(fill no)
		(layer "In8.Cu")
	)
	(gr_circle
		(center 53.949854 -318.699896)
		(end 54.203854 -318.699896)
		(stroke
			(width 0.1016)
			(type default)
		)
		(fill no)
		(layer "In8.Cu")
	)
	(gr_circle
		(center 53.949854 -317.749936)
		(end 54.203854 -317.749936)
		(stroke
			(width 0.1016)
			(type default)
		)
		(fill no)
		(layer "In8.Cu")
	)
	(gr_circle
		(center 53.949854 -313.949842)
		(end 54.203854 -313.949842)
		(stroke
			(width 0.1016)
			(type default)
		)
		(fill no)
		(layer "In8.Cu")
	)
	(gr_circle
		(center 53.949854 -312.999882)
		(end 54.203854 -312.999882)
		(stroke
			(width 0.1016)
			(type default)
		)
		(fill no)
		(layer "In8.Cu")
	)
	(gr_circle
		(center 53.949854 -278.799798)
		(end 54.203854 -278.799798)
		(stroke
			(width 0.1016)
			(type default)
		)
		(fill no)
		(layer "In8.Cu")
	)
	(gr_circle
		(center 53.949854 -277.849838)
		(end 54.203854 -277.849838)
		(stroke
			(width 0.1016)
			(type default)
		)
		(fill no)
		(layer "In8.Cu")
	)
	(gr_circle
		(center 54.899814 -316.799722)
		(end 55.153814 -316.799722)
		(stroke
			(width 0.1016)
			(type default)
		)
		(fill no)
		(layer "In8.Cu")
	)
	(gr_circle
		(center 54.899814 -315.849762)
		(end 55.153814 -315.849762)
		(stroke
			(width 0.1016)
			(type default)
		)
		(fill no)
		(layer "In8.Cu")
	)
	(gr_circle
		(center 54.899814 -312.049922)
		(end 55.153814 -312.049922)
		(stroke
			(width 0.1016)
			(type default)
		)
		(fill no)
		(layer "In8.Cu")
	)
	(gr_circle
		(center 54.899814 -311.099962)
		(end 55.153814 -311.099962)
		(stroke
			(width 0.1016)
			(type default)
		)
		(fill no)
		(layer "In8.Cu")
	)
	(gr_circle
		(center 54.899814 -280.699464)
		(end 55.153814 -280.699464)
		(stroke
			(width 0.1016)
			(type default)
		)
		(fill no)
		(layer "In8.Cu")
	)
	(gr_circle
		(center 54.899814 -279.749504)
		(end 55.153814 -279.749504)
		(stroke
			(width 0.1016)
			(type default)
		)
		(fill no)
		(layer "In8.Cu")
	)
	(gr_circle
		(center 55.849774 -318.699896)
		(end 56.103774 -318.699896)
		(stroke
			(width 0.1016)
			(type default)
		)
		(fill no)
		(layer "In8.Cu")
	)
	(gr_circle
		(center 55.849774 -317.749936)
		(end 56.103774 -317.749936)
		(stroke
			(width 0.1016)
			(type default)
		)
		(fill no)
		(layer "In8.Cu")
	)
	(gr_circle
		(center 55.849774 -313.949842)
		(end 56.103774 -313.949842)
		(stroke
			(width 0.1016)
			(type default)
		)
		(fill no)
		(layer "In8.Cu")
	)
	(gr_circle
		(center 55.849774 -312.999882)
		(end 56.103774 -312.999882)
		(stroke
			(width 0.1016)
			(type default)
		)
		(fill no)
		(layer "In8.Cu")
	)
	(gr_circle
		(center 55.849774 -278.799798)
		(end 56.103774 -278.799798)
		(stroke
			(width 0.1016)
			(type default)
		)
		(fill no)
		(layer "In8.Cu")
	)
	(gr_circle
		(center 55.849774 -277.849838)
		(end 56.103774 -277.849838)
		(stroke
			(width 0.1016)
			(type default)
		)
		(fill no)
		(layer "In8.Cu")
	)
	(gr_circle
		(center 56.799734 -280.699464)
		(end 57.053734 -280.699464)
		(stroke
			(width 0.1016)
			(type default)
		)
		(fill no)
		(layer "In8.Cu")
	)
	(gr_circle
		(center 56.799734 -279.749504)
		(end 57.053734 -279.749504)
		(stroke
			(width 0.1016)
			(type default)
		)
		(fill no)
		(layer "In8.Cu")
	)
	(gr_circle
		(center 56.799988 -316.799722)
		(end 57.053988 -316.799722)
		(stroke
			(width 0.1016)
			(type default)
		)
		(fill no)
		(layer "In8.Cu")
	)
	(gr_circle
		(center 56.799988 -315.849762)
		(end 57.053988 -315.849762)
		(stroke
			(width 0.1016)
			(type default)
		)
		(fill no)
		(layer "In8.Cu")
	)
	(gr_circle
		(center 56.799988 -312.049922)
		(end 57.053988 -312.049922)
		(stroke
			(width 0.1016)
			(type default)
		)
		(fill no)
		(layer "In8.Cu")
	)
	(gr_circle
		(center 56.799988 -311.099962)
		(end 57.053988 -311.099962)
		(stroke
			(width 0.1016)
			(type default)
		)
		(fill no)
		(layer "In8.Cu")
	)
	(gr_circle
		(center 57.749948 -318.699896)
		(end 58.003948 -318.699896)
		(stroke
			(width 0.1016)
			(type default)
		)
		(fill no)
		(layer "In8.Cu")
	)
	(gr_circle
		(center 57.749948 -317.749936)
		(end 58.003948 -317.749936)
		(stroke
			(width 0.1016)
			(type default)
		)
		(fill no)
		(layer "In8.Cu")
	)
	(gr_circle
		(center 57.749948 -313.949842)
		(end 58.003948 -313.949842)
		(stroke
			(width 0.1016)
			(type default)
		)
		(fill no)
		(layer "In8.Cu")
	)
	(gr_circle
		(center 57.749948 -312.999882)
		(end 58.003948 -312.999882)
		(stroke
			(width 0.1016)
			(type default)
		)
		(fill no)
		(layer "In8.Cu")
	)
	(gr_circle
		(center 57.749948 -278.799798)
		(end 58.003948 -278.799798)
		(stroke
			(width 0.1016)
			(type default)
		)
		(fill no)
		(layer "In8.Cu")
	)
	(gr_circle
		(center 57.749948 -277.849838)
		(end 58.003948 -277.849838)
		(stroke
			(width 0.1016)
			(type default)
		)
		(fill no)
		(layer "In8.Cu")
	)
	(gr_circle
		(center 58.699908 -316.799722)
		(end 58.953908 -316.799722)
		(stroke
			(width 0.1016)
			(type default)
		)
		(fill no)
		(layer "In8.Cu")
	)
	(gr_circle
		(center 58.699908 -315.849762)
		(end 58.953908 -315.849762)
		(stroke
			(width 0.1016)
			(type default)
		)
		(fill no)
		(layer "In8.Cu")
	)
	(gr_circle
		(center 58.699908 -280.699464)
		(end 58.953908 -280.699464)
		(stroke
			(width 0.1016)
			(type default)
		)
		(fill no)
		(layer "In8.Cu")
	)
	(gr_circle
		(center 58.699908 -279.749504)
		(end 58.953908 -279.749504)
		(stroke
			(width 0.1016)
			(type default)
		)
		(fill no)
		(layer "In8.Cu")
	)
	(gr_circle
		(center 59.649614 -278.799798)
		(end 59.903614 -278.799798)
		(stroke
			(width 0.1016)
			(type default)
		)
		(fill no)
		(layer "In8.Cu")
	)
	(gr_circle
		(center 59.649614 -277.849838)
		(end 59.903614 -277.849838)
		(stroke
			(width 0.1016)
			(type default)
		)
		(fill no)
		(layer "In8.Cu")
	)
	(gr_circle
		(center 59.649868 -318.699896)
		(end 59.903868 -318.699896)
		(stroke
			(width 0.1016)
			(type default)
		)
		(fill no)
		(layer "In8.Cu")
	)
	(gr_circle
		(center 59.649868 -317.749936)
		(end 59.903868 -317.749936)
		(stroke
			(width 0.1016)
			(type default)
		)
		(fill no)
		(layer "In8.Cu")
	)
	(gr_circle
		(center 60.599828 -316.799722)
		(end 60.853828 -316.799722)
		(stroke
			(width 0.1016)
			(type default)
		)
		(fill no)
		(layer "In8.Cu")
	)
	(gr_circle
		(center 60.599828 -315.849762)
		(end 60.853828 -315.849762)
		(stroke
			(width 0.1016)
			(type default)
		)
		(fill no)
		(layer "In8.Cu")
	)
	(gr_circle
		(center 60.599828 -280.699464)
		(end 60.853828 -280.699464)
		(stroke
			(width 0.1016)
			(type default)
		)
		(fill no)
		(layer "In8.Cu")
	)
	(gr_circle
		(center 60.599828 -279.749504)
		(end 60.853828 -279.749504)
		(stroke
			(width 0.1016)
			(type default)
		)
		(fill no)
		(layer "In8.Cu")
	)
	(gr_circle
		(center 61.549534 -278.799798)
		(end 61.803534 -278.799798)
		(stroke
			(width 0.1016)
			(type default)
		)
		(fill no)
		(layer "In8.Cu")
	)
	(gr_circle
		(center 61.549534 -277.849838)
		(end 61.803534 -277.849838)
		(stroke
			(width 0.1016)
			(type default)
		)
		(fill no)
		(layer "In8.Cu")
	)
	(gr_circle
		(center 61.549788 -318.699896)
		(end 61.803788 -318.699896)
		(stroke
			(width 0.1016)
			(type default)
		)
		(fill no)
		(layer "In8.Cu")
	)
	(gr_circle
		(center 61.549788 -317.749936)
		(end 61.803788 -317.749936)
		(stroke
			(width 0.1016)
			(type default)
		)
		(fill no)
		(layer "In8.Cu")
	)
	(gr_circle
		(center 62.499748 -316.799722)
		(end 62.753748 -316.799722)
		(stroke
			(width 0.1016)
			(type default)
		)
		(fill no)
		(layer "In8.Cu")
	)
	(gr_circle
		(center 62.499748 -315.849762)
		(end 62.753748 -315.849762)
		(stroke
			(width 0.1016)
			(type default)
		)
		(fill no)
		(layer "In8.Cu")
	)
	(gr_circle
		(center 62.499748 -280.699464)
		(end 62.753748 -280.699464)
		(stroke
			(width 0.1016)
			(type default)
		)
		(fill no)
		(layer "In8.Cu")
	)
	(gr_circle
		(center 62.499748 -279.749504)
		(end 62.753748 -279.749504)
		(stroke
			(width 0.1016)
			(type default)
		)
		(fill no)
		(layer "In8.Cu")
	)
	(gr_circle
		(center 63.449708 -278.799798)
		(end 63.703708 -278.799798)
		(stroke
			(width 0.1016)
			(type default)
		)
		(fill no)
		(layer "In8.Cu")
	)
	(gr_circle
		(center 63.449708 -277.849838)
		(end 63.703708 -277.849838)
		(stroke
			(width 0.1016)
			(type default)
		)
		(fill no)
		(layer "In8.Cu")
	)
	(gr_circle
		(center 63.449962 -318.699896)
		(end 63.703962 -318.699896)
		(stroke
			(width 0.1016)
			(type default)
		)
		(fill no)
		(layer "In8.Cu")
	)
	(gr_circle
		(center 63.449962 -317.749936)
		(end 63.703962 -317.749936)
		(stroke
			(width 0.1016)
			(type default)
		)
		(fill no)
		(layer "In8.Cu")
	)
	(gr_circle
		(center 64.399922 -316.799722)
		(end 64.653922 -316.799722)
		(stroke
			(width 0.1016)
			(type default)
		)
		(fill no)
		(layer "In8.Cu")
	)
	(gr_circle
		(center 64.399922 -315.849762)
		(end 64.653922 -315.849762)
		(stroke
			(width 0.1016)
			(type default)
		)
		(fill no)
		(layer "In8.Cu")
	)
	(gr_circle
		(center 64.399922 -280.699464)
		(end 64.653922 -280.699464)
		(stroke
			(width 0.1016)
			(type default)
		)
		(fill no)
		(layer "In8.Cu")
	)
	(gr_circle
		(center 64.399922 -279.749504)
		(end 64.653922 -279.749504)
		(stroke
			(width 0.1016)
			(type default)
		)
		(fill no)
		(layer "In8.Cu")
	)
	(gr_circle
		(center 65.349628 -278.799798)
		(end 65.603628 -278.799798)
		(stroke
			(width 0.1016)
			(type default)
		)
		(fill no)
		(layer "In8.Cu")
	)
	(gr_circle
		(center 65.349628 -277.849838)
		(end 65.603628 -277.849838)
		(stroke
			(width 0.1016)
			(type default)
		)
		(fill no)
		(layer "In8.Cu")
	)
	(gr_circle
		(center 65.349882 -318.699896)
		(end 65.603882 -318.699896)
		(stroke
			(width 0.1016)
			(type default)
		)
		(fill no)
		(layer "In8.Cu")
	)
	(gr_circle
		(center 65.349882 -317.749936)
		(end 65.603882 -317.749936)
		(stroke
			(width 0.1016)
			(type default)
		)
		(fill no)
		(layer "In8.Cu")
	)
	(gr_circle
		(center 66.299842 -280.699464)
		(end 66.553842 -280.699464)
		(stroke
			(width 0.1016)
			(type default)
		)
		(fill no)
		(layer "In8.Cu")
	)
	(gr_circle
		(center 66.299842 -279.749504)
		(end 66.553842 -279.749504)
		(stroke
			(width 0.1016)
			(type default)
		)
		(fill no)
		(layer "In8.Cu")
	)
	(gr_circle
		(center 67.249548 -278.799798)
		(end 67.503548 -278.799798)
		(stroke
			(width 0.1016)
			(type default)
		)
		(fill no)
		(layer "In8.Cu")
	)
	(gr_circle
		(center 67.249548 -277.849838)
		(end 67.503548 -277.849838)
		(stroke
			(width 0.1016)
			(type default)
		)
		(fill no)
		(layer "In8.Cu")
	)
	(gr_circle
		(center 68.199762 -280.699464)
		(end 68.453762 -280.699464)
		(stroke
			(width 0.1016)
			(type default)
		)
		(fill no)
		(layer "In8.Cu")
	)
	(gr_circle
		(center 68.199762 -279.749504)
		(end 68.453762 -279.749504)
		(stroke
			(width 0.1016)
			(type default)
		)
		(fill no)
		(layer "In8.Cu")
	)
	(gr_circle
		(center 69.149722 -278.799798)
		(end 69.403722 -278.799798)
		(stroke
			(width 0.1016)
			(type default)
		)
		(fill no)
		(layer "In8.Cu")
	)
	(gr_circle
		(center 69.149722 -277.849838)
		(end 69.403722 -277.849838)
		(stroke
			(width 0.1016)
			(type default)
		)
		(fill no)
		(layer "In8.Cu")
	)
	(gr_circle
		(center 70.099936 -280.699464)
		(end 70.353936 -280.699464)
		(stroke
			(width 0.1016)
			(type default)
		)
		(fill no)
		(layer "In8.Cu")
	)
	(gr_circle
		(center 70.099936 -279.749504)
		(end 70.353936 -279.749504)
		(stroke
			(width 0.1016)
			(type default)
		)
		(fill no)
		(layer "In8.Cu")
	)
	(gr_circle
		(center 71.049642 -278.799798)
		(end 71.303642 -278.799798)
		(stroke
			(width 0.1016)
			(type default)
		)
		(fill no)
		(layer "In8.Cu")
	)
	(gr_circle
		(center 71.049642 -277.849838)
		(end 71.303642 -277.849838)
		(stroke
			(width 0.1016)
			(type default)
		)
		(fill no)
		(layer "In8.Cu")
	)
	(gr_circle
		(center 71.999856 -280.699464)
		(end 72.253856 -280.699464)
		(stroke
			(width 0.1016)
			(type default)
		)
		(fill no)
		(layer "In8.Cu")
	)
	(gr_circle
		(center 71.999856 -279.749504)
		(end 72.253856 -279.749504)
		(stroke
			(width 0.1016)
			(type default)
		)
		(fill no)
		(layer "In8.Cu")
	)
	(gr_circle
		(center 72.949562 -278.799798)
		(end 73.203562 -278.799798)
		(stroke
			(width 0.1016)
			(type default)
		)
		(fill no)
		(layer "In8.Cu")
	)
	(gr_circle
		(center 72.949562 -277.849838)
		(end 73.203562 -277.849838)
		(stroke
			(width 0.1016)
			(type default)
		)
		(fill no)
		(layer "In8.Cu")
	)
	(gr_circle
		(center 73.899776 -316.799722)
		(end 74.153776 -316.799722)
		(stroke
			(width 0.1016)
			(type default)
		)
		(fill no)
		(layer "In8.Cu")
	)
	(gr_circle
		(center 73.899776 -315.849762)
		(end 74.153776 -315.849762)
		(stroke
			(width 0.1016)
			(type default)
		)
		(fill no)
		(layer "In8.Cu")
	)
	(gr_circle
		(center 73.899776 -312.049922)
		(end 74.153776 -312.049922)
		(stroke
			(width 0.1016)
			(type default)
		)
		(fill no)
		(layer "In8.Cu")
	)
	(gr_circle
		(center 73.899776 -311.099962)
		(end 74.153776 -311.099962)
		(stroke
			(width 0.1016)
			(type default)
		)
		(fill no)
		(layer "In8.Cu")
	)
	(gr_circle
		(center 73.899776 -280.699464)
		(end 74.153776 -280.699464)
		(stroke
			(width 0.1016)
			(type default)
		)
		(fill no)
		(layer "In8.Cu")
	)
	(gr_circle
		(center 73.899776 -279.749504)
		(end 74.153776 -279.749504)
		(stroke
			(width 0.1016)
			(type default)
		)
		(fill no)
		(layer "In8.Cu")
	)
	(gr_circle
		(center 74.849736 -278.799798)
		(end 75.103736 -278.799798)
		(stroke
			(width 0.1016)
			(type default)
		)
		(fill no)
		(layer "In8.Cu")
	)
	(gr_circle
		(center 74.849736 -277.849838)
		(end 75.103736 -277.849838)
		(stroke
			(width 0.1016)
			(type default)
		)
		(fill no)
		(layer "In8.Cu")
	)
	(gr_circle
		(center 74.84999 -318.699896)
		(end 75.10399 -318.699896)
		(stroke
			(width 0.1016)
			(type default)
		)
		(fill no)
		(layer "In8.Cu")
	)
	(gr_circle
		(center 74.84999 -317.749936)
		(end 75.10399 -317.749936)
		(stroke
			(width 0.1016)
			(type default)
		)
		(fill no)
		(layer "In8.Cu")
	)
	(gr_circle
		(center 74.84999 -313.949842)
		(end 75.10399 -313.949842)
		(stroke
			(width 0.1016)
			(type default)
		)
		(fill no)
		(layer "In8.Cu")
	)
	(gr_circle
		(center 74.84999 -312.999882)
		(end 75.10399 -312.999882)
		(stroke
			(width 0.1016)
			(type default)
		)
		(fill no)
		(layer "In8.Cu")
	)
	(gr_circle
		(center 74.84999 -308.249828)
		(end 75.10399 -308.249828)
		(stroke
			(width 0.1016)
			(type default)
		)
		(fill no)
		(layer "In8.Cu")
	)
	(gr_circle
		(center 74.84999 -306.349908)
		(end 75.10399 -306.349908)
		(stroke
			(width 0.1016)
			(type default)
		)
		(fill no)
		(layer "In8.Cu")
	)
	(gr_circle
		(center 74.84999 -304.449734)
		(end 75.10399 -304.449734)
		(stroke
			(width 0.1016)
			(type default)
		)
		(fill no)
		(layer "In8.Cu")
	)
	(gr_circle
		(center 74.84999 -287.349946)
		(end 75.10399 -287.349946)
		(stroke
			(width 0.1016)
			(type default)
		)
		(fill no)
		(layer "In8.Cu")
	)
	(gr_circle
		(center 74.84999 -285.449772)
		(end 75.10399 -285.449772)
		(stroke
			(width 0.1016)
			(type default)
		)
		(fill no)
		(layer "In8.Cu")
	)
	(gr_circle
		(center 74.84999 -283.549852)
		(end 75.10399 -283.549852)
		(stroke
			(width 0.1016)
			(type default)
		)
		(fill no)
		(layer "In8.Cu")
	)
	(gr_circle
		(center 75.79995 -316.799722)
		(end 76.05395 -316.799722)
		(stroke
			(width 0.1016)
			(type default)
		)
		(fill no)
		(layer "In8.Cu")
	)
	(gr_circle
		(center 75.79995 -315.849762)
		(end 76.05395 -315.849762)
		(stroke
			(width 0.1016)
			(type default)
		)
		(fill no)
		(layer "In8.Cu")
	)
	(gr_circle
		(center 75.79995 -312.049922)
		(end 76.05395 -312.049922)
		(stroke
			(width 0.1016)
			(type default)
		)
		(fill no)
		(layer "In8.Cu")
	)
	(gr_circle
		(center 75.79995 -311.099962)
		(end 76.05395 -311.099962)
		(stroke
			(width 0.1016)
			(type default)
		)
		(fill no)
		(layer "In8.Cu")
	)
	(gr_circle
		(center 75.79995 -308.249828)
		(end 76.05395 -308.249828)
		(stroke
			(width 0.1016)
			(type default)
		)
		(fill no)
		(layer "In8.Cu")
	)
	(gr_circle
		(center 75.79995 -306.349908)
		(end 76.05395 -306.349908)
		(stroke
			(width 0.1016)
			(type default)
		)
		(fill no)
		(layer "In8.Cu")
	)
	(gr_circle
		(center 75.79995 -304.449734)
		(end 76.05395 -304.449734)
		(stroke
			(width 0.1016)
			(type default)
		)
		(fill no)
		(layer "In8.Cu")
	)
	(gr_circle
		(center 75.79995 -287.349946)
		(end 76.05395 -287.349946)
		(stroke
			(width 0.1016)
			(type default)
		)
		(fill no)
		(layer "In8.Cu")
	)
	(gr_circle
		(center 75.79995 -285.449772)
		(end 76.05395 -285.449772)
		(stroke
			(width 0.1016)
			(type default)
		)
		(fill no)
		(layer "In8.Cu")
	)
	(gr_circle
		(center 75.79995 -283.549852)
		(end 76.05395 -283.549852)
		(stroke
			(width 0.1016)
			(type default)
		)
		(fill no)
		(layer "In8.Cu")
	)
	(gr_circle
		(center 75.79995 -280.699464)
		(end 76.05395 -280.699464)
		(stroke
			(width 0.1016)
			(type default)
		)
		(fill no)
		(layer "In8.Cu")
	)
	(gr_circle
		(center 75.79995 -279.749504)
		(end 76.05395 -279.749504)
		(stroke
			(width 0.1016)
			(type default)
		)
		(fill no)
		(layer "In8.Cu")
	)
	(gr_circle
		(center 76.749656 -278.799798)
		(end 77.003656 -278.799798)
		(stroke
			(width 0.1016)
			(type default)
		)
		(fill no)
		(layer "In8.Cu")
	)
	(gr_circle
		(center 76.749656 -277.849838)
		(end 77.003656 -277.849838)
		(stroke
			(width 0.1016)
			(type default)
		)
		(fill no)
		(layer "In8.Cu")
	)
	(gr_circle
		(center 76.74991 -318.699896)
		(end 77.00391 -318.699896)
		(stroke
			(width 0.1016)
			(type default)
		)
		(fill no)
		(layer "In8.Cu")
	)
	(gr_circle
		(center 76.74991 -317.749936)
		(end 77.00391 -317.749936)
		(stroke
			(width 0.1016)
			(type default)
		)
		(fill no)
		(layer "In8.Cu")
	)
	(gr_circle
		(center 76.74991 -313.949842)
		(end 77.00391 -313.949842)
		(stroke
			(width 0.1016)
			(type default)
		)
		(fill no)
		(layer "In8.Cu")
	)
	(gr_circle
		(center 76.74991 -312.999882)
		(end 77.00391 -312.999882)
		(stroke
			(width 0.1016)
			(type default)
		)
		(fill no)
		(layer "In8.Cu")
	)
	(gr_circle
		(center 76.74991 -309.199788)
		(end 77.00391 -309.199788)
		(stroke
			(width 0.1016)
			(type default)
		)
		(fill no)
		(layer "In8.Cu")
	)
	(gr_circle
		(center 76.74991 -307.299868)
		(end 77.00391 -307.299868)
		(stroke
			(width 0.1016)
			(type default)
		)
		(fill no)
		(layer "In8.Cu")
	)
	(gr_circle
		(center 76.74991 -305.399948)
		(end 77.00391 -305.399948)
		(stroke
			(width 0.1016)
			(type default)
		)
		(fill no)
		(layer "In8.Cu")
	)
	(gr_circle
		(center 76.74991 -288.299906)
		(end 77.00391 -288.299906)
		(stroke
			(width 0.1016)
			(type default)
		)
		(fill no)
		(layer "In8.Cu")
	)
	(gr_circle
		(center 76.74991 -286.399986)
		(end 77.00391 -286.399986)
		(stroke
			(width 0.1016)
			(type default)
		)
		(fill no)
		(layer "In8.Cu")
	)
	(gr_circle
		(center 76.74991 -284.499812)
		(end 77.00391 -284.499812)
		(stroke
			(width 0.1016)
			(type default)
		)
		(fill no)
		(layer "In8.Cu")
	)
	(gr_circle
		(center 76.74991 -282.599892)
		(end 77.00391 -282.599892)
		(stroke
			(width 0.1016)
			(type default)
		)
		(fill no)
		(layer "In8.Cu")
	)
	(gr_circle
		(center 77.69987 -316.799722)
		(end 77.95387 -316.799722)
		(stroke
			(width 0.1016)
			(type default)
		)
		(fill no)
		(layer "In8.Cu")
	)
	(gr_circle
		(center 77.69987 -315.849762)
		(end 77.95387 -315.849762)
		(stroke
			(width 0.1016)
			(type default)
		)
		(fill no)
		(layer "In8.Cu")
	)
	(gr_circle
		(center 77.69987 -312.049922)
		(end 77.95387 -312.049922)
		(stroke
			(width 0.1016)
			(type default)
		)
		(fill no)
		(layer "In8.Cu")
	)
	(gr_circle
		(center 77.69987 -311.099962)
		(end 77.95387 -311.099962)
		(stroke
			(width 0.1016)
			(type default)
		)
		(fill no)
		(layer "In8.Cu")
	)
	(gr_circle
		(center 77.69987 -309.199788)
		(end 77.95387 -309.199788)
		(stroke
			(width 0.1016)
			(type default)
		)
		(fill no)
		(layer "In8.Cu")
	)
	(gr_circle
		(center 77.69987 -307.299868)
		(end 77.95387 -307.299868)
		(stroke
			(width 0.1016)
			(type default)
		)
		(fill no)
		(layer "In8.Cu")
	)
	(gr_circle
		(center 77.69987 -305.399948)
		(end 77.95387 -305.399948)
		(stroke
			(width 0.1016)
			(type default)
		)
		(fill no)
		(layer "In8.Cu")
	)
	(gr_circle
		(center 77.69987 -288.299906)
		(end 77.95387 -288.299906)
		(stroke
			(width 0.1016)
			(type default)
		)
		(fill no)
		(layer "In8.Cu")
	)
	(gr_circle
		(center 77.69987 -286.399986)
		(end 77.95387 -286.399986)
		(stroke
			(width 0.1016)
			(type default)
		)
		(fill no)
		(layer "In8.Cu")
	)
	(gr_circle
		(center 77.69987 -284.499812)
		(end 77.95387 -284.499812)
		(stroke
			(width 0.1016)
			(type default)
		)
		(fill no)
		(layer "In8.Cu")
	)
	(gr_circle
		(center 77.69987 -282.599892)
		(end 77.95387 -282.599892)
		(stroke
			(width 0.1016)
			(type default)
		)
		(fill no)
		(layer "In8.Cu")
	)
	(gr_circle
		(center 77.69987 -280.699464)
		(end 77.95387 -280.699464)
		(stroke
			(width 0.1016)
			(type default)
		)
		(fill no)
		(layer "In8.Cu")
	)
	(gr_circle
		(center 77.69987 -279.749504)
		(end 77.95387 -279.749504)
		(stroke
			(width 0.1016)
			(type default)
		)
		(fill no)
		(layer "In8.Cu")
	)
	(gr_circle
		(center 78.649576 -278.799798)
		(end 78.903576 -278.799798)
		(stroke
			(width 0.1016)
			(type default)
		)
		(fill no)
		(layer "In8.Cu")
	)
	(gr_circle
		(center 78.649576 -277.849838)
		(end 78.903576 -277.849838)
		(stroke
			(width 0.1016)
			(type default)
		)
		(fill no)
		(layer "In8.Cu")
	)
	(gr_circle
		(center 78.64983 -318.699896)
		(end 78.90383 -318.699896)
		(stroke
			(width 0.1016)
			(type default)
		)
		(fill no)
		(layer "In8.Cu")
	)
	(gr_circle
		(center 78.64983 -317.749936)
		(end 78.90383 -317.749936)
		(stroke
			(width 0.1016)
			(type default)
		)
		(fill no)
		(layer "In8.Cu")
	)
	(gr_circle
		(center 78.64983 -313.949842)
		(end 78.90383 -313.949842)
		(stroke
			(width 0.1016)
			(type default)
		)
		(fill no)
		(layer "In8.Cu")
	)
	(gr_circle
		(center 78.64983 -312.999882)
		(end 78.90383 -312.999882)
		(stroke
			(width 0.1016)
			(type default)
		)
		(fill no)
		(layer "In8.Cu")
	)
	(gr_circle
		(center 79.59979 -316.799722)
		(end 79.85379 -316.799722)
		(stroke
			(width 0.1016)
			(type default)
		)
		(fill no)
		(layer "In8.Cu")
	)
	(gr_circle
		(center 79.59979 -315.849762)
		(end 79.85379 -315.849762)
		(stroke
			(width 0.1016)
			(type default)
		)
		(fill no)
		(layer "In8.Cu")
	)
	(gr_circle
		(center 79.59979 -312.049922)
		(end 79.85379 -312.049922)
		(stroke
			(width 0.1016)
			(type default)
		)
		(fill no)
		(layer "In8.Cu")
	)
	(gr_circle
		(center 79.59979 -311.099962)
		(end 79.85379 -311.099962)
		(stroke
			(width 0.1016)
			(type default)
		)
		(fill no)
		(layer "In8.Cu")
	)
	(gr_circle
		(center 79.59979 -309.199788)
		(end 79.85379 -309.199788)
		(stroke
			(width 0.1016)
			(type default)
		)
		(fill no)
		(layer "In8.Cu")
	)
	(gr_circle
		(center 79.59979 -307.299868)
		(end 79.85379 -307.299868)
		(stroke
			(width 0.1016)
			(type default)
		)
		(fill no)
		(layer "In8.Cu")
	)
	(gr_circle
		(center 79.59979 -305.399948)
		(end 79.85379 -305.399948)
		(stroke
			(width 0.1016)
			(type default)
		)
		(fill no)
		(layer "In8.Cu")
	)
	(gr_circle
		(center 79.59979 -280.699718)
		(end 79.85379 -280.699718)
		(stroke
			(width 0.1016)
			(type default)
		)
		(fill no)
		(layer "In8.Cu")
	)
	(gr_circle
		(center 79.59979 -279.749758)
		(end 79.85379 -279.749758)
		(stroke
			(width 0.1016)
			(type default)
		)
		(fill no)
		(layer "In8.Cu")
	)
	(gr_circle
		(center 80.54975 -318.699896)
		(end 80.80375 -318.699896)
		(stroke
			(width 0.1016)
			(type default)
		)
		(fill no)
		(layer "In8.Cu")
	)
	(gr_circle
		(center 80.54975 -317.749936)
		(end 80.80375 -317.749936)
		(stroke
			(width 0.1016)
			(type default)
		)
		(fill no)
		(layer "In8.Cu")
	)
	(gr_circle
		(center 80.54975 -313.949842)
		(end 80.80375 -313.949842)
		(stroke
			(width 0.1016)
			(type default)
		)
		(fill no)
		(layer "In8.Cu")
	)
	(gr_circle
		(center 80.54975 -312.999882)
		(end 80.80375 -312.999882)
		(stroke
			(width 0.1016)
			(type default)
		)
		(fill no)
		(layer "In8.Cu")
	)
	(gr_circle
		(center 80.54975 -309.199788)
		(end 80.80375 -309.199788)
		(stroke
			(width 0.1016)
			(type default)
		)
		(fill no)
		(layer "In8.Cu")
	)
	(gr_circle
		(center 80.54975 -307.299868)
		(end 80.80375 -307.299868)
		(stroke
			(width 0.1016)
			(type default)
		)
		(fill no)
		(layer "In8.Cu")
	)
	(gr_circle
		(center 80.54975 -305.399948)
		(end 80.80375 -305.399948)
		(stroke
			(width 0.1016)
			(type default)
		)
		(fill no)
		(layer "In8.Cu")
	)
	(gr_circle
		(center 80.54975 -278.799798)
		(end 80.80375 -278.799798)
		(stroke
			(width 0.1016)
			(type default)
		)
		(fill no)
		(layer "In8.Cu")
	)
	(gr_circle
		(center 80.54975 -277.849838)
		(end 80.80375 -277.849838)
		(stroke
			(width 0.1016)
			(type default)
		)
		(fill no)
		(layer "In8.Cu")
	)
	(gr_circle
		(center 81.499964 -316.799722)
		(end 81.753964 -316.799722)
		(stroke
			(width 0.1016)
			(type default)
		)
		(fill no)
		(layer "In8.Cu")
	)
	(gr_circle
		(center 81.499964 -314.899802)
		(end 81.753964 -314.899802)
		(stroke
			(width 0.1016)
			(type default)
		)
		(fill no)
		(layer "In8.Cu")
	)
	(gr_circle
		(center 81.499964 -312.049922)
		(end 81.753964 -312.049922)
		(stroke
			(width 0.1016)
			(type default)
		)
		(fill no)
		(layer "In8.Cu")
	)
	(gr_circle
		(center 81.499964 -310.149748)
		(end 81.753964 -310.149748)
		(stroke
			(width 0.1016)
			(type default)
		)
		(fill no)
		(layer "In8.Cu")
	)
	(gr_circle
		(center 81.499964 -308.249828)
		(end 81.753964 -308.249828)
		(stroke
			(width 0.1016)
			(type default)
		)
		(fill no)
		(layer "In8.Cu")
	)
	(gr_circle
		(center 81.499964 -306.349908)
		(end 81.753964 -306.349908)
		(stroke
			(width 0.1016)
			(type default)
		)
		(fill no)
		(layer "In8.Cu")
	)
	(gr_circle
		(center 81.499964 -304.449734)
		(end 81.753964 -304.449734)
		(stroke
			(width 0.1016)
			(type default)
		)
		(fill no)
		(layer "In8.Cu")
	)
	(gr_circle
		(center 81.499964 -279.749758)
		(end 81.753964 -279.749758)
		(stroke
			(width 0.1016)
			(type default)
		)
		(fill no)
		(layer "In8.Cu")
	)
	(gr_circle
		(center 81.499964 -276.899878)
		(end 81.753964 -276.899878)
		(stroke
			(width 0.1016)
			(type default)
		)
		(fill no)
		(layer "In8.Cu")
	)
	(gr_circle
		(center 82.449924 -316.799722)
		(end 82.703924 -316.799722)
		(stroke
			(width 0.1016)
			(type default)
		)
		(fill no)
		(layer "In8.Cu")
	)
	(gr_circle
		(center 82.449924 -314.899802)
		(end 82.703924 -314.899802)
		(stroke
			(width 0.1016)
			(type default)
		)
		(fill no)
		(layer "In8.Cu")
	)
	(gr_circle
		(center 82.449924 -312.049922)
		(end 82.703924 -312.049922)
		(stroke
			(width 0.1016)
			(type default)
		)
		(fill no)
		(layer "In8.Cu")
	)
	(gr_circle
		(center 82.449924 -310.149748)
		(end 82.703924 -310.149748)
		(stroke
			(width 0.1016)
			(type default)
		)
		(fill no)
		(layer "In8.Cu")
	)
	(gr_circle
		(center 82.449924 -308.249828)
		(end 82.703924 -308.249828)
		(stroke
			(width 0.1016)
			(type default)
		)
		(fill no)
		(layer "In8.Cu")
	)
	(gr_circle
		(center 82.449924 -306.349908)
		(end 82.703924 -306.349908)
		(stroke
			(width 0.1016)
			(type default)
		)
		(fill no)
		(layer "In8.Cu")
	)
	(gr_circle
		(center 82.449924 -304.449734)
		(end 82.703924 -304.449734)
		(stroke
			(width 0.1016)
			(type default)
		)
		(fill no)
		(layer "In8.Cu")
	)
	(gr_circle
		(center 82.449924 -279.749758)
		(end 82.703924 -279.749758)
		(stroke
			(width 0.1016)
			(type default)
		)
		(fill no)
		(layer "In8.Cu")
	)
	(gr_circle
		(center 82.449924 -276.899878)
		(end 82.703924 -276.899878)
		(stroke
			(width 0.1016)
			(type default)
		)
		(fill no)
		(layer "In8.Cu")
	)
	(gr_circle
		(center 152.94991 -316.799722)
		(end 153.20391 -316.799722)
		(stroke
			(width 0.1016)
			(type default)
		)
		(fill no)
		(layer "In8.Cu")
	)
	(gr_circle
		(center 152.94991 -314.899802)
		(end 153.20391 -314.899802)
		(stroke
			(width 0.1016)
			(type default)
		)
		(fill no)
		(layer "In8.Cu")
	)
	(gr_circle
		(center 152.94991 -312.049922)
		(end 153.20391 -312.049922)
		(stroke
			(width 0.1016)
			(type default)
		)
		(fill no)
		(layer "In8.Cu")
	)
	(gr_circle
		(center 152.94991 -310.149748)
		(end 153.20391 -310.149748)
		(stroke
			(width 0.1016)
			(type default)
		)
		(fill no)
		(layer "In8.Cu")
	)
	(gr_circle
		(center 152.94991 -308.249828)
		(end 153.20391 -308.249828)
		(stroke
			(width 0.1016)
			(type default)
		)
		(fill no)
		(layer "In8.Cu")
	)
	(gr_circle
		(center 152.94991 -306.349908)
		(end 153.20391 -306.349908)
		(stroke
			(width 0.1016)
			(type default)
		)
		(fill no)
		(layer "In8.Cu")
	)
	(gr_circle
		(center 152.94991 -304.449734)
		(end 153.20391 -304.449734)
		(stroke
			(width 0.1016)
			(type default)
		)
		(fill no)
		(layer "In8.Cu")
	)
	(gr_circle
		(center 152.94991 -302.549814)
		(end 153.20391 -302.549814)
		(stroke
			(width 0.1016)
			(type default)
		)
		(fill no)
		(layer "In8.Cu")
	)
	(gr_circle
		(center 153.89987 -316.799722)
		(end 154.15387 -316.799722)
		(stroke
			(width 0.1016)
			(type default)
		)
		(fill no)
		(layer "In8.Cu")
	)
	(gr_circle
		(center 153.89987 -314.899802)
		(end 154.15387 -314.899802)
		(stroke
			(width 0.1016)
			(type default)
		)
		(fill no)
		(layer "In8.Cu")
	)
	(gr_circle
		(center 153.89987 -312.049922)
		(end 154.15387 -312.049922)
		(stroke
			(width 0.1016)
			(type default)
		)
		(fill no)
		(layer "In8.Cu")
	)
	(gr_circle
		(center 153.89987 -310.149748)
		(end 154.15387 -310.149748)
		(stroke
			(width 0.1016)
			(type default)
		)
		(fill no)
		(layer "In8.Cu")
	)
	(gr_circle
		(center 153.89987 -308.249828)
		(end 154.15387 -308.249828)
		(stroke
			(width 0.1016)
			(type default)
		)
		(fill no)
		(layer "In8.Cu")
	)
	(gr_circle
		(center 153.89987 -306.349908)
		(end 154.15387 -306.349908)
		(stroke
			(width 0.1016)
			(type default)
		)
		(fill no)
		(layer "In8.Cu")
	)
	(gr_circle
		(center 153.89987 -304.449734)
		(end 154.15387 -304.449734)
		(stroke
			(width 0.1016)
			(type default)
		)
		(fill no)
		(layer "In8.Cu")
	)
	(gr_circle
		(center 153.89987 -302.549814)
		(end 154.15387 -302.549814)
		(stroke
			(width 0.1016)
			(type default)
		)
		(fill no)
		(layer "In8.Cu")
	)
	(gr_circle
		(center 154.850084 -318.699896)
		(end 155.104084 -318.699896)
		(stroke
			(width 0.1016)
			(type default)
		)
		(fill no)
		(layer "In8.Cu")
	)
	(gr_circle
		(center 154.850084 -317.749936)
		(end 155.104084 -317.749936)
		(stroke
			(width 0.1016)
			(type default)
		)
		(fill no)
		(layer "In8.Cu")
	)
	(gr_circle
		(center 154.850084 -313.949842)
		(end 155.104084 -313.949842)
		(stroke
			(width 0.1016)
			(type default)
		)
		(fill no)
		(layer "In8.Cu")
	)
	(gr_circle
		(center 154.850084 -312.999882)
		(end 155.104084 -312.999882)
		(stroke
			(width 0.1016)
			(type default)
		)
		(fill no)
		(layer "In8.Cu")
	)
	(gr_circle
		(center 154.850084 -309.199788)
		(end 155.104084 -309.199788)
		(stroke
			(width 0.1016)
			(type default)
		)
		(fill no)
		(layer "In8.Cu")
	)
	(gr_circle
		(center 154.850084 -307.299868)
		(end 155.104084 -307.299868)
		(stroke
			(width 0.1016)
			(type default)
		)
		(fill no)
		(layer "In8.Cu")
	)
	(gr_circle
		(center 154.850084 -305.399948)
		(end 155.104084 -305.399948)
		(stroke
			(width 0.1016)
			(type default)
		)
		(fill no)
		(layer "In8.Cu")
	)
	(gr_circle
		(center 154.850084 -303.499774)
		(end 155.104084 -303.499774)
		(stroke
			(width 0.1016)
			(type default)
		)
		(fill no)
		(layer "In8.Cu")
	)
	(gr_circle
		(center 154.850084 -301.599854)
		(end 155.104084 -301.599854)
		(stroke
			(width 0.1016)
			(type default)
		)
		(fill no)
		(layer "In8.Cu")
	)
	(gr_circle
		(center 155.800044 -316.799722)
		(end 156.054044 -316.799722)
		(stroke
			(width 0.1016)
			(type default)
		)
		(fill no)
		(layer "In8.Cu")
	)
	(gr_circle
		(center 155.800044 -315.849762)
		(end 156.054044 -315.849762)
		(stroke
			(width 0.1016)
			(type default)
		)
		(fill no)
		(layer "In8.Cu")
	)
	(gr_circle
		(center 155.800044 -312.049922)
		(end 156.054044 -312.049922)
		(stroke
			(width 0.1016)
			(type default)
		)
		(fill no)
		(layer "In8.Cu")
	)
	(gr_circle
		(center 155.800044 -311.099962)
		(end 156.054044 -311.099962)
		(stroke
			(width 0.1016)
			(type default)
		)
		(fill no)
		(layer "In8.Cu")
	)
	(gr_circle
		(center 155.800044 -309.199788)
		(end 156.054044 -309.199788)
		(stroke
			(width 0.1016)
			(type default)
		)
		(fill no)
		(layer "In8.Cu")
	)
	(gr_circle
		(center 155.800044 -307.299868)
		(end 156.054044 -307.299868)
		(stroke
			(width 0.1016)
			(type default)
		)
		(fill no)
		(layer "In8.Cu")
	)
	(gr_circle
		(center 155.800044 -305.399948)
		(end 156.054044 -305.399948)
		(stroke
			(width 0.1016)
			(type default)
		)
		(fill no)
		(layer "In8.Cu")
	)
	(gr_circle
		(center 155.800044 -303.499774)
		(end 156.054044 -303.499774)
		(stroke
			(width 0.1016)
			(type default)
		)
		(fill no)
		(layer "In8.Cu")
	)
	(gr_circle
		(center 155.800044 -301.599854)
		(end 156.054044 -301.599854)
		(stroke
			(width 0.1016)
			(type default)
		)
		(fill no)
		(layer "In8.Cu")
	)
	(gr_circle
		(center 156.750004 -318.699896)
		(end 157.004004 -318.699896)
		(stroke
			(width 0.1016)
			(type default)
		)
		(fill no)
		(layer "In8.Cu")
	)
	(gr_circle
		(center 156.750004 -317.749936)
		(end 157.004004 -317.749936)
		(stroke
			(width 0.1016)
			(type default)
		)
		(fill no)
		(layer "In8.Cu")
	)
	(gr_circle
		(center 156.750004 -313.949842)
		(end 157.004004 -313.949842)
		(stroke
			(width 0.1016)
			(type default)
		)
		(fill no)
		(layer "In8.Cu")
	)
	(gr_circle
		(center 156.750004 -312.999882)
		(end 157.004004 -312.999882)
		(stroke
			(width 0.1016)
			(type default)
		)
		(fill no)
		(layer "In8.Cu")
	)
	(gr_circle
		(center 157.699964 -316.799722)
		(end 157.953964 -316.799722)
		(stroke
			(width 0.1016)
			(type default)
		)
		(fill no)
		(layer "In8.Cu")
	)
	(gr_circle
		(center 157.699964 -315.849762)
		(end 157.953964 -315.849762)
		(stroke
			(width 0.1016)
			(type default)
		)
		(fill no)
		(layer "In8.Cu")
	)
	(gr_circle
		(center 157.699964 -312.049922)
		(end 157.953964 -312.049922)
		(stroke
			(width 0.1016)
			(type default)
		)
		(fill no)
		(layer "In8.Cu")
	)
	(gr_circle
		(center 157.699964 -311.099962)
		(end 157.953964 -311.099962)
		(stroke
			(width 0.1016)
			(type default)
		)
		(fill no)
		(layer "In8.Cu")
	)
	(gr_circle
		(center 157.699964 -309.199788)
		(end 157.953964 -309.199788)
		(stroke
			(width 0.1016)
			(type default)
		)
		(fill no)
		(layer "In8.Cu")
	)
	(gr_circle
		(center 157.699964 -307.299868)
		(end 157.953964 -307.299868)
		(stroke
			(width 0.1016)
			(type default)
		)
		(fill no)
		(layer "In8.Cu")
	)
	(gr_circle
		(center 157.699964 -305.399948)
		(end 157.953964 -305.399948)
		(stroke
			(width 0.1016)
			(type default)
		)
		(fill no)
		(layer "In8.Cu")
	)
	(gr_circle
		(center 157.699964 -303.499774)
		(end 157.953964 -303.499774)
		(stroke
			(width 0.1016)
			(type default)
		)
		(fill no)
		(layer "In8.Cu")
	)
	(gr_circle
		(center 157.699964 -301.599854)
		(end 157.953964 -301.599854)
		(stroke
			(width 0.1016)
			(type default)
		)
		(fill no)
		(layer "In8.Cu")
	)
	(gr_circle
		(center 158.649924 -318.699896)
		(end 158.903924 -318.699896)
		(stroke
			(width 0.1016)
			(type default)
		)
		(fill no)
		(layer "In8.Cu")
	)
	(gr_circle
		(center 158.649924 -317.749936)
		(end 158.903924 -317.749936)
		(stroke
			(width 0.1016)
			(type default)
		)
		(fill no)
		(layer "In8.Cu")
	)
	(gr_circle
		(center 158.649924 -313.949842)
		(end 158.903924 -313.949842)
		(stroke
			(width 0.1016)
			(type default)
		)
		(fill no)
		(layer "In8.Cu")
	)
	(gr_circle
		(center 158.649924 -312.999882)
		(end 158.903924 -312.999882)
		(stroke
			(width 0.1016)
			(type default)
		)
		(fill no)
		(layer "In8.Cu")
	)
	(gr_circle
		(center 158.649924 -309.199788)
		(end 158.903924 -309.199788)
		(stroke
			(width 0.1016)
			(type default)
		)
		(fill no)
		(layer "In8.Cu")
	)
	(gr_circle
		(center 158.649924 -307.299868)
		(end 158.903924 -307.299868)
		(stroke
			(width 0.1016)
			(type default)
		)
		(fill no)
		(layer "In8.Cu")
	)
	(gr_circle
		(center 158.649924 -305.399948)
		(end 158.903924 -305.399948)
		(stroke
			(width 0.1016)
			(type default)
		)
		(fill no)
		(layer "In8.Cu")
	)
	(gr_circle
		(center 158.649924 -303.499774)
		(end 158.903924 -303.499774)
		(stroke
			(width 0.1016)
			(type default)
		)
		(fill no)
		(layer "In8.Cu")
	)
	(gr_circle
		(center 158.649924 -301.599854)
		(end 158.903924 -301.599854)
		(stroke
			(width 0.1016)
			(type default)
		)
		(fill no)
		(layer "In8.Cu")
	)
	(gr_circle
		(center 159.599884 -316.799722)
		(end 159.853884 -316.799722)
		(stroke
			(width 0.1016)
			(type default)
		)
		(fill no)
		(layer "In8.Cu")
	)
	(gr_circle
		(center 159.599884 -315.849762)
		(end 159.853884 -315.849762)
		(stroke
			(width 0.1016)
			(type default)
		)
		(fill no)
		(layer "In8.Cu")
	)
	(gr_circle
		(center 159.599884 -312.049922)
		(end 159.853884 -312.049922)
		(stroke
			(width 0.1016)
			(type default)
		)
		(fill no)
		(layer "In8.Cu")
	)
	(gr_circle
		(center 159.599884 -311.099962)
		(end 159.853884 -311.099962)
		(stroke
			(width 0.1016)
			(type default)
		)
		(fill no)
		(layer "In8.Cu")
	)
	(gr_circle
		(center 159.599884 -308.249828)
		(end 159.853884 -308.249828)
		(stroke
			(width 0.1016)
			(type default)
		)
		(fill no)
		(layer "In8.Cu")
	)
	(gr_circle
		(center 159.599884 -306.349908)
		(end 159.853884 -306.349908)
		(stroke
			(width 0.1016)
			(type default)
		)
		(fill no)
		(layer "In8.Cu")
	)
	(gr_circle
		(center 159.599884 -304.449734)
		(end 159.853884 -304.449734)
		(stroke
			(width 0.1016)
			(type default)
		)
		(fill no)
		(layer "In8.Cu")
	)
	(gr_circle
		(center 159.599884 -302.549814)
		(end 159.853884 -302.549814)
		(stroke
			(width 0.1016)
			(type default)
		)
		(fill no)
		(layer "In8.Cu")
	)
	(gr_circle
		(center 160.549844 -318.699896)
		(end 160.803844 -318.699896)
		(stroke
			(width 0.1016)
			(type default)
		)
		(fill no)
		(layer "In8.Cu")
	)
	(gr_circle
		(center 160.549844 -317.749936)
		(end 160.803844 -317.749936)
		(stroke
			(width 0.1016)
			(type default)
		)
		(fill no)
		(layer "In8.Cu")
	)
	(gr_circle
		(center 160.549844 -313.949842)
		(end 160.803844 -313.949842)
		(stroke
			(width 0.1016)
			(type default)
		)
		(fill no)
		(layer "In8.Cu")
	)
	(gr_circle
		(center 160.549844 -312.999882)
		(end 160.803844 -312.999882)
		(stroke
			(width 0.1016)
			(type default)
		)
		(fill no)
		(layer "In8.Cu")
	)
	(gr_circle
		(center 160.549844 -308.249828)
		(end 160.803844 -308.249828)
		(stroke
			(width 0.1016)
			(type default)
		)
		(fill no)
		(layer "In8.Cu")
	)
	(gr_circle
		(center 160.549844 -306.349908)
		(end 160.803844 -306.349908)
		(stroke
			(width 0.1016)
			(type default)
		)
		(fill no)
		(layer "In8.Cu")
	)
	(gr_circle
		(center 160.549844 -304.449734)
		(end 160.803844 -304.449734)
		(stroke
			(width 0.1016)
			(type default)
		)
		(fill no)
		(layer "In8.Cu")
	)
	(gr_circle
		(center 160.549844 -302.549814)
		(end 160.803844 -302.549814)
		(stroke
			(width 0.1016)
			(type default)
		)
		(fill no)
		(layer "In8.Cu")
	)
	(gr_circle
		(center 160.549844 -278.799798)
		(end 160.803844 -278.799798)
		(stroke
			(width 0.1016)
			(type default)
		)
		(fill no)
		(layer "In8.Cu")
	)
	(gr_circle
		(center 160.549844 -277.849838)
		(end 160.803844 -277.849838)
		(stroke
			(width 0.1016)
			(type default)
		)
		(fill no)
		(layer "In8.Cu")
	)
	(gr_circle
		(center 161.500058 -316.799722)
		(end 161.754058 -316.799722)
		(stroke
			(width 0.1016)
			(type default)
		)
		(fill no)
		(layer "In8.Cu")
	)
	(gr_circle
		(center 161.500058 -315.849762)
		(end 161.754058 -315.849762)
		(stroke
			(width 0.1016)
			(type default)
		)
		(fill no)
		(layer "In8.Cu")
	)
	(gr_circle
		(center 161.500058 -312.049922)
		(end 161.754058 -312.049922)
		(stroke
			(width 0.1016)
			(type default)
		)
		(fill no)
		(layer "In8.Cu")
	)
	(gr_circle
		(center 161.500058 -311.099962)
		(end 161.754058 -311.099962)
		(stroke
			(width 0.1016)
			(type default)
		)
		(fill no)
		(layer "In8.Cu")
	)
	(gr_circle
		(center 161.500058 -280.699464)
		(end 161.754058 -280.699464)
		(stroke
			(width 0.1016)
			(type default)
		)
		(fill no)
		(layer "In8.Cu")
	)
	(gr_circle
		(center 161.500058 -279.749504)
		(end 161.754058 -279.749504)
		(stroke
			(width 0.1016)
			(type default)
		)
		(fill no)
		(layer "In8.Cu")
	)
	(gr_circle
		(center 162.450018 -318.699896)
		(end 162.704018 -318.699896)
		(stroke
			(width 0.1016)
			(type default)
		)
		(fill no)
		(layer "In8.Cu")
	)
	(gr_circle
		(center 162.450018 -317.749936)
		(end 162.704018 -317.749936)
		(stroke
			(width 0.1016)
			(type default)
		)
		(fill no)
		(layer "In8.Cu")
	)
	(gr_circle
		(center 162.450018 -313.949842)
		(end 162.704018 -313.949842)
		(stroke
			(width 0.1016)
			(type default)
		)
		(fill no)
		(layer "In8.Cu")
	)
	(gr_circle
		(center 162.450018 -312.999882)
		(end 162.704018 -312.999882)
		(stroke
			(width 0.1016)
			(type default)
		)
		(fill no)
		(layer "In8.Cu")
	)
	(gr_circle
		(center 162.450018 -278.799798)
		(end 162.704018 -278.799798)
		(stroke
			(width 0.1016)
			(type default)
		)
		(fill no)
		(layer "In8.Cu")
	)
	(gr_circle
		(center 162.450018 -277.849838)
		(end 162.704018 -277.849838)
		(stroke
			(width 0.1016)
			(type default)
		)
		(fill no)
		(layer "In8.Cu")
	)
	(gr_circle
		(center 163.399978 -316.799722)
		(end 163.653978 -316.799722)
		(stroke
			(width 0.1016)
			(type default)
		)
		(fill no)
		(layer "In8.Cu")
	)
	(gr_circle
		(center 163.399978 -315.849762)
		(end 163.653978 -315.849762)
		(stroke
			(width 0.1016)
			(type default)
		)
		(fill no)
		(layer "In8.Cu")
	)
	(gr_circle
		(center 163.399978 -312.049922)
		(end 163.653978 -312.049922)
		(stroke
			(width 0.1016)
			(type default)
		)
		(fill no)
		(layer "In8.Cu")
	)
	(gr_circle
		(center 163.399978 -311.099962)
		(end 163.653978 -311.099962)
		(stroke
			(width 0.1016)
			(type default)
		)
		(fill no)
		(layer "In8.Cu")
	)
	(gr_circle
		(center 163.399978 -280.699464)
		(end 163.653978 -280.699464)
		(stroke
			(width 0.1016)
			(type default)
		)
		(fill no)
		(layer "In8.Cu")
	)
	(gr_circle
		(center 163.399978 -279.749504)
		(end 163.653978 -279.749504)
		(stroke
			(width 0.1016)
			(type default)
		)
		(fill no)
		(layer "In8.Cu")
	)
	(gr_circle
		(center 164.349938 -318.699896)
		(end 164.603938 -318.699896)
		(stroke
			(width 0.1016)
			(type default)
		)
		(fill no)
		(layer "In8.Cu")
	)
	(gr_circle
		(center 164.349938 -317.749936)
		(end 164.603938 -317.749936)
		(stroke
			(width 0.1016)
			(type default)
		)
		(fill no)
		(layer "In8.Cu")
	)
	(gr_circle
		(center 164.349938 -313.949842)
		(end 164.603938 -313.949842)
		(stroke
			(width 0.1016)
			(type default)
		)
		(fill no)
		(layer "In8.Cu")
	)
	(gr_circle
		(center 164.349938 -312.999882)
		(end 164.603938 -312.999882)
		(stroke
			(width 0.1016)
			(type default)
		)
		(fill no)
		(layer "In8.Cu")
	)
	(gr_circle
		(center 164.349938 -278.799798)
		(end 164.603938 -278.799798)
		(stroke
			(width 0.1016)
			(type default)
		)
		(fill no)
		(layer "In8.Cu")
	)
	(gr_circle
		(center 164.349938 -277.849838)
		(end 164.603938 -277.849838)
		(stroke
			(width 0.1016)
			(type default)
		)
		(fill no)
		(layer "In8.Cu")
	)
	(gr_circle
		(center 165.299898 -316.799722)
		(end 165.553898 -316.799722)
		(stroke
			(width 0.1016)
			(type default)
		)
		(fill no)
		(layer "In8.Cu")
	)
	(gr_circle
		(center 165.299898 -315.849762)
		(end 165.553898 -315.849762)
		(stroke
			(width 0.1016)
			(type default)
		)
		(fill no)
		(layer "In8.Cu")
	)
	(gr_circle
		(center 165.299898 -312.049922)
		(end 165.553898 -312.049922)
		(stroke
			(width 0.1016)
			(type default)
		)
		(fill no)
		(layer "In8.Cu")
	)
	(gr_circle
		(center 165.299898 -311.099962)
		(end 165.553898 -311.099962)
		(stroke
			(width 0.1016)
			(type default)
		)
		(fill no)
		(layer "In8.Cu")
	)
	(gr_circle
		(center 165.299898 -280.699464)
		(end 165.553898 -280.699464)
		(stroke
			(width 0.1016)
			(type default)
		)
		(fill no)
		(layer "In8.Cu")
	)
	(gr_circle
		(center 165.299898 -279.749504)
		(end 165.553898 -279.749504)
		(stroke
			(width 0.1016)
			(type default)
		)
		(fill no)
		(layer "In8.Cu")
	)
	(gr_circle
		(center 166.249858 -318.699896)
		(end 166.503858 -318.699896)
		(stroke
			(width 0.1016)
			(type default)
		)
		(fill no)
		(layer "In8.Cu")
	)
	(gr_circle
		(center 166.249858 -317.749936)
		(end 166.503858 -317.749936)
		(stroke
			(width 0.1016)
			(type default)
		)
		(fill no)
		(layer "In8.Cu")
	)
	(gr_circle
		(center 166.249858 -313.949842)
		(end 166.503858 -313.949842)
		(stroke
			(width 0.1016)
			(type default)
		)
		(fill no)
		(layer "In8.Cu")
	)
	(gr_circle
		(center 166.249858 -312.999882)
		(end 166.503858 -312.999882)
		(stroke
			(width 0.1016)
			(type default)
		)
		(fill no)
		(layer "In8.Cu")
	)
	(gr_circle
		(center 166.249858 -278.799798)
		(end 166.503858 -278.799798)
		(stroke
			(width 0.1016)
			(type default)
		)
		(fill no)
		(layer "In8.Cu")
	)
	(gr_circle
		(center 166.249858 -277.849838)
		(end 166.503858 -277.849838)
		(stroke
			(width 0.1016)
			(type default)
		)
		(fill no)
		(layer "In8.Cu")
	)
	(gr_circle
		(center 167.200072 -280.699464)
		(end 167.454072 -280.699464)
		(stroke
			(width 0.1016)
			(type default)
		)
		(fill no)
		(layer "In8.Cu")
	)
	(gr_circle
		(center 167.200072 -279.749504)
		(end 167.454072 -279.749504)
		(stroke
			(width 0.1016)
			(type default)
		)
		(fill no)
		(layer "In8.Cu")
	)
	(gr_circle
		(center 168.150032 -278.799798)
		(end 168.404032 -278.799798)
		(stroke
			(width 0.1016)
			(type default)
		)
		(fill no)
		(layer "In8.Cu")
	)
	(gr_circle
		(center 168.150032 -277.849838)
		(end 168.404032 -277.849838)
		(stroke
			(width 0.1016)
			(type default)
		)
		(fill no)
		(layer "In8.Cu")
	)
	(gr_circle
		(center 169.099992 -280.699464)
		(end 169.353992 -280.699464)
		(stroke
			(width 0.1016)
			(type default)
		)
		(fill no)
		(layer "In8.Cu")
	)
	(gr_circle
		(center 169.099992 -279.749504)
		(end 169.353992 -279.749504)
		(stroke
			(width 0.1016)
			(type default)
		)
		(fill no)
		(layer "In8.Cu")
	)
	(gr_circle
		(center 170.049952 -278.799798)
		(end 170.303952 -278.799798)
		(stroke
			(width 0.1016)
			(type default)
		)
		(fill no)
		(layer "In8.Cu")
	)
	(gr_circle
		(center 170.049952 -277.849838)
		(end 170.303952 -277.849838)
		(stroke
			(width 0.1016)
			(type default)
		)
		(fill no)
		(layer "In8.Cu")
	)
	(gr_circle
		(center 170.999912 -280.699464)
		(end 171.253912 -280.699464)
		(stroke
			(width 0.1016)
			(type default)
		)
		(fill no)
		(layer "In8.Cu")
	)
	(gr_circle
		(center 170.999912 -279.749504)
		(end 171.253912 -279.749504)
		(stroke
			(width 0.1016)
			(type default)
		)
		(fill no)
		(layer "In8.Cu")
	)
	(gr_circle
		(center 171.949872 -278.799798)
		(end 172.203872 -278.799798)
		(stroke
			(width 0.1016)
			(type default)
		)
		(fill no)
		(layer "In8.Cu")
	)
	(gr_circle
		(center 171.949872 -277.849838)
		(end 172.203872 -277.849838)
		(stroke
			(width 0.1016)
			(type default)
		)
		(fill no)
		(layer "In8.Cu")
	)
	(gr_circle
		(center 172.899832 -280.699464)
		(end 173.153832 -280.699464)
		(stroke
			(width 0.1016)
			(type default)
		)
		(fill no)
		(layer "In8.Cu")
	)
	(gr_circle
		(center 172.899832 -279.749504)
		(end 173.153832 -279.749504)
		(stroke
			(width 0.1016)
			(type default)
		)
		(fill no)
		(layer "In8.Cu")
	)
	(gr_circle
		(center 173.850046 -278.799798)
		(end 174.104046 -278.799798)
		(stroke
			(width 0.1016)
			(type default)
		)
		(fill no)
		(layer "In8.Cu")
	)
	(gr_circle
		(center 173.850046 -277.849838)
		(end 174.104046 -277.849838)
		(stroke
			(width 0.1016)
			(type default)
		)
		(fill no)
		(layer "In8.Cu")
	)
	(gr_circle
		(center 174.800006 -280.699464)
		(end 175.054006 -280.699464)
		(stroke
			(width 0.1016)
			(type default)
		)
		(fill no)
		(layer "In8.Cu")
	)
	(gr_circle
		(center 174.800006 -279.749504)
		(end 175.054006 -279.749504)
		(stroke
			(width 0.1016)
			(type default)
		)
		(fill no)
		(layer "In8.Cu")
	)
	(gr_circle
		(center 175.749712 -278.799798)
		(end 176.003712 -278.799798)
		(stroke
			(width 0.1016)
			(type default)
		)
		(fill no)
		(layer "In8.Cu")
	)
	(gr_circle
		(center 175.749712 -277.849838)
		(end 176.003712 -277.849838)
		(stroke
			(width 0.1016)
			(type default)
		)
		(fill no)
		(layer "In8.Cu")
	)
	(gr_circle
		(center 176.699926 -280.699464)
		(end 176.953926 -280.699464)
		(stroke
			(width 0.1016)
			(type default)
		)
		(fill no)
		(layer "In8.Cu")
	)
	(gr_circle
		(center 176.699926 -279.749504)
		(end 176.953926 -279.749504)
		(stroke
			(width 0.1016)
			(type default)
		)
		(fill no)
		(layer "In8.Cu")
	)
	(gr_circle
		(center 177.649632 -278.799798)
		(end 177.903632 -278.799798)
		(stroke
			(width 0.1016)
			(type default)
		)
		(fill no)
		(layer "In8.Cu")
	)
	(gr_circle
		(center 177.649632 -277.849838)
		(end 177.903632 -277.849838)
		(stroke
			(width 0.1016)
			(type default)
		)
		(fill no)
		(layer "In8.Cu")
	)
	(gr_circle
		(center 178.599846 -280.699464)
		(end 178.853846 -280.699464)
		(stroke
			(width 0.1016)
			(type default)
		)
		(fill no)
		(layer "In8.Cu")
	)
	(gr_circle
		(center 178.599846 -279.749504)
		(end 178.853846 -279.749504)
		(stroke
			(width 0.1016)
			(type default)
		)
		(fill no)
		(layer "In8.Cu")
	)
	(gr_circle
		(center 179.549806 -278.799798)
		(end 179.803806 -278.799798)
		(stroke
			(width 0.1016)
			(type default)
		)
		(fill no)
		(layer "In8.Cu")
	)
	(gr_circle
		(center 179.549806 -277.849838)
		(end 179.803806 -277.849838)
		(stroke
			(width 0.1016)
			(type default)
		)
		(fill no)
		(layer "In8.Cu")
	)
	(gr_circle
		(center 180.50002 -280.699464)
		(end 180.75402 -280.699464)
		(stroke
			(width 0.1016)
			(type default)
		)
		(fill no)
		(layer "In8.Cu")
	)
	(gr_circle
		(center 180.50002 -279.749504)
		(end 180.75402 -279.749504)
		(stroke
			(width 0.1016)
			(type default)
		)
		(fill no)
		(layer "In8.Cu")
	)
	(gr_circle
		(center 181.449726 -278.799798)
		(end 181.703726 -278.799798)
		(stroke
			(width 0.1016)
			(type default)
		)
		(fill no)
		(layer "In8.Cu")
	)
	(gr_circle
		(center 181.449726 -277.849838)
		(end 181.703726 -277.849838)
		(stroke
			(width 0.1016)
			(type default)
		)
		(fill no)
		(layer "In8.Cu")
	)
	(gr_circle
		(center 182.39994 -316.799722)
		(end 182.65394 -316.799722)
		(stroke
			(width 0.1016)
			(type default)
		)
		(fill no)
		(layer "In8.Cu")
	)
	(gr_circle
		(center 182.39994 -315.849762)
		(end 182.65394 -315.849762)
		(stroke
			(width 0.1016)
			(type default)
		)
		(fill no)
		(layer "In8.Cu")
	)
	(gr_circle
		(center 182.39994 -312.049922)
		(end 182.65394 -312.049922)
		(stroke
			(width 0.1016)
			(type default)
		)
		(fill no)
		(layer "In8.Cu")
	)
	(gr_circle
		(center 182.39994 -311.099962)
		(end 182.65394 -311.099962)
		(stroke
			(width 0.1016)
			(type default)
		)
		(fill no)
		(layer "In8.Cu")
	)
	(gr_circle
		(center 182.39994 -280.699464)
		(end 182.65394 -280.699464)
		(stroke
			(width 0.1016)
			(type default)
		)
		(fill no)
		(layer "In8.Cu")
	)
	(gr_circle
		(center 182.39994 -279.749504)
		(end 182.65394 -279.749504)
		(stroke
			(width 0.1016)
			(type default)
		)
		(fill no)
		(layer "In8.Cu")
	)
	(gr_circle
		(center 183.349646 -278.799798)
		(end 183.603646 -278.799798)
		(stroke
			(width 0.1016)
			(type default)
		)
		(fill no)
		(layer "In8.Cu")
	)
	(gr_circle
		(center 183.349646 -277.849838)
		(end 183.603646 -277.849838)
		(stroke
			(width 0.1016)
			(type default)
		)
		(fill no)
		(layer "In8.Cu")
	)
	(gr_circle
		(center 183.3499 -318.699896)
		(end 183.6039 -318.699896)
		(stroke
			(width 0.1016)
			(type default)
		)
		(fill no)
		(layer "In8.Cu")
	)
	(gr_circle
		(center 183.3499 -317.749936)
		(end 183.6039 -317.749936)
		(stroke
			(width 0.1016)
			(type default)
		)
		(fill no)
		(layer "In8.Cu")
	)
	(gr_circle
		(center 183.3499 -313.949842)
		(end 183.6039 -313.949842)
		(stroke
			(width 0.1016)
			(type default)
		)
		(fill no)
		(layer "In8.Cu")
	)
	(gr_circle
		(center 183.3499 -312.999882)
		(end 183.6039 -312.999882)
		(stroke
			(width 0.1016)
			(type default)
		)
		(fill no)
		(layer "In8.Cu")
	)
	(gr_circle
		(center 184.29986 -316.799722)
		(end 184.55386 -316.799722)
		(stroke
			(width 0.1016)
			(type default)
		)
		(fill no)
		(layer "In8.Cu")
	)
	(gr_circle
		(center 184.29986 -315.849762)
		(end 184.55386 -315.849762)
		(stroke
			(width 0.1016)
			(type default)
		)
		(fill no)
		(layer "In8.Cu")
	)
	(gr_circle
		(center 184.29986 -312.049922)
		(end 184.55386 -312.049922)
		(stroke
			(width 0.1016)
			(type default)
		)
		(fill no)
		(layer "In8.Cu")
	)
	(gr_circle
		(center 184.29986 -311.099962)
		(end 184.55386 -311.099962)
		(stroke
			(width 0.1016)
			(type default)
		)
		(fill no)
		(layer "In8.Cu")
	)
	(gr_circle
		(center 184.29986 -280.699464)
		(end 184.55386 -280.699464)
		(stroke
			(width 0.1016)
			(type default)
		)
		(fill no)
		(layer "In8.Cu")
	)
	(gr_circle
		(center 184.29986 -279.749504)
		(end 184.55386 -279.749504)
		(stroke
			(width 0.1016)
			(type default)
		)
		(fill no)
		(layer "In8.Cu")
	)
	(gr_circle
		(center 185.24982 -278.799798)
		(end 185.50382 -278.799798)
		(stroke
			(width 0.1016)
			(type default)
		)
		(fill no)
		(layer "In8.Cu")
	)
	(gr_circle
		(center 185.24982 -277.849838)
		(end 185.50382 -277.849838)
		(stroke
			(width 0.1016)
			(type default)
		)
		(fill no)
		(layer "In8.Cu")
	)
	(gr_circle
		(center 185.250074 -318.699896)
		(end 185.504074 -318.699896)
		(stroke
			(width 0.1016)
			(type default)
		)
		(fill no)
		(layer "In8.Cu")
	)
	(gr_circle
		(center 185.250074 -317.749936)
		(end 185.504074 -317.749936)
		(stroke
			(width 0.1016)
			(type default)
		)
		(fill no)
		(layer "In8.Cu")
	)
	(gr_circle
		(center 185.250074 -313.949842)
		(end 185.504074 -313.949842)
		(stroke
			(width 0.1016)
			(type default)
		)
		(fill no)
		(layer "In8.Cu")
	)
	(gr_circle
		(center 185.250074 -312.999882)
		(end 185.504074 -312.999882)
		(stroke
			(width 0.1016)
			(type default)
		)
		(fill no)
		(layer "In8.Cu")
	)
	(gr_circle
		(center 186.200034 -316.799722)
		(end 186.454034 -316.799722)
		(stroke
			(width 0.1016)
			(type default)
		)
		(fill no)
		(layer "In8.Cu")
	)
	(gr_circle
		(center 186.200034 -315.849762)
		(end 186.454034 -315.849762)
		(stroke
			(width 0.1016)
			(type default)
		)
		(fill no)
		(layer "In8.Cu")
	)
	(gr_circle
		(center 186.200034 -312.049922)
		(end 186.454034 -312.049922)
		(stroke
			(width 0.1016)
			(type default)
		)
		(fill no)
		(layer "In8.Cu")
	)
	(gr_circle
		(center 186.200034 -311.099962)
		(end 186.454034 -311.099962)
		(stroke
			(width 0.1016)
			(type default)
		)
		(fill no)
		(layer "In8.Cu")
	)
	(gr_circle
		(center 186.200034 -280.699464)
		(end 186.454034 -280.699464)
		(stroke
			(width 0.1016)
			(type default)
		)
		(fill no)
		(layer "In8.Cu")
	)
	(gr_circle
		(center 186.200034 -279.749504)
		(end 186.454034 -279.749504)
		(stroke
			(width 0.1016)
			(type default)
		)
		(fill no)
		(layer "In8.Cu")
	)
	(gr_circle
		(center 187.14974 -278.799798)
		(end 187.40374 -278.799798)
		(stroke
			(width 0.1016)
			(type default)
		)
		(fill no)
		(layer "In8.Cu")
	)
	(gr_circle
		(center 187.14974 -277.849838)
		(end 187.40374 -277.849838)
		(stroke
			(width 0.1016)
			(type default)
		)
		(fill no)
		(layer "In8.Cu")
	)
	(gr_circle
		(center 187.149994 -318.699896)
		(end 187.403994 -318.699896)
		(stroke
			(width 0.1016)
			(type default)
		)
		(fill no)
		(layer "In8.Cu")
	)
	(gr_circle
		(center 187.149994 -317.749936)
		(end 187.403994 -317.749936)
		(stroke
			(width 0.1016)
			(type default)
		)
		(fill no)
		(layer "In8.Cu")
	)
	(gr_circle
		(center 187.149994 -313.949842)
		(end 187.403994 -313.949842)
		(stroke
			(width 0.1016)
			(type default)
		)
		(fill no)
		(layer "In8.Cu")
	)
	(gr_circle
		(center 187.149994 -312.999882)
		(end 187.403994 -312.999882)
		(stroke
			(width 0.1016)
			(type default)
		)
		(fill no)
		(layer "In8.Cu")
	)
	(gr_circle
		(center 188.099954 -316.799722)
		(end 188.353954 -316.799722)
		(stroke
			(width 0.1016)
			(type default)
		)
		(fill no)
		(layer "In8.Cu")
	)
	(gr_circle
		(center 188.099954 -315.849762)
		(end 188.353954 -315.849762)
		(stroke
			(width 0.1016)
			(type default)
		)
		(fill no)
		(layer "In8.Cu")
	)
	(gr_circle
		(center 188.099954 -312.049922)
		(end 188.353954 -312.049922)
		(stroke
			(width 0.1016)
			(type default)
		)
		(fill no)
		(layer "In8.Cu")
	)
	(gr_circle
		(center 188.099954 -311.099962)
		(end 188.353954 -311.099962)
		(stroke
			(width 0.1016)
			(type default)
		)
		(fill no)
		(layer "In8.Cu")
	)
	(gr_circle
		(center 188.099954 -280.699464)
		(end 188.353954 -280.699464)
		(stroke
			(width 0.1016)
			(type default)
		)
		(fill no)
		(layer "In8.Cu")
	)
	(gr_circle
		(center 188.099954 -279.749504)
		(end 188.353954 -279.749504)
		(stroke
			(width 0.1016)
			(type default)
		)
		(fill no)
		(layer "In8.Cu")
	)
	(gr_circle
		(center 189.04966 -278.799798)
		(end 189.30366 -278.799798)
		(stroke
			(width 0.1016)
			(type default)
		)
		(fill no)
		(layer "In8.Cu")
	)
	(gr_circle
		(center 189.04966 -277.849838)
		(end 189.30366 -277.849838)
		(stroke
			(width 0.1016)
			(type default)
		)
		(fill no)
		(layer "In8.Cu")
	)
	(gr_circle
		(center 189.049914 -318.699896)
		(end 189.303914 -318.699896)
		(stroke
			(width 0.1016)
			(type default)
		)
		(fill no)
		(layer "In8.Cu")
	)
	(gr_circle
		(center 189.049914 -317.749936)
		(end 189.303914 -317.749936)
		(stroke
			(width 0.1016)
			(type default)
		)
		(fill no)
		(layer "In8.Cu")
	)
	(gr_circle
		(center 189.049914 -313.949842)
		(end 189.303914 -313.949842)
		(stroke
			(width 0.1016)
			(type default)
		)
		(fill no)
		(layer "In8.Cu")
	)
	(gr_circle
		(center 189.049914 -312.999882)
		(end 189.303914 -312.999882)
		(stroke
			(width 0.1016)
			(type default)
		)
		(fill no)
		(layer "In8.Cu")
	)
	(gr_circle
		(center 189.999874 -280.699464)
		(end 190.253874 -280.699464)
		(stroke
			(width 0.1016)
			(type default)
		)
		(fill no)
		(layer "In8.Cu")
	)
	(gr_circle
		(center 189.999874 -279.749504)
		(end 190.253874 -279.749504)
		(stroke
			(width 0.1016)
			(type default)
		)
		(fill no)
		(layer "In8.Cu")
	)
	(gr_circle
		(center 190.949834 -278.799798)
		(end 191.203834 -278.799798)
		(stroke
			(width 0.1016)
			(type default)
		)
		(fill no)
		(layer "In8.Cu")
	)
	(gr_circle
		(center 190.949834 -277.849838)
		(end 191.203834 -277.849838)
		(stroke
			(width 0.1016)
			(type default)
		)
		(fill no)
		(layer "In8.Cu")
	)
	(gr_circle
		(center 190.950088 -287.349946)
		(end 191.204088 -287.349946)
		(stroke
			(width 0.1016)
			(type default)
		)
		(fill no)
		(layer "In8.Cu")
	)
	(gr_circle
		(center 190.950088 -285.449772)
		(end 191.204088 -285.449772)
		(stroke
			(width 0.1016)
			(type default)
		)
		(fill no)
		(layer "In8.Cu")
	)
	(gr_circle
		(center 190.950088 -283.549852)
		(end 191.204088 -283.549852)
		(stroke
			(width 0.1016)
			(type default)
		)
		(fill no)
		(layer "In8.Cu")
	)
	(gr_circle
		(center 191.900048 -287.349946)
		(end 192.154048 -287.349946)
		(stroke
			(width 0.1016)
			(type default)
		)
		(fill no)
		(layer "In8.Cu")
	)
	(gr_circle
		(center 191.900048 -285.449772)
		(end 192.154048 -285.449772)
		(stroke
			(width 0.1016)
			(type default)
		)
		(fill no)
		(layer "In8.Cu")
	)
	(gr_circle
		(center 191.900048 -283.549852)
		(end 192.154048 -283.549852)
		(stroke
			(width 0.1016)
			(type default)
		)
		(fill no)
		(layer "In8.Cu")
	)
	(gr_circle
		(center 191.900048 -280.699464)
		(end 192.154048 -280.699464)
		(stroke
			(width 0.1016)
			(type default)
		)
		(fill no)
		(layer "In8.Cu")
	)
	(gr_circle
		(center 191.900048 -279.749504)
		(end 192.154048 -279.749504)
		(stroke
			(width 0.1016)
			(type default)
		)
		(fill no)
		(layer "In8.Cu")
	)
	(gr_circle
		(center 192.849754 -278.799798)
		(end 193.103754 -278.799798)
		(stroke
			(width 0.1016)
			(type default)
		)
		(fill no)
		(layer "In8.Cu")
	)
	(gr_circle
		(center 192.849754 -277.849838)
		(end 193.103754 -277.849838)
		(stroke
			(width 0.1016)
			(type default)
		)
		(fill no)
		(layer "In8.Cu")
	)
	(gr_circle
		(center 192.850008 -288.299906)
		(end 193.104008 -288.299906)
		(stroke
			(width 0.1016)
			(type default)
		)
		(fill no)
		(layer "In8.Cu")
	)
	(gr_circle
		(center 192.850008 -286.399986)
		(end 193.104008 -286.399986)
		(stroke
			(width 0.1016)
			(type default)
		)
		(fill no)
		(layer "In8.Cu")
	)
	(gr_circle
		(center 192.850008 -284.499812)
		(end 193.104008 -284.499812)
		(stroke
			(width 0.1016)
			(type default)
		)
		(fill no)
		(layer "In8.Cu")
	)
	(gr_circle
		(center 192.850008 -282.599892)
		(end 193.104008 -282.599892)
		(stroke
			(width 0.1016)
			(type default)
		)
		(fill no)
		(layer "In8.Cu")
	)
	(gr_circle
		(center 193.799968 -288.299906)
		(end 194.053968 -288.299906)
		(stroke
			(width 0.1016)
			(type default)
		)
		(fill no)
		(layer "In8.Cu")
	)
	(gr_circle
		(center 193.799968 -286.399986)
		(end 194.053968 -286.399986)
		(stroke
			(width 0.1016)
			(type default)
		)
		(fill no)
		(layer "In8.Cu")
	)
	(gr_circle
		(center 193.799968 -284.499812)
		(end 194.053968 -284.499812)
		(stroke
			(width 0.1016)
			(type default)
		)
		(fill no)
		(layer "In8.Cu")
	)
	(gr_circle
		(center 193.799968 -282.599892)
		(end 194.053968 -282.599892)
		(stroke
			(width 0.1016)
			(type default)
		)
		(fill no)
		(layer "In8.Cu")
	)
	(gr_circle
		(center 193.799968 -280.699464)
		(end 194.053968 -280.699464)
		(stroke
			(width 0.1016)
			(type default)
		)
		(fill no)
		(layer "In8.Cu")
	)
	(gr_circle
		(center 193.799968 -279.749504)
		(end 194.053968 -279.749504)
		(stroke
			(width 0.1016)
			(type default)
		)
		(fill no)
		(layer "In8.Cu")
	)
	(gr_circle
		(center 194.749674 -278.799798)
		(end 195.003674 -278.799798)
		(stroke
			(width 0.1016)
			(type default)
		)
		(fill no)
		(layer "In8.Cu")
	)
	(gr_circle
		(center 194.749674 -277.849838)
		(end 195.003674 -277.849838)
		(stroke
			(width 0.1016)
			(type default)
		)
		(fill no)
		(layer "In8.Cu")
	)
	(gr_circle
		(center 195.699888 -280.699718)
		(end 195.953888 -280.699718)
		(stroke
			(width 0.1016)
			(type default)
		)
		(fill no)
		(layer "In8.Cu")
	)
	(gr_circle
		(center 195.699888 -279.749758)
		(end 195.953888 -279.749758)
		(stroke
			(width 0.1016)
			(type default)
		)
		(fill no)
		(layer "In8.Cu")
	)
	(gr_circle
		(center 196.649848 -278.799798)
		(end 196.903848 -278.799798)
		(stroke
			(width 0.1016)
			(type default)
		)
		(fill no)
		(layer "In8.Cu")
	)
	(gr_circle
		(center 196.649848 -277.849838)
		(end 196.903848 -277.849838)
		(stroke
			(width 0.1016)
			(type default)
		)
		(fill no)
		(layer "In8.Cu")
	)
	(gr_circle
		(center 197.600062 -279.749758)
		(end 197.854062 -279.749758)
		(stroke
			(width 0.1016)
			(type default)
		)
		(fill no)
		(layer "In8.Cu")
	)
	(gr_circle
		(center 197.600062 -276.899878)
		(end 197.854062 -276.899878)
		(stroke
			(width 0.1016)
			(type default)
		)
		(fill no)
		(layer "In8.Cu")
	)
	(gr_circle
		(center 198.550022 -279.749758)
		(end 198.804022 -279.749758)
		(stroke
			(width 0.1016)
			(type default)
		)
		(fill no)
		(layer "In8.Cu")
	)
	(gr_circle
		(center 198.550022 -276.899878)
		(end 198.804022 -276.899878)
		(stroke
			(width 0.1016)
			(type default)
		)
		(fill no)
		(layer "In8.Cu")
	)
	(gr_circle
		(center 275.699728 -312.049922)
		(end 275.953728 -312.049922)
		(stroke
			(width 0.1016)
			(type default)
		)
		(fill no)
		(layer "In8.Cu")
	)
	(gr_circle
		(center 275.699728 -311.099962)
		(end 275.953728 -311.099962)
		(stroke
			(width 0.1016)
			(type default)
		)
		(fill no)
		(layer "In8.Cu")
	)
	(gr_circle
		(center 276.649688 -313.949842)
		(end 276.903688 -313.949842)
		(stroke
			(width 0.1016)
			(type default)
		)
		(fill no)
		(layer "In8.Cu")
	)
	(gr_circle
		(center 276.649688 -312.999882)
		(end 276.903688 -312.999882)
		(stroke
			(width 0.1016)
			(type default)
		)
		(fill no)
		(layer "In8.Cu")
	)
	(gr_circle
		(center 276.649688 -278.799798)
		(end 276.903688 -278.799798)
		(stroke
			(width 0.1016)
			(type default)
		)
		(fill no)
		(layer "In8.Cu")
	)
	(gr_circle
		(center 276.649688 -277.849838)
		(end 276.903688 -277.849838)
		(stroke
			(width 0.1016)
			(type default)
		)
		(fill no)
		(layer "In8.Cu")
	)
	(gr_circle
		(center 277.599902 -312.049922)
		(end 277.853902 -312.049922)
		(stroke
			(width 0.1016)
			(type default)
		)
		(fill no)
		(layer "In8.Cu")
	)
	(gr_circle
		(center 277.599902 -311.099962)
		(end 277.853902 -311.099962)
		(stroke
			(width 0.1016)
			(type default)
		)
		(fill no)
		(layer "In8.Cu")
	)
	(gr_circle
		(center 277.599902 -280.699464)
		(end 277.853902 -280.699464)
		(stroke
			(width 0.1016)
			(type default)
		)
		(fill no)
		(layer "In8.Cu")
	)
	(gr_circle
		(center 277.599902 -279.749504)
		(end 277.853902 -279.749504)
		(stroke
			(width 0.1016)
			(type default)
		)
		(fill no)
		(layer "In8.Cu")
	)
	(gr_circle
		(center 278.549862 -313.949842)
		(end 278.803862 -313.949842)
		(stroke
			(width 0.1016)
			(type default)
		)
		(fill no)
		(layer "In8.Cu")
	)
	(gr_circle
		(center 278.549862 -312.999882)
		(end 278.803862 -312.999882)
		(stroke
			(width 0.1016)
			(type default)
		)
		(fill no)
		(layer "In8.Cu")
	)
	(gr_circle
		(center 278.549862 -278.799798)
		(end 278.803862 -278.799798)
		(stroke
			(width 0.1016)
			(type default)
		)
		(fill no)
		(layer "In8.Cu")
	)
	(gr_circle
		(center 278.549862 -277.849838)
		(end 278.803862 -277.849838)
		(stroke
			(width 0.1016)
			(type default)
		)
		(fill no)
		(layer "In8.Cu")
	)
	(gr_circle
		(center 279.499822 -312.049922)
		(end 279.753822 -312.049922)
		(stroke
			(width 0.1016)
			(type default)
		)
		(fill no)
		(layer "In8.Cu")
	)
	(gr_circle
		(center 279.499822 -311.099962)
		(end 279.753822 -311.099962)
		(stroke
			(width 0.1016)
			(type default)
		)
		(fill no)
		(layer "In8.Cu")
	)
	(gr_circle
		(center 279.499822 -280.699464)
		(end 279.753822 -280.699464)
		(stroke
			(width 0.1016)
			(type default)
		)
		(fill no)
		(layer "In8.Cu")
	)
	(gr_circle
		(center 279.499822 -279.749504)
		(end 279.753822 -279.749504)
		(stroke
			(width 0.1016)
			(type default)
		)
		(fill no)
		(layer "In8.Cu")
	)
	(gr_circle
		(center 280.449782 -313.949842)
		(end 280.703782 -313.949842)
		(stroke
			(width 0.1016)
			(type default)
		)
		(fill no)
		(layer "In8.Cu")
	)
	(gr_circle
		(center 280.449782 -312.999882)
		(end 280.703782 -312.999882)
		(stroke
			(width 0.1016)
			(type default)
		)
		(fill no)
		(layer "In8.Cu")
	)
	(gr_circle
		(center 280.449782 -278.799798)
		(end 280.703782 -278.799798)
		(stroke
			(width 0.1016)
			(type default)
		)
		(fill no)
		(layer "In8.Cu")
	)
	(gr_circle
		(center 280.449782 -277.849838)
		(end 280.703782 -277.849838)
		(stroke
			(width 0.1016)
			(type default)
		)
		(fill no)
		(layer "In8.Cu")
	)
	(gr_circle
		(center 281.399742 -312.049922)
		(end 281.653742 -312.049922)
		(stroke
			(width 0.1016)
			(type default)
		)
		(fill no)
		(layer "In8.Cu")
	)
	(gr_circle
		(center 281.399742 -311.099962)
		(end 281.653742 -311.099962)
		(stroke
			(width 0.1016)
			(type default)
		)
		(fill no)
		(layer "In8.Cu")
	)
	(gr_circle
		(center 281.399742 -280.699464)
		(end 281.653742 -280.699464)
		(stroke
			(width 0.1016)
			(type default)
		)
		(fill no)
		(layer "In8.Cu")
	)
	(gr_circle
		(center 281.399742 -279.749504)
		(end 281.653742 -279.749504)
		(stroke
			(width 0.1016)
			(type default)
		)
		(fill no)
		(layer "In8.Cu")
	)
	(gr_circle
		(center 282.349702 -313.949842)
		(end 282.603702 -313.949842)
		(stroke
			(width 0.1016)
			(type default)
		)
		(fill no)
		(layer "In8.Cu")
	)
	(gr_circle
		(center 282.349702 -312.999882)
		(end 282.603702 -312.999882)
		(stroke
			(width 0.1016)
			(type default)
		)
		(fill no)
		(layer "In8.Cu")
	)
	(gr_circle
		(center 282.349702 -278.799798)
		(end 282.603702 -278.799798)
		(stroke
			(width 0.1016)
			(type default)
		)
		(fill no)
		(layer "In8.Cu")
	)
	(gr_circle
		(center 282.349702 -277.849838)
		(end 282.603702 -277.849838)
		(stroke
			(width 0.1016)
			(type default)
		)
		(fill no)
		(layer "In8.Cu")
	)
	(gr_circle
		(center 283.299916 -316.799722)
		(end 283.553916 -316.799722)
		(stroke
			(width 0.1016)
			(type default)
		)
		(fill no)
		(layer "In8.Cu")
	)
	(gr_circle
		(center 283.299916 -315.849762)
		(end 283.553916 -315.849762)
		(stroke
			(width 0.1016)
			(type default)
		)
		(fill no)
		(layer "In8.Cu")
	)
	(gr_circle
		(center 283.299916 -312.049922)
		(end 283.553916 -312.049922)
		(stroke
			(width 0.1016)
			(type default)
		)
		(fill no)
		(layer "In8.Cu")
	)
	(gr_circle
		(center 283.299916 -311.099962)
		(end 283.553916 -311.099962)
		(stroke
			(width 0.1016)
			(type default)
		)
		(fill no)
		(layer "In8.Cu")
	)
	(gr_circle
		(center 283.299916 -280.699464)
		(end 283.553916 -280.699464)
		(stroke
			(width 0.1016)
			(type default)
		)
		(fill no)
		(layer "In8.Cu")
	)
	(gr_circle
		(center 283.299916 -279.749504)
		(end 283.553916 -279.749504)
		(stroke
			(width 0.1016)
			(type default)
		)
		(fill no)
		(layer "In8.Cu")
	)
	(gr_circle
		(center 284.249876 -318.699896)
		(end 284.503876 -318.699896)
		(stroke
			(width 0.1016)
			(type default)
		)
		(fill no)
		(layer "In8.Cu")
	)
	(gr_circle
		(center 284.249876 -317.749936)
		(end 284.503876 -317.749936)
		(stroke
			(width 0.1016)
			(type default)
		)
		(fill no)
		(layer "In8.Cu")
	)
	(gr_circle
		(center 284.249876 -313.949842)
		(end 284.503876 -313.949842)
		(stroke
			(width 0.1016)
			(type default)
		)
		(fill no)
		(layer "In8.Cu")
	)
	(gr_circle
		(center 284.249876 -312.999882)
		(end 284.503876 -312.999882)
		(stroke
			(width 0.1016)
			(type default)
		)
		(fill no)
		(layer "In8.Cu")
	)
	(gr_circle
		(center 284.249876 -278.799798)
		(end 284.503876 -278.799798)
		(stroke
			(width 0.1016)
			(type default)
		)
		(fill no)
		(layer "In8.Cu")
	)
	(gr_circle
		(center 284.249876 -277.849838)
		(end 284.503876 -277.849838)
		(stroke
			(width 0.1016)
			(type default)
		)
		(fill no)
		(layer "In8.Cu")
	)
	(gr_circle
		(center 285.199836 -316.799722)
		(end 285.453836 -316.799722)
		(stroke
			(width 0.1016)
			(type default)
		)
		(fill no)
		(layer "In8.Cu")
	)
	(gr_circle
		(center 285.199836 -315.849762)
		(end 285.453836 -315.849762)
		(stroke
			(width 0.1016)
			(type default)
		)
		(fill no)
		(layer "In8.Cu")
	)
	(gr_circle
		(center 285.199836 -312.049922)
		(end 285.453836 -312.049922)
		(stroke
			(width 0.1016)
			(type default)
		)
		(fill no)
		(layer "In8.Cu")
	)
	(gr_circle
		(center 285.199836 -311.099962)
		(end 285.453836 -311.099962)
		(stroke
			(width 0.1016)
			(type default)
		)
		(fill no)
		(layer "In8.Cu")
	)
	(gr_circle
		(center 285.199836 -280.699464)
		(end 285.453836 -280.699464)
		(stroke
			(width 0.1016)
			(type default)
		)
		(fill no)
		(layer "In8.Cu")
	)
	(gr_circle
		(center 285.199836 -279.749504)
		(end 285.453836 -279.749504)
		(stroke
			(width 0.1016)
			(type default)
		)
		(fill no)
		(layer "In8.Cu")
	)
	(gr_circle
		(center 286.149796 -318.699896)
		(end 286.403796 -318.699896)
		(stroke
			(width 0.1016)
			(type default)
		)
		(fill no)
		(layer "In8.Cu")
	)
	(gr_circle
		(center 286.149796 -317.749936)
		(end 286.403796 -317.749936)
		(stroke
			(width 0.1016)
			(type default)
		)
		(fill no)
		(layer "In8.Cu")
	)
	(gr_circle
		(center 286.149796 -313.949842)
		(end 286.403796 -313.949842)
		(stroke
			(width 0.1016)
			(type default)
		)
		(fill no)
		(layer "In8.Cu")
	)
	(gr_circle
		(center 286.149796 -312.999882)
		(end 286.403796 -312.999882)
		(stroke
			(width 0.1016)
			(type default)
		)
		(fill no)
		(layer "In8.Cu")
	)
	(gr_circle
		(center 286.149796 -278.799798)
		(end 286.403796 -278.799798)
		(stroke
			(width 0.1016)
			(type default)
		)
		(fill no)
		(layer "In8.Cu")
	)
	(gr_circle
		(center 286.149796 -277.849838)
		(end 286.403796 -277.849838)
		(stroke
			(width 0.1016)
			(type default)
		)
		(fill no)
		(layer "In8.Cu")
	)
	(gr_circle
		(center 287.099756 -316.799722)
		(end 287.353756 -316.799722)
		(stroke
			(width 0.1016)
			(type default)
		)
		(fill no)
		(layer "In8.Cu")
	)
	(gr_circle
		(center 287.099756 -315.849762)
		(end 287.353756 -315.849762)
		(stroke
			(width 0.1016)
			(type default)
		)
		(fill no)
		(layer "In8.Cu")
	)
	(gr_circle
		(center 287.099756 -312.049922)
		(end 287.353756 -312.049922)
		(stroke
			(width 0.1016)
			(type default)
		)
		(fill no)
		(layer "In8.Cu")
	)
	(gr_circle
		(center 287.099756 -311.099962)
		(end 287.353756 -311.099962)
		(stroke
			(width 0.1016)
			(type default)
		)
		(fill no)
		(layer "In8.Cu")
	)
	(gr_circle
		(center 287.099756 -280.699464)
		(end 287.353756 -280.699464)
		(stroke
			(width 0.1016)
			(type default)
		)
		(fill no)
		(layer "In8.Cu")
	)
	(gr_circle
		(center 287.099756 -279.749504)
		(end 287.353756 -279.749504)
		(stroke
			(width 0.1016)
			(type default)
		)
		(fill no)
		(layer "In8.Cu")
	)
	(gr_circle
		(center 288.049716 -318.699896)
		(end 288.303716 -318.699896)
		(stroke
			(width 0.1016)
			(type default)
		)
		(fill no)
		(layer "In8.Cu")
	)
	(gr_circle
		(center 288.049716 -317.749936)
		(end 288.303716 -317.749936)
		(stroke
			(width 0.1016)
			(type default)
		)
		(fill no)
		(layer "In8.Cu")
	)
	(gr_circle
		(center 288.049716 -313.949842)
		(end 288.303716 -313.949842)
		(stroke
			(width 0.1016)
			(type default)
		)
		(fill no)
		(layer "In8.Cu")
	)
	(gr_circle
		(center 288.049716 -312.999882)
		(end 288.303716 -312.999882)
		(stroke
			(width 0.1016)
			(type default)
		)
		(fill no)
		(layer "In8.Cu")
	)
	(gr_circle
		(center 288.049716 -278.799798)
		(end 288.303716 -278.799798)
		(stroke
			(width 0.1016)
			(type default)
		)
		(fill no)
		(layer "In8.Cu")
	)
	(gr_circle
		(center 288.049716 -277.849838)
		(end 288.303716 -277.849838)
		(stroke
			(width 0.1016)
			(type default)
		)
		(fill no)
		(layer "In8.Cu")
	)
	(gr_circle
		(center 288.999676 -280.699464)
		(end 289.253676 -280.699464)
		(stroke
			(width 0.1016)
			(type default)
		)
		(fill no)
		(layer "In8.Cu")
	)
	(gr_circle
		(center 288.999676 -279.749504)
		(end 289.253676 -279.749504)
		(stroke
			(width 0.1016)
			(type default)
		)
		(fill no)
		(layer "In8.Cu")
	)
	(gr_circle
		(center 288.99993 -316.799722)
		(end 289.25393 -316.799722)
		(stroke
			(width 0.1016)
			(type default)
		)
		(fill no)
		(layer "In8.Cu")
	)
	(gr_circle
		(center 288.99993 -315.849762)
		(end 289.25393 -315.849762)
		(stroke
			(width 0.1016)
			(type default)
		)
		(fill no)
		(layer "In8.Cu")
	)
	(gr_circle
		(center 288.99993 -312.049922)
		(end 289.25393 -312.049922)
		(stroke
			(width 0.1016)
			(type default)
		)
		(fill no)
		(layer "In8.Cu")
	)
	(gr_circle
		(center 288.99993 -311.099962)
		(end 289.25393 -311.099962)
		(stroke
			(width 0.1016)
			(type default)
		)
		(fill no)
		(layer "In8.Cu")
	)
	(gr_circle
		(center 289.94989 -318.699896)
		(end 290.20389 -318.699896)
		(stroke
			(width 0.1016)
			(type default)
		)
		(fill no)
		(layer "In8.Cu")
	)
	(gr_circle
		(center 289.94989 -317.749936)
		(end 290.20389 -317.749936)
		(stroke
			(width 0.1016)
			(type default)
		)
		(fill no)
		(layer "In8.Cu")
	)
	(gr_circle
		(center 289.94989 -313.949842)
		(end 290.20389 -313.949842)
		(stroke
			(width 0.1016)
			(type default)
		)
		(fill no)
		(layer "In8.Cu")
	)
	(gr_circle
		(center 289.94989 -312.999882)
		(end 290.20389 -312.999882)
		(stroke
			(width 0.1016)
			(type default)
		)
		(fill no)
		(layer "In8.Cu")
	)
	(gr_circle
		(center 289.94989 -278.799798)
		(end 290.20389 -278.799798)
		(stroke
			(width 0.1016)
			(type default)
		)
		(fill no)
		(layer "In8.Cu")
	)
	(gr_circle
		(center 289.94989 -277.849838)
		(end 290.20389 -277.849838)
		(stroke
			(width 0.1016)
			(type default)
		)
		(fill no)
		(layer "In8.Cu")
	)
	(gr_circle
		(center 290.89985 -316.799722)
		(end 291.15385 -316.799722)
		(stroke
			(width 0.1016)
			(type default)
		)
		(fill no)
		(layer "In8.Cu")
	)
	(gr_circle
		(center 290.89985 -315.849762)
		(end 291.15385 -315.849762)
		(stroke
			(width 0.1016)
			(type default)
		)
		(fill no)
		(layer "In8.Cu")
	)
	(gr_circle
		(center 290.89985 -280.699464)
		(end 291.15385 -280.699464)
		(stroke
			(width 0.1016)
			(type default)
		)
		(fill no)
		(layer "In8.Cu")
	)
	(gr_circle
		(center 290.89985 -279.749504)
		(end 291.15385 -279.749504)
		(stroke
			(width 0.1016)
			(type default)
		)
		(fill no)
		(layer "In8.Cu")
	)
	(gr_circle
		(center 291.849556 -278.799798)
		(end 292.103556 -278.799798)
		(stroke
			(width 0.1016)
			(type default)
		)
		(fill no)
		(layer "In8.Cu")
	)
	(gr_circle
		(center 291.849556 -277.849838)
		(end 292.103556 -277.849838)
		(stroke
			(width 0.1016)
			(type default)
		)
		(fill no)
		(layer "In8.Cu")
	)
	(gr_circle
		(center 291.84981 -318.699896)
		(end 292.10381 -318.699896)
		(stroke
			(width 0.1016)
			(type default)
		)
		(fill no)
		(layer "In8.Cu")
	)
	(gr_circle
		(center 291.84981 -317.749936)
		(end 292.10381 -317.749936)
		(stroke
			(width 0.1016)
			(type default)
		)
		(fill no)
		(layer "In8.Cu")
	)
	(gr_circle
		(center 292.79977 -316.799722)
		(end 293.05377 -316.799722)
		(stroke
			(width 0.1016)
			(type default)
		)
		(fill no)
		(layer "In8.Cu")
	)
	(gr_circle
		(center 292.79977 -315.849762)
		(end 293.05377 -315.849762)
		(stroke
			(width 0.1016)
			(type default)
		)
		(fill no)
		(layer "In8.Cu")
	)
	(gr_circle
		(center 292.79977 -280.699464)
		(end 293.05377 -280.699464)
		(stroke
			(width 0.1016)
			(type default)
		)
		(fill no)
		(layer "In8.Cu")
	)
	(gr_circle
		(center 292.79977 -279.749504)
		(end 293.05377 -279.749504)
		(stroke
			(width 0.1016)
			(type default)
		)
		(fill no)
		(layer "In8.Cu")
	)
	(gr_circle
		(center 293.749476 -278.799798)
		(end 294.003476 -278.799798)
		(stroke
			(width 0.1016)
			(type default)
		)
		(fill no)
		(layer "In8.Cu")
	)
	(gr_circle
		(center 293.749476 -277.849838)
		(end 294.003476 -277.849838)
		(stroke
			(width 0.1016)
			(type default)
		)
		(fill no)
		(layer "In8.Cu")
	)
	(gr_circle
		(center 293.74973 -318.699896)
		(end 294.00373 -318.699896)
		(stroke
			(width 0.1016)
			(type default)
		)
		(fill no)
		(layer "In8.Cu")
	)
	(gr_circle
		(center 293.74973 -317.749936)
		(end 294.00373 -317.749936)
		(stroke
			(width 0.1016)
			(type default)
		)
		(fill no)
		(layer "In8.Cu")
	)
	(gr_circle
		(center 294.69969 -316.799722)
		(end 294.95369 -316.799722)
		(stroke
			(width 0.1016)
			(type default)
		)
		(fill no)
		(layer "In8.Cu")
	)
	(gr_circle
		(center 294.69969 -315.849762)
		(end 294.95369 -315.849762)
		(stroke
			(width 0.1016)
			(type default)
		)
		(fill no)
		(layer "In8.Cu")
	)
	(gr_circle
		(center 294.69969 -280.699464)
		(end 294.95369 -280.699464)
		(stroke
			(width 0.1016)
			(type default)
		)
		(fill no)
		(layer "In8.Cu")
	)
	(gr_circle
		(center 294.69969 -279.749504)
		(end 294.95369 -279.749504)
		(stroke
			(width 0.1016)
			(type default)
		)
		(fill no)
		(layer "In8.Cu")
	)
	(gr_circle
		(center 295.64965 -278.799798)
		(end 295.90365 -278.799798)
		(stroke
			(width 0.1016)
			(type default)
		)
		(fill no)
		(layer "In8.Cu")
	)
	(gr_circle
		(center 295.64965 -277.849838)
		(end 295.90365 -277.849838)
		(stroke
			(width 0.1016)
			(type default)
		)
		(fill no)
		(layer "In8.Cu")
	)
	(gr_circle
		(center 295.649904 -318.699896)
		(end 295.903904 -318.699896)
		(stroke
			(width 0.1016)
			(type default)
		)
		(fill no)
		(layer "In8.Cu")
	)
	(gr_circle
		(center 295.649904 -317.749936)
		(end 295.903904 -317.749936)
		(stroke
			(width 0.1016)
			(type default)
		)
		(fill no)
		(layer "In8.Cu")
	)
	(gr_circle
		(center 296.599864 -316.799722)
		(end 296.853864 -316.799722)
		(stroke
			(width 0.1016)
			(type default)
		)
		(fill no)
		(layer "In8.Cu")
	)
	(gr_circle
		(center 296.599864 -315.849762)
		(end 296.853864 -315.849762)
		(stroke
			(width 0.1016)
			(type default)
		)
		(fill no)
		(layer "In8.Cu")
	)
	(gr_circle
		(center 296.599864 -280.699464)
		(end 296.853864 -280.699464)
		(stroke
			(width 0.1016)
			(type default)
		)
		(fill no)
		(layer "In8.Cu")
	)
	(gr_circle
		(center 296.599864 -279.749504)
		(end 296.853864 -279.749504)
		(stroke
			(width 0.1016)
			(type default)
		)
		(fill no)
		(layer "In8.Cu")
	)
	(gr_circle
		(center 297.54957 -278.799798)
		(end 297.80357 -278.799798)
		(stroke
			(width 0.1016)
			(type default)
		)
		(fill no)
		(layer "In8.Cu")
	)
	(gr_circle
		(center 297.54957 -277.849838)
		(end 297.80357 -277.849838)
		(stroke
			(width 0.1016)
			(type default)
		)
		(fill no)
		(layer "In8.Cu")
	)
	(gr_circle
		(center 297.549824 -318.699896)
		(end 297.803824 -318.699896)
		(stroke
			(width 0.1016)
			(type default)
		)
		(fill no)
		(layer "In8.Cu")
	)
	(gr_circle
		(center 297.549824 -317.749936)
		(end 297.803824 -317.749936)
		(stroke
			(width 0.1016)
			(type default)
		)
		(fill no)
		(layer "In8.Cu")
	)
	(gr_circle
		(center 298.499784 -280.699464)
		(end 298.753784 -280.699464)
		(stroke
			(width 0.1016)
			(type default)
		)
		(fill no)
		(layer "In8.Cu")
	)
	(gr_circle
		(center 298.499784 -279.749504)
		(end 298.753784 -279.749504)
		(stroke
			(width 0.1016)
			(type default)
		)
		(fill no)
		(layer "In8.Cu")
	)
	(gr_circle
		(center 299.44949 -278.799798)
		(end 299.70349 -278.799798)
		(stroke
			(width 0.1016)
			(type default)
		)
		(fill no)
		(layer "In8.Cu")
	)
	(gr_circle
		(center 299.44949 -277.849838)
		(end 299.70349 -277.849838)
		(stroke
			(width 0.1016)
			(type default)
		)
		(fill no)
		(layer "In8.Cu")
	)
	(gr_circle
		(center 300.399704 -280.699464)
		(end 300.653704 -280.699464)
		(stroke
			(width 0.1016)
			(type default)
		)
		(fill no)
		(layer "In8.Cu")
	)
	(gr_circle
		(center 300.399704 -279.749504)
		(end 300.653704 -279.749504)
		(stroke
			(width 0.1016)
			(type default)
		)
		(fill no)
		(layer "In8.Cu")
	)
	(gr_circle
		(center 301.349664 -278.799798)
		(end 301.603664 -278.799798)
		(stroke
			(width 0.1016)
			(type default)
		)
		(fill no)
		(layer "In8.Cu")
	)
	(gr_circle
		(center 301.349664 -277.849838)
		(end 301.603664 -277.849838)
		(stroke
			(width 0.1016)
			(type default)
		)
		(fill no)
		(layer "In8.Cu")
	)
	(gr_circle
		(center 302.299878 -280.699464)
		(end 302.553878 -280.699464)
		(stroke
			(width 0.1016)
			(type default)
		)
		(fill no)
		(layer "In8.Cu")
	)
	(gr_circle
		(center 302.299878 -279.749504)
		(end 302.553878 -279.749504)
		(stroke
			(width 0.1016)
			(type default)
		)
		(fill no)
		(layer "In8.Cu")
	)
	(gr_circle
		(center 303.249584 -278.799798)
		(end 303.503584 -278.799798)
		(stroke
			(width 0.1016)
			(type default)
		)
		(fill no)
		(layer "In8.Cu")
	)
	(gr_circle
		(center 303.249584 -277.849838)
		(end 303.503584 -277.849838)
		(stroke
			(width 0.1016)
			(type default)
		)
		(fill no)
		(layer "In8.Cu")
	)
	(gr_circle
		(center 304.199798 -280.699464)
		(end 304.453798 -280.699464)
		(stroke
			(width 0.1016)
			(type default)
		)
		(fill no)
		(layer "In8.Cu")
	)
	(gr_circle
		(center 304.199798 -279.749504)
		(end 304.453798 -279.749504)
		(stroke
			(width 0.1016)
			(type default)
		)
		(fill no)
		(layer "In8.Cu")
	)
	(gr_circle
		(center 305.149504 -278.799798)
		(end 305.403504 -278.799798)
		(stroke
			(width 0.1016)
			(type default)
		)
		(fill no)
		(layer "In8.Cu")
	)
	(gr_circle
		(center 305.149504 -277.849838)
		(end 305.403504 -277.849838)
		(stroke
			(width 0.1016)
			(type default)
		)
		(fill no)
		(layer "In8.Cu")
	)
	(gr_circle
		(center 306.099718 -316.799722)
		(end 306.353718 -316.799722)
		(stroke
			(width 0.1016)
			(type default)
		)
		(fill no)
		(layer "In8.Cu")
	)
	(gr_circle
		(center 306.099718 -315.849762)
		(end 306.353718 -315.849762)
		(stroke
			(width 0.1016)
			(type default)
		)
		(fill no)
		(layer "In8.Cu")
	)
	(gr_circle
		(center 306.099718 -312.049922)
		(end 306.353718 -312.049922)
		(stroke
			(width 0.1016)
			(type default)
		)
		(fill no)
		(layer "In8.Cu")
	)
	(gr_circle
		(center 306.099718 -311.099962)
		(end 306.353718 -311.099962)
		(stroke
			(width 0.1016)
			(type default)
		)
		(fill no)
		(layer "In8.Cu")
	)
	(gr_circle
		(center 306.099718 -280.699464)
		(end 306.353718 -280.699464)
		(stroke
			(width 0.1016)
			(type default)
		)
		(fill no)
		(layer "In8.Cu")
	)
	(gr_circle
		(center 306.099718 -279.749504)
		(end 306.353718 -279.749504)
		(stroke
			(width 0.1016)
			(type default)
		)
		(fill no)
		(layer "In8.Cu")
	)
	(gr_circle
		(center 307.049678 -278.799798)
		(end 307.303678 -278.799798)
		(stroke
			(width 0.1016)
			(type default)
		)
		(fill no)
		(layer "In8.Cu")
	)
	(gr_circle
		(center 307.049678 -277.849838)
		(end 307.303678 -277.849838)
		(stroke
			(width 0.1016)
			(type default)
		)
		(fill no)
		(layer "In8.Cu")
	)
	(gr_circle
		(center 307.049932 -318.699896)
		(end 307.303932 -318.699896)
		(stroke
			(width 0.1016)
			(type default)
		)
		(fill no)
		(layer "In8.Cu")
	)
	(gr_circle
		(center 307.049932 -317.749936)
		(end 307.303932 -317.749936)
		(stroke
			(width 0.1016)
			(type default)
		)
		(fill no)
		(layer "In8.Cu")
	)
	(gr_circle
		(center 307.049932 -313.949842)
		(end 307.303932 -313.949842)
		(stroke
			(width 0.1016)
			(type default)
		)
		(fill no)
		(layer "In8.Cu")
	)
	(gr_circle
		(center 307.049932 -312.999882)
		(end 307.303932 -312.999882)
		(stroke
			(width 0.1016)
			(type default)
		)
		(fill no)
		(layer "In8.Cu")
	)
	(gr_circle
		(center 307.049932 -308.249828)
		(end 307.303932 -308.249828)
		(stroke
			(width 0.1016)
			(type default)
		)
		(fill no)
		(layer "In8.Cu")
	)
	(gr_circle
		(center 307.049932 -306.349908)
		(end 307.303932 -306.349908)
		(stroke
			(width 0.1016)
			(type default)
		)
		(fill no)
		(layer "In8.Cu")
	)
	(gr_circle
		(center 307.049932 -304.449734)
		(end 307.303932 -304.449734)
		(stroke
			(width 0.1016)
			(type default)
		)
		(fill no)
		(layer "In8.Cu")
	)
	(gr_circle
		(center 307.049932 -287.349946)
		(end 307.303932 -287.349946)
		(stroke
			(width 0.1016)
			(type default)
		)
		(fill no)
		(layer "In8.Cu")
	)
	(gr_circle
		(center 307.049932 -285.449772)
		(end 307.303932 -285.449772)
		(stroke
			(width 0.1016)
			(type default)
		)
		(fill no)
		(layer "In8.Cu")
	)
	(gr_circle
		(center 307.049932 -283.549852)
		(end 307.303932 -283.549852)
		(stroke
			(width 0.1016)
			(type default)
		)
		(fill no)
		(layer "In8.Cu")
	)
	(gr_circle
		(center 307.999892 -316.799722)
		(end 308.253892 -316.799722)
		(stroke
			(width 0.1016)
			(type default)
		)
		(fill no)
		(layer "In8.Cu")
	)
	(gr_circle
		(center 307.999892 -315.849762)
		(end 308.253892 -315.849762)
		(stroke
			(width 0.1016)
			(type default)
		)
		(fill no)
		(layer "In8.Cu")
	)
	(gr_circle
		(center 307.999892 -312.049922)
		(end 308.253892 -312.049922)
		(stroke
			(width 0.1016)
			(type default)
		)
		(fill no)
		(layer "In8.Cu")
	)
	(gr_circle
		(center 307.999892 -311.099962)
		(end 308.253892 -311.099962)
		(stroke
			(width 0.1016)
			(type default)
		)
		(fill no)
		(layer "In8.Cu")
	)
	(gr_circle
		(center 307.999892 -308.249828)
		(end 308.253892 -308.249828)
		(stroke
			(width 0.1016)
			(type default)
		)
		(fill no)
		(layer "In8.Cu")
	)
	(gr_circle
		(center 307.999892 -306.349908)
		(end 308.253892 -306.349908)
		(stroke
			(width 0.1016)
			(type default)
		)
		(fill no)
		(layer "In8.Cu")
	)
	(gr_circle
		(center 307.999892 -304.449734)
		(end 308.253892 -304.449734)
		(stroke
			(width 0.1016)
			(type default)
		)
		(fill no)
		(layer "In8.Cu")
	)
	(gr_circle
		(center 307.999892 -287.349946)
		(end 308.253892 -287.349946)
		(stroke
			(width 0.1016)
			(type default)
		)
		(fill no)
		(layer "In8.Cu")
	)
	(gr_circle
		(center 307.999892 -285.449772)
		(end 308.253892 -285.449772)
		(stroke
			(width 0.1016)
			(type default)
		)
		(fill no)
		(layer "In8.Cu")
	)
	(gr_circle
		(center 307.999892 -283.549852)
		(end 308.253892 -283.549852)
		(stroke
			(width 0.1016)
			(type default)
		)
		(fill no)
		(layer "In8.Cu")
	)
	(gr_circle
		(center 307.999892 -280.699464)
		(end 308.253892 -280.699464)
		(stroke
			(width 0.1016)
			(type default)
		)
		(fill no)
		(layer "In8.Cu")
	)
	(gr_circle
		(center 307.999892 -279.749504)
		(end 308.253892 -279.749504)
		(stroke
			(width 0.1016)
			(type default)
		)
		(fill no)
		(layer "In8.Cu")
	)
	(gr_circle
		(center 308.949598 -278.799798)
		(end 309.203598 -278.799798)
		(stroke
			(width 0.1016)
			(type default)
		)
		(fill no)
		(layer "In8.Cu")
	)
	(gr_circle
		(center 308.949598 -277.849838)
		(end 309.203598 -277.849838)
		(stroke
			(width 0.1016)
			(type default)
		)
		(fill no)
		(layer "In8.Cu")
	)
	(gr_circle
		(center 308.949852 -318.699896)
		(end 309.203852 -318.699896)
		(stroke
			(width 0.1016)
			(type default)
		)
		(fill no)
		(layer "In8.Cu")
	)
	(gr_circle
		(center 308.949852 -317.749936)
		(end 309.203852 -317.749936)
		(stroke
			(width 0.1016)
			(type default)
		)
		(fill no)
		(layer "In8.Cu")
	)
	(gr_circle
		(center 308.949852 -313.949842)
		(end 309.203852 -313.949842)
		(stroke
			(width 0.1016)
			(type default)
		)
		(fill no)
		(layer "In8.Cu")
	)
	(gr_circle
		(center 308.949852 -312.999882)
		(end 309.203852 -312.999882)
		(stroke
			(width 0.1016)
			(type default)
		)
		(fill no)
		(layer "In8.Cu")
	)
	(gr_circle
		(center 308.949852 -309.199788)
		(end 309.203852 -309.199788)
		(stroke
			(width 0.1016)
			(type default)
		)
		(fill no)
		(layer "In8.Cu")
	)
	(gr_circle
		(center 308.949852 -307.299868)
		(end 309.203852 -307.299868)
		(stroke
			(width 0.1016)
			(type default)
		)
		(fill no)
		(layer "In8.Cu")
	)
	(gr_circle
		(center 308.949852 -305.399948)
		(end 309.203852 -305.399948)
		(stroke
			(width 0.1016)
			(type default)
		)
		(fill no)
		(layer "In8.Cu")
	)
	(gr_circle
		(center 308.949852 -288.299906)
		(end 309.203852 -288.299906)
		(stroke
			(width 0.1016)
			(type default)
		)
		(fill no)
		(layer "In8.Cu")
	)
	(gr_circle
		(center 308.949852 -286.399986)
		(end 309.203852 -286.399986)
		(stroke
			(width 0.1016)
			(type default)
		)
		(fill no)
		(layer "In8.Cu")
	)
	(gr_circle
		(center 308.949852 -284.499812)
		(end 309.203852 -284.499812)
		(stroke
			(width 0.1016)
			(type default)
		)
		(fill no)
		(layer "In8.Cu")
	)
	(gr_circle
		(center 308.949852 -282.599892)
		(end 309.203852 -282.599892)
		(stroke
			(width 0.1016)
			(type default)
		)
		(fill no)
		(layer "In8.Cu")
	)
	(gr_circle
		(center 309.899812 -316.799722)
		(end 310.153812 -316.799722)
		(stroke
			(width 0.1016)
			(type default)
		)
		(fill no)
		(layer "In8.Cu")
	)
	(gr_circle
		(center 309.899812 -315.849762)
		(end 310.153812 -315.849762)
		(stroke
			(width 0.1016)
			(type default)
		)
		(fill no)
		(layer "In8.Cu")
	)
	(gr_circle
		(center 309.899812 -312.049922)
		(end 310.153812 -312.049922)
		(stroke
			(width 0.1016)
			(type default)
		)
		(fill no)
		(layer "In8.Cu")
	)
	(gr_circle
		(center 309.899812 -311.099962)
		(end 310.153812 -311.099962)
		(stroke
			(width 0.1016)
			(type default)
		)
		(fill no)
		(layer "In8.Cu")
	)
	(gr_circle
		(center 309.899812 -309.199788)
		(end 310.153812 -309.199788)
		(stroke
			(width 0.1016)
			(type default)
		)
		(fill no)
		(layer "In8.Cu")
	)
	(gr_circle
		(center 309.899812 -307.299868)
		(end 310.153812 -307.299868)
		(stroke
			(width 0.1016)
			(type default)
		)
		(fill no)
		(layer "In8.Cu")
	)
	(gr_circle
		(center 309.899812 -305.399948)
		(end 310.153812 -305.399948)
		(stroke
			(width 0.1016)
			(type default)
		)
		(fill no)
		(layer "In8.Cu")
	)
	(gr_circle
		(center 309.899812 -288.299906)
		(end 310.153812 -288.299906)
		(stroke
			(width 0.1016)
			(type default)
		)
		(fill no)
		(layer "In8.Cu")
	)
	(gr_circle
		(center 309.899812 -286.399986)
		(end 310.153812 -286.399986)
		(stroke
			(width 0.1016)
			(type default)
		)
		(fill no)
		(layer "In8.Cu")
	)
	(gr_circle
		(center 309.899812 -284.499812)
		(end 310.153812 -284.499812)
		(stroke
			(width 0.1016)
			(type default)
		)
		(fill no)
		(layer "In8.Cu")
	)
	(gr_circle
		(center 309.899812 -282.599892)
		(end 310.153812 -282.599892)
		(stroke
			(width 0.1016)
			(type default)
		)
		(fill no)
		(layer "In8.Cu")
	)
	(gr_circle
		(center 309.899812 -280.699464)
		(end 310.153812 -280.699464)
		(stroke
			(width 0.1016)
			(type default)
		)
		(fill no)
		(layer "In8.Cu")
	)
	(gr_circle
		(center 309.899812 -279.749504)
		(end 310.153812 -279.749504)
		(stroke
			(width 0.1016)
			(type default)
		)
		(fill no)
		(layer "In8.Cu")
	)
	(gr_circle
		(center 310.849518 -278.799798)
		(end 311.103518 -278.799798)
		(stroke
			(width 0.1016)
			(type default)
		)
		(fill no)
		(layer "In8.Cu")
	)
	(gr_circle
		(center 310.849518 -277.849838)
		(end 311.103518 -277.849838)
		(stroke
			(width 0.1016)
			(type default)
		)
		(fill no)
		(layer "In8.Cu")
	)
	(gr_circle
		(center 310.849772 -318.699896)
		(end 311.103772 -318.699896)
		(stroke
			(width 0.1016)
			(type default)
		)
		(fill no)
		(layer "In8.Cu")
	)
	(gr_circle
		(center 310.849772 -317.749936)
		(end 311.103772 -317.749936)
		(stroke
			(width 0.1016)
			(type default)
		)
		(fill no)
		(layer "In8.Cu")
	)
	(gr_circle
		(center 310.849772 -313.949842)
		(end 311.103772 -313.949842)
		(stroke
			(width 0.1016)
			(type default)
		)
		(fill no)
		(layer "In8.Cu")
	)
	(gr_circle
		(center 310.849772 -312.999882)
		(end 311.103772 -312.999882)
		(stroke
			(width 0.1016)
			(type default)
		)
		(fill no)
		(layer "In8.Cu")
	)
	(gr_circle
		(center 311.799732 -316.799722)
		(end 312.053732 -316.799722)
		(stroke
			(width 0.1016)
			(type default)
		)
		(fill no)
		(layer "In8.Cu")
	)
	(gr_circle
		(center 311.799732 -315.849762)
		(end 312.053732 -315.849762)
		(stroke
			(width 0.1016)
			(type default)
		)
		(fill no)
		(layer "In8.Cu")
	)
	(gr_circle
		(center 311.799732 -312.049922)
		(end 312.053732 -312.049922)
		(stroke
			(width 0.1016)
			(type default)
		)
		(fill no)
		(layer "In8.Cu")
	)
	(gr_circle
		(center 311.799732 -311.099962)
		(end 312.053732 -311.099962)
		(stroke
			(width 0.1016)
			(type default)
		)
		(fill no)
		(layer "In8.Cu")
	)
	(gr_circle
		(center 311.799732 -309.199788)
		(end 312.053732 -309.199788)
		(stroke
			(width 0.1016)
			(type default)
		)
		(fill no)
		(layer "In8.Cu")
	)
	(gr_circle
		(center 311.799732 -307.299868)
		(end 312.053732 -307.299868)
		(stroke
			(width 0.1016)
			(type default)
		)
		(fill no)
		(layer "In8.Cu")
	)
	(gr_circle
		(center 311.799732 -305.399948)
		(end 312.053732 -305.399948)
		(stroke
			(width 0.1016)
			(type default)
		)
		(fill no)
		(layer "In8.Cu")
	)
	(gr_circle
		(center 311.799732 -280.699718)
		(end 312.053732 -280.699718)
		(stroke
			(width 0.1016)
			(type default)
		)
		(fill no)
		(layer "In8.Cu")
	)
	(gr_circle
		(center 311.799732 -279.749758)
		(end 312.053732 -279.749758)
		(stroke
			(width 0.1016)
			(type default)
		)
		(fill no)
		(layer "In8.Cu")
	)
	(gr_circle
		(center 312.749692 -318.699896)
		(end 313.003692 -318.699896)
		(stroke
			(width 0.1016)
			(type default)
		)
		(fill no)
		(layer "In8.Cu")
	)
	(gr_circle
		(center 312.749692 -317.749936)
		(end 313.003692 -317.749936)
		(stroke
			(width 0.1016)
			(type default)
		)
		(fill no)
		(layer "In8.Cu")
	)
	(gr_circle
		(center 312.749692 -313.949842)
		(end 313.003692 -313.949842)
		(stroke
			(width 0.1016)
			(type default)
		)
		(fill no)
		(layer "In8.Cu")
	)
	(gr_circle
		(center 312.749692 -312.999882)
		(end 313.003692 -312.999882)
		(stroke
			(width 0.1016)
			(type default)
		)
		(fill no)
		(layer "In8.Cu")
	)
	(gr_circle
		(center 312.749692 -309.199788)
		(end 313.003692 -309.199788)
		(stroke
			(width 0.1016)
			(type default)
		)
		(fill no)
		(layer "In8.Cu")
	)
	(gr_circle
		(center 312.749692 -307.299868)
		(end 313.003692 -307.299868)
		(stroke
			(width 0.1016)
			(type default)
		)
		(fill no)
		(layer "In8.Cu")
	)
	(gr_circle
		(center 312.749692 -305.399948)
		(end 313.003692 -305.399948)
		(stroke
			(width 0.1016)
			(type default)
		)
		(fill no)
		(layer "In8.Cu")
	)
	(gr_circle
		(center 312.749692 -278.799798)
		(end 313.003692 -278.799798)
		(stroke
			(width 0.1016)
			(type default)
		)
		(fill no)
		(layer "In8.Cu")
	)
	(gr_circle
		(center 312.749692 -277.849838)
		(end 313.003692 -277.849838)
		(stroke
			(width 0.1016)
			(type default)
		)
		(fill no)
		(layer "In8.Cu")
	)
	(gr_circle
		(center 313.699906 -316.799722)
		(end 313.953906 -316.799722)
		(stroke
			(width 0.1016)
			(type default)
		)
		(fill no)
		(layer "In8.Cu")
	)
	(gr_circle
		(center 313.699906 -314.899802)
		(end 313.953906 -314.899802)
		(stroke
			(width 0.1016)
			(type default)
		)
		(fill no)
		(layer "In8.Cu")
	)
	(gr_circle
		(center 313.699906 -312.049922)
		(end 313.953906 -312.049922)
		(stroke
			(width 0.1016)
			(type default)
		)
		(fill no)
		(layer "In8.Cu")
	)
	(gr_circle
		(center 313.699906 -310.149748)
		(end 313.953906 -310.149748)
		(stroke
			(width 0.1016)
			(type default)
		)
		(fill no)
		(layer "In8.Cu")
	)
	(gr_circle
		(center 313.699906 -308.249828)
		(end 313.953906 -308.249828)
		(stroke
			(width 0.1016)
			(type default)
		)
		(fill no)
		(layer "In8.Cu")
	)
	(gr_circle
		(center 313.699906 -306.349908)
		(end 313.953906 -306.349908)
		(stroke
			(width 0.1016)
			(type default)
		)
		(fill no)
		(layer "In8.Cu")
	)
	(gr_circle
		(center 313.699906 -304.449734)
		(end 313.953906 -304.449734)
		(stroke
			(width 0.1016)
			(type default)
		)
		(fill no)
		(layer "In8.Cu")
	)
	(gr_circle
		(center 313.699906 -279.749758)
		(end 313.953906 -279.749758)
		(stroke
			(width 0.1016)
			(type default)
		)
		(fill no)
		(layer "In8.Cu")
	)
	(gr_circle
		(center 313.699906 -276.899878)
		(end 313.953906 -276.899878)
		(stroke
			(width 0.1016)
			(type default)
		)
		(fill no)
		(layer "In8.Cu")
	)
	(gr_circle
		(center 314.649866 -316.799722)
		(end 314.903866 -316.799722)
		(stroke
			(width 0.1016)
			(type default)
		)
		(fill no)
		(layer "In8.Cu")
	)
	(gr_circle
		(center 314.649866 -314.899802)
		(end 314.903866 -314.899802)
		(stroke
			(width 0.1016)
			(type default)
		)
		(fill no)
		(layer "In8.Cu")
	)
	(gr_circle
		(center 314.649866 -312.049922)
		(end 314.903866 -312.049922)
		(stroke
			(width 0.1016)
			(type default)
		)
		(fill no)
		(layer "In8.Cu")
	)
	(gr_circle
		(center 314.649866 -310.149748)
		(end 314.903866 -310.149748)
		(stroke
			(width 0.1016)
			(type default)
		)
		(fill no)
		(layer "In8.Cu")
	)
	(gr_circle
		(center 314.649866 -308.249828)
		(end 314.903866 -308.249828)
		(stroke
			(width 0.1016)
			(type default)
		)
		(fill no)
		(layer "In8.Cu")
	)
	(gr_circle
		(center 314.649866 -306.349908)
		(end 314.903866 -306.349908)
		(stroke
			(width 0.1016)
			(type default)
		)
		(fill no)
		(layer "In8.Cu")
	)
	(gr_circle
		(center 314.649866 -304.449734)
		(end 314.903866 -304.449734)
		(stroke
			(width 0.1016)
			(type default)
		)
		(fill no)
		(layer "In8.Cu")
	)
	(gr_circle
		(center 314.649866 -279.749758)
		(end 314.903866 -279.749758)
		(stroke
			(width 0.1016)
			(type default)
		)
		(fill no)
		(layer "In8.Cu")
	)
	(gr_circle
		(center 314.649866 -276.899878)
		(end 314.903866 -276.899878)
		(stroke
			(width 0.1016)
			(type default)
		)
		(fill no)
		(layer "In8.Cu")
	)
	(gr_circle
		(center 385.149852 -316.799722)
		(end 385.403852 -316.799722)
		(stroke
			(width 0.1016)
			(type default)
		)
		(fill no)
		(layer "In8.Cu")
	)
	(gr_circle
		(center 385.149852 -314.899802)
		(end 385.403852 -314.899802)
		(stroke
			(width 0.1016)
			(type default)
		)
		(fill no)
		(layer "In8.Cu")
	)
	(gr_circle
		(center 385.149852 -312.049922)
		(end 385.403852 -312.049922)
		(stroke
			(width 0.1016)
			(type default)
		)
		(fill no)
		(layer "In8.Cu")
	)
	(gr_circle
		(center 385.149852 -310.149748)
		(end 385.403852 -310.149748)
		(stroke
			(width 0.1016)
			(type default)
		)
		(fill no)
		(layer "In8.Cu")
	)
	(gr_circle
		(center 385.149852 -308.249828)
		(end 385.403852 -308.249828)
		(stroke
			(width 0.1016)
			(type default)
		)
		(fill no)
		(layer "In8.Cu")
	)
	(gr_circle
		(center 385.149852 -306.349908)
		(end 385.403852 -306.349908)
		(stroke
			(width 0.1016)
			(type default)
		)
		(fill no)
		(layer "In8.Cu")
	)
	(gr_circle
		(center 385.149852 -304.449734)
		(end 385.403852 -304.449734)
		(stroke
			(width 0.1016)
			(type default)
		)
		(fill no)
		(layer "In8.Cu")
	)
	(gr_circle
		(center 385.149852 -302.549814)
		(end 385.403852 -302.549814)
		(stroke
			(width 0.1016)
			(type default)
		)
		(fill no)
		(layer "In8.Cu")
	)
	(gr_circle
		(center 386.099812 -316.799722)
		(end 386.353812 -316.799722)
		(stroke
			(width 0.1016)
			(type default)
		)
		(fill no)
		(layer "In8.Cu")
	)
	(gr_circle
		(center 386.099812 -314.899802)
		(end 386.353812 -314.899802)
		(stroke
			(width 0.1016)
			(type default)
		)
		(fill no)
		(layer "In8.Cu")
	)
	(gr_circle
		(center 386.099812 -312.049922)
		(end 386.353812 -312.049922)
		(stroke
			(width 0.1016)
			(type default)
		)
		(fill no)
		(layer "In8.Cu")
	)
	(gr_circle
		(center 386.099812 -310.149748)
		(end 386.353812 -310.149748)
		(stroke
			(width 0.1016)
			(type default)
		)
		(fill no)
		(layer "In8.Cu")
	)
	(gr_circle
		(center 386.099812 -308.249828)
		(end 386.353812 -308.249828)
		(stroke
			(width 0.1016)
			(type default)
		)
		(fill no)
		(layer "In8.Cu")
	)
	(gr_circle
		(center 386.099812 -306.349908)
		(end 386.353812 -306.349908)
		(stroke
			(width 0.1016)
			(type default)
		)
		(fill no)
		(layer "In8.Cu")
	)
	(gr_circle
		(center 386.099812 -304.449734)
		(end 386.353812 -304.449734)
		(stroke
			(width 0.1016)
			(type default)
		)
		(fill no)
		(layer "In8.Cu")
	)
	(gr_circle
		(center 386.099812 -302.549814)
		(end 386.353812 -302.549814)
		(stroke
			(width 0.1016)
			(type default)
		)
		(fill no)
		(layer "In8.Cu")
	)
	(gr_circle
		(center 387.050026 -318.699896)
		(end 387.304026 -318.699896)
		(stroke
			(width 0.1016)
			(type default)
		)
		(fill no)
		(layer "In8.Cu")
	)
	(gr_circle
		(center 387.050026 -317.749936)
		(end 387.304026 -317.749936)
		(stroke
			(width 0.1016)
			(type default)
		)
		(fill no)
		(layer "In8.Cu")
	)
	(gr_circle
		(center 387.050026 -313.949842)
		(end 387.304026 -313.949842)
		(stroke
			(width 0.1016)
			(type default)
		)
		(fill no)
		(layer "In8.Cu")
	)
	(gr_circle
		(center 387.050026 -312.999882)
		(end 387.304026 -312.999882)
		(stroke
			(width 0.1016)
			(type default)
		)
		(fill no)
		(layer "In8.Cu")
	)
	(gr_circle
		(center 387.050026 -309.199788)
		(end 387.304026 -309.199788)
		(stroke
			(width 0.1016)
			(type default)
		)
		(fill no)
		(layer "In8.Cu")
	)
	(gr_circle
		(center 387.050026 -307.299868)
		(end 387.304026 -307.299868)
		(stroke
			(width 0.1016)
			(type default)
		)
		(fill no)
		(layer "In8.Cu")
	)
	(gr_circle
		(center 387.050026 -305.399948)
		(end 387.304026 -305.399948)
		(stroke
			(width 0.1016)
			(type default)
		)
		(fill no)
		(layer "In8.Cu")
	)
	(gr_circle
		(center 387.050026 -303.499774)
		(end 387.304026 -303.499774)
		(stroke
			(width 0.1016)
			(type default)
		)
		(fill no)
		(layer "In8.Cu")
	)
	(gr_circle
		(center 387.050026 -301.599854)
		(end 387.304026 -301.599854)
		(stroke
			(width 0.1016)
			(type default)
		)
		(fill no)
		(layer "In8.Cu")
	)
	(gr_circle
		(center 387.999986 -316.799722)
		(end 388.253986 -316.799722)
		(stroke
			(width 0.1016)
			(type default)
		)
		(fill no)
		(layer "In8.Cu")
	)
	(gr_circle
		(center 387.999986 -315.849762)
		(end 388.253986 -315.849762)
		(stroke
			(width 0.1016)
			(type default)
		)
		(fill no)
		(layer "In8.Cu")
	)
	(gr_circle
		(center 387.999986 -312.049922)
		(end 388.253986 -312.049922)
		(stroke
			(width 0.1016)
			(type default)
		)
		(fill no)
		(layer "In8.Cu")
	)
	(gr_circle
		(center 387.999986 -311.099962)
		(end 388.253986 -311.099962)
		(stroke
			(width 0.1016)
			(type default)
		)
		(fill no)
		(layer "In8.Cu")
	)
	(gr_circle
		(center 387.999986 -309.199788)
		(end 388.253986 -309.199788)
		(stroke
			(width 0.1016)
			(type default)
		)
		(fill no)
		(layer "In8.Cu")
	)
	(gr_circle
		(center 387.999986 -307.299868)
		(end 388.253986 -307.299868)
		(stroke
			(width 0.1016)
			(type default)
		)
		(fill no)
		(layer "In8.Cu")
	)
	(gr_circle
		(center 387.999986 -305.399948)
		(end 388.253986 -305.399948)
		(stroke
			(width 0.1016)
			(type default)
		)
		(fill no)
		(layer "In8.Cu")
	)
	(gr_circle
		(center 387.999986 -303.499774)
		(end 388.253986 -303.499774)
		(stroke
			(width 0.1016)
			(type default)
		)
		(fill no)
		(layer "In8.Cu")
	)
	(gr_circle
		(center 387.999986 -301.599854)
		(end 388.253986 -301.599854)
		(stroke
			(width 0.1016)
			(type default)
		)
		(fill no)
		(layer "In8.Cu")
	)
	(gr_circle
		(center 388.949946 -318.699896)
		(end 389.203946 -318.699896)
		(stroke
			(width 0.1016)
			(type default)
		)
		(fill no)
		(layer "In8.Cu")
	)
	(gr_circle
		(center 388.949946 -317.749936)
		(end 389.203946 -317.749936)
		(stroke
			(width 0.1016)
			(type default)
		)
		(fill no)
		(layer "In8.Cu")
	)
	(gr_circle
		(center 388.949946 -313.949842)
		(end 389.203946 -313.949842)
		(stroke
			(width 0.1016)
			(type default)
		)
		(fill no)
		(layer "In8.Cu")
	)
	(gr_circle
		(center 388.949946 -312.999882)
		(end 389.203946 -312.999882)
		(stroke
			(width 0.1016)
			(type default)
		)
		(fill no)
		(layer "In8.Cu")
	)
	(gr_circle
		(center 389.899906 -316.799722)
		(end 390.153906 -316.799722)
		(stroke
			(width 0.1016)
			(type default)
		)
		(fill no)
		(layer "In8.Cu")
	)
	(gr_circle
		(center 389.899906 -315.849762)
		(end 390.153906 -315.849762)
		(stroke
			(width 0.1016)
			(type default)
		)
		(fill no)
		(layer "In8.Cu")
	)
	(gr_circle
		(center 389.899906 -312.049922)
		(end 390.153906 -312.049922)
		(stroke
			(width 0.1016)
			(type default)
		)
		(fill no)
		(layer "In8.Cu")
	)
	(gr_circle
		(center 389.899906 -311.099962)
		(end 390.153906 -311.099962)
		(stroke
			(width 0.1016)
			(type default)
		)
		(fill no)
		(layer "In8.Cu")
	)
	(gr_circle
		(center 389.899906 -309.199788)
		(end 390.153906 -309.199788)
		(stroke
			(width 0.1016)
			(type default)
		)
		(fill no)
		(layer "In8.Cu")
	)
	(gr_circle
		(center 389.899906 -307.299868)
		(end 390.153906 -307.299868)
		(stroke
			(width 0.1016)
			(type default)
		)
		(fill no)
		(layer "In8.Cu")
	)
	(gr_circle
		(center 389.899906 -305.399948)
		(end 390.153906 -305.399948)
		(stroke
			(width 0.1016)
			(type default)
		)
		(fill no)
		(layer "In8.Cu")
	)
	(gr_circle
		(center 389.899906 -303.499774)
		(end 390.153906 -303.499774)
		(stroke
			(width 0.1016)
			(type default)
		)
		(fill no)
		(layer "In8.Cu")
	)
	(gr_circle
		(center 389.899906 -301.599854)
		(end 390.153906 -301.599854)
		(stroke
			(width 0.1016)
			(type default)
		)
		(fill no)
		(layer "In8.Cu")
	)
	(gr_circle
		(center 390.849866 -318.699896)
		(end 391.103866 -318.699896)
		(stroke
			(width 0.1016)
			(type default)
		)
		(fill no)
		(layer "In8.Cu")
	)
	(gr_circle
		(center 390.849866 -317.749936)
		(end 391.103866 -317.749936)
		(stroke
			(width 0.1016)
			(type default)
		)
		(fill no)
		(layer "In8.Cu")
	)
	(gr_circle
		(center 390.849866 -313.949842)
		(end 391.103866 -313.949842)
		(stroke
			(width 0.1016)
			(type default)
		)
		(fill no)
		(layer "In8.Cu")
	)
	(gr_circle
		(center 390.849866 -312.999882)
		(end 391.103866 -312.999882)
		(stroke
			(width 0.1016)
			(type default)
		)
		(fill no)
		(layer "In8.Cu")
	)
	(gr_circle
		(center 390.849866 -309.199788)
		(end 391.103866 -309.199788)
		(stroke
			(width 0.1016)
			(type default)
		)
		(fill no)
		(layer "In8.Cu")
	)
	(gr_circle
		(center 390.849866 -307.299868)
		(end 391.103866 -307.299868)
		(stroke
			(width 0.1016)
			(type default)
		)
		(fill no)
		(layer "In8.Cu")
	)
	(gr_circle
		(center 390.849866 -305.399948)
		(end 391.103866 -305.399948)
		(stroke
			(width 0.1016)
			(type default)
		)
		(fill no)
		(layer "In8.Cu")
	)
	(gr_circle
		(center 390.849866 -303.499774)
		(end 391.103866 -303.499774)
		(stroke
			(width 0.1016)
			(type default)
		)
		(fill no)
		(layer "In8.Cu")
	)
	(gr_circle
		(center 390.849866 -301.599854)
		(end 391.103866 -301.599854)
		(stroke
			(width 0.1016)
			(type default)
		)
		(fill no)
		(layer "In8.Cu")
	)
	(gr_circle
		(center 391.799826 -316.799722)
		(end 392.053826 -316.799722)
		(stroke
			(width 0.1016)
			(type default)
		)
		(fill no)
		(layer "In8.Cu")
	)
	(gr_circle
		(center 391.799826 -315.849762)
		(end 392.053826 -315.849762)
		(stroke
			(width 0.1016)
			(type default)
		)
		(fill no)
		(layer "In8.Cu")
	)
	(gr_circle
		(center 391.799826 -312.049922)
		(end 392.053826 -312.049922)
		(stroke
			(width 0.1016)
			(type default)
		)
		(fill no)
		(layer "In8.Cu")
	)
	(gr_circle
		(center 391.799826 -311.099962)
		(end 392.053826 -311.099962)
		(stroke
			(width 0.1016)
			(type default)
		)
		(fill no)
		(layer "In8.Cu")
	)
	(gr_circle
		(center 391.799826 -308.249828)
		(end 392.053826 -308.249828)
		(stroke
			(width 0.1016)
			(type default)
		)
		(fill no)
		(layer "In8.Cu")
	)
	(gr_circle
		(center 391.799826 -306.349908)
		(end 392.053826 -306.349908)
		(stroke
			(width 0.1016)
			(type default)
		)
		(fill no)
		(layer "In8.Cu")
	)
	(gr_circle
		(center 391.799826 -304.449734)
		(end 392.053826 -304.449734)
		(stroke
			(width 0.1016)
			(type default)
		)
		(fill no)
		(layer "In8.Cu")
	)
	(gr_circle
		(center 391.799826 -302.549814)
		(end 392.053826 -302.549814)
		(stroke
			(width 0.1016)
			(type default)
		)
		(fill no)
		(layer "In8.Cu")
	)
	(gr_circle
		(center 392.749786 -318.699896)
		(end 393.003786 -318.699896)
		(stroke
			(width 0.1016)
			(type default)
		)
		(fill no)
		(layer "In8.Cu")
	)
	(gr_circle
		(center 392.749786 -317.749936)
		(end 393.003786 -317.749936)
		(stroke
			(width 0.1016)
			(type default)
		)
		(fill no)
		(layer "In8.Cu")
	)
	(gr_circle
		(center 392.749786 -313.949842)
		(end 393.003786 -313.949842)
		(stroke
			(width 0.1016)
			(type default)
		)
		(fill no)
		(layer "In8.Cu")
	)
	(gr_circle
		(center 392.749786 -312.999882)
		(end 393.003786 -312.999882)
		(stroke
			(width 0.1016)
			(type default)
		)
		(fill no)
		(layer "In8.Cu")
	)
	(gr_circle
		(center 392.749786 -308.249828)
		(end 393.003786 -308.249828)
		(stroke
			(width 0.1016)
			(type default)
		)
		(fill no)
		(layer "In8.Cu")
	)
	(gr_circle
		(center 392.749786 -306.349908)
		(end 393.003786 -306.349908)
		(stroke
			(width 0.1016)
			(type default)
		)
		(fill no)
		(layer "In8.Cu")
	)
	(gr_circle
		(center 392.749786 -304.449734)
		(end 393.003786 -304.449734)
		(stroke
			(width 0.1016)
			(type default)
		)
		(fill no)
		(layer "In8.Cu")
	)
	(gr_circle
		(center 392.749786 -302.549814)
		(end 393.003786 -302.549814)
		(stroke
			(width 0.1016)
			(type default)
		)
		(fill no)
		(layer "In8.Cu")
	)
	(gr_circle
		(center 392.749786 -278.799798)
		(end 393.003786 -278.799798)
		(stroke
			(width 0.1016)
			(type default)
		)
		(fill no)
		(layer "In8.Cu")
	)
	(gr_circle
		(center 392.749786 -277.849838)
		(end 393.003786 -277.849838)
		(stroke
			(width 0.1016)
			(type default)
		)
		(fill no)
		(layer "In8.Cu")
	)
	(gr_circle
		(center 393.7 -316.799722)
		(end 393.954 -316.799722)
		(stroke
			(width 0.1016)
			(type default)
		)
		(fill no)
		(layer "In8.Cu")
	)
	(gr_circle
		(center 393.7 -315.849762)
		(end 393.954 -315.849762)
		(stroke
			(width 0.1016)
			(type default)
		)
		(fill no)
		(layer "In8.Cu")
	)
	(gr_circle
		(center 393.7 -312.049922)
		(end 393.954 -312.049922)
		(stroke
			(width 0.1016)
			(type default)
		)
		(fill no)
		(layer "In8.Cu")
	)
	(gr_circle
		(center 393.7 -311.099962)
		(end 393.954 -311.099962)
		(stroke
			(width 0.1016)
			(type default)
		)
		(fill no)
		(layer "In8.Cu")
	)
	(gr_circle
		(center 393.7 -280.699464)
		(end 393.954 -280.699464)
		(stroke
			(width 0.1016)
			(type default)
		)
		(fill no)
		(layer "In8.Cu")
	)
	(gr_circle
		(center 393.7 -279.749504)
		(end 393.954 -279.749504)
		(stroke
			(width 0.1016)
			(type default)
		)
		(fill no)
		(layer "In8.Cu")
	)
	(gr_circle
		(center 394.64996 -318.699896)
		(end 394.90396 -318.699896)
		(stroke
			(width 0.1016)
			(type default)
		)
		(fill no)
		(layer "In8.Cu")
	)
	(gr_circle
		(center 394.64996 -317.749936)
		(end 394.90396 -317.749936)
		(stroke
			(width 0.1016)
			(type default)
		)
		(fill no)
		(layer "In8.Cu")
	)
	(gr_circle
		(center 394.64996 -313.949842)
		(end 394.90396 -313.949842)
		(stroke
			(width 0.1016)
			(type default)
		)
		(fill no)
		(layer "In8.Cu")
	)
	(gr_circle
		(center 394.64996 -312.999882)
		(end 394.90396 -312.999882)
		(stroke
			(width 0.1016)
			(type default)
		)
		(fill no)
		(layer "In8.Cu")
	)
	(gr_circle
		(center 394.64996 -278.799798)
		(end 394.90396 -278.799798)
		(stroke
			(width 0.1016)
			(type default)
		)
		(fill no)
		(layer "In8.Cu")
	)
	(gr_circle
		(center 394.64996 -277.849838)
		(end 394.90396 -277.849838)
		(stroke
			(width 0.1016)
			(type default)
		)
		(fill no)
		(layer "In8.Cu")
	)
	(gr_circle
		(center 395.59992 -316.799722)
		(end 395.85392 -316.799722)
		(stroke
			(width 0.1016)
			(type default)
		)
		(fill no)
		(layer "In8.Cu")
	)
	(gr_circle
		(center 395.59992 -315.849762)
		(end 395.85392 -315.849762)
		(stroke
			(width 0.1016)
			(type default)
		)
		(fill no)
		(layer "In8.Cu")
	)
	(gr_circle
		(center 395.59992 -312.049922)
		(end 395.85392 -312.049922)
		(stroke
			(width 0.1016)
			(type default)
		)
		(fill no)
		(layer "In8.Cu")
	)
	(gr_circle
		(center 395.59992 -311.099962)
		(end 395.85392 -311.099962)
		(stroke
			(width 0.1016)
			(type default)
		)
		(fill no)
		(layer "In8.Cu")
	)
	(gr_circle
		(center 395.59992 -280.699464)
		(end 395.85392 -280.699464)
		(stroke
			(width 0.1016)
			(type default)
		)
		(fill no)
		(layer "In8.Cu")
	)
	(gr_circle
		(center 395.59992 -279.749504)
		(end 395.85392 -279.749504)
		(stroke
			(width 0.1016)
			(type default)
		)
		(fill no)
		(layer "In8.Cu")
	)
	(gr_circle
		(center 396.54988 -318.699896)
		(end 396.80388 -318.699896)
		(stroke
			(width 0.1016)
			(type default)
		)
		(fill no)
		(layer "In8.Cu")
	)
	(gr_circle
		(center 396.54988 -317.749936)
		(end 396.80388 -317.749936)
		(stroke
			(width 0.1016)
			(type default)
		)
		(fill no)
		(layer "In8.Cu")
	)
	(gr_circle
		(center 396.54988 -313.949842)
		(end 396.80388 -313.949842)
		(stroke
			(width 0.1016)
			(type default)
		)
		(fill no)
		(layer "In8.Cu")
	)
	(gr_circle
		(center 396.54988 -312.999882)
		(end 396.80388 -312.999882)
		(stroke
			(width 0.1016)
			(type default)
		)
		(fill no)
		(layer "In8.Cu")
	)
	(gr_circle
		(center 396.54988 -278.799798)
		(end 396.80388 -278.799798)
		(stroke
			(width 0.1016)
			(type default)
		)
		(fill no)
		(layer "In8.Cu")
	)
	(gr_circle
		(center 396.54988 -277.849838)
		(end 396.80388 -277.849838)
		(stroke
			(width 0.1016)
			(type default)
		)
		(fill no)
		(layer "In8.Cu")
	)
	(gr_circle
		(center 397.49984 -316.799722)
		(end 397.75384 -316.799722)
		(stroke
			(width 0.1016)
			(type default)
		)
		(fill no)
		(layer "In8.Cu")
	)
	(gr_circle
		(center 397.49984 -315.849762)
		(end 397.75384 -315.849762)
		(stroke
			(width 0.1016)
			(type default)
		)
		(fill no)
		(layer "In8.Cu")
	)
	(gr_circle
		(center 397.49984 -312.049922)
		(end 397.75384 -312.049922)
		(stroke
			(width 0.1016)
			(type default)
		)
		(fill no)
		(layer "In8.Cu")
	)
	(gr_circle
		(center 397.49984 -311.099962)
		(end 397.75384 -311.099962)
		(stroke
			(width 0.1016)
			(type default)
		)
		(fill no)
		(layer "In8.Cu")
	)
	(gr_circle
		(center 397.49984 -280.699464)
		(end 397.75384 -280.699464)
		(stroke
			(width 0.1016)
			(type default)
		)
		(fill no)
		(layer "In8.Cu")
	)
	(gr_circle
		(center 397.49984 -279.749504)
		(end 397.75384 -279.749504)
		(stroke
			(width 0.1016)
			(type default)
		)
		(fill no)
		(layer "In8.Cu")
	)
	(gr_circle
		(center 398.4498 -318.699896)
		(end 398.7038 -318.699896)
		(stroke
			(width 0.1016)
			(type default)
		)
		(fill no)
		(layer "In8.Cu")
	)
	(gr_circle
		(center 398.4498 -317.749936)
		(end 398.7038 -317.749936)
		(stroke
			(width 0.1016)
			(type default)
		)
		(fill no)
		(layer "In8.Cu")
	)
	(gr_circle
		(center 398.4498 -313.949842)
		(end 398.7038 -313.949842)
		(stroke
			(width 0.1016)
			(type default)
		)
		(fill no)
		(layer "In8.Cu")
	)
	(gr_circle
		(center 398.4498 -312.999882)
		(end 398.7038 -312.999882)
		(stroke
			(width 0.1016)
			(type default)
		)
		(fill no)
		(layer "In8.Cu")
	)
	(gr_circle
		(center 398.4498 -278.799798)
		(end 398.7038 -278.799798)
		(stroke
			(width 0.1016)
			(type default)
		)
		(fill no)
		(layer "In8.Cu")
	)
	(gr_circle
		(center 398.4498 -277.849838)
		(end 398.7038 -277.849838)
		(stroke
			(width 0.1016)
			(type default)
		)
		(fill no)
		(layer "In8.Cu")
	)
	(gr_circle
		(center 399.400014 -280.699464)
		(end 399.654014 -280.699464)
		(stroke
			(width 0.1016)
			(type default)
		)
		(fill no)
		(layer "In8.Cu")
	)
	(gr_circle
		(center 399.400014 -279.749504)
		(end 399.654014 -279.749504)
		(stroke
			(width 0.1016)
			(type default)
		)
		(fill no)
		(layer "In8.Cu")
	)
	(gr_circle
		(center 400.349974 -278.799798)
		(end 400.603974 -278.799798)
		(stroke
			(width 0.1016)
			(type default)
		)
		(fill no)
		(layer "In8.Cu")
	)
	(gr_circle
		(center 400.349974 -277.849838)
		(end 400.603974 -277.849838)
		(stroke
			(width 0.1016)
			(type default)
		)
		(fill no)
		(layer "In8.Cu")
	)
	(gr_circle
		(center 401.299934 -280.699464)
		(end 401.553934 -280.699464)
		(stroke
			(width 0.1016)
			(type default)
		)
		(fill no)
		(layer "In8.Cu")
	)
	(gr_circle
		(center 401.299934 -279.749504)
		(end 401.553934 -279.749504)
		(stroke
			(width 0.1016)
			(type default)
		)
		(fill no)
		(layer "In8.Cu")
	)
	(gr_circle
		(center 402.249894 -278.799798)
		(end 402.503894 -278.799798)
		(stroke
			(width 0.1016)
			(type default)
		)
		(fill no)
		(layer "In8.Cu")
	)
	(gr_circle
		(center 402.249894 -277.849838)
		(end 402.503894 -277.849838)
		(stroke
			(width 0.1016)
			(type default)
		)
		(fill no)
		(layer "In8.Cu")
	)
	(gr_circle
		(center 403.199854 -280.699464)
		(end 403.453854 -280.699464)
		(stroke
			(width 0.1016)
			(type default)
		)
		(fill no)
		(layer "In8.Cu")
	)
	(gr_circle
		(center 403.199854 -279.749504)
		(end 403.453854 -279.749504)
		(stroke
			(width 0.1016)
			(type default)
		)
		(fill no)
		(layer "In8.Cu")
	)
	(gr_circle
		(center 404.149814 -278.799798)
		(end 404.403814 -278.799798)
		(stroke
			(width 0.1016)
			(type default)
		)
		(fill no)
		(layer "In8.Cu")
	)
	(gr_circle
		(center 404.149814 -277.849838)
		(end 404.403814 -277.849838)
		(stroke
			(width 0.1016)
			(type default)
		)
		(fill no)
		(layer "In8.Cu")
	)
	(gr_circle
		(center 405.099774 -280.699464)
		(end 405.353774 -280.699464)
		(stroke
			(width 0.1016)
			(type default)
		)
		(fill no)
		(layer "In8.Cu")
	)
	(gr_circle
		(center 405.099774 -279.749504)
		(end 405.353774 -279.749504)
		(stroke
			(width 0.1016)
			(type default)
		)
		(fill no)
		(layer "In8.Cu")
	)
	(gr_circle
		(center 406.049988 -278.799798)
		(end 406.303988 -278.799798)
		(stroke
			(width 0.1016)
			(type default)
		)
		(fill no)
		(layer "In8.Cu")
	)
	(gr_circle
		(center 406.049988 -277.849838)
		(end 406.303988 -277.849838)
		(stroke
			(width 0.1016)
			(type default)
		)
		(fill no)
		(layer "In8.Cu")
	)
	(gr_circle
		(center 406.999948 -280.699464)
		(end 407.253948 -280.699464)
		(stroke
			(width 0.1016)
			(type default)
		)
		(fill no)
		(layer "In8.Cu")
	)
	(gr_circle
		(center 406.999948 -279.749504)
		(end 407.253948 -279.749504)
		(stroke
			(width 0.1016)
			(type default)
		)
		(fill no)
		(layer "In8.Cu")
	)
	(gr_circle
		(center 407.949654 -278.799798)
		(end 408.203654 -278.799798)
		(stroke
			(width 0.1016)
			(type default)
		)
		(fill no)
		(layer "In8.Cu")
	)
	(gr_circle
		(center 407.949654 -277.849838)
		(end 408.203654 -277.849838)
		(stroke
			(width 0.1016)
			(type default)
		)
		(fill no)
		(layer "In8.Cu")
	)
	(gr_circle
		(center 408.899868 -280.699464)
		(end 409.153868 -280.699464)
		(stroke
			(width 0.1016)
			(type default)
		)
		(fill no)
		(layer "In8.Cu")
	)
	(gr_circle
		(center 408.899868 -279.749504)
		(end 409.153868 -279.749504)
		(stroke
			(width 0.1016)
			(type default)
		)
		(fill no)
		(layer "In8.Cu")
	)
	(gr_circle
		(center 409.849574 -278.799798)
		(end 410.103574 -278.799798)
		(stroke
			(width 0.1016)
			(type default)
		)
		(fill no)
		(layer "In8.Cu")
	)
	(gr_circle
		(center 409.849574 -277.849838)
		(end 410.103574 -277.849838)
		(stroke
			(width 0.1016)
			(type default)
		)
		(fill no)
		(layer "In8.Cu")
	)
	(gr_circle
		(center 410.799788 -280.699464)
		(end 411.053788 -280.699464)
		(stroke
			(width 0.1016)
			(type default)
		)
		(fill no)
		(layer "In8.Cu")
	)
	(gr_circle
		(center 410.799788 -279.749504)
		(end 411.053788 -279.749504)
		(stroke
			(width 0.1016)
			(type default)
		)
		(fill no)
		(layer "In8.Cu")
	)
	(gr_circle
		(center 411.749748 -278.799798)
		(end 412.003748 -278.799798)
		(stroke
			(width 0.1016)
			(type default)
		)
		(fill no)
		(layer "In8.Cu")
	)
	(gr_circle
		(center 411.749748 -277.849838)
		(end 412.003748 -277.849838)
		(stroke
			(width 0.1016)
			(type default)
		)
		(fill no)
		(layer "In8.Cu")
	)
	(gr_circle
		(center 412.699962 -280.699464)
		(end 412.953962 -280.699464)
		(stroke
			(width 0.1016)
			(type default)
		)
		(fill no)
		(layer "In8.Cu")
	)
	(gr_circle
		(center 412.699962 -279.749504)
		(end 412.953962 -279.749504)
		(stroke
			(width 0.1016)
			(type default)
		)
		(fill no)
		(layer "In8.Cu")
	)
	(gr_circle
		(center 413.649668 -278.799798)
		(end 413.903668 -278.799798)
		(stroke
			(width 0.1016)
			(type default)
		)
		(fill no)
		(layer "In8.Cu")
	)
	(gr_circle
		(center 413.649668 -277.849838)
		(end 413.903668 -277.849838)
		(stroke
			(width 0.1016)
			(type default)
		)
		(fill no)
		(layer "In8.Cu")
	)
	(gr_circle
		(center 414.599882 -316.799722)
		(end 414.853882 -316.799722)
		(stroke
			(width 0.1016)
			(type default)
		)
		(fill no)
		(layer "In8.Cu")
	)
	(gr_circle
		(center 414.599882 -315.849762)
		(end 414.853882 -315.849762)
		(stroke
			(width 0.1016)
			(type default)
		)
		(fill no)
		(layer "In8.Cu")
	)
	(gr_circle
		(center 414.599882 -312.049922)
		(end 414.853882 -312.049922)
		(stroke
			(width 0.1016)
			(type default)
		)
		(fill no)
		(layer "In8.Cu")
	)
	(gr_circle
		(center 414.599882 -311.099962)
		(end 414.853882 -311.099962)
		(stroke
			(width 0.1016)
			(type default)
		)
		(fill no)
		(layer "In8.Cu")
	)
	(gr_circle
		(center 414.599882 -280.699464)
		(end 414.853882 -280.699464)
		(stroke
			(width 0.1016)
			(type default)
		)
		(fill no)
		(layer "In8.Cu")
	)
	(gr_circle
		(center 414.599882 -279.749504)
		(end 414.853882 -279.749504)
		(stroke
			(width 0.1016)
			(type default)
		)
		(fill no)
		(layer "In8.Cu")
	)
	(gr_circle
		(center 415.549588 -278.799798)
		(end 415.803588 -278.799798)
		(stroke
			(width 0.1016)
			(type default)
		)
		(fill no)
		(layer "In8.Cu")
	)
	(gr_circle
		(center 415.549588 -277.849838)
		(end 415.803588 -277.849838)
		(stroke
			(width 0.1016)
			(type default)
		)
		(fill no)
		(layer "In8.Cu")
	)
	(gr_circle
		(center 415.549842 -318.699896)
		(end 415.803842 -318.699896)
		(stroke
			(width 0.1016)
			(type default)
		)
		(fill no)
		(layer "In8.Cu")
	)
	(gr_circle
		(center 415.549842 -317.749936)
		(end 415.803842 -317.749936)
		(stroke
			(width 0.1016)
			(type default)
		)
		(fill no)
		(layer "In8.Cu")
	)
	(gr_circle
		(center 415.549842 -313.949842)
		(end 415.803842 -313.949842)
		(stroke
			(width 0.1016)
			(type default)
		)
		(fill no)
		(layer "In8.Cu")
	)
	(gr_circle
		(center 415.549842 -312.999882)
		(end 415.803842 -312.999882)
		(stroke
			(width 0.1016)
			(type default)
		)
		(fill no)
		(layer "In8.Cu")
	)
	(gr_circle
		(center 416.499802 -316.799722)
		(end 416.753802 -316.799722)
		(stroke
			(width 0.1016)
			(type default)
		)
		(fill no)
		(layer "In8.Cu")
	)
	(gr_circle
		(center 416.499802 -315.849762)
		(end 416.753802 -315.849762)
		(stroke
			(width 0.1016)
			(type default)
		)
		(fill no)
		(layer "In8.Cu")
	)
	(gr_circle
		(center 416.499802 -312.049922)
		(end 416.753802 -312.049922)
		(stroke
			(width 0.1016)
			(type default)
		)
		(fill no)
		(layer "In8.Cu")
	)
	(gr_circle
		(center 416.499802 -311.099962)
		(end 416.753802 -311.099962)
		(stroke
			(width 0.1016)
			(type default)
		)
		(fill no)
		(layer "In8.Cu")
	)
	(gr_circle
		(center 416.499802 -280.699464)
		(end 416.753802 -280.699464)
		(stroke
			(width 0.1016)
			(type default)
		)
		(fill no)
		(layer "In8.Cu")
	)
	(gr_circle
		(center 416.499802 -279.749504)
		(end 416.753802 -279.749504)
		(stroke
			(width 0.1016)
			(type default)
		)
		(fill no)
		(layer "In8.Cu")
	)
	(gr_circle
		(center 417.449762 -278.799798)
		(end 417.703762 -278.799798)
		(stroke
			(width 0.1016)
			(type default)
		)
		(fill no)
		(layer "In8.Cu")
	)
	(gr_circle
		(center 417.449762 -277.849838)
		(end 417.703762 -277.849838)
		(stroke
			(width 0.1016)
			(type default)
		)
		(fill no)
		(layer "In8.Cu")
	)
	(gr_circle
		(center 417.450016 -318.699896)
		(end 417.704016 -318.699896)
		(stroke
			(width 0.1016)
			(type default)
		)
		(fill no)
		(layer "In8.Cu")
	)
	(gr_circle
		(center 417.450016 -317.749936)
		(end 417.704016 -317.749936)
		(stroke
			(width 0.1016)
			(type default)
		)
		(fill no)
		(layer "In8.Cu")
	)
	(gr_circle
		(center 417.450016 -313.949842)
		(end 417.704016 -313.949842)
		(stroke
			(width 0.1016)
			(type default)
		)
		(fill no)
		(layer "In8.Cu")
	)
	(gr_circle
		(center 417.450016 -312.999882)
		(end 417.704016 -312.999882)
		(stroke
			(width 0.1016)
			(type default)
		)
		(fill no)
		(layer "In8.Cu")
	)
	(gr_circle
		(center 418.399976 -316.799722)
		(end 418.653976 -316.799722)
		(stroke
			(width 0.1016)
			(type default)
		)
		(fill no)
		(layer "In8.Cu")
	)
	(gr_circle
		(center 418.399976 -315.849762)
		(end 418.653976 -315.849762)
		(stroke
			(width 0.1016)
			(type default)
		)
		(fill no)
		(layer "In8.Cu")
	)
	(gr_circle
		(center 418.399976 -312.049922)
		(end 418.653976 -312.049922)
		(stroke
			(width 0.1016)
			(type default)
		)
		(fill no)
		(layer "In8.Cu")
	)
	(gr_circle
		(center 418.399976 -311.099962)
		(end 418.653976 -311.099962)
		(stroke
			(width 0.1016)
			(type default)
		)
		(fill no)
		(layer "In8.Cu")
	)
	(gr_circle
		(center 418.399976 -280.699464)
		(end 418.653976 -280.699464)
		(stroke
			(width 0.1016)
			(type default)
		)
		(fill no)
		(layer "In8.Cu")
	)
	(gr_circle
		(center 418.399976 -279.749504)
		(end 418.653976 -279.749504)
		(stroke
			(width 0.1016)
			(type default)
		)
		(fill no)
		(layer "In8.Cu")
	)
	(gr_circle
		(center 419.349682 -278.799798)
		(end 419.603682 -278.799798)
		(stroke
			(width 0.1016)
			(type default)
		)
		(fill no)
		(layer "In8.Cu")
	)
	(gr_circle
		(center 419.349682 -277.849838)
		(end 419.603682 -277.849838)
		(stroke
			(width 0.1016)
			(type default)
		)
		(fill no)
		(layer "In8.Cu")
	)
	(gr_circle
		(center 419.349936 -318.699896)
		(end 419.603936 -318.699896)
		(stroke
			(width 0.1016)
			(type default)
		)
		(fill no)
		(layer "In8.Cu")
	)
	(gr_circle
		(center 419.349936 -317.749936)
		(end 419.603936 -317.749936)
		(stroke
			(width 0.1016)
			(type default)
		)
		(fill no)
		(layer "In8.Cu")
	)
	(gr_circle
		(center 419.349936 -313.949842)
		(end 419.603936 -313.949842)
		(stroke
			(width 0.1016)
			(type default)
		)
		(fill no)
		(layer "In8.Cu")
	)
	(gr_circle
		(center 419.349936 -312.999882)
		(end 419.603936 -312.999882)
		(stroke
			(width 0.1016)
			(type default)
		)
		(fill no)
		(layer "In8.Cu")
	)
	(gr_circle
		(center 420.299896 -316.799722)
		(end 420.553896 -316.799722)
		(stroke
			(width 0.1016)
			(type default)
		)
		(fill no)
		(layer "In8.Cu")
	)
	(gr_circle
		(center 420.299896 -315.849762)
		(end 420.553896 -315.849762)
		(stroke
			(width 0.1016)
			(type default)
		)
		(fill no)
		(layer "In8.Cu")
	)
	(gr_circle
		(center 420.299896 -312.049922)
		(end 420.553896 -312.049922)
		(stroke
			(width 0.1016)
			(type default)
		)
		(fill no)
		(layer "In8.Cu")
	)
	(gr_circle
		(center 420.299896 -311.099962)
		(end 420.553896 -311.099962)
		(stroke
			(width 0.1016)
			(type default)
		)
		(fill no)
		(layer "In8.Cu")
	)
	(gr_circle
		(center 420.299896 -280.699464)
		(end 420.553896 -280.699464)
		(stroke
			(width 0.1016)
			(type default)
		)
		(fill no)
		(layer "In8.Cu")
	)
	(gr_circle
		(center 420.299896 -279.749504)
		(end 420.553896 -279.749504)
		(stroke
			(width 0.1016)
			(type default)
		)
		(fill no)
		(layer "In8.Cu")
	)
	(gr_circle
		(center 421.249602 -278.799798)
		(end 421.503602 -278.799798)
		(stroke
			(width 0.1016)
			(type default)
		)
		(fill no)
		(layer "In8.Cu")
	)
	(gr_circle
		(center 421.249602 -277.849838)
		(end 421.503602 -277.849838)
		(stroke
			(width 0.1016)
			(type default)
		)
		(fill no)
		(layer "In8.Cu")
	)
	(gr_circle
		(center 421.249856 -318.699896)
		(end 421.503856 -318.699896)
		(stroke
			(width 0.1016)
			(type default)
		)
		(fill no)
		(layer "In8.Cu")
	)
	(gr_circle
		(center 421.249856 -317.749936)
		(end 421.503856 -317.749936)
		(stroke
			(width 0.1016)
			(type default)
		)
		(fill no)
		(layer "In8.Cu")
	)
	(gr_circle
		(center 421.249856 -313.949842)
		(end 421.503856 -313.949842)
		(stroke
			(width 0.1016)
			(type default)
		)
		(fill no)
		(layer "In8.Cu")
	)
	(gr_circle
		(center 421.249856 -312.999882)
		(end 421.503856 -312.999882)
		(stroke
			(width 0.1016)
			(type default)
		)
		(fill no)
		(layer "In8.Cu")
	)
	(gr_circle
		(center 422.199816 -280.699464)
		(end 422.453816 -280.699464)
		(stroke
			(width 0.1016)
			(type default)
		)
		(fill no)
		(layer "In8.Cu")
	)
	(gr_circle
		(center 422.199816 -279.749504)
		(end 422.453816 -279.749504)
		(stroke
			(width 0.1016)
			(type default)
		)
		(fill no)
		(layer "In8.Cu")
	)
	(gr_circle
		(center 423.149776 -278.799798)
		(end 423.403776 -278.799798)
		(stroke
			(width 0.1016)
			(type default)
		)
		(fill no)
		(layer "In8.Cu")
	)
	(gr_circle
		(center 423.149776 -277.849838)
		(end 423.403776 -277.849838)
		(stroke
			(width 0.1016)
			(type default)
		)
		(fill no)
		(layer "In8.Cu")
	)
	(gr_circle
		(center 423.15003 -287.349946)
		(end 423.40403 -287.349946)
		(stroke
			(width 0.1016)
			(type default)
		)
		(fill no)
		(layer "In8.Cu")
	)
	(gr_circle
		(center 423.15003 -285.449772)
		(end 423.40403 -285.449772)
		(stroke
			(width 0.1016)
			(type default)
		)
		(fill no)
		(layer "In8.Cu")
	)
	(gr_circle
		(center 423.15003 -283.549852)
		(end 423.40403 -283.549852)
		(stroke
			(width 0.1016)
			(type default)
		)
		(fill no)
		(layer "In8.Cu")
	)
	(gr_circle
		(center 424.09999 -287.349946)
		(end 424.35399 -287.349946)
		(stroke
			(width 0.1016)
			(type default)
		)
		(fill no)
		(layer "In8.Cu")
	)
	(gr_circle
		(center 424.09999 -285.449772)
		(end 424.35399 -285.449772)
		(stroke
			(width 0.1016)
			(type default)
		)
		(fill no)
		(layer "In8.Cu")
	)
	(gr_circle
		(center 424.09999 -283.549852)
		(end 424.35399 -283.549852)
		(stroke
			(width 0.1016)
			(type default)
		)
		(fill no)
		(layer "In8.Cu")
	)
	(gr_circle
		(center 424.09999 -280.699464)
		(end 424.35399 -280.699464)
		(stroke
			(width 0.1016)
			(type default)
		)
		(fill no)
		(layer "In8.Cu")
	)
	(gr_circle
		(center 424.09999 -279.749504)
		(end 424.35399 -279.749504)
		(stroke
			(width 0.1016)
			(type default)
		)
		(fill no)
		(layer "In8.Cu")
	)
	(gr_circle
		(center 425.049696 -278.799798)
		(end 425.303696 -278.799798)
		(stroke
			(width 0.1016)
			(type default)
		)
		(fill no)
		(layer "In8.Cu")
	)
	(gr_circle
		(center 425.049696 -277.849838)
		(end 425.303696 -277.849838)
		(stroke
			(width 0.1016)
			(type default)
		)
		(fill no)
		(layer "In8.Cu")
	)
	(gr_circle
		(center 425.04995 -288.299906)
		(end 425.30395 -288.299906)
		(stroke
			(width 0.1016)
			(type default)
		)
		(fill no)
		(layer "In8.Cu")
	)
	(gr_circle
		(center 425.04995 -286.399986)
		(end 425.30395 -286.399986)
		(stroke
			(width 0.1016)
			(type default)
		)
		(fill no)
		(layer "In8.Cu")
	)
	(gr_circle
		(center 425.04995 -284.499812)
		(end 425.30395 -284.499812)
		(stroke
			(width 0.1016)
			(type default)
		)
		(fill no)
		(layer "In8.Cu")
	)
	(gr_circle
		(center 425.04995 -282.599892)
		(end 425.30395 -282.599892)
		(stroke
			(width 0.1016)
			(type default)
		)
		(fill no)
		(layer "In8.Cu")
	)
	(gr_circle
		(center 425.99991 -288.299906)
		(end 426.25391 -288.299906)
		(stroke
			(width 0.1016)
			(type default)
		)
		(fill no)
		(layer "In8.Cu")
	)
	(gr_circle
		(center 425.99991 -286.399986)
		(end 426.25391 -286.399986)
		(stroke
			(width 0.1016)
			(type default)
		)
		(fill no)
		(layer "In8.Cu")
	)
	(gr_circle
		(center 425.99991 -284.499812)
		(end 426.25391 -284.499812)
		(stroke
			(width 0.1016)
			(type default)
		)
		(fill no)
		(layer "In8.Cu")
	)
	(gr_circle
		(center 425.99991 -282.599892)
		(end 426.25391 -282.599892)
		(stroke
			(width 0.1016)
			(type default)
		)
		(fill no)
		(layer "In8.Cu")
	)
	(gr_circle
		(center 425.99991 -280.699464)
		(end 426.25391 -280.699464)
		(stroke
			(width 0.1016)
			(type default)
		)
		(fill no)
		(layer "In8.Cu")
	)
	(gr_circle
		(center 425.99991 -279.749504)
		(end 426.25391 -279.749504)
		(stroke
			(width 0.1016)
			(type default)
		)
		(fill no)
		(layer "In8.Cu")
	)
	(gr_circle
		(center 426.949616 -278.799798)
		(end 427.203616 -278.799798)
		(stroke
			(width 0.1016)
			(type default)
		)
		(fill no)
		(layer "In8.Cu")
	)
	(gr_circle
		(center 426.949616 -277.849838)
		(end 427.203616 -277.849838)
		(stroke
			(width 0.1016)
			(type default)
		)
		(fill no)
		(layer "In8.Cu")
	)
	(gr_circle
		(center 427.89983 -280.699718)
		(end 428.15383 -280.699718)
		(stroke
			(width 0.1016)
			(type default)
		)
		(fill no)
		(layer "In8.Cu")
	)
	(gr_circle
		(center 427.89983 -279.749758)
		(end 428.15383 -279.749758)
		(stroke
			(width 0.1016)
			(type default)
		)
		(fill no)
		(layer "In8.Cu")
	)
	(gr_circle
		(center 428.84979 -278.799798)
		(end 429.10379 -278.799798)
		(stroke
			(width 0.1016)
			(type default)
		)
		(fill no)
		(layer "In8.Cu")
	)
	(gr_circle
		(center 428.84979 -277.849838)
		(end 429.10379 -277.849838)
		(stroke
			(width 0.1016)
			(type default)
		)
		(fill no)
		(layer "In8.Cu")
	)
	(gr_circle
		(center 429.800004 -279.749758)
		(end 430.054004 -279.749758)
		(stroke
			(width 0.1016)
			(type default)
		)
		(fill no)
		(layer "In8.Cu")
	)
	(gr_circle
		(center 429.800004 -276.899878)
		(end 430.054004 -276.899878)
		(stroke
			(width 0.1016)
			(type default)
		)
		(fill no)
		(layer "In8.Cu")
	)
	(gr_circle
		(center 430.749964 -279.749758)
		(end 431.003964 -279.749758)
		(stroke
			(width 0.1016)
			(type default)
		)
		(fill no)
		(layer "In8.Cu")
	)
	(gr_circle
		(center 430.749964 -276.899878)
		(end 431.003964 -276.899878)
		(stroke
			(width 0.1016)
			(type default)
		)
		(fill no)
		(layer "In8.Cu")
	)
	(gr_poly
		(pts
			(arc
				(start 252.431042 -397.963136)
				(mid 252.450565 -397.959235)
				(end 252.46711 -397.94815)
			)
			(arc
				(start 252.932438 -397.482822)
				(mid 252.943549 -397.466288)
				(end 252.947424 -397.446754)
			)
			(arc
				(start 252.947424 -392.961114)
				(mid 252.943523 -392.941591)
				(end 252.932438 -392.925046)
			)
			(arc
				(start 252.451362 -392.44397)
				(mid 252.434828 -392.432859)
				(end 252.415294 -392.428984)
			)
			(arc
				(start 245.184422 -392.428984)
				(mid 245.164899 -392.432885)
				(end 245.148354 -392.44397)
			)
			(arc
				(start 244.746526 -392.845798)
				(mid 244.735415 -392.862332)
				(end 244.73154 -392.881866)
			)
			(arc
				(start 244.73154 -397.594328)
				(mid 244.735441 -397.613851)
				(end 244.746526 -397.630396)
			)
			(arc
				(start 245.06428 -397.94815)
				(mid 245.080814 -397.959261)
				(end 245.100348 -397.963136)
			)
		)
		(stroke
			(width 0)
			(type solid)
		)
		(fill yes)
		(layer "In9.Cu")
		(net "P12V_STBY_FUSE")
	)
	(gr_poly
		(pts
			(xy 266.35329 -365.71428) (xy 266.35329 -364.812834) (xy 266.35329 -362.120688) (xy 266.35329 -360.949494)
			(xy 262.298434 -356.894638) (xy 261.237476 -356.894638)
			(arc
				(start 253.270258 -356.894638)
				(mid 253.250735 -356.898539)
				(end 253.23419 -356.909624)
			)
			(arc
				(start 252.95987 -357.183944)
				(mid 252.948759 -357.200478)
				(end 252.944884 -357.220012)
			)
			(arc
				(start 252.944884 -358.53751)
				(mid 252.940983 -358.557033)
				(end 252.929898 -358.573578)
			)
			(arc
				(start 251.742448 -359.761028)
				(mid 251.725914 -359.772139)
				(end 251.70638 -359.776014)
			)
			(arc
				(start 246.79783 -359.776014)
				(mid 246.778307 -359.779915)
				(end 246.761762 -359.791)
			)
			(arc
				(start 245.756938 -360.795824)
				(mid 245.740404 -360.806935)
				(end 245.72087 -360.81081)
			)
			(xy 237.543594 -360.81081) (xy 237.320074 -361.03433) (xy 236.795564 -361.55884) (xy 236.795564 -365.914686)
			(xy 237.133384 -366.252506) (xy 265.815064 -366.252506)
		)
		(stroke
			(width 0)
			(type solid)
		)
		(fill yes)
		(layer "In9.Cu")
		(net "P12V_AUX")
	)
	(gr_poly
		(pts
			(arc
				(start 221.297754 -370.944648)
				(mid 221.326038 -370.936046)
				(end 221.344744 -370.913152)
			)
			(xy 221.350586 -370.898674) (xy 221.344744 -370.868956)
			(arc
				(start 221.337632 -370.861844)
				(mid 221.326521 -370.84531)
				(end 221.322646 -370.825776)
			)
			(arc
				(start 221.322646 -367.359692)
				(mid 221.318745 -367.340169)
				(end 221.30766 -367.323624)
			)
			(arc
				(start 221.24416 -367.260124)
				(mid 221.227626 -367.249013)
				(end 221.208092 -367.245138)
			)
			(arc
				(start 218.078304 -367.245138)
				(mid 218.058781 -367.249039)
				(end 218.042236 -367.260124)
			)
			(arc
				(start 217.916506 -367.385854)
				(mid 217.905395 -367.402388)
				(end 217.90152 -367.421922)
			)
			(arc
				(start 217.90152 -370.80063)
				(mid 217.897619 -370.820153)
				(end 217.886534 -370.836698)
			)
			(arc
				(start 217.865452 -370.85778)
				(mid 217.851446 -370.883771)
				(end 217.854276 -370.913152)
			)
			(xy 217.860372 -370.92763) (xy 217.885518 -370.944648)
		)
		(stroke
			(width 0)
			(type solid)
		)
		(fill yes)
		(layer "In9.Cu")
		(net "P12V_STBY")
	)
	(gr_poly
		(pts
			(xy 353.162616 -160.032192)
			(arc
				(start 353.60229 -159.592518)
				(mid 353.613352 -159.576101)
				(end 353.617276 -159.556704)
			)
			(arc
				(start 353.617276 -158.837376)
				(mid 353.602397 -158.801455)
				(end 353.566476 -158.786576)
			)
			(xy 353.560126 -158.786576)
			(arc
				(start 353.554284 -158.7881)
				(mid 353.53105 -158.793141)
				(end 353.507548 -158.796736)
			)
			(xy 353.49688 -158.798006)
			(arc
				(start 353.462844 -158.79953)
				(mid 353.317511 -158.770764)
				(end 353.194112 -158.688786)
			)
			(xy 353.187254 -158.681928)
			(arc
				(start 353.165664 -158.672784)
				(mid 353.146282 -158.668663)
				(end 353.126802 -158.672276)
			)
			(arc
				(start 353.118928 -158.675578)
				(mid 353.095647 -158.694277)
				(end 353.086924 -158.722822)
			)
			(arc
				(start 353.086924 -159.985202)
				(mid 353.095526 -160.013486)
				(end 353.11842 -160.032192)
			)
			(xy 353.132898 -160.038034)
		)
		(stroke
			(width 0)
			(type solid)
		)
		(fill yes)
		(layer "In9.Cu")
		(net "GND")
	)
	(gr_poly
		(pts
			(arc
				(start 208.891886 -370.745512)
				(mid 208.92017 -370.73691)
				(end 208.938876 -370.714016)
			)
			(xy 208.944718 -370.699538) (xy 208.938876 -370.66982)
			(arc
				(start 208.832196 -370.56314)
				(mid 208.821085 -370.546606)
				(end 208.81721 -370.527072)
			)
			(arc
				(start 208.81721 -370.46027)
				(mid 208.813309 -370.440747)
				(end 208.802224 -370.424202)
			)
			(xy 208.795366 -370.417344)
			(arc
				(start 208.220056 -370.417344)
				(mid 208.200533 -370.413443)
				(end 208.183988 -370.402358)
			)
			(arc
				(start 208.098898 -370.317268)
				(mid 208.087787 -370.300734)
				(end 208.083912 -370.2812)
			)
			(arc
				(start 208.083912 -367.384584)
				(mid 208.080011 -367.365061)
				(end 208.068926 -367.348516)
			)
			(arc
				(start 207.996028 -367.275618)
				(mid 207.979494 -367.264507)
				(end 207.95996 -367.260632)
			)
			(arc
				(start 204.786484 -367.260632)
				(mid 204.766961 -367.264533)
				(end 204.750416 -367.275618)
			)
			(arc
				(start 204.68082 -367.345214)
				(mid 204.669709 -367.361748)
				(end 204.665834 -367.381282)
			)
			(arc
				(start 204.665834 -370.694712)
				(mid 204.680713 -370.730633)
				(end 204.716634 -370.745512)
			)
		)
		(stroke
			(width 0)
			(type solid)
		)
		(fill yes)
		(layer "In9.Cu")
		(net "P12V_STBY")
	)
	(gr_poly
		(pts
			(arc
				(start 242.051078 -375.289572)
				(mid 242.070601 -375.285671)
				(end 242.087146 -375.274586)
			)
			(arc
				(start 242.310666 -375.051066)
				(mid 242.321777 -375.034532)
				(end 242.325652 -375.014998)
			)
			(arc
				(start 242.325652 -368.584988)
				(mid 242.321751 -368.565465)
				(end 242.310666 -368.54892)
			)
			(arc
				(start 242.213638 -368.451892)
				(mid 242.197104 -368.440781)
				(end 242.17757 -368.436906)
			)
			(arc
				(start 236.987334 -368.436906)
				(mid 236.967811 -368.440807)
				(end 236.951266 -368.451892)
			)
			(xy 236.95025 -368.452908) (xy 236.931708 -368.460528)
			(arc
				(start 236.348524 -368.460528)
				(mid 236.329001 -368.464429)
				(end 236.312456 -368.475514)
			)
			(arc
				(start 236.016546 -368.771424)
				(mid 236.005435 -368.787958)
				(end 236.00156 -368.807492)
			)
			(arc
				(start 236.00156 -372.73357)
				(mid 236.005461 -372.753093)
				(end 236.016546 -372.769638)
			)
			(arc
				(start 236.697266 -373.450358)
				(mid 236.708377 -373.466892)
				(end 236.712252 -373.486426)
			)
			(arc
				(start 236.712252 -374.694196)
				(mid 236.716153 -374.713719)
				(end 236.727238 -374.730264)
			)
			(arc
				(start 237.27156 -375.274586)
				(mid 237.288094 -375.285697)
				(end 237.307628 -375.289572)
			)
		)
		(stroke
			(width 0)
			(type solid)
		)
		(fill yes)
		(layer "In9.Cu")
		(net "P12V_STBY_R1")
	)
	(gr_poly
		(pts
			(arc
				(start 264.246106 -376.253248)
				(mid 264.27594 -376.243565)
				(end 264.294366 -376.218196)
			)
			(arc
				(start 264.294366 -376.218196)
				(mid 265.21858 -374.299675)
				(end 266.61618 -372.69293)
			)
			(arc
				(start 266.61618 -372.69293)
				(mid 266.62895 -372.67562)
				(end 266.633452 -372.654576)
			)
			(arc
				(start 266.633452 -368.922046)
				(mid 266.629551 -368.902523)
				(end 266.618466 -368.885978)
			)
			(arc
				(start 266.291568 -368.55908)
				(mid 266.275034 -368.547969)
				(end 266.2555 -368.544094)
			)
			(xy 243.539264 -368.544094) (xy 243.533676 -368.538506)
			(arc
				(start 242.778534 -368.538506)
				(mid 242.759011 -368.542407)
				(end 242.742466 -368.553492)
			)
			(arc
				(start 242.620038 -368.67592)
				(mid 242.608927 -368.692454)
				(end 242.605052 -368.711988)
			)
			(arc
				(start 242.605052 -375.809002)
				(mid 242.608953 -375.828525)
				(end 242.620038 -375.84507)
			)
			(arc
				(start 243.01323 -376.238262)
				(mid 243.029764 -376.249373)
				(end 243.049298 -376.253248)
			)
		)
		(stroke
			(width 0)
			(type solid)
		)
		(fill yes)
		(layer "In9.Cu")
		(net "P12V_STBY_R2")
	)
	(gr_poly
		(pts
			(arc
				(start 367.21542 -333.898494)
				(mid 367.241411 -333.9125)
				(end 367.270792 -333.90967)
			)
			(xy 367.28527 -333.903574) (xy 367.302288 -333.878428)
			(arc
				(start 367.302288 -332.42885)
				(mid 367.298338 -332.409463)
				(end 367.287302 -332.393036)
			)
			(arc
				(start 366.956594 -332.062328)
				(mid 366.940148 -332.051402)
				(end 366.92078 -332.047596)
			)
			(arc
				(start 365.48695 -332.047596)
				(mid 365.458763 -332.056133)
				(end 365.43996 -332.078838)
			)
			(xy 365.434118 -332.093316) (xy 365.43996 -332.123034) (xy 365.77016 -332.453234) (xy 365.789972 -332.460854)
			(xy 365.800894 -332.460092) (xy 365.82604 -332.459584)
			(arc
				(start 366.68964 -332.459584)
				(mid 367.013288 -332.593644)
				(end 367.147348 -332.917292)
			)
			(arc
				(start 367.147348 -332.917292)
				(mid 367.068636 -333.174)
				(end 366.859566 -333.342488)
			)
			(xy 366.847628 -333.34706) (xy 366.831372 -333.366618)
			(arc
				(start 366.81156 -333.462376)
				(mid 366.812711 -333.487251)
				(end 366.82553 -333.508604)
			)
		)
		(stroke
			(width 0)
			(type solid)
		)
		(fill yes)
		(layer "In9.Cu")
		(net "GND")
	)
	(gr_poly
		(pts
			(arc
				(start 144.143984 -210.649058)
				(mid 144.168976 -210.648127)
				(end 144.190466 -210.635342)
			)
			(arc
				(start 145.22069 -209.605118)
				(mid 145.231752 -209.588701)
				(end 145.235676 -209.569304)
			)
			(arc
				(start 145.235676 -207.942688)
				(mid 145.226915 -207.914169)
				(end 145.203672 -207.895444)
			)
			(xy 145.147792 -207.873346) (xy 145.141696 -207.879696)
			(arc
				(start 144.111726 -208.909412)
				(mid 144.097895 -208.9349)
				(end 144.100296 -208.963768)
			)
			(xy 144.139158 -209.064606) (xy 144.163288 -209.082132)
			(arc
				(start 144.178528 -209.082894)
				(mid 144.43619 -209.200805)
				(end 144.541494 -209.463894)
			)
			(arc
				(start 144.541494 -209.463894)
				(mid 144.159986 -209.845402)
				(end 143.778478 -209.463894)
			)
			(arc
				(start 143.778478 -209.463894)
				(mid 143.781851 -209.413277)
				(end 143.79194 -209.363564)
			)
			(xy 143.795496 -209.350356) (xy 143.788384 -209.32394)
			(arc
				(start 143.778732 -209.314288)
				(mid 143.742828 -209.299528)
				(end 143.70685 -209.314288)
			)
			(arc
				(start 143.67891 -209.342482)
				(mid 143.667848 -209.358899)
				(end 143.663924 -209.378296)
			)
			(arc
				(start 143.663924 -210.178904)
				(mid 143.667874 -210.198291)
				(end 143.67891 -210.214718)
			)
			(arc
				(start 143.948912 -210.48472)
				(mid 143.992409 -210.538457)
				(end 144.023842 -210.600036)
			)
			(xy 144.028668 -210.612228) (xy 144.047972 -210.628738)
		)
		(stroke
			(width 0)
			(type solid)
		)
		(fill yes)
		(layer "In9.Cu")
		(net "GND")
	)
	(gr_poly
		(pts
			(xy 332.40218 -206.098902) (xy 332.40218 -205.902306) (xy 332.40218 -203.068428)
			(arc
				(start 331.92466 -202.590908)
				(mid 331.908126 -202.579797)
				(end 331.888592 -202.575922)
			)
			(arc
				(start 330.280772 -202.575922)
				(mid 330.254748 -202.582943)
				(end 330.236068 -202.602338)
			)
			(xy 330.186538 -202.69327) (xy 330.187554 -202.720702)
			(arc
				(start 330.195428 -202.73264)
				(mid 330.240885 -202.83174)
				(end 330.256388 -202.93965)
			)
			(arc
				(start 330.256388 -202.93965)
				(mid 330.144647 -203.209417)
				(end 329.87488 -203.321158)
			)
			(arc
				(start 329.87488 -203.321158)
				(mid 329.681427 -203.268513)
				(end 329.541378 -203.12507)
			)
			(xy 329.535028 -203.113386) (xy 329.512676 -203.09967) (xy 329.3999 -203.094336) (xy 329.376532 -203.105766)
			(arc
				(start 329.368912 -203.116942)
				(mid 329.232183 -203.238258)
				(end 329.054714 -203.282042)
			)
			(arc
				(start 329.054714 -203.282042)
				(mid 328.952274 -203.267961)
				(end 328.857356 -203.226924)
			)
			(xy 328.845418 -203.219812) (xy 328.81824 -203.219304)
			(arc
				(start 328.729086 -203.269596)
				(mid 328.710122 -203.288306)
				(end 328.703178 -203.314046)
			)
			(arc
				(start 328.703178 -205.820518)
				(mid 328.707079 -205.840041)
				(end 328.718164 -205.856586)
			)
			(arc
				(start 328.973688 -206.11211)
				(mid 328.990222 -206.123221)
				(end 329.009756 -206.127096)
			)
			(arc
				(start 330.464922 -206.127096)
				(mid 330.482353 -206.124012)
				(end 330.497688 -206.115158)
			)
			(arc
				(start 330.497688 -206.115158)
				(mid 330.612677 -206.048492)
				(end 330.74356 -206.025242)
			)
			(arc
				(start 330.74356 -206.025242)
				(mid 330.874474 -206.048407)
				(end 330.989432 -206.115158)
			)
			(arc
				(start 330.989432 -206.115158)
				(mid 331.004756 -206.124042)
				(end 331.022198 -206.127096)
			)
			(xy 331.164438 -206.127096) (xy 331.244956 -206.207614) (xy 331.244956 -206.58201) (xy 331.346556 -206.68361)
			(xy 331.817472 -206.68361)
		)
		(stroke
			(width 0)
			(type solid)
		)
		(fill yes)
		(layer "In9.Cu")
		(net "GND")
	)
	(gr_poly
		(pts
			(xy 42.390314 -13.820648) (xy 42.390314 -13.401548) (xy 42.34688 -13.358114)
			(arc
				(start 34.964878 -13.358114)
				(mid 33.898562 -12.916432)
				(end 33.45688 -11.850116)
			)
			(arc
				(start 33.45688 -1.999996)
				(mid 33.019884 -0.944996)
				(end 31.964884 -0.508)
			)
			(arc
				(start 19.964908 -0.508)
				(mid 18.909908 -0.944996)
				(end 18.472912 -1.999996)
			)
			(xy 18.472912 -11.631422) (xy 18.980404 -11.631422)
			(arc
				(start 18.980404 -1.999996)
				(mid 19.268759 -1.303847)
				(end 19.964908 -1.015492)
			)
			(arc
				(start 31.964884 -1.015492)
				(mid 32.661033 -1.303847)
				(end 32.949388 -1.999996)
			)
			(arc
				(start 32.949388 -11.850116)
				(mid 33.539801 -13.275118)
				(end 34.964878 -13.865352)
			)
			(xy 42.34561 -13.865352)
		)
		(stroke
			(width 0)
			(type solid)
		)
		(fill yes)
		(layer "In9.Cu")
		(net "GND")
	)
	(gr_poly
		(pts
			(xy 68.431156 -13.728954) (xy 68.431156 -13.494512) (xy 68.294758 -13.358114)
			(arc
				(start 60.96508 -13.358114)
				(mid 59.898764 -12.916432)
				(end 59.457082 -11.850116)
			)
			(arc
				(start 59.457082 -1.999996)
				(mid 59.020086 -0.944996)
				(end 57.965086 -0.508)
			)
			(arc
				(start 45.96511 -0.508)
				(mid 44.91011 -0.944996)
				(end 44.473114 -1.999996)
			)
			(xy 44.473114 -11.726418) (xy 44.980352 -11.726418)
			(arc
				(start 44.980352 -1.999996)
				(mid 45.268617 -1.303936)
				(end 45.964602 -1.015492)
			)
			(arc
				(start 57.965086 -1.015492)
				(mid 58.661325 -1.303831)
				(end 58.949844 -1.999996)
			)
			(arc
				(start 58.949844 -11.850116)
				(mid 59.540093 -13.275103)
				(end 60.96508 -13.865352)
			)
			(xy 68.294758 -13.865352)
		)
		(stroke
			(width 0)
			(type solid)
		)
		(fill yes)
		(layer "In9.Cu")
		(net "GND")
	)
	(gr_poly
		(pts
			(xy 94.285816 -13.833856) (xy 94.285816 -13.444728) (xy 94.199202 -13.358114)
			(arc
				(start 86.965028 -13.358114)
				(mid 85.898712 -12.916432)
				(end 85.45703 -11.850116)
			)
			(arc
				(start 85.45703 -1.999996)
				(mid 85.020034 -0.944996)
				(end 83.965034 -0.508)
			)
			(arc
				(start 71.965058 -0.508)
				(mid 70.910058 -0.944996)
				(end 70.473062 -1.999996)
			)
			(xy 70.473062 -11.716004) (xy 70.9803 -11.716004)
			(arc
				(start 70.9803 -1.999996)
				(mid 71.268565 -1.303936)
				(end 71.96455 -1.015492)
			)
			(arc
				(start 83.965034 -1.015492)
				(mid 84.661273 -1.303831)
				(end 84.949792 -1.999996)
			)
			(arc
				(start 84.949792 -11.850116)
				(mid 85.540041 -13.275103)
				(end 86.965028 -13.865352)
			)
			(xy 94.25432 -13.865352)
		)
		(stroke
			(width 0)
			(type solid)
		)
		(fill yes)
		(layer "In9.Cu")
		(net "GND")
	)
	(gr_poly
		(pts
			(xy 132.291582 -13.80998) (xy 132.291582 -13.413486) (xy 132.23621 -13.358114)
			(arc
				(start 125.065028 -13.358114)
				(mid 123.998712 -12.916432)
				(end 123.55703 -11.850116)
			)
			(arc
				(start 123.55703 -1.999996)
				(mid 123.120034 -0.944996)
				(end 122.065034 -0.508)
			)
			(arc
				(start 97.965006 -0.508)
				(mid 96.910006 -0.944996)
				(end 96.47301 -1.999996)
			)
			(xy 96.47301 -11.72464) (xy 96.980248 -11.72464)
			(arc
				(start 96.980248 -1.999996)
				(mid 97.268513 -1.303936)
				(end 97.964498 -1.015492)
			)
			(arc
				(start 122.065034 -1.015492)
				(mid 122.761273 -1.303831)
				(end 123.049792 -1.999996)
			)
			(arc
				(start 123.049792 -11.850116)
				(mid 123.640041 -13.275103)
				(end 125.065028 -13.865352)
			)
			(xy 132.23621 -13.865352)
		)
		(stroke
			(width 0)
			(type solid)
		)
		(fill yes)
		(layer "In9.Cu")
		(net "GND")
	)
	(gr_poly
		(pts
			(xy 158.365444 -13.805662) (xy 158.365444 -13.417804) (xy 158.305754 -13.358114)
			(arc
				(start 151.064976 -13.358114)
				(mid 149.99866 -12.916432)
				(end 149.556978 -11.850116)
			)
			(arc
				(start 149.556978 -1.999996)
				(mid 149.119982 -0.944996)
				(end 148.064982 -0.508)
			)
			(arc
				(start 136.065006 -0.508)
				(mid 135.010006 -0.944996)
				(end 134.57301 -1.999996)
			)
			(xy 134.57301 -11.817604) (xy 135.080248 -11.817604)
			(arc
				(start 135.080248 -1.999996)
				(mid 135.368513 -1.303936)
				(end 136.064498 -1.015492)
			)
			(arc
				(start 148.064982 -1.015492)
				(mid 148.761221 -1.303831)
				(end 149.04974 -1.999996)
			)
			(arc
				(start 149.04974 -11.850116)
				(mid 149.639989 -13.275103)
				(end 151.064976 -13.865352)
			)
			(xy 158.305754 -13.865352)
		)
		(stroke
			(width 0)
			(type solid)
		)
		(fill yes)
		(layer "In9.Cu")
		(net "GND")
	)
	(gr_poly
		(pts
			(xy 184.389268 -13.77569) (xy 184.389268 -13.447776) (xy 184.299606 -13.358114)
			(arc
				(start 177.064924 -13.358114)
				(mid 175.998608 -12.916432)
				(end 175.556926 -11.850116)
			)
			(arc
				(start 175.556926 -1.999996)
				(mid 175.11993 -0.944996)
				(end 174.06493 -0.508)
			)
			(arc
				(start 162.064954 -0.508)
				(mid 161.009954 -0.944996)
				(end 160.572958 -1.999996)
			)
			(xy 160.572958 -11.62304) (xy 161.080196 -11.62304)
			(arc
				(start 161.080196 -1.999996)
				(mid 161.368461 -1.303936)
				(end 162.064446 -1.015492)
			)
			(arc
				(start 174.06493 -1.015492)
				(mid 174.761169 -1.303831)
				(end 175.049688 -1.999996)
			)
			(arc
				(start 175.049688 -11.850116)
				(mid 175.639937 -13.275103)
				(end 177.064924 -13.865352)
			)
			(xy 184.299606 -13.865352)
		)
		(stroke
			(width 0)
			(type solid)
		)
		(fill yes)
		(layer "In9.Cu")
		(net "GND")
	)
	(gr_poly
		(pts
			(xy 210.250024 -13.829284) (xy 210.250024 -13.394182) (xy 210.213956 -13.358114)
			(arc
				(start 203.064872 -13.358114)
				(mid 201.998721 -12.916342)
				(end 201.556874 -11.850116)
			)
			(arc
				(start 201.556874 -1.999996)
				(mid 201.119878 -0.944996)
				(end 200.064878 -0.508)
			)
			(arc
				(start 188.064902 -0.508)
				(mid 187.009902 -0.944996)
				(end 186.572906 -1.999996)
			)
			(xy 186.572906 -11.750294) (xy 187.080144 -11.750294)
			(arc
				(start 187.080144 -1.999996)
				(mid 187.368409 -1.303936)
				(end 188.064394 -1.015492)
			)
			(arc
				(start 200.064878 -1.015492)
				(mid 200.761117 -1.303831)
				(end 201.049636 -1.999996)
			)
			(arc
				(start 201.049636 -11.850116)
				(mid 201.63987 -13.275193)
				(end 203.064872 -13.865352)
			)
			(xy 210.213956 -13.865352)
		)
		(stroke
			(width 0)
			(type solid)
		)
		(fill yes)
		(layer "In9.Cu")
		(net "GND")
	)
	(gr_poly
		(pts
			(xy 300.515782 -13.7541) (xy 300.515782 -13.469366) (xy 300.40453 -13.358114)
			(arc
				(start 293.165022 -13.358114)
				(mid 292.098706 -12.916432)
				(end 291.657024 -11.850116)
			)
			(arc
				(start 291.657024 -1.999996)
				(mid 291.220028 -0.944996)
				(end 290.165028 -0.508)
			)
			(arc
				(start 278.165052 -0.508)
				(mid 277.110052 -0.944996)
				(end 276.673056 -1.999996)
			)
			(xy 276.673056 -11.825732) (xy 277.180548 -11.825732)
			(arc
				(start 277.180548 -1.999996)
				(mid 277.468903 -1.303847)
				(end 278.165052 -1.015492)
			)
			(arc
				(start 290.165028 -1.015492)
				(mid 290.861177 -1.303847)
				(end 291.149532 -1.999996)
			)
			(arc
				(start 291.149532 -11.850116)
				(mid 291.739945 -13.275118)
				(end 293.165022 -13.865352)
			)
			(xy 300.40453 -13.865352)
		)
		(stroke
			(width 0)
			(type solid)
		)
		(fill yes)
		(layer "In9.Cu")
		(net "GND")
	)
	(gr_poly
		(pts
			(xy 442.67882 -13.82903) (xy 442.67882 -13.394436) (xy 442.642498 -13.358114)
			(arc
				(start 435.265068 -13.358114)
				(mid 434.198752 -12.916432)
				(end 433.75707 -11.850116)
			)
			(arc
				(start 433.75707 -1.999996)
				(mid 433.320074 -0.944996)
				(end 432.265074 -0.508)
			)
			(arc
				(start 420.265098 -0.508)
				(mid 419.210098 -0.944996)
				(end 418.773102 -1.999996)
			)
			(xy 418.773102 -11.73734) (xy 419.28034 -11.73734)
			(arc
				(start 419.28034 -1.999996)
				(mid 419.568605 -1.303936)
				(end 420.26459 -1.015492)
			)
			(arc
				(start 432.265074 -1.015492)
				(mid 432.961313 -1.303831)
				(end 433.249832 -1.999996)
			)
			(arc
				(start 433.249832 -11.850116)
				(mid 433.840081 -13.275103)
				(end 435.265068 -13.865352)
			)
			(xy 442.642498 -13.865352)
		)
		(stroke
			(width 0)
			(type solid)
		)
		(fill yes)
		(layer "In9.Cu")
		(net "GND")
	)
	(gr_poly
		(pts
			(arc
				(start 52.038758 -315.472826)
				(mid 52.058883 -315.475356)
				(end 52.078382 -315.469778)
			)
			(arc
				(start 52.09667 -315.460634)
				(mid 52.110391 -315.450545)
				(end 52.120038 -315.436504)
			)
			(arc
				(start 52.120038 -315.436504)
				(mid 52.157282 -315.365119)
				(end 52.200302 -315.297058)
			)
			(arc
				(start 52.200302 -315.297058)
				(mid 52.204322 -315.289968)
				(end 52.20716 -315.282326)
			)
			(arc
				(start 52.20716 -315.282326)
				(mid 52.29091 -315.140778)
				(end 52.432458 -315.057028)
			)
			(arc
				(start 52.432458 -315.057028)
				(mid 52.440103 -315.054197)
				(end 52.44719 -315.05017)
			)
			(arc
				(start 52.44719 -315.05017)
				(mid 52.539468 -314.993703)
				(end 52.637436 -314.947808)
			)
			(arc
				(start 52.637436 -314.947808)
				(mid 52.660439 -314.929147)
				(end 52.669186 -314.900818)
			)
			(arc
				(start 52.669186 -314.899802)
				(mid 52.689205 -314.786487)
				(end 52.74691 -314.68695)
			)
			(arc
				(start 52.73929 -314.680854)
				(mid 52.711085 -314.654336)
				(end 52.686458 -314.624466)
			)
			(xy 52.68595 -314.623704) (xy 52.684934 -314.62218) (xy 52.683156 -314.619894) (xy 52.681632 -314.617608)
			(xy 52.681378 -314.6171)
			(arc
				(start 52.612798 -314.510166)
				(mid 52.607335 -314.498472)
				(end 52.604924 -314.485782)
			)
			(xy 52.601114 -314.42025)
			(arc
				(start 52.601114 -314.419742)
				(mid 52.577088 -314.369054)
				(end 52.524914 -314.348368)
			)
			(arc
				(start 52.524914 -314.348368)
				(mid 52.470853 -314.370761)
				(end 52.44846 -314.424822)
			)
			(arc
				(start 52.44846 -314.434474)
				(mid 52.396323 -314.604781)
				(end 52.25796 -314.716922)
			)
			(arc
				(start 52.25796 -314.716922)
				(mid 52.231813 -314.728208)
				(end 52.206144 -314.740544)
			)
			(xy 52.202334 -314.742576) (xy 52.199794 -314.7441) (xy 52.19446 -314.747148) (xy 52.193698 -314.747656)
			(xy 52.188872 -314.749942) (xy 52.182268 -314.753244) (xy 52.175918 -314.7568) (xy 52.151026 -314.77077)
			(xy 52.150518 -314.77077)
			(arc
				(start 52.120038 -314.787534)
				(mid 52.107632 -314.792412)
				(end 52.094384 -314.793884)
			)
			(arc
				(start 52.025804 -314.792614)
				(mid 51.946951 -314.780679)
				(end 51.873912 -314.748672)
			)
			(xy 51.87061 -314.746894)
			(arc
				(start 51.80203 -314.704222)
				(mid 51.790362 -314.699533)
				(end 51.7779 -314.697872)
			)
			(xy 51.769518 -314.697872) (xy 51.75631 -314.701428) (xy 51.755548 -314.701936)
			(arc
				(start 51.74996 -314.705492)
				(mid 51.665857 -314.742913)
				(end 51.5747 -314.755784)
			)
			(arc
				(start 51.5747 -314.755784)
				(mid 51.513979 -314.750119)
				(end 51.45532 -314.733432)
			)
			(arc
				(start 51.45532 -314.733432)
				(mid 51.432565 -314.723608)
				(end 51.410616 -314.712096)
			)
			(xy 51.403504 -314.708032)
			(arc
				(start 51.398678 -314.704984)
				(mid 51.381237 -314.698469)
				(end 51.36261 -314.698634)
			)
			(arc
				(start 51.36261 -314.698634)
				(mid 51.413213 -314.793613)
				(end 51.430682 -314.899802)
			)
			(arc
				(start 51.430682 -314.900818)
				(mid 51.43935 -314.9292)
				(end 51.462432 -314.947808)
			)
			(arc
				(start 51.462432 -314.947808)
				(mid 51.767458 -315.143106)
				(end 51.97983 -315.436504)
			)
			(arc
				(start 51.97983 -315.436504)
				(mid 51.991952 -315.452889)
				(end 52.009548 -315.463174)
			)
		)
		(stroke
			(width 0)
			(type solid)
		)
		(fill yes)
		(layer "In9.Cu")
		(net "GND")
	)
	(gr_poly
		(pts
			(arc
				(start 53.938678 -315.472826)
				(mid 53.958803 -315.475356)
				(end 53.978302 -315.469778)
			)
			(arc
				(start 53.99659 -315.460634)
				(mid 54.010311 -315.450545)
				(end 54.019958 -315.436504)
			)
			(arc
				(start 54.019958 -315.436504)
				(mid 54.057202 -315.365119)
				(end 54.100222 -315.297058)
			)
			(arc
				(start 54.100222 -315.297058)
				(mid 54.104242 -315.289968)
				(end 54.10708 -315.282326)
			)
			(arc
				(start 54.10708 -315.282326)
				(mid 54.19083 -315.140778)
				(end 54.332378 -315.057028)
			)
			(arc
				(start 54.332378 -315.057028)
				(mid 54.340023 -315.054197)
				(end 54.34711 -315.05017)
			)
			(arc
				(start 54.34711 -315.05017)
				(mid 54.439388 -314.993703)
				(end 54.537356 -314.947808)
			)
			(arc
				(start 54.537356 -314.947808)
				(mid 54.560359 -314.929147)
				(end 54.569106 -314.900818)
			)
			(arc
				(start 54.569106 -314.899802)
				(mid 54.589125 -314.786487)
				(end 54.64683 -314.68695)
			)
			(arc
				(start 54.63921 -314.680854)
				(mid 54.611005 -314.654336)
				(end 54.586378 -314.624466)
			)
			(xy 54.58587 -314.623704) (xy 54.584854 -314.62218) (xy 54.583076 -314.619894) (xy 54.581552 -314.617608)
			(xy 54.581298 -314.6171)
			(arc
				(start 54.512718 -314.510166)
				(mid 54.507255 -314.498472)
				(end 54.504844 -314.485782)
			)
			(xy 54.501034 -314.42025)
			(arc
				(start 54.501034 -314.419742)
				(mid 54.477008 -314.369054)
				(end 54.424834 -314.348368)
			)
			(arc
				(start 54.424834 -314.348368)
				(mid 54.370773 -314.370761)
				(end 54.34838 -314.424822)
			)
			(arc
				(start 54.34838 -314.434474)
				(mid 54.296243 -314.604781)
				(end 54.15788 -314.716922)
			)
			(arc
				(start 54.15788 -314.716922)
				(mid 54.131733 -314.728208)
				(end 54.106064 -314.740544)
			)
			(xy 54.102254 -314.742576) (xy 54.099714 -314.7441) (xy 54.09438 -314.747148) (xy 54.093618 -314.747656)
			(xy 54.088792 -314.749942) (xy 54.082188 -314.753244) (xy 54.075838 -314.7568) (xy 54.050946 -314.77077)
			(xy 54.050438 -314.77077)
			(arc
				(start 54.019958 -314.787534)
				(mid 54.007552 -314.792412)
				(end 53.994304 -314.793884)
			)
			(arc
				(start 53.925724 -314.792614)
				(mid 53.846871 -314.780679)
				(end 53.773832 -314.748672)
			)
			(xy 53.77053 -314.746894)
			(arc
				(start 53.70195 -314.704222)
				(mid 53.690282 -314.699533)
				(end 53.67782 -314.697872)
			)
			(xy 53.669438 -314.697872) (xy 53.65623 -314.701428) (xy 53.655468 -314.701936)
			(arc
				(start 53.64988 -314.705492)
				(mid 53.565777 -314.742913)
				(end 53.47462 -314.755784)
			)
			(arc
				(start 53.47462 -314.755784)
				(mid 53.413899 -314.750119)
				(end 53.35524 -314.733432)
			)
			(arc
				(start 53.35524 -314.733432)
				(mid 53.332485 -314.723608)
				(end 53.310536 -314.712096)
			)
			(xy 53.303424 -314.708032)
			(arc
				(start 53.298598 -314.704984)
				(mid 53.281157 -314.698469)
				(end 53.26253 -314.698634)
			)
			(arc
				(start 53.26253 -314.698634)
				(mid 53.313133 -314.793613)
				(end 53.330602 -314.899802)
			)
			(arc
				(start 53.330602 -314.900818)
				(mid 53.33927 -314.9292)
				(end 53.362352 -314.947808)
			)
			(arc
				(start 53.362352 -314.947808)
				(mid 53.667378 -315.143106)
				(end 53.87975 -315.436504)
			)
			(arc
				(start 53.87975 -315.436504)
				(mid 53.891872 -315.452889)
				(end 53.909468 -315.463174)
			)
		)
		(stroke
			(width 0)
			(type solid)
		)
		(fill yes)
		(layer "In9.Cu")
		(net "GND")
	)
	(gr_poly
		(pts
			(xy 248.61139 -13.829538) (xy 248.61139 -13.393928) (xy 248.575576 -13.358114)
			(arc
				(start 241.164872 -13.358114)
				(mid 240.098721 -12.916342)
				(end 239.656874 -11.850116)
			)
			(arc
				(start 239.656874 -1.999996)
				(mid 239.219878 -0.944996)
				(end 238.164878 -0.508)
			)
			(arc
				(start 214.065104 -0.508)
				(mid 213.010104 -0.944996)
				(end 212.573108 -1.999996)
			)
			(xy 212.573108 -11.851132) (xy 212.571584 -11.91895) (xy 213.07933 -11.91895) (xy 213.0806 -11.850116)
			(arc
				(start 213.0806 -1.999996)
				(mid 213.368955 -1.303847)
				(end 214.065104 -1.015492)
			)
			(arc
				(start 238.164878 -1.015492)
				(mid 238.861117 -1.303831)
				(end 239.149636 -1.999996)
			)
			(arc
				(start 239.149636 -11.850116)
				(mid 239.73987 -13.275193)
				(end 241.164872 -13.865352)
			)
			(xy 248.575576 -13.865352)
		)
		(stroke
			(width 0)
			(type solid)
		)
		(fill yes)
		(layer "In9.Cu")
		(net "GND")
	)
	(gr_poly
		(pts
			(xy 274.599654 -13.810742) (xy 274.599654 -13.412724) (xy 274.545044 -13.358114)
			(arc
				(start 267.165074 -13.358114)
				(mid 266.098758 -12.916432)
				(end 265.657076 -11.850116)
			)
			(arc
				(start 265.657076 -1.999996)
				(mid 265.22008 -0.944996)
				(end 264.16508 -0.508)
			)
			(arc
				(start 252.165104 -0.508)
				(mid 251.110104 -0.944996)
				(end 250.673108 -1.999996)
			)
			(xy 250.673108 -11.850116) (xy 250.673108 -11.851386) (xy 251.1806 -11.851386) (xy 251.1806 -11.850116)
			(arc
				(start 251.1806 -1.999996)
				(mid 251.468955 -1.303847)
				(end 252.165104 -1.015492)
			)
			(arc
				(start 264.16508 -1.015492)
				(mid 264.861229 -1.303847)
				(end 265.149584 -1.999996)
			)
			(arc
				(start 265.149584 -11.850116)
				(mid 265.739997 -13.275118)
				(end 267.165074 -13.865352)
			)
			(xy 274.545044 -13.865352)
		)
		(stroke
			(width 0)
			(type solid)
		)
		(fill yes)
		(layer "In9.Cu")
		(net "GND")
	)
	(gr_poly
		(pts
			(xy 416.458146 -13.816076) (xy 416.458146 -13.40739) (xy 416.40887 -13.358114)
			(arc
				(start 409.26512 -13.358114)
				(mid 408.198804 -12.916432)
				(end 407.757122 -11.850116)
			)
			(arc
				(start 407.757122 -1.999996)
				(mid 407.320126 -0.944996)
				(end 406.265126 -0.508)
			)
			(arc
				(start 394.264896 -0.508)
				(mid 393.209896 -0.944996)
				(end 392.7729 -1.999996)
			)
			(arc
				(start 392.7729 -11.850116)
				(mid 392.702216 -12.306469)
				(end 392.496802 -12.720066)
			)
			(xy 392.496802 -12.748514) (xy 392.499088 -12.7508)
			(arc
				(start 393.067794 -12.7508)
				(mid 393.226496 -12.312827)
				(end 393.280392 -11.850116)
			)
			(arc
				(start 393.280392 -1.999996)
				(mid 393.568747 -1.303847)
				(end 394.264896 -1.015492)
			)
			(arc
				(start 406.265126 -1.015492)
				(mid 406.961365 -1.303831)
				(end 407.249884 -1.999996)
			)
			(arc
				(start 407.249884 -11.850116)
				(mid 407.840133 -13.275103)
				(end 409.26512 -13.865352)
			)
			(xy 416.40887 -13.865352)
		)
		(stroke
			(width 0)
			(type solid)
		)
		(fill yes)
		(layer "In9.Cu")
		(net "GND")
	)
	(gr_poly
		(pts
			(xy 364.71606 -13.770102) (xy 364.71606 -13.453364) (xy 364.62081 -13.358114)
			(arc
				(start 357.26497 -13.358114)
				(mid 356.198654 -12.916432)
				(end 355.756972 -11.850116)
			)
			(arc
				(start 355.756972 -1.999996)
				(mid 355.319976 -0.944996)
				(end 354.264976 -0.508)
			)
			(arc
				(start 330.164948 -0.508)
				(mid 329.109948 -0.944996)
				(end 328.672952 -1.999996)
			)
			(arc
				(start 328.672952 -11.850116)
				(mid 328.570197 -12.397292)
				(end 328.27595 -12.869926)
			)
			(xy 328.27595 -12.876784) (xy 328.28738 -12.888214) (xy 328.885042 -12.888214)
			(arc
				(start 328.90333 -12.869926)
				(mid 329.10994 -12.378512)
				(end 329.180444 -11.850116)
			)
			(arc
				(start 329.180444 -1.999996)
				(mid 329.468799 -1.303847)
				(end 330.164948 -1.015492)
			)
			(arc
				(start 354.264976 -1.015492)
				(mid 354.961125 -1.303847)
				(end 355.24948 -1.999996)
			)
			(arc
				(start 355.24948 -11.850116)
				(mid 355.839893 -13.275118)
				(end 357.26497 -13.865352)
			)
			(xy 364.62081 -13.865352)
		)
		(stroke
			(width 0)
			(type solid)
		)
		(fill yes)
		(layer "In9.Cu")
		(net "GND")
	)
	(gr_poly
		(pts
			(xy 390.499092 -13.810996) (xy 390.499092 -13.41247) (xy 390.444736 -13.358114)
			(arc
				(start 383.264918 -13.358114)
				(mid 382.198602 -12.916432)
				(end 381.75692 -11.850116)
			)
			(arc
				(start 381.75692 -1.999996)
				(mid 381.319924 -0.944996)
				(end 380.264924 -0.508)
			)
			(arc
				(start 368.264948 -0.508)
				(mid 367.209948 -0.944996)
				(end 366.772952 -1.999996)
			)
			(arc
				(start 366.772952 -11.850116)
				(mid 366.670132 -12.397459)
				(end 366.375696 -12.87018)
			)
			(xy 366.375696 -12.899644) (xy 366.434878 -12.958826) (xy 366.914684 -12.958826)
			(arc
				(start 367.00333 -12.87018)
				(mid 367.209881 -12.378884)
				(end 367.280444 -11.850624)
			)
			(arc
				(start 367.280444 -1.999996)
				(mid 367.568799 -1.303847)
				(end 368.264948 -1.015492)
			)
			(arc
				(start 380.264924 -1.015492)
				(mid 380.961073 -1.303847)
				(end 381.249428 -1.999996)
			)
			(arc
				(start 381.249428 -11.850116)
				(mid 381.839841 -13.275118)
				(end 383.264918 -13.865352)
			)
			(xy 390.444736 -13.865352)
		)
		(stroke
			(width 0)
			(type solid)
		)
		(fill yes)
		(layer "In9.Cu")
		(net "GND")
	)
	(gr_poly
		(pts
			(xy 326.45985 -13.852906) (xy 326.45985 -13.37945) (xy 326.438514 -13.358114)
			(arc
				(start 319.16497 -13.358114)
				(mid 318.098654 -12.916432)
				(end 317.656972 -11.850116)
			)
			(arc
				(start 317.656972 -1.999996)
				(mid 317.219976 -0.944996)
				(end 316.164976 -0.508)
			)
			(arc
				(start 304.165 -0.508)
				(mid 303.11 -0.944996)
				(end 302.673004 -1.999996)
			)
			(arc
				(start 302.673004 -11.850116)
				(mid 302.577528 -12.378214)
				(end 302.30318 -12.839446)
			)
			(xy 302.30318 -12.884912) (xy 302.304196 -12.885928) (xy 302.874426 -12.885928)
			(arc
				(start 302.920908 -12.839446)
				(mid 303.114524 -12.361527)
				(end 303.180496 -11.850116)
			)
			(arc
				(start 303.180496 -1.999996)
				(mid 303.468851 -1.303847)
				(end 304.165 -1.015492)
			)
			(arc
				(start 316.164976 -1.015492)
				(mid 316.861125 -1.303847)
				(end 317.14948 -1.999996)
			)
			(arc
				(start 317.14948 -11.850116)
				(mid 317.739893 -13.275118)
				(end 319.16497 -13.865352)
			)
			(xy 326.438514 -13.865352) (xy 326.447404 -13.865352)
		)
		(stroke
			(width 0)
			(type solid)
		)
		(fill yes)
		(layer "In9.Cu")
		(net "GND")
	)
	(gr_poly
		(pts
			(xy 27.839924 -300.928024) (xy 27.849993 -300.927597) (xy 27.868593 -300.919879) (xy 27.875992 -300.913038)
			(xy 27.926284 -300.862746) (xy 27.933124 -300.855345) (xy 27.940841 -300.836747) (xy 27.94127 -300.826678)
			(xy 27.94127 -299.58538) (xy 27.940679 -299.573053) (xy 27.929227 -299.551223) (xy 27.919426 -299.543724)
			(xy 27.840178 -299.48886) (xy 27.81554 -299.485812) (xy 27.803856 -299.490384) (xy 27.77133 -299.501881)
			(xy 27.703472 -299.514273) (xy 27.668982 -299.515022) (xy 27.641731 -299.514535) (xy 27.587783 -299.506776)
			(xy 27.535488 -299.491419) (xy 27.485912 -299.468776) (xy 27.440062 -299.439308) (xy 27.398872 -299.403615)
			(xy 27.363181 -299.362424) (xy 27.333716 -299.316573) (xy 27.311075 -299.266995) (xy 27.29572 -299.2147)
			(xy 27.287964 -299.160751) (xy 27.287964 -299.106249) (xy 27.29572 -299.0523) (xy 27.311075 -299.000005)
			(xy 27.333716 -298.950427) (xy 27.363181 -298.904576) (xy 27.398872 -298.863385) (xy 27.440062 -298.827692)
			(xy 27.485912 -298.798224) (xy 27.535488 -298.775581) (xy 27.587783 -298.760224) (xy 27.641731 -298.752465)
			(xy 27.668982 -298.752006) (xy 27.703473 -298.752746) (xy 27.771332 -298.765139) (xy 27.803856 -298.776644)
			(xy 27.81554 -298.781216) (xy 27.840178 -298.778168) (xy 27.919426 -298.723304) (xy 27.929097 -298.715691)
			(xy 27.940517 -298.693932) (xy 27.94127 -298.681648) (xy 27.94127 -296.38498) (xy 27.940679 -296.372653)
			(xy 27.929227 -296.350823) (xy 27.919426 -296.343324) (xy 27.840178 -296.28846) (xy 27.81554 -296.285412)
			(xy 27.803856 -296.289984) (xy 27.77133 -296.301481) (xy 27.703472 -296.313873) (xy 27.668982 -296.314622)
			(xy 27.641731 -296.314135) (xy 27.587783 -296.306376) (xy 27.535488 -296.291019) (xy 27.485912 -296.268376)
			(xy 27.440062 -296.238908) (xy 27.398872 -296.203215) (xy 27.363181 -296.162024) (xy 27.333716 -296.116173)
			(xy 27.311075 -296.066595) (xy 27.29572 -296.0143) (xy 27.287964 -295.960351) (xy 27.287964 -295.905849)
			(xy 27.29572 -295.8519) (xy 27.311075 -295.799605) (xy 27.333716 -295.750027) (xy 27.363181 -295.704176)
			(xy 27.398872 -295.662985) (xy 27.440062 -295.627292) (xy 27.485912 -295.597824) (xy 27.535488 -295.575181)
			(xy 27.587783 -295.559824) (xy 27.641731 -295.552065) (xy 27.668982 -295.551606) (xy 27.703473 -295.552346)
			(xy 27.771332 -295.564739) (xy 27.803856 -295.576244) (xy 27.81554 -295.580816) (xy 27.840178 -295.577768)
			(xy 27.919426 -295.522904) (xy 27.929097 -295.515291) (xy 27.940517 -295.493532) (xy 27.94127 -295.481248)
			(xy 27.94127 -294.495474) (xy 27.940841 -294.485407) (xy 27.933117 -294.466812) (xy 27.926284 -294.459406)
			(xy 27.854148 -294.38727) (xy 27.84675 -294.380424) (xy 27.828151 -294.372697) (xy 27.81808 -294.372284)
			(xy 24.14143 -294.372284) (xy 24.131365 -294.372719) (xy 24.112778 -294.38045) (xy 24.105362 -294.38727)
			(xy 23.872698 -294.619934) (xy 23.865857 -294.627335) (xy 23.858135 -294.645933) (xy 23.857712 -294.656002)
			(xy 23.857712 -295.933114) (xy 25.811478 -295.933114) (xy 25.815549 -295.877492) (xy 25.827675 -295.823055)
			(xy 25.847598 -295.770964) (xy 25.874894 -295.722329) (xy 25.90898 -295.678186) (xy 25.949129 -295.639477)
			(xy 25.994487 -295.607026) (xy 26.044087 -295.581525) (xy 26.096871 -295.563518) (xy 26.151714 -295.553388)
			(xy 26.207448 -295.551351) (xy 26.262885 -295.557451) (xy 26.316842 -295.571557) (xy 26.368171 -295.593369)
			(xy 26.415777 -295.622423) (xy 26.458645 -295.658098) (xy 26.495862 -295.699635) (xy 26.526635 -295.746148)
			(xy 26.550307 -295.796645) (xy 26.566375 -295.850052) (xy 26.574495 -295.905228) (xy 26.575004 -295.933114)
			(xy 26.574495 -295.961) (xy 26.566375 -296.016176) (xy 26.550307 -296.069583) (xy 26.526635 -296.12008)
			(xy 26.495862 -296.166593) (xy 26.458645 -296.20813) (xy 26.415777 -296.243805) (xy 26.368171 -296.272859)
			(xy 26.316842 -296.294671) (xy 26.262885 -296.308777) (xy 26.207448 -296.314877) (xy 26.151714 -296.31284)
			(xy 26.096871 -296.30271) (xy 26.044087 -296.284703) (xy 25.994487 -296.259202) (xy 25.949129 -296.226751)
			(xy 25.90898 -296.188042) (xy 25.874894 -296.143899) (xy 25.847598 -296.095264) (xy 25.827675 -296.043173)
			(xy 25.815549 -295.988736) (xy 25.811478 -295.933114) (xy 23.857712 -295.933114) (xy 23.857712 -299.133514)
			(xy 25.826718 -299.133514) (xy 25.830789 -299.077892) (xy 25.842915 -299.023455) (xy 25.862838 -298.971364)
			(xy 25.890134 -298.922729) (xy 25.92422 -298.878586) (xy 25.964369 -298.839877) (xy 26.009727 -298.807426)
			(xy 26.059327 -298.781925) (xy 26.112111 -298.763918) (xy 26.166954 -298.753788) (xy 26.222688 -298.751751)
			(xy 26.278125 -298.757851) (xy 26.332082 -298.771957) (xy 26.383411 -298.793769) (xy 26.431017 -298.822823)
			(xy 26.473885 -298.858498) (xy 26.511102 -298.900035) (xy 26.541875 -298.946548) (xy 26.565547 -298.997045)
			(xy 26.581615 -299.050452) (xy 26.589735 -299.105628) (xy 26.590244 -299.133514) (xy 26.589735 -299.1614)
			(xy 26.581615 -299.216576) (xy 26.565547 -299.269983) (xy 26.541875 -299.32048) (xy 26.511102 -299.366993)
			(xy 26.473885 -299.40853) (xy 26.431017 -299.444205) (xy 26.383411 -299.473259) (xy 26.332082 -299.495071)
			(xy 26.278125 -299.509177) (xy 26.222688 -299.515277) (xy 26.166954 -299.51324) (xy 26.112111 -299.50311)
			(xy 26.059327 -299.485103) (xy 26.009727 -299.459602) (xy 25.964369 -299.427151) (xy 25.92422 -299.388442)
			(xy 25.890134 -299.344299) (xy 25.862838 -299.295664) (xy 25.842915 -299.243573) (xy 25.830789 -299.189136)
			(xy 25.826718 -299.133514) (xy 23.857712 -299.133514) (xy 23.857712 -300.228762) (xy 23.858147 -300.238827)
			(xy 23.865878 -300.257414) (xy 23.872698 -300.26483) (xy 24.520906 -300.913038) (xy 24.528302 -300.91989)
			(xy 24.546901 -300.927632) (xy 24.556974 -300.928024)
		)
		(stroke
			(width 0)
			(type solid)
		)
		(fill yes)
		(layer "In9.Cu")
		(net "P1V8_PLL0_PEX0")
	)
	(gr_poly
		(pts
			(arc
				(start 200.481692 -418.081968)
				(mid 201.086106 -417.953924)
				(end 201.586846 -417.592002)
			)
			(arc
				(start 201.586846 -417.592002)
				(mid 202.42889 -416.98332)
				(end 203.445364 -416.768026)
			)
			(arc
				(start 271.794732 -416.768026)
				(mid 272.811071 -416.983322)
				(end 273.652996 -417.592002)
			)
			(arc
				(start 273.652996 -417.592002)
				(mid 274.153727 -417.953921)
				(end 274.75815 -418.081968)
			)
			(arc
				(start 465.600034 -418.081968)
				(mid 466.655034 -417.644972)
				(end 467.09203 -416.589972)
			)
			(xy 467.09203 -317.499746) (xy 466.584792 -317.499746)
			(arc
				(start 466.584792 -416.589972)
				(mid 466.296527 -417.286032)
				(end 465.600542 -417.574476)
			)
			(xy 414.915604 -417.574476) (xy 414.915604 -417.797742) (xy 400.95424 -417.797742) (xy 400.95424 -417.574476)
			(xy 326.621648 -417.574476) (xy 326.621648 -417.747958) (xy 313.065922 -417.747958) (xy 313.065922 -417.574476)
			(arc
				(start 274.757896 -417.574476)
				(mid 274.359217 -417.490052)
				(end 274.028916 -417.251388)
			)
			(arc
				(start 274.028916 -417.251388)
				(mid 273.01669 -416.519565)
				(end 271.794732 -416.260788)
			)
			(arc
				(start 203.445364 -416.260788)
				(mid 202.223266 -416.519531)
				(end 201.210926 -417.251388)
			)
			(arc
				(start 201.210926 -417.251388)
				(mid 200.880626 -417.490098)
				(end 200.481946 -417.574476)
			)
			(xy 154.673554 -417.574476) (xy 154.673554 -417.693856) (xy 141.027912 -417.693856) (xy 141.027912 -417.574476)
			(xy 66.745104 -417.574476) (xy 66.745104 -417.671758) (xy 53.039772 -417.671758) (xy 53.039772 -417.574476)
			(arc
				(start 1.999996 -417.574476)
				(mid 1.303847 -417.286121)
				(end 1.015492 -416.589972)
			)
			(xy 1.015492 -388.549388) (xy 0.995172 -388.529068) (xy 1.015492 -388.508748) (xy 1.015492 -384.32486)
			(xy 1.015492 -316.13983) (xy 0.508 -316.13983)
			(arc
				(start 0.508 -416.589972)
				(mid 0.944996 -417.644972)
				(end 1.999996 -418.081968)
			)
		)
		(stroke
			(width 0)
			(type solid)
		)
		(fill yes)
		(layer "In9.Cu")
		(net "GND")
	)
	(gr_poly
		(pts
			(arc
				(start 467.09203 -246.488204)
				(mid 466.978493 -245.917325)
				(end 466.65515 -245.433342)
			)
			(arc
				(start 464.026504 -242.80495)
				(mid 463.482885 -241.991412)
				(end 463.291936 -241.031776)
			)
			(arc
				(start 463.291936 -87.588344)
				(mid 463.482826 -86.628673)
				(end 464.026504 -85.81517)
			)
			(arc
				(start 466.65515 -83.186524)
				(mid 466.978483 -82.702667)
				(end 467.09203 -82.131916)
			)
			(arc
				(start 467.09203 -1.999996)
				(mid 466.655034 -0.944996)
				(end 465.600034 -0.508)
			)
			(arc
				(start 446.265046 -0.508)
				(mid 445.210046 -0.944996)
				(end 444.77305 -1.999996)
			)
			(arc
				(start 444.77305 -11.850116)
				(mid 444.676277 -12.381671)
				(end 444.3984 -12.845034)
			)
			(xy 444.3984 -12.869164) (xy 444.399924 -12.870688)
			(arc
				(start 445.002666 -12.870688)
				(mid 445.20965 -12.378943)
				(end 445.280288 -11.850116)
			)
			(arc
				(start 445.280288 -1.999996)
				(mid 445.568553 -1.303936)
				(end 446.264538 -1.015492)
			)
			(arc
				(start 465.600034 -1.015492)
				(mid 466.296273 -1.303831)
				(end 466.584792 -1.999996)
			)
			(arc
				(start 466.584792 -82.131916)
				(mid 466.509885 -82.508586)
				(end 466.296502 -82.827876)
			)
			(arc
				(start 463.667856 -85.456522)
				(mid 463.014235 -86.434595)
				(end 462.784698 -87.588344)
			)
			(xy 462.784444 -87.588344) (xy 462.784444 -241.031776)
			(arc
				(start 462.784698 -241.031776)
				(mid 463.014268 -242.185519)
				(end 463.667856 -243.163598)
			)
			(arc
				(start 466.296502 -245.79199)
				(mid 466.509882 -246.11143)
				(end 466.584792 -246.488204)
			)
			(xy 466.584792 -311.303416) (xy 467.09203 -311.303416)
		)
		(stroke
			(width 0)
			(type solid)
		)
		(fill yes)
		(layer "In9.Cu")
		(net "GND")
	)
	(gr_poly
		(pts
			(arc
				(start 235.636562 -413.132016)
				(mid 235.656085 -413.128115)
				(end 235.67263 -413.11703)
			)
			(arc
				(start 236.812328 -411.977332)
				(mid 236.823439 -411.960798)
				(end 236.827314 -411.941264)
			)
			(arc
				(start 236.827314 -402.776436)
				(mid 236.831215 -402.756913)
				(end 236.8423 -402.740368)
			)
			(arc
				(start 238.886238 -400.69643)
				(mid 238.902772 -400.685319)
				(end 238.922306 -400.681444)
			)
			(arc
				(start 242.916964 -400.681444)
				(mid 242.936487 -400.677543)
				(end 242.953032 -400.666458)
			)
			(arc
				(start 243.86286 -399.75663)
				(mid 243.873971 -399.740096)
				(end 243.877846 -399.720562)
			)
			(arc
				(start 243.877846 -392.486896)
				(mid 243.881747 -392.467373)
				(end 243.892832 -392.450828)
			)
			(xy 243.896388 -392.447272)
			(arc
				(start 243.896388 -391.97026)
				(mid 243.900289 -391.950737)
				(end 243.911374 -391.934192)
			)
			(arc
				(start 245.02999 -390.815576)
				(mid 245.046524 -390.804465)
				(end 245.066058 -390.80059)
			)
			(arc
				(start 259.092954 -390.80059)
				(mid 259.112477 -390.796689)
				(end 259.129022 -390.785604)
			)
			(arc
				(start 262.060944 -387.853682)
				(mid 262.072055 -387.837148)
				(end 262.07593 -387.817614)
			)
			(arc
				(start 262.07593 -379.165866)
				(mid 262.072029 -379.146343)
				(end 262.060944 -379.129798)
			)
			(arc
				(start 261.987538 -379.056392)
				(mid 261.971004 -379.045281)
				(end 261.95147 -379.041406)
			)
			(xy 243.1415 -379.041406) (xy 243.140484 -379.042422)
			(arc
				(start 240.581688 -379.042422)
				(mid 240.562165 -379.046323)
				(end 240.54562 -379.057408)
			)
			(arc
				(start 239.903 -379.700028)
				(mid 239.886466 -379.711139)
				(end 239.866932 -379.715014)
			)
			(arc
				(start 237.06963 -379.715014)
				(mid 237.050107 -379.711113)
				(end 237.033562 -379.700028)
			)
			(arc
				(start 232.94086 -375.607326)
				(mid 232.929749 -375.590792)
				(end 232.925874 -375.571258)
			)
			(arc
				(start 232.925874 -372.098062)
				(mid 232.921973 -372.078539)
				(end 232.910888 -372.061994)
			)
			(arc
				(start 232.189274 -371.34038)
				(mid 232.178163 -371.323846)
				(end 232.174288 -371.304312)
			)
			(arc
				(start 232.174288 -371.057424)
				(mid 232.170387 -371.037901)
				(end 232.159302 -371.021356)
			)
			(xy 232.119932 -370.981986) (xy 232.118408 -370.981986)
			(arc
				(start 232.015284 -370.878862)
				(mid 232.004173 -370.862328)
				(end 232.000298 -370.842794)
			)
			(arc
				(start 232.000298 -367.379758)
				(mid 231.996397 -367.360235)
				(end 231.985312 -367.34369)
			)
			(arc
				(start 231.905048 -367.263426)
				(mid 231.888514 -367.252315)
				(end 231.86898 -367.24844)
			)
			(arc
				(start 228.707696 -367.24844)
				(mid 228.688173 -367.252341)
				(end 228.671628 -367.263426)
			)
			(arc
				(start 228.614478 -367.320576)
				(mid 228.603367 -367.33711)
				(end 228.599492 -367.356644)
			)
			(arc
				(start 228.599492 -370.828062)
				(mid 228.595591 -370.847585)
				(end 228.584506 -370.86413)
			)
			(arc
				(start 228.431344 -371.017292)
				(mid 228.420233 -371.033826)
				(end 228.416358 -371.05336)
			)
			(arc
				(start 228.416358 -371.446552)
				(mid 228.412457 -371.466075)
				(end 228.401372 -371.48262)
			)
			(arc
				(start 227.137722 -372.74627)
				(mid 227.126611 -372.762804)
				(end 227.122736 -372.782338)
			)
			(arc
				(start 227.122736 -374.248426)
				(mid 227.118835 -374.267949)
				(end 227.10775 -374.284494)
			)
			(arc
				(start 225.693224 -375.69902)
				(mid 225.67669 -375.710131)
				(end 225.657156 -375.714006)
			)
			(arc
				(start 223.582484 -375.714006)
				(mid 223.562961 -375.710105)
				(end 223.546416 -375.69902)
			)
			(arc
				(start 221.539816 -373.69242)
				(mid 221.528705 -373.675886)
				(end 221.52483 -373.656352)
			)
			(arc
				(start 221.52483 -371.757956)
				(mid 221.509951 -371.722035)
				(end 221.47403 -371.707156)
			)
			(arc
				(start 217.036904 -371.707156)
				(mid 217.017517 -371.711106)
				(end 217.00109 -371.722142)
			)
			(arc
				(start 216.72931 -371.993922)
				(mid 216.712776 -372.005033)
				(end 216.693242 -372.008908)
			)
			(arc
				(start 210.338924 -372.008908)
				(mid 210.319401 -372.005007)
				(end 210.302856 -371.993922)
			)
			(arc
				(start 210.054698 -371.745764)
				(mid 210.043587 -371.72923)
				(end 210.039712 -371.709696)
			)
			(arc
				(start 210.039712 -371.55882)
				(mid 210.024833 -371.522899)
				(end 209.988912 -371.50802)
			)
			(arc
				(start 204.85989 -371.50802)
				(mid 204.823969 -371.522899)
				(end 204.80909 -371.55882)
			)
			(arc
				(start 204.80909 -372.841012)
				(mid 204.815471 -372.865662)
				(end 204.832966 -372.884192)
			)
			(xy 204.917548 -372.93677) (xy 204.94371 -372.93804)
			(arc
				(start 204.955648 -372.932198)
				(mid 205.037716 -372.902845)
				(end 205.124304 -372.892828)
			)
			(arc
				(start 205.124304 -372.892828)
				(mid 205.505812 -373.274336)
				(end 205.124304 -373.655844)
			)
			(arc
				(start 205.124304 -373.655844)
				(mid 205.037702 -373.645885)
				(end 204.955648 -373.616474)
			)
			(xy 204.94371 -373.610632) (xy 204.917548 -373.611902)
			(arc
				(start 204.832966 -373.66448)
				(mid 204.815396 -373.682968)
				(end 204.80909 -373.70766)
			)
			(arc
				(start 204.80909 -374.498616)
				(mid 204.812991 -374.518139)
				(end 204.824076 -374.534684)
			)
			(arc
				(start 204.905102 -374.61571)
				(mid 204.916213 -374.632244)
				(end 204.920088 -374.651778)
			)
			(arc
				(start 204.920088 -387.060948)
				(mid 204.923989 -387.080471)
				(end 204.935074 -387.097016)
			)
			(arc
				(start 207.491838 -389.65378)
				(mid 207.502949 -389.670314)
				(end 207.506824 -389.689848)
			)
			(arc
				(start 207.506824 -411.710124)
				(mid 207.510725 -411.729647)
				(end 207.52181 -411.746192)
			)
			(arc
				(start 208.892648 -413.11703)
				(mid 208.909182 -413.128141)
				(end 208.928716 -413.132016)
			)
		)
		(stroke
			(width 0)
			(type solid)
		)
		(fill yes)
		(layer "In9.Cu")
		(net "P12V_STBY")
	)
	(gr_poly
		(pts
			(arc
				(start 1.015492 -246.48795)
				(mid 1.090466 -246.111319)
				(end 1.303782 -245.79199)
			)
			(arc
				(start 3.93192 -243.163852)
				(mid 4.58575 -242.18556)
				(end 4.815332 -241.031522)
			)
			(arc
				(start 4.815332 -87.588344)
				(mid 4.585694 -86.434435)
				(end 3.93192 -85.456268)
			)
			(arc
				(start 1.303528 -82.827876)
				(mid 1.090411 -82.508641)
				(end 1.015492 -82.13217)
			)
			(arc
				(start 1.015492 -1.999996)
				(mid 1.303847 -1.303847)
				(end 1.999996 -1.015492)
			)
			(arc
				(start 5.964936 -1.015492)
				(mid 6.661085 -1.303847)
				(end 6.94944 -1.999996)
			)
			(arc
				(start 6.94944 -11.850116)
				(mid 7.539853 -13.275118)
				(end 8.96493 -13.865352)
			)
			(xy 16.2814 -13.865352) (xy 16.371316 -13.775436) (xy 16.371316 -13.44803) (xy 16.2814 -13.358114)
			(arc
				(start 8.96493 -13.358114)
				(mid 7.898614 -12.916432)
				(end 7.456932 -11.850116)
			)
			(arc
				(start 7.456932 -1.999996)
				(mid 7.019936 -0.944996)
				(end 5.964936 -0.508)
			)
			(arc
				(start 1.999996 -0.508)
				(mid 0.944996 -0.944996)
				(end 0.508 -1.999996)
			)
			(arc
				(start 0.508 -82.131916)
				(mid 0.621601 -82.702644)
				(end 0.94488 -83.186524)
			)
			(arc
				(start 3.573272 -85.81517)
				(mid 4.117081 -86.628665)
				(end 4.308094 -87.588344)
			)
			(arc
				(start 4.308094 -241.031522)
				(mid 4.117082 -241.991334)
				(end 3.573272 -242.80495)
			)
			(arc
				(start 0.94488 -245.433342)
				(mid 0.621552 -245.917331)
				(end 0.508 -246.488204)
			)
			(xy 0.508 -307.918358) (xy 1.015492 -307.918358)
		)
		(stroke
			(width 0)
			(type solid)
		)
		(fill yes)
		(layer "In9.Cu")
		(net "GND")
	)
	(gr_poly
		(pts
			(xy 453.021954 -70.086728) (xy 453.03202 -70.086296) (xy 453.050613 -70.078571) (xy 453.058022 -70.071742)
			(xy 453.213216 -69.916548) (xy 453.220064 -69.909151) (xy 453.227792 -69.890552) (xy 453.228202 -69.88048)
			(xy 453.228202 -52.08524) (xy 453.227768 -52.075175) (xy 453.220038 -52.056586) (xy 453.213216 -52.049172)
			(xy 452.826882 -51.662838) (xy 452.819484 -51.65599) (xy 452.800886 -51.648256) (xy 452.790814 -51.647852)
			(xy 447.500756 -51.647852) (xy 447.490691 -51.648285) (xy 447.472103 -51.656016) (xy 447.464688 -51.662838)
			(xy 447.424556 -51.70297) (xy 447.417872 -51.71038) (xy 447.410286 -51.728816) (xy 447.409824 -51.738784)
			(xy 447.409824 -52.034186) (xy 447.410309 -52.044277) (xy 447.418166 -52.062872) (xy 447.425064 -52.070254)
			(xy 447.4845 -52.12842) (xy 447.503042 -52.135786) (xy 447.513456 -52.135532) (xy 447.522092 -52.135532)
			(xy 447.549342 -52.135995) (xy 447.603289 -52.14375) (xy 447.655582 -52.159104) (xy 447.705158 -52.181743)
			(xy 447.751007 -52.211208) (xy 447.792196 -52.246898) (xy 447.827887 -52.288086) (xy 447.857353 -52.333935)
			(xy 447.879994 -52.383511) (xy 447.895348 -52.435804) (xy 447.903105 -52.48975) (xy 447.903105 -52.54425)
			(xy 447.896901 -52.587398) (xy 451.05523 -52.587398) (xy 451.059301 -52.531776) (xy 451.071427 -52.477339)
			(xy 451.09135 -52.425248) (xy 451.118646 -52.376613) (xy 451.152732 -52.33247) (xy 451.192881 -52.293761)
			(xy 451.238239 -52.26131) (xy 451.287839 -52.235809) (xy 451.340623 -52.217802) (xy 451.395466 -52.207672)
			(xy 451.4512 -52.205635) (xy 451.506637 -52.211735) (xy 451.560594 -52.225841) (xy 451.611923 -52.247653)
			(xy 451.659529 -52.276707) (xy 451.702397 -52.312382) (xy 451.739614 -52.353919) (xy 451.770387 -52.400432)
			(xy 451.794059 -52.450929) (xy 451.810127 -52.504336) (xy 451.818247 -52.559512) (xy 451.818756 -52.587398)
			(xy 451.818247 -52.615284) (xy 451.810127 -52.67046) (xy 451.794059 -52.723867) (xy 451.770387 -52.774364)
			(xy 451.739614 -52.820877) (xy 451.702397 -52.862414) (xy 451.659529 -52.898089) (xy 451.611923 -52.927143)
			(xy 451.560594 -52.948955) (xy 451.506637 -52.963061) (xy 451.4512 -52.969161) (xy 451.395466 -52.967124)
			(xy 451.340623 -52.956994) (xy 451.287839 -52.938987) (xy 451.238239 -52.913486) (xy 451.192881 -52.881035)
			(xy 451.152732 -52.842326) (xy 451.118646 -52.798183) (xy 451.09135 -52.749548) (xy 451.071427 -52.697457)
			(xy 451.059301 -52.64302) (xy 451.05523 -52.587398) (xy 447.896901 -52.587398) (xy 447.895348 -52.598196)
			(xy 447.879994 -52.650489) (xy 447.857353 -52.700065) (xy 447.827887 -52.745914) (xy 447.792196 -52.787102)
			(xy 447.751007 -52.822792) (xy 447.705158 -52.852257) (xy 447.655582 -52.874896) (xy 447.603289 -52.89025)
			(xy 447.549342 -52.898005) (xy 447.522092 -52.898548) (xy 447.513456 -52.898548) (xy 447.503042 -52.898294)
			(xy 447.4845 -52.90566) (xy 447.425064 -52.963826) (xy 447.418162 -52.971202) (xy 447.410322 -52.989802)
			(xy 447.409824 -52.999894) (xy 447.409824 -53.96357) (xy 451.071994 -53.96357) (xy 451.076065 -53.907948)
			(xy 451.088191 -53.853511) (xy 451.108114 -53.80142) (xy 451.13541 -53.752785) (xy 451.169496 -53.708642)
			(xy 451.209645 -53.669933) (xy 451.255003 -53.637482) (xy 451.304603 -53.611981) (xy 451.357387 -53.593974)
			(xy 451.41223 -53.583844) (xy 451.467964 -53.581807) (xy 451.523401 -53.587907) (xy 451.577358 -53.602013)
			(xy 451.628687 -53.623825) (xy 451.676293 -53.652879) (xy 451.719161 -53.688554) (xy 451.756378 -53.730091)
			(xy 451.787151 -53.776604) (xy 451.810823 -53.827101) (xy 451.826891 -53.880508) (xy 451.835011 -53.935684)
			(xy 451.83552 -53.96357) (xy 451.835011 -53.991456) (xy 451.826891 -54.046632) (xy 451.810823 -54.100039)
			(xy 451.787151 -54.150536) (xy 451.756378 -54.197049) (xy 451.719161 -54.238586) (xy 451.676293 -54.274261)
			(xy 451.628687 -54.303315) (xy 451.577358 -54.325127) (xy 451.523401 -54.339233) (xy 451.467964 -54.345333)
			(xy 451.41223 -54.343296) (xy 451.357387 -54.333166) (xy 451.304603 -54.315159) (xy 451.255003 -54.289658)
			(xy 451.209645 -54.257207) (xy 451.169496 -54.218498) (xy 451.13541 -54.174355) (xy 451.108114 -54.12572)
			(xy 451.088191 -54.073629) (xy 451.076065 -54.019192) (xy 451.071994 -53.96357) (xy 447.409824 -53.96357)
			(xy 447.409824 -55.722266) (xy 452.133968 -55.722266) (xy 452.138039 -55.666644) (xy 452.150165 -55.612207)
			(xy 452.170088 -55.560116) (xy 452.197384 -55.511481) (xy 452.23147 -55.467338) (xy 452.271619 -55.428629)
			(xy 452.316977 -55.396178) (xy 452.366577 -55.370677) (xy 452.419361 -55.35267) (xy 452.474204 -55.34254)
			(xy 452.529938 -55.340503) (xy 452.585375 -55.346603) (xy 452.639332 -55.360709) (xy 452.690661 -55.382521)
			(xy 452.738267 -55.411575) (xy 452.781135 -55.44725) (xy 452.818352 -55.488787) (xy 452.849125 -55.5353)
			(xy 452.872797 -55.585797) (xy 452.888865 -55.639204) (xy 452.896985 -55.69438) (xy 452.897494 -55.722266)
			(xy 452.896985 -55.750152) (xy 452.888865 -55.805328) (xy 452.872797 -55.858735) (xy 452.849125 -55.909232)
			(xy 452.818352 -55.955745) (xy 452.781135 -55.997282) (xy 452.738267 -56.032957) (xy 452.690661 -56.062011)
			(xy 452.639332 -56.083823) (xy 452.585375 -56.097929) (xy 452.529938 -56.104029) (xy 452.474204 -56.101992)
			(xy 452.419361 -56.091862) (xy 452.366577 -56.073855) (xy 452.316977 -56.048354) (xy 452.271619 -56.015903)
			(xy 452.23147 -55.977194) (xy 452.197384 -55.933051) (xy 452.170088 -55.884416) (xy 452.150165 -55.832325)
			(xy 452.138039 -55.777888) (xy 452.133968 -55.722266) (xy 447.409824 -55.722266) (xy 447.409824 -58.072274)
			(xy 452.29348 -58.072274) (xy 452.297551 -58.016652) (xy 452.309677 -57.962215) (xy 452.3296 -57.910124)
			(xy 452.356896 -57.861489) (xy 452.390982 -57.817346) (xy 452.431131 -57.778637) (xy 452.476489 -57.746186)
			(xy 452.526089 -57.720685) (xy 452.578873 -57.702678) (xy 452.633716 -57.692548) (xy 452.68945 -57.690511)
			(xy 452.744887 -57.696611) (xy 452.798844 -57.710717) (xy 452.850173 -57.732529) (xy 452.897779 -57.761583)
			(xy 452.940647 -57.797258) (xy 452.977864 -57.838795) (xy 453.008637 -57.885308) (xy 453.032309 -57.935805)
			(xy 453.048377 -57.989212) (xy 453.056497 -58.044388) (xy 453.057006 -58.072274) (xy 453.056497 -58.10016)
			(xy 453.048377 -58.155336) (xy 453.032309 -58.208743) (xy 453.008637 -58.25924) (xy 452.977864 -58.305753)
			(xy 452.940647 -58.34729) (xy 452.897779 -58.382965) (xy 452.850173 -58.412019) (xy 452.798844 -58.433831)
			(xy 452.744887 -58.447937) (xy 452.68945 -58.454037) (xy 452.633716 -58.452) (xy 452.578873 -58.44187)
			(xy 452.526089 -58.423863) (xy 452.476489 -58.398362) (xy 452.431131 -58.365911) (xy 452.390982 -58.327202)
			(xy 452.356896 -58.283059) (xy 452.3296 -58.234424) (xy 452.309677 -58.182333) (xy 452.297551 -58.127896)
			(xy 452.29348 -58.072274) (xy 447.409824 -58.072274) (xy 447.409824 -64.797178) (xy 447.410249 -64.806896)
			(xy 447.417461 -64.824944) (xy 447.430862 -64.839021) (xy 447.439542 -64.843406) (xy 447.537586 -64.887856)
			(xy 447.56705 -64.883284) (xy 447.57848 -64.873378) (xy 447.599483 -64.855571) (xy 447.645643 -64.825552)
			(xy 447.695636 -64.802473) (xy 447.748426 -64.786813) (xy 447.802917 -64.778898) (xy 447.830448 -64.778382)
			(xy 447.857698 -64.778871) (xy 447.911642 -64.786633) (xy 447.963932 -64.801993) (xy 448.013505 -64.824638)
			(xy 448.05935 -64.854106) (xy 448.100536 -64.889798) (xy 448.136223 -64.930988) (xy 448.165686 -64.976838)
			(xy 448.188324 -65.026413) (xy 448.203677 -65.078705) (xy 448.211432 -65.13265) (xy 448.211432 -65.18715)
			(xy 448.203677 -65.241095) (xy 448.188324 -65.293387) (xy 448.165686 -65.342962) (xy 448.136223 -65.388812)
			(xy 448.100536 -65.430002) (xy 448.05935 -65.465694) (xy 448.013505 -65.495162) (xy 447.963932 -65.517807)
			(xy 447.911642 -65.533167) (xy 447.857698 -65.540929) (xy 447.830448 -65.541398) (xy 447.802914 -65.540919)
			(xy 447.748416 -65.53301) (xy 447.695622 -65.51735) (xy 447.645626 -65.494263) (xy 447.599468 -65.46423)
			(xy 447.57848 -65.446402) (xy 447.56705 -65.436496) (xy 447.537586 -65.431924) (xy 447.439542 -65.476374)
			(xy 447.430879 -65.480794) (xy 447.417461 -65.494849) (xy 447.410234 -65.512886) (xy 447.409824 -65.522602)
			(xy 447.409824 -67.592956) (xy 447.64528 -67.592956) (xy 447.649351 -67.537334) (xy 447.661477 -67.482897)
			(xy 447.6814 -67.430806) (xy 447.708696 -67.382171) (xy 447.742782 -67.338028) (xy 447.782931 -67.299319)
			(xy 447.828289 -67.266868) (xy 447.877889 -67.241367) (xy 447.930673 -67.22336) (xy 447.985516 -67.21323)
			(xy 448.04125 -67.211193) (xy 448.096687 -67.217293) (xy 448.150644 -67.231399) (xy 448.201973 -67.253211)
			(xy 448.249579 -67.282265) (xy 448.292447 -67.31794) (xy 448.329664 -67.359477) (xy 448.360437 -67.40599)
			(xy 448.384109 -67.456487) (xy 448.400177 -67.509894) (xy 448.408297 -67.56507) (xy 448.408806 -67.592956)
			(xy 448.408297 -67.620842) (xy 448.400177 -67.676018) (xy 448.384109 -67.729425) (xy 448.360437 -67.779922)
			(xy 448.329664 -67.826435) (xy 448.292447 -67.867972) (xy 448.249579 -67.903647) (xy 448.201973 -67.932701)
			(xy 448.150644 -67.954513) (xy 448.096687 -67.968619) (xy 448.04125 -67.974719) (xy 447.985516 -67.972682)
			(xy 447.930673 -67.962552) (xy 447.877889 -67.944545) (xy 447.828289 -67.919044) (xy 447.782931 -67.886593)
			(xy 447.742782 -67.847884) (xy 447.708696 -67.803741) (xy 447.6814 -67.755106) (xy 447.661477 -67.703015)
			(xy 447.649351 -67.648578) (xy 447.64528 -67.592956) (xy 447.409824 -67.592956) (xy 447.409824 -70.035928)
			(xy 447.410317 -70.04593) (xy 447.417983 -70.064408) (xy 447.432135 -70.078547) (xy 447.450621 -70.086193)
			(xy 447.460624 -70.086728)
		)
		(stroke
			(width 0)
			(type solid)
		)
		(fill yes)
		(layer "In9.Cu")
		(net "P12V_AUX")
	)
	(gr_poly
		(pts
			(xy 104.722168 -70.086728) (xy 104.73222 -70.086225) (xy 104.750784 -70.078506) (xy 104.758236 -70.071742)
			(xy 104.91343 -69.916548) (xy 104.920276 -69.90915) (xy 104.928003 -69.890551) (xy 104.928416 -69.88048)
			(xy 104.928416 -52.08524) (xy 104.927982 -52.075174) (xy 104.920255 -52.056584) (xy 104.91343 -52.049172)
			(xy 104.527096 -51.662838) (xy 104.519984 -51.655472) (xy 104.501188 -51.647852) (xy 99.20097 -51.647852)
			(xy 99.190903 -51.648282) (xy 99.172312 -51.65601) (xy 99.164902 -51.662838) (xy 99.12477 -51.70297)
			(xy 99.118084 -51.710379) (xy 99.110496 -51.728815) (xy 99.110038 -51.738784) (xy 99.110038 -52.033932)
			(xy 99.110486 -52.044088) (xy 99.118347 -52.062817) (xy 99.125278 -52.070254) (xy 99.184714 -52.12842)
			(xy 99.20351 -52.135786) (xy 99.21367 -52.135532) (xy 99.222306 -52.135532) (xy 99.249554 -52.136019)
			(xy 99.303495 -52.143775) (xy 99.355784 -52.159129) (xy 99.405355 -52.181768) (xy 99.4512 -52.211231)
			(xy 99.492385 -52.246919) (xy 99.528072 -52.288105) (xy 99.557535 -52.33395) (xy 99.580173 -52.383522)
			(xy 99.595526 -52.43581) (xy 99.603282 -52.489752) (xy 99.603282 -52.544248) (xy 99.597078 -52.587398)
			(xy 102.75519 -52.587398) (xy 102.759261 -52.531776) (xy 102.771387 -52.477339) (xy 102.79131 -52.425248)
			(xy 102.818606 -52.376613) (xy 102.852692 -52.33247) (xy 102.892841 -52.293761) (xy 102.938199 -52.26131)
			(xy 102.987799 -52.235809) (xy 103.040583 -52.217802) (xy 103.095426 -52.207672) (xy 103.15116 -52.205635)
			(xy 103.206597 -52.211735) (xy 103.260554 -52.225841) (xy 103.311883 -52.247653) (xy 103.359489 -52.276707)
			(xy 103.402357 -52.312382) (xy 103.439574 -52.353919) (xy 103.470347 -52.400432) (xy 103.494019 -52.450929)
			(xy 103.510087 -52.504336) (xy 103.518207 -52.559512) (xy 103.518716 -52.587398) (xy 103.518207 -52.615284)
			(xy 103.510087 -52.67046) (xy 103.494019 -52.723867) (xy 103.470347 -52.774364) (xy 103.439574 -52.820877)
			(xy 103.402357 -52.862414) (xy 103.359489 -52.898089) (xy 103.311883 -52.927143) (xy 103.260554 -52.948955)
			(xy 103.206597 -52.963061) (xy 103.15116 -52.969161) (xy 103.095426 -52.967124) (xy 103.040583 -52.956994)
			(xy 102.987799 -52.938987) (xy 102.938199 -52.913486) (xy 102.892841 -52.881035) (xy 102.852692 -52.842326)
			(xy 102.818606 -52.798183) (xy 102.79131 -52.749548) (xy 102.771387 -52.697457) (xy 102.759261 -52.64302)
			(xy 102.75519 -52.587398) (xy 99.597078 -52.587398) (xy 99.595526 -52.59819) (xy 99.580173 -52.650478)
			(xy 99.557535 -52.70005) (xy 99.528072 -52.745895) (xy 99.492385 -52.787081) (xy 99.4512 -52.822769)
			(xy 99.405355 -52.852232) (xy 99.355784 -52.874871) (xy 99.303495 -52.890225) (xy 99.249554 -52.897981)
			(xy 99.222306 -52.898548) (xy 99.21367 -52.898548) (xy 99.20351 -52.898294) (xy 99.184714 -52.90566)
			(xy 99.125278 -52.963826) (xy 99.118374 -52.971201) (xy 99.110532 -52.989802) (xy 99.110038 -52.999894)
			(xy 99.110038 -53.96357) (xy 102.771954 -53.96357) (xy 102.776025 -53.907948) (xy 102.788151 -53.853511)
			(xy 102.808074 -53.80142) (xy 102.83537 -53.752785) (xy 102.869456 -53.708642) (xy 102.909605 -53.669933)
			(xy 102.954963 -53.637482) (xy 103.004563 -53.611981) (xy 103.057347 -53.593974) (xy 103.11219 -53.583844)
			(xy 103.167924 -53.581807) (xy 103.223361 -53.587907) (xy 103.277318 -53.602013) (xy 103.328647 -53.623825)
			(xy 103.376253 -53.652879) (xy 103.419121 -53.688554) (xy 103.456338 -53.730091) (xy 103.487111 -53.776604)
			(xy 103.510783 -53.827101) (xy 103.526851 -53.880508) (xy 103.534971 -53.935684) (xy 103.53548 -53.96357)
			(xy 103.534971 -53.991456) (xy 103.526851 -54.046632) (xy 103.510783 -54.100039) (xy 103.487111 -54.150536)
			(xy 103.456338 -54.197049) (xy 103.419121 -54.238586) (xy 103.376253 -54.274261) (xy 103.328647 -54.303315)
			(xy 103.277318 -54.325127) (xy 103.223361 -54.339233) (xy 103.167924 -54.345333) (xy 103.11219 -54.343296)
			(xy 103.057347 -54.333166) (xy 103.004563 -54.315159) (xy 102.954963 -54.289658) (xy 102.909605 -54.257207)
			(xy 102.869456 -54.218498) (xy 102.83537 -54.174355) (xy 102.808074 -54.12572) (xy 102.788151 -54.073629)
			(xy 102.776025 -54.019192) (xy 102.771954 -53.96357) (xy 99.110038 -53.96357) (xy 99.110038 -55.722266)
			(xy 103.833928 -55.722266) (xy 103.837999 -55.666644) (xy 103.850125 -55.612207) (xy 103.870048 -55.560116)
			(xy 103.897344 -55.511481) (xy 103.93143 -55.467338) (xy 103.971579 -55.428629) (xy 104.016937 -55.396178)
			(xy 104.066537 -55.370677) (xy 104.119321 -55.35267) (xy 104.174164 -55.34254) (xy 104.229898 -55.340503)
			(xy 104.285335 -55.346603) (xy 104.339292 -55.360709) (xy 104.390621 -55.382521) (xy 104.438227 -55.411575)
			(xy 104.481095 -55.44725) (xy 104.518312 -55.488787) (xy 104.549085 -55.5353) (xy 104.572757 -55.585797)
			(xy 104.588825 -55.639204) (xy 104.596945 -55.69438) (xy 104.597454 -55.722266) (xy 104.596945 -55.750152)
			(xy 104.588825 -55.805328) (xy 104.572757 -55.858735) (xy 104.549085 -55.909232) (xy 104.518312 -55.955745)
			(xy 104.481095 -55.997282) (xy 104.438227 -56.032957) (xy 104.390621 -56.062011) (xy 104.339292 -56.083823)
			(xy 104.285335 -56.097929) (xy 104.229898 -56.104029) (xy 104.174164 -56.101992) (xy 104.119321 -56.091862)
			(xy 104.066537 -56.073855) (xy 104.016937 -56.048354) (xy 103.971579 -56.015903) (xy 103.93143 -55.977194)
			(xy 103.897344 -55.933051) (xy 103.870048 -55.884416) (xy 103.850125 -55.832325) (xy 103.837999 -55.777888)
			(xy 103.833928 -55.722266) (xy 99.110038 -55.722266) (xy 99.110038 -58.072274) (xy 103.993186 -58.072274)
			(xy 103.997259 -58.016615) (xy 104.009394 -57.962142) (xy 104.02933 -57.910016) (xy 104.056644 -57.861348)
			(xy 104.090752 -57.817176) (xy 104.130929 -57.778441) (xy 104.176317 -57.745969) (xy 104.225949 -57.720451)
			(xy 104.278769 -57.702432) (xy 104.333648 -57.692295) (xy 104.389419 -57.690257) (xy 104.444893 -57.69636)
			(xy 104.498886 -57.710476) (xy 104.550249 -57.732303) (xy 104.597887 -57.761376) (xy 104.640783 -57.797075)
			(xy 104.678025 -57.838639) (xy 104.708819 -57.885183) (xy 104.732507 -57.935714) (xy 104.748585 -57.989156)
			(xy 104.756711 -58.04437) (xy 104.75722 -58.072274) (xy 104.756711 -58.100178) (xy 104.748585 -58.155392)
			(xy 104.732507 -58.208834) (xy 104.708819 -58.259365) (xy 104.678025 -58.305909) (xy 104.640783 -58.347473)
			(xy 104.597887 -58.383172) (xy 104.550249 -58.412245) (xy 104.498886 -58.434072) (xy 104.444893 -58.448188)
			(xy 104.389419 -58.454291) (xy 104.333648 -58.452253) (xy 104.278769 -58.442116) (xy 104.225949 -58.424097)
			(xy 104.176317 -58.398579) (xy 104.130929 -58.366107) (xy 104.090752 -58.327372) (xy 104.056644 -58.2832)
			(xy 104.02933 -58.234532) (xy 104.009394 -58.182406) (xy 103.997259 -58.127933) (xy 103.993186 -58.072274)
			(xy 99.110038 -58.072274) (xy 99.110038 -64.797178) (xy 99.110463 -64.806895) (xy 99.117677 -64.824942)
			(xy 99.131079 -64.839016) (xy 99.139756 -64.843406) (xy 99.237546 -64.887856) (xy 99.267264 -64.883284)
			(xy 99.27844 -64.873378) (xy 99.299442 -64.855568) (xy 99.345601 -64.825544) (xy 99.395594 -64.80246)
			(xy 99.448384 -64.786795) (xy 99.502876 -64.778874) (xy 99.530408 -64.778382) (xy 99.530662 -64.778382)
			(xy 99.557917 -64.778842) (xy 99.611874 -64.786595) (xy 99.664178 -64.801948) (xy 99.713764 -64.824589)
			(xy 99.759623 -64.854057) (xy 99.800821 -64.889752) (xy 99.83652 -64.930946) (xy 99.865993 -64.976803)
			(xy 99.888638 -65.026387) (xy 99.903997 -65.078689) (xy 99.911755 -65.132645) (xy 99.911755 -65.187155)
			(xy 99.903997 -65.241111) (xy 99.888638 -65.293413) (xy 99.865993 -65.342997) (xy 99.83652 -65.388854)
			(xy 99.800821 -65.430048) (xy 99.759623 -65.465743) (xy 99.713764 -65.495211) (xy 99.664178 -65.517852)
			(xy 99.611874 -65.533205) (xy 99.557917 -65.540958) (xy 99.530662 -65.541398) (xy 99.530408 -65.541398)
			(xy 99.502875 -65.540916) (xy 99.44838 -65.533002) (xy 99.395589 -65.517337) (xy 99.345597 -65.494247)
			(xy 99.299444 -65.464211) (xy 99.27844 -65.446402) (xy 99.267264 -65.436496) (xy 99.237546 -65.431924)
			(xy 99.139756 -65.476374) (xy 99.131091 -65.480792) (xy 99.11767 -65.494847) (xy 99.11044 -65.512885)
			(xy 99.110038 -65.522602) (xy 99.110038 -67.592956) (xy 99.34524 -67.592956) (xy 99.349311 -67.537334)
			(xy 99.361437 -67.482897) (xy 99.38136 -67.430806) (xy 99.408656 -67.382171) (xy 99.442742 -67.338028)
			(xy 99.482891 -67.299319) (xy 99.528249 -67.266868) (xy 99.577849 -67.241367) (xy 99.630633 -67.22336)
			(xy 99.685476 -67.21323) (xy 99.74121 -67.211193) (xy 99.796647 -67.217293) (xy 99.850604 -67.231399)
			(xy 99.901933 -67.253211) (xy 99.949539 -67.282265) (xy 99.992407 -67.31794) (xy 100.029624 -67.359477)
			(xy 100.060397 -67.40599) (xy 100.084069 -67.456487) (xy 100.100137 -67.509894) (xy 100.108257 -67.56507)
			(xy 100.108766 -67.592956) (xy 100.108257 -67.620842) (xy 100.100137 -67.676018) (xy 100.084069 -67.729425)
			(xy 100.060397 -67.779922) (xy 100.029624 -67.826435) (xy 99.992407 -67.867972) (xy 99.949539 -67.903647)
			(xy 99.901933 -67.932701) (xy 99.850604 -67.954513) (xy 99.796647 -67.968619) (xy 99.74121 -67.974719)
			(xy 99.685476 -67.972682) (xy 99.630633 -67.962552) (xy 99.577849 -67.944545) (xy 99.528249 -67.919044)
			(xy 99.482891 -67.886593) (xy 99.442742 -67.847884) (xy 99.408656 -67.803741) (xy 99.38136 -67.755106)
			(xy 99.361437 -67.703015) (xy 99.349311 -67.648578) (xy 99.34524 -67.592956) (xy 99.110038 -67.592956)
			(xy 99.110038 -70.035928) (xy 99.110463 -70.045943) (xy 99.118139 -70.064444) (xy 99.132312 -70.078598)
			(xy 99.150823 -70.08625) (xy 99.160838 -70.086728)
		)
		(stroke
			(width 0)
			(type solid)
		)
		(fill yes)
		(layer "In9.Cu")
		(net "P12V_AUX")
	)
	(gr_poly
		(pts
			(xy 26.751026 -70.079108) (xy 26.758138 -70.071742) (xy 26.913332 -69.916548) (xy 26.920178 -69.90915)
			(xy 26.927904 -69.890551) (xy 26.928318 -69.88048) (xy 26.928318 -52.07508) (xy 26.920698 -52.056284)
			(xy 26.913332 -52.049172) (xy 26.526998 -51.662838) (xy 26.519601 -51.655988) (xy 26.501003 -51.648248)
			(xy 26.49093 -51.647852) (xy 21.190712 -51.647852) (xy 21.171916 -51.655472) (xy 21.164804 -51.662838)
			(xy 21.124672 -51.70297) (xy 21.117986 -51.710379) (xy 21.110397 -51.728815) (xy 21.10994 -51.738784)
			(xy 21.10994 -52.033932) (xy 21.110388 -52.044088) (xy 21.11825 -52.062817) (xy 21.12518 -52.070254)
			(xy 21.184616 -52.12842) (xy 21.203412 -52.135786) (xy 21.213572 -52.135532) (xy 21.222208 -52.135532)
			(xy 21.249461 -52.135995) (xy 21.303412 -52.143752) (xy 21.35571 -52.159108) (xy 21.405291 -52.18175)
			(xy 21.451144 -52.211218) (xy 21.492337 -52.246912) (xy 21.528031 -52.288104) (xy 21.557499 -52.333958)
			(xy 21.580142 -52.383538) (xy 21.595498 -52.435836) (xy 21.603255 -52.489787) (xy 21.603255 -52.544293)
			(xy 21.597057 -52.587398) (xy 24.755346 -52.587398) (xy 24.759417 -52.531776) (xy 24.771543 -52.477339)
			(xy 24.791466 -52.425248) (xy 24.818762 -52.376613) (xy 24.852848 -52.33247) (xy 24.892997 -52.293761)
			(xy 24.938355 -52.26131) (xy 24.987955 -52.235809) (xy 25.040739 -52.217802) (xy 25.095582 -52.207672)
			(xy 25.151316 -52.205635) (xy 25.206753 -52.211735) (xy 25.26071 -52.225841) (xy 25.312039 -52.247653)
			(xy 25.359645 -52.276707) (xy 25.402513 -52.312382) (xy 25.43973 -52.353919) (xy 25.470503 -52.400432)
			(xy 25.494175 -52.450929) (xy 25.510243 -52.504336) (xy 25.518363 -52.559512) (xy 25.518872 -52.587398)
			(xy 25.518363 -52.615284) (xy 25.510243 -52.67046) (xy 25.494175 -52.723867) (xy 25.470503 -52.774364)
			(xy 25.43973 -52.820877) (xy 25.402513 -52.862414) (xy 25.359645 -52.898089) (xy 25.312039 -52.927143)
			(xy 25.26071 -52.948955) (xy 25.206753 -52.963061) (xy 25.151316 -52.969161) (xy 25.095582 -52.967124)
			(xy 25.040739 -52.956994) (xy 24.987955 -52.938987) (xy 24.938355 -52.913486) (xy 24.892997 -52.881035)
			(xy 24.852848 -52.842326) (xy 24.818762 -52.798183) (xy 24.791466 -52.749548) (xy 24.771543 -52.697457)
			(xy 24.759417 -52.64302) (xy 24.755346 -52.587398) (xy 21.597057 -52.587398) (xy 21.595498 -52.598244)
			(xy 21.580142 -52.650542) (xy 21.557499 -52.700122) (xy 21.528031 -52.745976) (xy 21.492337 -52.787168)
			(xy 21.451144 -52.822862) (xy 21.405291 -52.85233) (xy 21.35571 -52.874972) (xy 21.303412 -52.890328)
			(xy 21.249461 -52.898085) (xy 21.222208 -52.898548) (xy 21.213572 -52.898548) (xy 21.203412 -52.898294)
			(xy 21.184616 -52.90566) (xy 21.12518 -52.963826) (xy 21.118276 -52.971201) (xy 21.110433 -52.989802)
			(xy 21.10994 -52.999894) (xy 21.10994 -53.96357) (xy 24.77211 -53.96357) (xy 24.776181 -53.907948)
			(xy 24.788307 -53.853511) (xy 24.80823 -53.80142) (xy 24.835526 -53.752785) (xy 24.869612 -53.708642)
			(xy 24.909761 -53.669933) (xy 24.955119 -53.637482) (xy 25.004719 -53.611981) (xy 25.057503 -53.593974)
			(xy 25.112346 -53.583844) (xy 25.16808 -53.581807) (xy 25.223517 -53.587907) (xy 25.277474 -53.602013)
			(xy 25.328803 -53.623825) (xy 25.376409 -53.652879) (xy 25.419277 -53.688554) (xy 25.456494 -53.730091)
			(xy 25.487267 -53.776604) (xy 25.510939 -53.827101) (xy 25.527007 -53.880508) (xy 25.535127 -53.935684)
			(xy 25.535636 -53.96357) (xy 25.535127 -53.991456) (xy 25.527007 -54.046632) (xy 25.510939 -54.100039)
			(xy 25.487267 -54.150536) (xy 25.456494 -54.197049) (xy 25.419277 -54.238586) (xy 25.376409 -54.274261)
			(xy 25.328803 -54.303315) (xy 25.277474 -54.325127) (xy 25.223517 -54.339233) (xy 25.16808 -54.345333)
			(xy 25.112346 -54.343296) (xy 25.057503 -54.333166) (xy 25.004719 -54.315159) (xy 24.955119 -54.289658)
			(xy 24.909761 -54.257207) (xy 24.869612 -54.218498) (xy 24.835526 -54.174355) (xy 24.80823 -54.12572)
			(xy 24.788307 -54.073629) (xy 24.776181 -54.019192) (xy 24.77211 -53.96357) (xy 21.10994 -53.96357)
			(xy 21.10994 -55.722266) (xy 25.834084 -55.722266) (xy 25.838155 -55.666644) (xy 25.850281 -55.612207)
			(xy 25.870204 -55.560116) (xy 25.8975 -55.511481) (xy 25.931586 -55.467338) (xy 25.971735 -55.428629)
			(xy 26.017093 -55.396178) (xy 26.066693 -55.370677) (xy 26.119477 -55.35267) (xy 26.17432 -55.34254)
			(xy 26.230054 -55.340503) (xy 26.285491 -55.346603) (xy 26.339448 -55.360709) (xy 26.390777 -55.382521)
			(xy 26.438383 -55.411575) (xy 26.481251 -55.44725) (xy 26.518468 -55.488787) (xy 26.549241 -55.5353)
			(xy 26.572913 -55.585797) (xy 26.588981 -55.639204) (xy 26.597101 -55.69438) (xy 26.59761 -55.722266)
			(xy 26.597101 -55.750152) (xy 26.588981 -55.805328) (xy 26.572913 -55.858735) (xy 26.549241 -55.909232)
			(xy 26.518468 -55.955745) (xy 26.481251 -55.997282) (xy 26.438383 -56.032957) (xy 26.390777 -56.062011)
			(xy 26.339448 -56.083823) (xy 26.285491 -56.097929) (xy 26.230054 -56.104029) (xy 26.17432 -56.101992)
			(xy 26.119477 -56.091862) (xy 26.066693 -56.073855) (xy 26.017093 -56.048354) (xy 25.971735 -56.015903)
			(xy 25.931586 -55.977194) (xy 25.8975 -55.933051) (xy 25.870204 -55.884416) (xy 25.850281 -55.832325)
			(xy 25.838155 -55.777888) (xy 25.834084 -55.722266) (xy 21.10994 -55.722266) (xy 21.10994 -58.072274)
			(xy 25.993596 -58.072274) (xy 25.997667 -58.016652) (xy 26.009793 -57.962215) (xy 26.029716 -57.910124)
			(xy 26.057012 -57.861489) (xy 26.091098 -57.817346) (xy 26.131247 -57.778637) (xy 26.176605 -57.746186)
			(xy 26.226205 -57.720685) (xy 26.278989 -57.702678) (xy 26.333832 -57.692548) (xy 26.389566 -57.690511)
			(xy 26.445003 -57.696611) (xy 26.49896 -57.710717) (xy 26.550289 -57.732529) (xy 26.597895 -57.761583)
			(xy 26.640763 -57.797258) (xy 26.67798 -57.838795) (xy 26.708753 -57.885308) (xy 26.732425 -57.935805)
			(xy 26.748493 -57.989212) (xy 26.756613 -58.044388) (xy 26.757122 -58.072274) (xy 26.756613 -58.10016)
			(xy 26.748493 -58.155336) (xy 26.732425 -58.208743) (xy 26.708753 -58.25924) (xy 26.67798 -58.305753)
			(xy 26.640763 -58.34729) (xy 26.597895 -58.382965) (xy 26.550289 -58.412019) (xy 26.49896 -58.433831)
			(xy 26.445003 -58.447937) (xy 26.389566 -58.454037) (xy 26.333832 -58.452) (xy 26.278989 -58.44187)
			(xy 26.226205 -58.423863) (xy 26.176605 -58.398362) (xy 26.131247 -58.365911) (xy 26.091098 -58.327202)
			(xy 26.057012 -58.283059) (xy 26.029716 -58.234424) (xy 26.009793 -58.182333) (xy 25.997667 -58.127896)
			(xy 25.993596 -58.072274) (xy 21.10994 -58.072274) (xy 21.10994 -64.797178) (xy 21.110363 -64.806928)
			(xy 21.117642 -64.825016) (xy 21.131182 -64.839045) (xy 21.139912 -64.843406) (xy 21.222208 -64.880744)
			(xy 21.232755 -64.884751) (xy 21.255284 -64.884207) (xy 21.265642 -64.879728) (xy 21.278342 -64.873378)
			(xy 21.283168 -64.869568) (xy 21.303957 -64.852435) (xy 21.34945 -64.823584) (xy 21.398555 -64.801432)
			(xy 21.450292 -64.786421) (xy 21.503629 -64.778852) (xy 21.530564 -64.778382) (xy 21.557819 -64.778842)
			(xy 21.611776 -64.786595) (xy 21.664079 -64.801949) (xy 21.713665 -64.82459) (xy 21.759524 -64.854058)
			(xy 21.800722 -64.889752) (xy 21.836421 -64.930947) (xy 21.865893 -64.976803) (xy 21.888539 -65.026387)
			(xy 21.903897 -65.078689) (xy 21.911655 -65.132645) (xy 21.911655 -65.187155) (xy 21.903897 -65.241111)
			(xy 21.888539 -65.293413) (xy 21.865893 -65.342997) (xy 21.836421 -65.388853) (xy 21.800722 -65.430048)
			(xy 21.759524 -65.465742) (xy 21.713665 -65.49521) (xy 21.664079 -65.517851) (xy 21.611776 -65.533205)
			(xy 21.557819 -65.540958) (xy 21.530564 -65.541398) (xy 21.503632 -65.540913) (xy 21.450307 -65.533304)
			(xy 21.398579 -65.518282) (xy 21.349473 -65.496146) (xy 21.303961 -65.467335) (xy 21.283168 -65.450212)
			(xy 21.278342 -65.446402) (xy 21.265642 -65.440052) (xy 21.255301 -65.435522) (xy 21.232759 -65.435012)
			(xy 21.222208 -65.439036) (xy 21.139912 -65.476374) (xy 21.131218 -65.480777) (xy 21.117726 -65.494818)
			(xy 21.110419 -65.512868) (xy 21.10994 -65.522602) (xy 21.10994 -67.592956) (xy 21.345396 -67.592956)
			(xy 21.349467 -67.537334) (xy 21.361593 -67.482897) (xy 21.381516 -67.430806) (xy 21.408812 -67.382171)
			(xy 21.442898 -67.338028) (xy 21.483047 -67.299319) (xy 21.528405 -67.266868) (xy 21.578005 -67.241367)
			(xy 21.630789 -67.22336) (xy 21.685632 -67.21323) (xy 21.741366 -67.211193) (xy 21.796803 -67.217293)
			(xy 21.85076 -67.231399) (xy 21.902089 -67.253211) (xy 21.949695 -67.282265) (xy 21.992563 -67.31794)
			(xy 22.02978 -67.359477) (xy 22.060553 -67.40599) (xy 22.084225 -67.456487) (xy 22.100293 -67.509894)
			(xy 22.108413 -67.56507) (xy 22.108922 -67.592956) (xy 22.108413 -67.620842) (xy 22.100293 -67.676018)
			(xy 22.084225 -67.729425) (xy 22.060553 -67.779922) (xy 22.02978 -67.826435) (xy 21.992563 -67.867972)
			(xy 21.949695 -67.903647) (xy 21.902089 -67.932701) (xy 21.85076 -67.954513) (xy 21.796803 -67.968619)
			(xy 21.741366 -67.974719) (xy 21.685632 -67.972682) (xy 21.630789 -67.962552) (xy 21.578005 -67.944545)
			(xy 21.528405 -67.919044) (xy 21.483047 -67.886593) (xy 21.442898 -67.847884) (xy 21.408812 -67.803741)
			(xy 21.381516 -67.755106) (xy 21.361593 -67.703015) (xy 21.349467 -67.648578) (xy 21.345396 -67.592956)
			(xy 21.10994 -67.592956) (xy 21.10994 -70.035928) (xy 21.110365 -70.045943) (xy 21.118041 -70.064443)
			(xy 21.132214 -70.078597) (xy 21.150725 -70.086248) (xy 21.16074 -70.086728) (xy 26.73223 -70.086728)
		)
		(stroke
			(width 0)
			(type solid)
		)
		(fill yes)
		(layer "In9.Cu")
		(net "P12V_AUX")
	)
	(gr_poly
		(pts
			(xy 52.750974 -70.079108) (xy 52.758086 -70.071742) (xy 52.91328 -69.916548) (xy 52.920121 -69.909148)
			(xy 52.927839 -69.890549) (xy 52.928266 -69.88048) (xy 52.928266 -52.07508) (xy 52.920646 -52.056284)
			(xy 52.91328 -52.049172) (xy 52.526946 -51.662838) (xy 52.519546 -51.655996) (xy 52.500948 -51.648275)
			(xy 52.490878 -51.647852) (xy 47.19066 -51.647852) (xy 47.171864 -51.655472) (xy 47.164752 -51.662838)
			(xy 47.12462 -51.70297) (xy 47.117929 -51.710377) (xy 47.110333 -51.728813) (xy 47.109888 -51.738784)
			(xy 47.109888 -52.033932) (xy 47.110334 -52.044089) (xy 47.11819 -52.062823) (xy 47.125128 -52.070254)
			(xy 47.184564 -52.12842) (xy 47.20336 -52.135786) (xy 47.21352 -52.135532) (xy 47.222156 -52.135532)
			(xy 47.249408 -52.135992) (xy 47.303358 -52.143743) (xy 47.355656 -52.159094) (xy 47.405236 -52.181732)
			(xy 47.45109 -52.211195) (xy 47.492284 -52.246885) (xy 47.527978 -52.288075) (xy 47.557447 -52.333925)
			(xy 47.580091 -52.383503) (xy 47.595447 -52.435799) (xy 47.603205 -52.489748) (xy 47.603205 -52.544252)
			(xy 47.597 -52.587398) (xy 50.755294 -52.587398) (xy 50.759365 -52.531776) (xy 50.771491 -52.477339)
			(xy 50.791414 -52.425248) (xy 50.81871 -52.376613) (xy 50.852796 -52.33247) (xy 50.892945 -52.293761)
			(xy 50.938303 -52.26131) (xy 50.987903 -52.235809) (xy 51.040687 -52.217802) (xy 51.09553 -52.207672)
			(xy 51.151264 -52.205635) (xy 51.206701 -52.211735) (xy 51.260658 -52.225841) (xy 51.311987 -52.247653)
			(xy 51.359593 -52.276707) (xy 51.402461 -52.312382) (xy 51.439678 -52.353919) (xy 51.470451 -52.400432)
			(xy 51.494123 -52.450929) (xy 51.510191 -52.504336) (xy 51.518311 -52.559512) (xy 51.51882 -52.587398)
			(xy 51.518311 -52.615284) (xy 51.510191 -52.67046) (xy 51.494123 -52.723867) (xy 51.470451 -52.774364)
			(xy 51.439678 -52.820877) (xy 51.402461 -52.862414) (xy 51.359593 -52.898089) (xy 51.311987 -52.927143)
			(xy 51.260658 -52.948955) (xy 51.206701 -52.963061) (xy 51.151264 -52.969161) (xy 51.09553 -52.967124)
			(xy 51.040687 -52.956994) (xy 50.987903 -52.938987) (xy 50.938303 -52.913486) (xy 50.892945 -52.881035)
			(xy 50.852796 -52.842326) (xy 50.81871 -52.798183) (xy 50.791414 -52.749548) (xy 50.771491 -52.697457)
			(xy 50.759365 -52.64302) (xy 50.755294 -52.587398) (xy 47.597 -52.587398) (xy 47.595447 -52.598201)
			(xy 47.580091 -52.650497) (xy 47.557447 -52.700075) (xy 47.527978 -52.745925) (xy 47.492284 -52.787115)
			(xy 47.45109 -52.822805) (xy 47.405236 -52.852268) (xy 47.355656 -52.874906) (xy 47.303358 -52.890257)
			(xy 47.249408 -52.898008) (xy 47.222156 -52.898548) (xy 47.21352 -52.898548) (xy 47.20336 -52.898294)
			(xy 47.184564 -52.90566) (xy 47.125128 -52.963826) (xy 47.118218 -52.971199) (xy 47.110368 -52.9898)
			(xy 47.109888 -52.999894) (xy 47.109888 -53.96357) (xy 50.772058 -53.96357) (xy 50.776129 -53.907948)
			(xy 50.788255 -53.853511) (xy 50.808178 -53.80142) (xy 50.835474 -53.752785) (xy 50.86956 -53.708642)
			(xy 50.909709 -53.669933) (xy 50.955067 -53.637482) (xy 51.004667 -53.611981) (xy 51.057451 -53.593974)
			(xy 51.112294 -53.583844) (xy 51.168028 -53.581807) (xy 51.223465 -53.587907) (xy 51.277422 -53.602013)
			(xy 51.328751 -53.623825) (xy 51.376357 -53.652879) (xy 51.419225 -53.688554) (xy 51.456442 -53.730091)
			(xy 51.487215 -53.776604) (xy 51.510887 -53.827101) (xy 51.526955 -53.880508) (xy 51.535075 -53.935684)
			(xy 51.535584 -53.96357) (xy 51.535075 -53.991456) (xy 51.526955 -54.046632) (xy 51.510887 -54.100039)
			(xy 51.487215 -54.150536) (xy 51.456442 -54.197049) (xy 51.419225 -54.238586) (xy 51.376357 -54.274261)
			(xy 51.328751 -54.303315) (xy 51.277422 -54.325127) (xy 51.223465 -54.339233) (xy 51.168028 -54.345333)
			(xy 51.112294 -54.343296) (xy 51.057451 -54.333166) (xy 51.004667 -54.315159) (xy 50.955067 -54.289658)
			(xy 50.909709 -54.257207) (xy 50.86956 -54.218498) (xy 50.835474 -54.174355) (xy 50.808178 -54.12572)
			(xy 50.788255 -54.073629) (xy 50.776129 -54.019192) (xy 50.772058 -53.96357) (xy 47.109888 -53.96357)
			(xy 47.109888 -55.722266) (xy 51.834032 -55.722266) (xy 51.838103 -55.666644) (xy 51.850229 -55.612207)
			(xy 51.870152 -55.560116) (xy 51.897448 -55.511481) (xy 51.931534 -55.467338) (xy 51.971683 -55.428629)
			(xy 52.017041 -55.396178) (xy 52.066641 -55.370677) (xy 52.119425 -55.35267) (xy 52.174268 -55.34254)
			(xy 52.230002 -55.340503) (xy 52.285439 -55.346603) (xy 52.339396 -55.360709) (xy 52.390725 -55.382521)
			(xy 52.438331 -55.411575) (xy 52.481199 -55.44725) (xy 52.518416 -55.488787) (xy 52.549189 -55.5353)
			(xy 52.572861 -55.585797) (xy 52.588929 -55.639204) (xy 52.597049 -55.69438) (xy 52.597558 -55.722266)
			(xy 52.597049 -55.750152) (xy 52.588929 -55.805328) (xy 52.572861 -55.858735) (xy 52.549189 -55.909232)
			(xy 52.518416 -55.955745) (xy 52.481199 -55.997282) (xy 52.438331 -56.032957) (xy 52.390725 -56.062011)
			(xy 52.339396 -56.083823) (xy 52.285439 -56.097929) (xy 52.230002 -56.104029) (xy 52.174268 -56.101992)
			(xy 52.119425 -56.091862) (xy 52.066641 -56.073855) (xy 52.017041 -56.048354) (xy 51.971683 -56.015903)
			(xy 51.931534 -55.977194) (xy 51.897448 -55.933051) (xy 51.870152 -55.884416) (xy 51.850229 -55.832325)
			(xy 51.838103 -55.777888) (xy 51.834032 -55.722266) (xy 47.109888 -55.722266) (xy 47.109888 -58.072274)
			(xy 51.993544 -58.072274) (xy 51.997615 -58.016652) (xy 52.009741 -57.962215) (xy 52.029664 -57.910124)
			(xy 52.05696 -57.861489) (xy 52.091046 -57.817346) (xy 52.131195 -57.778637) (xy 52.176553 -57.746186)
			(xy 52.226153 -57.720685) (xy 52.278937 -57.702678) (xy 52.33378 -57.692548) (xy 52.389514 -57.690511)
			(xy 52.444951 -57.696611) (xy 52.498908 -57.710717) (xy 52.550237 -57.732529) (xy 52.597843 -57.761583)
			(xy 52.640711 -57.797258) (xy 52.677928 -57.838795) (xy 52.708701 -57.885308) (xy 52.732373 -57.935805)
			(xy 52.748441 -57.989212) (xy 52.756561 -58.044388) (xy 52.75707 -58.072274) (xy 52.756561 -58.10016)
			(xy 52.748441 -58.155336) (xy 52.732373 -58.208743) (xy 52.708701 -58.25924) (xy 52.677928 -58.305753)
			(xy 52.640711 -58.34729) (xy 52.597843 -58.382965) (xy 52.550237 -58.412019) (xy 52.498908 -58.433831)
			(xy 52.444951 -58.447937) (xy 52.389514 -58.454037) (xy 52.33378 -58.452) (xy 52.278937 -58.44187)
			(xy 52.226153 -58.423863) (xy 52.176553 -58.398362) (xy 52.131195 -58.365911) (xy 52.091046 -58.327202)
			(xy 52.05696 -58.283059) (xy 52.029664 -58.234424) (xy 52.009741 -58.182333) (xy 51.997615 -58.127896)
			(xy 51.993544 -58.072274) (xy 47.109888 -58.072274) (xy 47.109888 -64.797178) (xy 47.11031 -64.80693)
			(xy 47.117585 -64.825024) (xy 47.131119 -64.839065) (xy 47.13986 -64.843406) (xy 47.222156 -64.880744)
			(xy 47.232704 -64.884762) (xy 47.255243 -64.884239) (xy 47.26559 -64.879728) (xy 47.27829 -64.873378)
			(xy 47.283116 -64.869568) (xy 47.303904 -64.852432) (xy 47.349396 -64.823575) (xy 47.398501 -64.801416)
			(xy 47.450238 -64.786399) (xy 47.503575 -64.778822) (xy 47.530512 -64.778382) (xy 47.557763 -64.778869)
			(xy 47.611711 -64.786627) (xy 47.664006 -64.801983) (xy 47.713583 -64.824626) (xy 47.759433 -64.854093)
			(xy 47.800623 -64.889786) (xy 47.836314 -64.930977) (xy 47.86578 -64.976828) (xy 47.888421 -65.026405)
			(xy 47.903776 -65.0787) (xy 47.911532 -65.132649) (xy 47.911532 -65.187151) (xy 47.903776 -65.2411)
			(xy 47.888421 -65.293395) (xy 47.86578 -65.342972) (xy 47.836314 -65.388823) (xy 47.800623 -65.430014)
			(xy 47.759433 -65.465707) (xy 47.713583 -65.495174) (xy 47.664006 -65.517817) (xy 47.611711 -65.533173)
			(xy 47.557763 -65.540931) (xy 47.530512 -65.541398) (xy 47.503581 -65.54091) (xy 47.45026 -65.533293)
			(xy 47.398536 -65.518266) (xy 47.349435 -65.496126) (xy 47.303928 -65.467311) (xy 47.283116 -65.450212)
			(xy 47.27829 -65.446402) (xy 47.26559 -65.440052) (xy 47.255248 -65.435511) (xy 47.232698 -65.434982)
			(xy 47.222156 -65.439036) (xy 47.13986 -65.476374) (xy 47.131172 -65.480782) (xy 47.117695 -65.494826)
			(xy 47.110396 -65.512871) (xy 47.109888 -65.522602) (xy 47.109888 -67.592956) (xy 47.345344 -67.592956)
			(xy 47.349415 -67.537334) (xy 47.361541 -67.482897) (xy 47.381464 -67.430806) (xy 47.40876 -67.382171)
			(xy 47.442846 -67.338028) (xy 47.482995 -67.299319) (xy 47.528353 -67.266868) (xy 47.577953 -67.241367)
			(xy 47.630737 -67.22336) (xy 47.68558 -67.21323) (xy 47.741314 -67.211193) (xy 47.796751 -67.217293)
			(xy 47.850708 -67.231399) (xy 47.902037 -67.253211) (xy 47.949643 -67.282265) (xy 47.992511 -67.31794)
			(xy 48.029728 -67.359477) (xy 48.060501 -67.40599) (xy 48.084173 -67.456487) (xy 48.100241 -67.509894)
			(xy 48.108361 -67.56507) (xy 48.10887 -67.592956) (xy 48.108361 -67.620842) (xy 48.100241 -67.676018)
			(xy 48.084173 -67.729425) (xy 48.060501 -67.779922) (xy 48.029728 -67.826435) (xy 47.992511 -67.867972)
			(xy 47.949643 -67.903647) (xy 47.902037 -67.932701) (xy 47.850708 -67.954513) (xy 47.796751 -67.968619)
			(xy 47.741314 -67.974719) (xy 47.68558 -67.972682) (xy 47.630737 -67.962552) (xy 47.577953 -67.944545)
			(xy 47.528353 -67.919044) (xy 47.482995 -67.886593) (xy 47.442846 -67.847884) (xy 47.40876 -67.803741)
			(xy 47.381464 -67.755106) (xy 47.361541 -67.703015) (xy 47.349415 -67.648578) (xy 47.345344 -67.592956)
			(xy 47.109888 -67.592956) (xy 47.109888 -70.035928) (xy 47.110381 -70.045933) (xy 47.118045 -70.064417)
			(xy 47.132196 -70.078564) (xy 47.150683 -70.086222) (xy 47.160688 -70.086728) (xy 52.732178 -70.086728)
		)
		(stroke
			(width 0)
			(type solid)
		)
		(fill yes)
		(layer "In9.Cu")
		(net "P12V_AUX")
	)
	(gr_poly
		(pts
			(xy 78.750922 -70.079108) (xy 78.758034 -70.071742) (xy 78.913228 -69.916548) (xy 78.920074 -69.90915)
			(xy 78.927801 -69.890551) (xy 78.928214 -69.88048) (xy 78.928214 -52.07508) (xy 78.920594 -52.056284)
			(xy 78.913228 -52.049172) (xy 78.526894 -51.662838) (xy 78.519497 -51.655988) (xy 78.500899 -51.64825)
			(xy 78.490826 -51.647852) (xy 73.190608 -51.647852) (xy 73.171812 -51.655472) (xy 73.1647 -51.662838)
			(xy 73.124568 -51.70297) (xy 73.117882 -51.710379) (xy 73.110294 -51.728815) (xy 73.109836 -51.738784)
			(xy 73.109836 -52.033932) (xy 73.110284 -52.044088) (xy 73.118145 -52.062817) (xy 73.125076 -52.070254)
			(xy 73.184512 -52.12842) (xy 73.203308 -52.135786) (xy 73.213468 -52.135532) (xy 73.222104 -52.135532)
			(xy 73.249352 -52.136018) (xy 73.303294 -52.143775) (xy 73.355582 -52.159128) (xy 73.405154 -52.181767)
			(xy 73.450999 -52.211231) (xy 73.492184 -52.246918) (xy 73.527872 -52.288104) (xy 73.557334 -52.33395)
			(xy 73.579973 -52.383521) (xy 73.595326 -52.43581) (xy 73.603082 -52.489752) (xy 73.603082 -52.544248)
			(xy 73.596878 -52.587398) (xy 76.755242 -52.587398) (xy 76.759313 -52.531776) (xy 76.771439 -52.477339)
			(xy 76.791362 -52.425248) (xy 76.818658 -52.376613) (xy 76.852744 -52.33247) (xy 76.892893 -52.293761)
			(xy 76.938251 -52.26131) (xy 76.987851 -52.235809) (xy 77.040635 -52.217802) (xy 77.095478 -52.207672)
			(xy 77.151212 -52.205635) (xy 77.206649 -52.211735) (xy 77.260606 -52.225841) (xy 77.311935 -52.247653)
			(xy 77.359541 -52.276707) (xy 77.402409 -52.312382) (xy 77.439626 -52.353919) (xy 77.470399 -52.400432)
			(xy 77.494071 -52.450929) (xy 77.510139 -52.504336) (xy 77.518259 -52.559512) (xy 77.518768 -52.587398)
			(xy 77.518259 -52.615284) (xy 77.510139 -52.67046) (xy 77.494071 -52.723867) (xy 77.470399 -52.774364)
			(xy 77.439626 -52.820877) (xy 77.402409 -52.862414) (xy 77.359541 -52.898089) (xy 77.311935 -52.927143)
			(xy 77.260606 -52.948955) (xy 77.206649 -52.963061) (xy 77.151212 -52.969161) (xy 77.095478 -52.967124)
			(xy 77.040635 -52.956994) (xy 76.987851 -52.938987) (xy 76.938251 -52.913486) (xy 76.892893 -52.881035)
			(xy 76.852744 -52.842326) (xy 76.818658 -52.798183) (xy 76.791362 -52.749548) (xy 76.771439 -52.697457)
			(xy 76.759313 -52.64302) (xy 76.755242 -52.587398) (xy 73.596878 -52.587398) (xy 73.595326 -52.59819)
			(xy 73.579973 -52.650479) (xy 73.557334 -52.70005) (xy 73.527872 -52.745896) (xy 73.492184 -52.787082)
			(xy 73.450999 -52.822769) (xy 73.405154 -52.852233) (xy 73.355582 -52.874872) (xy 73.303294 -52.890225)
			(xy 73.249352 -52.897982) (xy 73.222104 -52.898548) (xy 73.213468 -52.898548) (xy 73.203308 -52.898294)
			(xy 73.184512 -52.90566) (xy 73.125076 -52.963826) (xy 73.118172 -52.971202) (xy 73.11033 -52.989802)
			(xy 73.109836 -52.999894) (xy 73.109836 -53.96357) (xy 76.772006 -53.96357) (xy 76.776077 -53.907948)
			(xy 76.788203 -53.853511) (xy 76.808126 -53.80142) (xy 76.835422 -53.752785) (xy 76.869508 -53.708642)
			(xy 76.909657 -53.669933) (xy 76.955015 -53.637482) (xy 77.004615 -53.611981) (xy 77.057399 -53.593974)
			(xy 77.112242 -53.583844) (xy 77.167976 -53.581807) (xy 77.223413 -53.587907) (xy 77.27737 -53.602013)
			(xy 77.328699 -53.623825) (xy 77.376305 -53.652879) (xy 77.419173 -53.688554) (xy 77.45639 -53.730091)
			(xy 77.487163 -53.776604) (xy 77.510835 -53.827101) (xy 77.526903 -53.880508) (xy 77.535023 -53.935684)
			(xy 77.535532 -53.96357) (xy 77.535023 -53.991456) (xy 77.526903 -54.046632) (xy 77.510835 -54.100039)
			(xy 77.487163 -54.150536) (xy 77.45639 -54.197049) (xy 77.419173 -54.238586) (xy 77.376305 -54.274261)
			(xy 77.328699 -54.303315) (xy 77.27737 -54.325127) (xy 77.223413 -54.339233) (xy 77.167976 -54.345333)
			(xy 77.112242 -54.343296) (xy 77.057399 -54.333166) (xy 77.004615 -54.315159) (xy 76.955015 -54.289658)
			(xy 76.909657 -54.257207) (xy 76.869508 -54.218498) (xy 76.835422 -54.174355) (xy 76.808126 -54.12572)
			(xy 76.788203 -54.073629) (xy 76.776077 -54.019192) (xy 76.772006 -53.96357) (xy 73.109836 -53.96357)
			(xy 73.109836 -55.722266) (xy 77.83398 -55.722266) (xy 77.838051 -55.666644) (xy 77.850177 -55.612207)
			(xy 77.8701 -55.560116) (xy 77.897396 -55.511481) (xy 77.931482 -55.467338) (xy 77.971631 -55.428629)
			(xy 78.016989 -55.396178) (xy 78.066589 -55.370677) (xy 78.119373 -55.35267) (xy 78.174216 -55.34254)
			(xy 78.22995 -55.340503) (xy 78.285387 -55.346603) (xy 78.339344 -55.360709) (xy 78.390673 -55.382521)
			(xy 78.438279 -55.411575) (xy 78.481147 -55.44725) (xy 78.518364 -55.488787) (xy 78.549137 -55.5353)
			(xy 78.572809 -55.585797) (xy 78.588877 -55.639204) (xy 78.596997 -55.69438) (xy 78.597506 -55.722266)
			(xy 78.596997 -55.750152) (xy 78.588877 -55.805328) (xy 78.572809 -55.858735) (xy 78.549137 -55.909232)
			(xy 78.518364 -55.955745) (xy 78.481147 -55.997282) (xy 78.438279 -56.032957) (xy 78.390673 -56.062011)
			(xy 78.339344 -56.083823) (xy 78.285387 -56.097929) (xy 78.22995 -56.104029) (xy 78.174216 -56.101992)
			(xy 78.119373 -56.091862) (xy 78.066589 -56.073855) (xy 78.016989 -56.048354) (xy 77.971631 -56.015903)
			(xy 77.931482 -55.977194) (xy 77.897396 -55.933051) (xy 77.8701 -55.884416) (xy 77.850177 -55.832325)
			(xy 77.838051 -55.777888) (xy 77.83398 -55.722266) (xy 73.109836 -55.722266) (xy 73.109836 -58.072274)
			(xy 77.993492 -58.072274) (xy 77.997563 -58.016652) (xy 78.009689 -57.962215) (xy 78.029612 -57.910124)
			(xy 78.056908 -57.861489) (xy 78.090994 -57.817346) (xy 78.131143 -57.778637) (xy 78.176501 -57.746186)
			(xy 78.226101 -57.720685) (xy 78.278885 -57.702678) (xy 78.333728 -57.692548) (xy 78.389462 -57.690511)
			(xy 78.444899 -57.696611) (xy 78.498856 -57.710717) (xy 78.550185 -57.732529) (xy 78.597791 -57.761583)
			(xy 78.640659 -57.797258) (xy 78.677876 -57.838795) (xy 78.708649 -57.885308) (xy 78.732321 -57.935805)
			(xy 78.748389 -57.989212) (xy 78.756509 -58.044388) (xy 78.757018 -58.072274) (xy 78.756509 -58.10016)
			(xy 78.748389 -58.155336) (xy 78.732321 -58.208743) (xy 78.708649 -58.25924) (xy 78.677876 -58.305753)
			(xy 78.640659 -58.34729) (xy 78.597791 -58.382965) (xy 78.550185 -58.412019) (xy 78.498856 -58.433831)
			(xy 78.444899 -58.447937) (xy 78.389462 -58.454037) (xy 78.333728 -58.452) (xy 78.278885 -58.44187)
			(xy 78.226101 -58.423863) (xy 78.176501 -58.398362) (xy 78.131143 -58.365911) (xy 78.090994 -58.327202)
			(xy 78.056908 -58.283059) (xy 78.029612 -58.234424) (xy 78.009689 -58.182333) (xy 77.997563 -58.127896)
			(xy 77.993492 -58.072274) (xy 73.109836 -58.072274) (xy 73.109836 -64.797178) (xy 73.110259 -64.806928)
			(xy 73.117538 -64.825016) (xy 73.131077 -64.839047) (xy 73.139808 -64.843406) (xy 73.222104 -64.880744)
			(xy 73.232651 -64.884752) (xy 73.255181 -64.884209) (xy 73.265538 -64.879728) (xy 73.278238 -64.873378)
			(xy 73.283064 -64.869568) (xy 73.303853 -64.852435) (xy 73.349346 -64.823583) (xy 73.398451 -64.801431)
			(xy 73.450188 -64.78642) (xy 73.503524 -64.77885) (xy 73.53046 -64.778382) (xy 73.557715 -64.778842)
			(xy 73.611672 -64.786595) (xy 73.663976 -64.801948) (xy 73.713563 -64.824589) (xy 73.759422 -64.854056)
			(xy 73.800621 -64.889751) (xy 73.83632 -64.930946) (xy 73.865792 -64.976802) (xy 73.888438 -65.026386)
			(xy 73.903797 -65.078689) (xy 73.911555 -65.132645) (xy 73.911555 -65.187155) (xy 73.903797 -65.241111)
			(xy 73.888438 -65.293414) (xy 73.865792 -65.342998) (xy 73.83632 -65.388854) (xy 73.800621 -65.430049)
			(xy 73.759422 -65.465744) (xy 73.713563 -65.495211) (xy 73.663976 -65.517852) (xy 73.611672 -65.533205)
			(xy 73.557715 -65.540958) (xy 73.53046 -65.541398) (xy 73.503528 -65.540913) (xy 73.450204 -65.533303)
			(xy 73.398476 -65.518281) (xy 73.34937 -65.496145) (xy 73.303858 -65.467333) (xy 73.283064 -65.450212)
			(xy 73.278238 -65.446402) (xy 73.265538 -65.440052) (xy 73.255197 -65.435523) (xy 73.232656 -65.435014)
			(xy 73.222104 -65.439036) (xy 73.139808 -65.476374) (xy 73.131114 -65.480778) (xy 73.117624 -65.494819)
			(xy 73.110317 -65.512868) (xy 73.109836 -65.522602) (xy 73.109836 -67.592956) (xy 73.345292 -67.592956)
			(xy 73.349363 -67.537334) (xy 73.361489 -67.482897) (xy 73.381412 -67.430806) (xy 73.408708 -67.382171)
			(xy 73.442794 -67.338028) (xy 73.482943 -67.299319) (xy 73.528301 -67.266868) (xy 73.577901 -67.241367)
			(xy 73.630685 -67.22336) (xy 73.685528 -67.21323) (xy 73.741262 -67.211193) (xy 73.796699 -67.217293)
			(xy 73.850656 -67.231399) (xy 73.901985 -67.253211) (xy 73.949591 -67.282265) (xy 73.992459 -67.31794)
			(xy 74.029676 -67.359477) (xy 74.060449 -67.40599) (xy 74.084121 -67.456487) (xy 74.100189 -67.509894)
			(xy 74.108309 -67.56507) (xy 74.108818 -67.592956) (xy 74.108309 -67.620842) (xy 74.100189 -67.676018)
			(xy 74.084121 -67.729425) (xy 74.060449 -67.779922) (xy 74.029676 -67.826435) (xy 73.992459 -67.867972)
			(xy 73.949591 -67.903647) (xy 73.901985 -67.932701) (xy 73.850656 -67.954513) (xy 73.796699 -67.968619)
			(xy 73.741262 -67.974719) (xy 73.685528 -67.972682) (xy 73.630685 -67.962552) (xy 73.577901 -67.944545)
			(xy 73.528301 -67.919044) (xy 73.482943 -67.886593) (xy 73.442794 -67.847884) (xy 73.408708 -67.803741)
			(xy 73.381412 -67.755106) (xy 73.361489 -67.703015) (xy 73.349363 -67.648578) (xy 73.345292 -67.592956)
			(xy 73.109836 -67.592956) (xy 73.109836 -70.035928) (xy 73.110261 -70.045943) (xy 73.117937 -70.064444)
			(xy 73.13211 -70.078599) (xy 73.15062 -70.086252) (xy 73.160636 -70.086728) (xy 78.732126 -70.086728)
		)
		(stroke
			(width 0)
			(type solid)
		)
		(fill yes)
		(layer "In9.Cu")
		(net "P12V_AUX")
	)
	(gr_poly
		(pts
			(xy 142.851124 -70.079108) (xy 142.858236 -70.071742) (xy 143.01343 -69.916548) (xy 143.020276 -69.90915)
			(xy 143.028003 -69.890551) (xy 143.028416 -69.88048) (xy 143.028416 -52.07508) (xy 143.020796 -52.056284)
			(xy 143.01343 -52.049172) (xy 142.627096 -51.662838) (xy 142.619699 -51.655988) (xy 142.601101 -51.648249)
			(xy 142.591028 -51.647852) (xy 137.29081 -51.647852) (xy 137.272014 -51.655472) (xy 137.264902 -51.662838)
			(xy 137.22477 -51.70297) (xy 137.218084 -51.710379) (xy 137.210496 -51.728815) (xy 137.210038 -51.738784)
			(xy 137.210038 -52.033932) (xy 137.210486 -52.044088) (xy 137.218347 -52.062817) (xy 137.225278 -52.070254)
			(xy 137.284714 -52.12842) (xy 137.30351 -52.135786) (xy 137.31367 -52.135532) (xy 137.322306 -52.135532)
			(xy 137.349554 -52.136019) (xy 137.403495 -52.143775) (xy 137.455784 -52.159129) (xy 137.505355 -52.181768)
			(xy 137.5512 -52.211231) (xy 137.592385 -52.246919) (xy 137.628072 -52.288105) (xy 137.657535 -52.33395)
			(xy 137.680173 -52.383522) (xy 137.695526 -52.43581) (xy 137.703282 -52.489752) (xy 137.703282 -52.544248)
			(xy 137.697078 -52.587398) (xy 140.855444 -52.587398) (xy 140.859515 -52.531776) (xy 140.871641 -52.477339)
			(xy 140.891564 -52.425248) (xy 140.91886 -52.376613) (xy 140.952946 -52.33247) (xy 140.993095 -52.293761)
			(xy 141.038453 -52.26131) (xy 141.088053 -52.235809) (xy 141.140837 -52.217802) (xy 141.19568 -52.207672)
			(xy 141.251414 -52.205635) (xy 141.306851 -52.211735) (xy 141.360808 -52.225841) (xy 141.412137 -52.247653)
			(xy 141.459743 -52.276707) (xy 141.502611 -52.312382) (xy 141.539828 -52.353919) (xy 141.570601 -52.400432)
			(xy 141.594273 -52.450929) (xy 141.610341 -52.504336) (xy 141.618461 -52.559512) (xy 141.61897 -52.587398)
			(xy 141.618461 -52.615284) (xy 141.610341 -52.67046) (xy 141.594273 -52.723867) (xy 141.570601 -52.774364)
			(xy 141.539828 -52.820877) (xy 141.502611 -52.862414) (xy 141.459743 -52.898089) (xy 141.412137 -52.927143)
			(xy 141.360808 -52.948955) (xy 141.306851 -52.963061) (xy 141.251414 -52.969161) (xy 141.19568 -52.967124)
			(xy 141.140837 -52.956994) (xy 141.088053 -52.938987) (xy 141.038453 -52.913486) (xy 140.993095 -52.881035)
			(xy 140.952946 -52.842326) (xy 140.91886 -52.798183) (xy 140.891564 -52.749548) (xy 140.871641 -52.697457)
			(xy 140.859515 -52.64302) (xy 140.855444 -52.587398) (xy 137.697078 -52.587398) (xy 137.695526 -52.59819)
			(xy 137.680173 -52.650478) (xy 137.657535 -52.70005) (xy 137.628072 -52.745895) (xy 137.592385 -52.787081)
			(xy 137.5512 -52.822769) (xy 137.505355 -52.852232) (xy 137.455784 -52.874871) (xy 137.403495 -52.890225)
			(xy 137.349554 -52.897981) (xy 137.322306 -52.898548) (xy 137.31367 -52.898548) (xy 137.30351 -52.898294)
			(xy 137.284714 -52.90566) (xy 137.225278 -52.963826) (xy 137.218374 -52.971201) (xy 137.210532 -52.989802)
			(xy 137.210038 -52.999894) (xy 137.210038 -53.96357) (xy 140.872208 -53.96357) (xy 140.876279 -53.907948)
			(xy 140.888405 -53.853511) (xy 140.908328 -53.80142) (xy 140.935624 -53.752785) (xy 140.96971 -53.708642)
			(xy 141.009859 -53.669933) (xy 141.055217 -53.637482) (xy 141.104817 -53.611981) (xy 141.157601 -53.593974)
			(xy 141.212444 -53.583844) (xy 141.268178 -53.581807) (xy 141.323615 -53.587907) (xy 141.377572 -53.602013)
			(xy 141.428901 -53.623825) (xy 141.476507 -53.652879) (xy 141.519375 -53.688554) (xy 141.556592 -53.730091)
			(xy 141.587365 -53.776604) (xy 141.611037 -53.827101) (xy 141.627105 -53.880508) (xy 141.635225 -53.935684)
			(xy 141.635734 -53.96357) (xy 141.635225 -53.991456) (xy 141.627105 -54.046632) (xy 141.611037 -54.100039)
			(xy 141.587365 -54.150536) (xy 141.556592 -54.197049) (xy 141.519375 -54.238586) (xy 141.476507 -54.274261)
			(xy 141.428901 -54.303315) (xy 141.377572 -54.325127) (xy 141.323615 -54.339233) (xy 141.268178 -54.345333)
			(xy 141.212444 -54.343296) (xy 141.157601 -54.333166) (xy 141.104817 -54.315159) (xy 141.055217 -54.289658)
			(xy 141.009859 -54.257207) (xy 140.96971 -54.218498) (xy 140.935624 -54.174355) (xy 140.908328 -54.12572)
			(xy 140.888405 -54.073629) (xy 140.876279 -54.019192) (xy 140.872208 -53.96357) (xy 137.210038 -53.96357)
			(xy 137.210038 -55.722266) (xy 141.934182 -55.722266) (xy 141.938253 -55.666644) (xy 141.950379 -55.612207)
			(xy 141.970302 -55.560116) (xy 141.997598 -55.511481) (xy 142.031684 -55.467338) (xy 142.071833 -55.428629)
			(xy 142.117191 -55.396178) (xy 142.166791 -55.370677) (xy 142.219575 -55.35267) (xy 142.274418 -55.34254)
			(xy 142.330152 -55.340503) (xy 142.385589 -55.346603) (xy 142.439546 -55.360709) (xy 142.490875 -55.382521)
			(xy 142.538481 -55.411575) (xy 142.581349 -55.44725) (xy 142.618566 -55.488787) (xy 142.649339 -55.5353)
			(xy 142.673011 -55.585797) (xy 142.689079 -55.639204) (xy 142.697199 -55.69438) (xy 142.697708 -55.722266)
			(xy 142.697199 -55.750152) (xy 142.689079 -55.805328) (xy 142.673011 -55.858735) (xy 142.649339 -55.909232)
			(xy 142.618566 -55.955745) (xy 142.581349 -55.997282) (xy 142.538481 -56.032957) (xy 142.490875 -56.062011)
			(xy 142.439546 -56.083823) (xy 142.385589 -56.097929) (xy 142.330152 -56.104029) (xy 142.274418 -56.101992)
			(xy 142.219575 -56.091862) (xy 142.166791 -56.073855) (xy 142.117191 -56.048354) (xy 142.071833 -56.015903)
			(xy 142.031684 -55.977194) (xy 141.997598 -55.933051) (xy 141.970302 -55.884416) (xy 141.950379 -55.832325)
			(xy 141.938253 -55.777888) (xy 141.934182 -55.722266) (xy 137.210038 -55.722266) (xy 137.210038 -58.072274)
			(xy 142.093694 -58.072274) (xy 142.097765 -58.016652) (xy 142.109891 -57.962215) (xy 142.129814 -57.910124)
			(xy 142.15711 -57.861489) (xy 142.191196 -57.817346) (xy 142.231345 -57.778637) (xy 142.276703 -57.746186)
			(xy 142.326303 -57.720685) (xy 142.379087 -57.702678) (xy 142.43393 -57.692548) (xy 142.489664 -57.690511)
			(xy 142.545101 -57.696611) (xy 142.599058 -57.710717) (xy 142.650387 -57.732529) (xy 142.697993 -57.761583)
			(xy 142.740861 -57.797258) (xy 142.778078 -57.838795) (xy 142.808851 -57.885308) (xy 142.832523 -57.935805)
			(xy 142.848591 -57.989212) (xy 142.856711 -58.044388) (xy 142.85722 -58.072274) (xy 142.856711 -58.10016)
			(xy 142.848591 -58.155336) (xy 142.832523 -58.208743) (xy 142.808851 -58.25924) (xy 142.778078 -58.305753)
			(xy 142.740861 -58.34729) (xy 142.697993 -58.382965) (xy 142.650387 -58.412019) (xy 142.599058 -58.433831)
			(xy 142.545101 -58.447937) (xy 142.489664 -58.454037) (xy 142.43393 -58.452) (xy 142.379087 -58.44187)
			(xy 142.326303 -58.423863) (xy 142.276703 -58.398362) (xy 142.231345 -58.365911) (xy 142.191196 -58.327202)
			(xy 142.15711 -58.283059) (xy 142.129814 -58.234424) (xy 142.109891 -58.182333) (xy 142.097765 -58.127896)
			(xy 142.093694 -58.072274) (xy 137.210038 -58.072274) (xy 137.210038 -64.797178) (xy 137.210461 -64.806928)
			(xy 137.21774 -64.825016) (xy 137.231279 -64.839046) (xy 137.24001 -64.843406) (xy 137.322306 -64.880744)
			(xy 137.332853 -64.884752) (xy 137.355382 -64.884208) (xy 137.36574 -64.879728) (xy 137.37844 -64.873378)
			(xy 137.383266 -64.869568) (xy 137.404055 -64.852435) (xy 137.449548 -64.823583) (xy 137.498653 -64.801431)
			(xy 137.55039 -64.786421) (xy 137.603727 -64.778851) (xy 137.630662 -64.778382) (xy 137.657917 -64.778842)
			(xy 137.711874 -64.786595) (xy 137.764178 -64.801948) (xy 137.813764 -64.824589) (xy 137.859623 -64.854057)
			(xy 137.900821 -64.889752) (xy 137.93652 -64.930946) (xy 137.965993 -64.976803) (xy 137.988638 -65.026387)
			(xy 138.003997 -65.078689) (xy 138.011755 -65.132645) (xy 138.011755 -65.187155) (xy 138.003997 -65.241111)
			(xy 137.988638 -65.293413) (xy 137.965993 -65.342997) (xy 137.93652 -65.388854) (xy 137.900821 -65.430048)
			(xy 137.859623 -65.465743) (xy 137.813764 -65.495211) (xy 137.764178 -65.517852) (xy 137.711874 -65.533205)
			(xy 137.657917 -65.540958) (xy 137.630662 -65.541398) (xy 137.60373 -65.540913) (xy 137.550405 -65.533303)
			(xy 137.498678 -65.518281) (xy 137.449571 -65.496146) (xy 137.40406 -65.467334) (xy 137.383266 -65.450212)
			(xy 137.37844 -65.446402) (xy 137.36574 -65.440052) (xy 137.355399 -65.435522) (xy 137.332857 -65.435013)
			(xy 137.322306 -65.439036) (xy 137.24001 -65.476374) (xy 137.231316 -65.480777) (xy 137.217825 -65.494818)
			(xy 137.210518 -65.512868) (xy 137.210038 -65.522602) (xy 137.210038 -67.592956) (xy 137.445494 -67.592956)
			(xy 137.449565 -67.537334) (xy 137.461691 -67.482897) (xy 137.481614 -67.430806) (xy 137.50891 -67.382171)
			(xy 137.542996 -67.338028) (xy 137.583145 -67.299319) (xy 137.628503 -67.266868) (xy 137.678103 -67.241367)
			(xy 137.730887 -67.22336) (xy 137.78573 -67.21323) (xy 137.841464 -67.211193) (xy 137.896901 -67.217293)
			(xy 137.950858 -67.231399) (xy 138.002187 -67.253211) (xy 138.049793 -67.282265) (xy 138.092661 -67.31794)
			(xy 138.129878 -67.359477) (xy 138.160651 -67.40599) (xy 138.184323 -67.456487) (xy 138.200391 -67.509894)
			(xy 138.208511 -67.56507) (xy 138.20902 -67.592956) (xy 138.208511 -67.620842) (xy 138.200391 -67.676018)
			(xy 138.184323 -67.729425) (xy 138.160651 -67.779922) (xy 138.129878 -67.826435) (xy 138.092661 -67.867972)
			(xy 138.049793 -67.903647) (xy 138.002187 -67.932701) (xy 137.950858 -67.954513) (xy 137.896901 -67.968619)
			(xy 137.841464 -67.974719) (xy 137.78573 -67.972682) (xy 137.730887 -67.962552) (xy 137.678103 -67.944545)
			(xy 137.628503 -67.919044) (xy 137.583145 -67.886593) (xy 137.542996 -67.847884) (xy 137.50891 -67.803741)
			(xy 137.481614 -67.755106) (xy 137.461691 -67.703015) (xy 137.449565 -67.648578) (xy 137.445494 -67.592956)
			(xy 137.210038 -67.592956) (xy 137.210038 -70.035928) (xy 137.210463 -70.045943) (xy 137.218139 -70.064444)
			(xy 137.232312 -70.078598) (xy 137.250823 -70.08625) (xy 137.260838 -70.086728) (xy 142.832328 -70.086728)
		)
		(stroke
			(width 0)
			(type solid)
		)
		(fill yes)
		(layer "In9.Cu")
		(net "P12V_AUX")
	)
	(gr_poly
		(pts
			(xy 168.851072 -70.079108) (xy 168.858184 -70.071742) (xy 169.013378 -69.916548) (xy 169.020218 -69.909148)
			(xy 169.027937 -69.890549) (xy 169.028364 -69.88048) (xy 169.028364 -52.07508) (xy 169.020744 -52.056284)
			(xy 169.013378 -52.049172) (xy 168.627044 -51.662838) (xy 168.619644 -51.655996) (xy 168.601046 -51.648276)
			(xy 168.590976 -51.647852) (xy 163.290758 -51.647852) (xy 163.271962 -51.655472) (xy 163.26485 -51.662838)
			(xy 163.224718 -51.70297) (xy 163.218027 -51.710377) (xy 163.210431 -51.728813) (xy 163.209986 -51.738784)
			(xy 163.209986 -52.033932) (xy 163.210432 -52.044089) (xy 163.218288 -52.062823) (xy 163.225226 -52.070254)
			(xy 163.284662 -52.12842) (xy 163.303458 -52.135786) (xy 163.313618 -52.135532) (xy 163.322254 -52.135532)
			(xy 163.349506 -52.135992) (xy 163.403456 -52.143743) (xy 163.455754 -52.159093) (xy 163.505335 -52.181731)
			(xy 163.551189 -52.211195) (xy 163.592383 -52.246884) (xy 163.628078 -52.288074) (xy 163.657547 -52.333925)
			(xy 163.680191 -52.383503) (xy 163.695547 -52.435799) (xy 163.703305 -52.489748) (xy 163.703305 -52.544252)
			(xy 163.6971 -52.587398) (xy 166.855392 -52.587398) (xy 166.859463 -52.531776) (xy 166.871589 -52.477339)
			(xy 166.891512 -52.425248) (xy 166.918808 -52.376613) (xy 166.952894 -52.33247) (xy 166.993043 -52.293761)
			(xy 167.038401 -52.26131) (xy 167.088001 -52.235809) (xy 167.140785 -52.217802) (xy 167.195628 -52.207672)
			(xy 167.251362 -52.205635) (xy 167.306799 -52.211735) (xy 167.360756 -52.225841) (xy 167.412085 -52.247653)
			(xy 167.459691 -52.276707) (xy 167.502559 -52.312382) (xy 167.539776 -52.353919) (xy 167.570549 -52.400432)
			(xy 167.594221 -52.450929) (xy 167.610289 -52.504336) (xy 167.618409 -52.559512) (xy 167.618918 -52.587398)
			(xy 167.618409 -52.615284) (xy 167.610289 -52.67046) (xy 167.594221 -52.723867) (xy 167.570549 -52.774364)
			(xy 167.539776 -52.820877) (xy 167.502559 -52.862414) (xy 167.459691 -52.898089) (xy 167.412085 -52.927143)
			(xy 167.360756 -52.948955) (xy 167.306799 -52.963061) (xy 167.251362 -52.969161) (xy 167.195628 -52.967124)
			(xy 167.140785 -52.956994) (xy 167.088001 -52.938987) (xy 167.038401 -52.913486) (xy 166.993043 -52.881035)
			(xy 166.952894 -52.842326) (xy 166.918808 -52.798183) (xy 166.891512 -52.749548) (xy 166.871589 -52.697457)
			(xy 166.859463 -52.64302) (xy 166.855392 -52.587398) (xy 163.6971 -52.587398) (xy 163.695547 -52.598201)
			(xy 163.680191 -52.650497) (xy 163.657547 -52.700075) (xy 163.628078 -52.745926) (xy 163.592383 -52.787116)
			(xy 163.551189 -52.822805) (xy 163.505335 -52.852269) (xy 163.455754 -52.874907) (xy 163.403456 -52.890257)
			(xy 163.349506 -52.898008) (xy 163.322254 -52.898548) (xy 163.313618 -52.898548) (xy 163.303458 -52.898294)
			(xy 163.284662 -52.90566) (xy 163.225226 -52.963826) (xy 163.218317 -52.971199) (xy 163.210467 -52.9898)
			(xy 163.209986 -52.999894) (xy 163.209986 -53.96357) (xy 166.872156 -53.96357) (xy 166.876227 -53.907948)
			(xy 166.888353 -53.853511) (xy 166.908276 -53.80142) (xy 166.935572 -53.752785) (xy 166.969658 -53.708642)
			(xy 167.009807 -53.669933) (xy 167.055165 -53.637482) (xy 167.104765 -53.611981) (xy 167.157549 -53.593974)
			(xy 167.212392 -53.583844) (xy 167.268126 -53.581807) (xy 167.323563 -53.587907) (xy 167.37752 -53.602013)
			(xy 167.428849 -53.623825) (xy 167.476455 -53.652879) (xy 167.519323 -53.688554) (xy 167.55654 -53.730091)
			(xy 167.587313 -53.776604) (xy 167.610985 -53.827101) (xy 167.627053 -53.880508) (xy 167.635173 -53.935684)
			(xy 167.635682 -53.96357) (xy 167.635173 -53.991456) (xy 167.627053 -54.046632) (xy 167.610985 -54.100039)
			(xy 167.587313 -54.150536) (xy 167.55654 -54.197049) (xy 167.519323 -54.238586) (xy 167.476455 -54.274261)
			(xy 167.428849 -54.303315) (xy 167.37752 -54.325127) (xy 167.323563 -54.339233) (xy 167.268126 -54.345333)
			(xy 167.212392 -54.343296) (xy 167.157549 -54.333166) (xy 167.104765 -54.315159) (xy 167.055165 -54.289658)
			(xy 167.009807 -54.257207) (xy 166.969658 -54.218498) (xy 166.935572 -54.174355) (xy 166.908276 -54.12572)
			(xy 166.888353 -54.073629) (xy 166.876227 -54.019192) (xy 166.872156 -53.96357) (xy 163.209986 -53.96357)
			(xy 163.209986 -55.722266) (xy 167.93413 -55.722266) (xy 167.938201 -55.666644) (xy 167.950327 -55.612207)
			(xy 167.97025 -55.560116) (xy 167.997546 -55.511481) (xy 168.031632 -55.467338) (xy 168.071781 -55.428629)
			(xy 168.117139 -55.396178) (xy 168.166739 -55.370677) (xy 168.219523 -55.35267) (xy 168.274366 -55.34254)
			(xy 168.3301 -55.340503) (xy 168.385537 -55.346603) (xy 168.439494 -55.360709) (xy 168.490823 -55.382521)
			(xy 168.538429 -55.411575) (xy 168.581297 -55.44725) (xy 168.618514 -55.488787) (xy 168.649287 -55.5353)
			(xy 168.672959 -55.585797) (xy 168.689027 -55.639204) (xy 168.697147 -55.69438) (xy 168.697656 -55.722266)
			(xy 168.697147 -55.750152) (xy 168.689027 -55.805328) (xy 168.672959 -55.858735) (xy 168.649287 -55.909232)
			(xy 168.618514 -55.955745) (xy 168.581297 -55.997282) (xy 168.538429 -56.032957) (xy 168.490823 -56.062011)
			(xy 168.439494 -56.083823) (xy 168.385537 -56.097929) (xy 168.3301 -56.104029) (xy 168.274366 -56.101992)
			(xy 168.219523 -56.091862) (xy 168.166739 -56.073855) (xy 168.117139 -56.048354) (xy 168.071781 -56.015903)
			(xy 168.031632 -55.977194) (xy 167.997546 -55.933051) (xy 167.97025 -55.884416) (xy 167.950327 -55.832325)
			(xy 167.938201 -55.777888) (xy 167.93413 -55.722266) (xy 163.209986 -55.722266) (xy 163.209986 -58.072274)
			(xy 168.093642 -58.072274) (xy 168.097713 -58.016652) (xy 168.109839 -57.962215) (xy 168.129762 -57.910124)
			(xy 168.157058 -57.861489) (xy 168.191144 -57.817346) (xy 168.231293 -57.778637) (xy 168.276651 -57.746186)
			(xy 168.326251 -57.720685) (xy 168.379035 -57.702678) (xy 168.433878 -57.692548) (xy 168.489612 -57.690511)
			(xy 168.545049 -57.696611) (xy 168.599006 -57.710717) (xy 168.650335 -57.732529) (xy 168.697941 -57.761583)
			(xy 168.740809 -57.797258) (xy 168.778026 -57.838795) (xy 168.808799 -57.885308) (xy 168.832471 -57.935805)
			(xy 168.848539 -57.989212) (xy 168.856659 -58.044388) (xy 168.857168 -58.072274) (xy 168.856659 -58.10016)
			(xy 168.848539 -58.155336) (xy 168.832471 -58.208743) (xy 168.808799 -58.25924) (xy 168.778026 -58.305753)
			(xy 168.740809 -58.34729) (xy 168.697941 -58.382965) (xy 168.650335 -58.412019) (xy 168.599006 -58.433831)
			(xy 168.545049 -58.447937) (xy 168.489612 -58.454037) (xy 168.433878 -58.452) (xy 168.379035 -58.44187)
			(xy 168.326251 -58.423863) (xy 168.276651 -58.398362) (xy 168.231293 -58.365911) (xy 168.191144 -58.327202)
			(xy 168.157058 -58.283059) (xy 168.129762 -58.234424) (xy 168.109839 -58.182333) (xy 168.097713 -58.127896)
			(xy 168.093642 -58.072274) (xy 163.209986 -58.072274) (xy 163.209986 -64.797178) (xy 163.210408 -64.80693)
			(xy 163.217683 -64.825024) (xy 163.231217 -64.839066) (xy 163.239958 -64.843406) (xy 163.322254 -64.880744)
			(xy 163.332802 -64.884763) (xy 163.355342 -64.88424) (xy 163.365688 -64.879728) (xy 163.378388 -64.873378)
			(xy 163.383214 -64.869568) (xy 163.404002 -64.852432) (xy 163.449494 -64.823574) (xy 163.498599 -64.801415)
			(xy 163.550336 -64.786398) (xy 163.603673 -64.778821) (xy 163.63061 -64.778382) (xy 163.657861 -64.778868)
			(xy 163.71181 -64.786626) (xy 163.764104 -64.801983) (xy 163.813682 -64.824625) (xy 163.859532 -64.854092)
			(xy 163.900722 -64.889785) (xy 163.936414 -64.930976) (xy 163.96588 -64.976827) (xy 163.988521 -65.026405)
			(xy 164.003876 -65.0787) (xy 164.011632 -65.132648) (xy 164.011632 -65.187152) (xy 164.003876 -65.2411)
			(xy 163.988521 -65.293395) (xy 163.96588 -65.342973) (xy 163.936414 -65.388824) (xy 163.900722 -65.430015)
			(xy 163.859532 -65.465708) (xy 163.813682 -65.495175) (xy 163.764104 -65.517817) (xy 163.71181 -65.533174)
			(xy 163.657861 -65.540932) (xy 163.63061 -65.541398) (xy 163.603679 -65.54091) (xy 163.550358 -65.533293)
			(xy 163.498635 -65.518266) (xy 163.449533 -65.496125) (xy 163.404027 -65.46731) (xy 163.383214 -65.450212)
			(xy 163.378388 -65.446402) (xy 163.365688 -65.440052) (xy 163.355346 -65.435512) (xy 163.332796 -65.434983)
			(xy 163.322254 -65.439036) (xy 163.239958 -65.476374) (xy 163.231271 -65.480782) (xy 163.217793 -65.494827)
			(xy 163.210495 -65.512872) (xy 163.209986 -65.522602) (xy 163.209986 -67.592956) (xy 163.445442 -67.592956)
			(xy 163.449513 -67.537334) (xy 163.461639 -67.482897) (xy 163.481562 -67.430806) (xy 163.508858 -67.382171)
			(xy 163.542944 -67.338028) (xy 163.583093 -67.299319) (xy 163.628451 -67.266868) (xy 163.678051 -67.241367)
			(xy 163.730835 -67.22336) (xy 163.785678 -67.21323) (xy 163.841412 -67.211193) (xy 163.896849 -67.217293)
			(xy 163.950806 -67.231399) (xy 164.002135 -67.253211) (xy 164.049741 -67.282265) (xy 164.092609 -67.31794)
			(xy 164.129826 -67.359477) (xy 164.160599 -67.40599) (xy 164.184271 -67.456487) (xy 164.200339 -67.509894)
			(xy 164.208459 -67.56507) (xy 164.208968 -67.592956) (xy 164.208459 -67.620842) (xy 164.200339 -67.676018)
			(xy 164.184271 -67.729425) (xy 164.160599 -67.779922) (xy 164.129826 -67.826435) (xy 164.092609 -67.867972)
			(xy 164.049741 -67.903647) (xy 164.002135 -67.932701) (xy 163.950806 -67.954513) (xy 163.896849 -67.968619)
			(xy 163.841412 -67.974719) (xy 163.785678 -67.972682) (xy 163.730835 -67.962552) (xy 163.678051 -67.944545)
			(xy 163.628451 -67.919044) (xy 163.583093 -67.886593) (xy 163.542944 -67.847884) (xy 163.508858 -67.803741)
			(xy 163.481562 -67.755106) (xy 163.461639 -67.703015) (xy 163.449513 -67.648578) (xy 163.445442 -67.592956)
			(xy 163.209986 -67.592956) (xy 163.209986 -70.035928) (xy 163.210478 -70.045933) (xy 163.218142 -70.064418)
			(xy 163.232294 -70.078565) (xy 163.250781 -70.086224) (xy 163.260786 -70.086728) (xy 168.832276 -70.086728)
		)
		(stroke
			(width 0)
			(type solid)
		)
		(fill yes)
		(layer "In9.Cu")
		(net "P12V_AUX")
	)
	(gr_poly
		(pts
			(xy 194.85102 -70.079108) (xy 194.858132 -70.071742) (xy 195.013326 -69.916548) (xy 195.020172 -69.90915)
			(xy 195.0279 -69.890551) (xy 195.028312 -69.88048) (xy 195.028312 -52.07508) (xy 195.020692 -52.056284)
			(xy 195.013326 -52.049172) (xy 194.626992 -51.662838) (xy 194.619595 -51.655989) (xy 194.600996 -51.648251)
			(xy 194.590924 -51.647852) (xy 189.290706 -51.647852) (xy 189.27191 -51.655472) (xy 189.264798 -51.662838)
			(xy 189.224666 -51.70297) (xy 189.217981 -51.71038) (xy 189.210393 -51.728815) (xy 189.209934 -51.738784)
			(xy 189.209934 -52.033932) (xy 189.210382 -52.044088) (xy 189.218242 -52.062818) (xy 189.225174 -52.070254)
			(xy 189.28461 -52.12842) (xy 189.303406 -52.135786) (xy 189.313566 -52.135532) (xy 189.322202 -52.135532)
			(xy 189.34945 -52.136018) (xy 189.403392 -52.143774) (xy 189.455681 -52.159128) (xy 189.505253 -52.181767)
			(xy 189.551098 -52.21123) (xy 189.592284 -52.246918) (xy 189.627971 -52.288104) (xy 189.657434 -52.333949)
			(xy 189.680073 -52.383521) (xy 189.695426 -52.43581) (xy 189.703182 -52.489752) (xy 189.703182 -52.544248)
			(xy 189.696978 -52.587398) (xy 192.85534 -52.587398) (xy 192.859411 -52.531776) (xy 192.871537 -52.477339)
			(xy 192.89146 -52.425248) (xy 192.918756 -52.376613) (xy 192.952842 -52.33247) (xy 192.992991 -52.293761)
			(xy 193.038349 -52.26131) (xy 193.087949 -52.235809) (xy 193.140733 -52.217802) (xy 193.195576 -52.207672)
			(xy 193.25131 -52.205635) (xy 193.306747 -52.211735) (xy 193.360704 -52.225841) (xy 193.412033 -52.247653)
			(xy 193.459639 -52.276707) (xy 193.502507 -52.312382) (xy 193.539724 -52.353919) (xy 193.570497 -52.400432)
			(xy 193.594169 -52.450929) (xy 193.610237 -52.504336) (xy 193.618357 -52.559512) (xy 193.618866 -52.587398)
			(xy 193.618357 -52.615284) (xy 193.610237 -52.67046) (xy 193.594169 -52.723867) (xy 193.570497 -52.774364)
			(xy 193.539724 -52.820877) (xy 193.502507 -52.862414) (xy 193.459639 -52.898089) (xy 193.412033 -52.927143)
			(xy 193.360704 -52.948955) (xy 193.306747 -52.963061) (xy 193.25131 -52.969161) (xy 193.195576 -52.967124)
			(xy 193.140733 -52.956994) (xy 193.087949 -52.938987) (xy 193.038349 -52.913486) (xy 192.992991 -52.881035)
			(xy 192.952842 -52.842326) (xy 192.918756 -52.798183) (xy 192.89146 -52.749548) (xy 192.871537 -52.697457)
			(xy 192.859411 -52.64302) (xy 192.85534 -52.587398) (xy 189.696978 -52.587398) (xy 189.695426 -52.59819)
			(xy 189.680073 -52.650479) (xy 189.657434 -52.700051) (xy 189.627971 -52.745896) (xy 189.592284 -52.787082)
			(xy 189.551098 -52.82277) (xy 189.505253 -52.852233) (xy 189.455681 -52.874872) (xy 189.403392 -52.890226)
			(xy 189.34945 -52.897982) (xy 189.322202 -52.898548) (xy 189.313566 -52.898548) (xy 189.303406 -52.898294)
			(xy 189.28461 -52.90566) (xy 189.225174 -52.963826) (xy 189.21827 -52.971202) (xy 189.210429 -52.989802)
			(xy 189.209934 -52.999894) (xy 189.209934 -53.96357) (xy 192.872104 -53.96357) (xy 192.876175 -53.907948)
			(xy 192.888301 -53.853511) (xy 192.908224 -53.80142) (xy 192.93552 -53.752785) (xy 192.969606 -53.708642)
			(xy 193.009755 -53.669933) (xy 193.055113 -53.637482) (xy 193.104713 -53.611981) (xy 193.157497 -53.593974)
			(xy 193.21234 -53.583844) (xy 193.268074 -53.581807) (xy 193.323511 -53.587907) (xy 193.377468 -53.602013)
			(xy 193.428797 -53.623825) (xy 193.476403 -53.652879) (xy 193.519271 -53.688554) (xy 193.556488 -53.730091)
			(xy 193.587261 -53.776604) (xy 193.610933 -53.827101) (xy 193.627001 -53.880508) (xy 193.635121 -53.935684)
			(xy 193.63563 -53.96357) (xy 193.635121 -53.991456) (xy 193.627001 -54.046632) (xy 193.610933 -54.100039)
			(xy 193.587261 -54.150536) (xy 193.556488 -54.197049) (xy 193.519271 -54.238586) (xy 193.476403 -54.274261)
			(xy 193.428797 -54.303315) (xy 193.377468 -54.325127) (xy 193.323511 -54.339233) (xy 193.268074 -54.345333)
			(xy 193.21234 -54.343296) (xy 193.157497 -54.333166) (xy 193.104713 -54.315159) (xy 193.055113 -54.289658)
			(xy 193.009755 -54.257207) (xy 192.969606 -54.218498) (xy 192.93552 -54.174355) (xy 192.908224 -54.12572)
			(xy 192.888301 -54.073629) (xy 192.876175 -54.019192) (xy 192.872104 -53.96357) (xy 189.209934 -53.96357)
			(xy 189.209934 -55.722266) (xy 193.934078 -55.722266) (xy 193.938149 -55.666644) (xy 193.950275 -55.612207)
			(xy 193.970198 -55.560116) (xy 193.997494 -55.511481) (xy 194.03158 -55.467338) (xy 194.071729 -55.428629)
			(xy 194.117087 -55.396178) (xy 194.166687 -55.370677) (xy 194.219471 -55.35267) (xy 194.274314 -55.34254)
			(xy 194.330048 -55.340503) (xy 194.385485 -55.346603) (xy 194.439442 -55.360709) (xy 194.490771 -55.382521)
			(xy 194.538377 -55.411575) (xy 194.581245 -55.44725) (xy 194.618462 -55.488787) (xy 194.649235 -55.5353)
			(xy 194.672907 -55.585797) (xy 194.688975 -55.639204) (xy 194.697095 -55.69438) (xy 194.697604 -55.722266)
			(xy 194.697095 -55.750152) (xy 194.688975 -55.805328) (xy 194.672907 -55.858735) (xy 194.649235 -55.909232)
			(xy 194.618462 -55.955745) (xy 194.581245 -55.997282) (xy 194.538377 -56.032957) (xy 194.490771 -56.062011)
			(xy 194.439442 -56.083823) (xy 194.385485 -56.097929) (xy 194.330048 -56.104029) (xy 194.274314 -56.101992)
			(xy 194.219471 -56.091862) (xy 194.166687 -56.073855) (xy 194.117087 -56.048354) (xy 194.071729 -56.015903)
			(xy 194.03158 -55.977194) (xy 193.997494 -55.933051) (xy 193.970198 -55.884416) (xy 193.950275 -55.832325)
			(xy 193.938149 -55.777888) (xy 193.934078 -55.722266) (xy 189.209934 -55.722266) (xy 189.209934 -57.032144)
			(xy 193.585844 -57.032144) (xy 193.589915 -56.976522) (xy 193.602041 -56.922085) (xy 193.621964 -56.869994)
			(xy 193.64926 -56.821359) (xy 193.683346 -56.777216) (xy 193.723495 -56.738507) (xy 193.768853 -56.706056)
			(xy 193.818453 -56.680555) (xy 193.871237 -56.662548) (xy 193.92608 -56.652418) (xy 193.981814 -56.650381)
			(xy 194.037251 -56.656481) (xy 194.091208 -56.670587) (xy 194.142537 -56.692399) (xy 194.190143 -56.721453)
			(xy 194.233011 -56.757128) (xy 194.270228 -56.798665) (xy 194.301001 -56.845178) (xy 194.324673 -56.895675)
			(xy 194.340741 -56.949082) (xy 194.348861 -57.004258) (xy 194.34937 -57.032144) (xy 194.348861 -57.06003)
			(xy 194.340741 -57.115206) (xy 194.324673 -57.168613) (xy 194.301001 -57.21911) (xy 194.270228 -57.265623)
			(xy 194.233011 -57.30716) (xy 194.190143 -57.342835) (xy 194.142537 -57.371889) (xy 194.091208 -57.393701)
			(xy 194.037251 -57.407807) (xy 193.981814 -57.413907) (xy 193.92608 -57.41187) (xy 193.871237 -57.40174)
			(xy 193.818453 -57.383733) (xy 193.768853 -57.358232) (xy 193.723495 -57.325781) (xy 193.683346 -57.287072)
			(xy 193.64926 -57.242929) (xy 193.621964 -57.194294) (xy 193.602041 -57.142203) (xy 193.589915 -57.087766)
			(xy 193.585844 -57.032144) (xy 189.209934 -57.032144) (xy 189.209934 -64.797178) (xy 189.210357 -64.806928)
			(xy 189.217636 -64.825017) (xy 189.231175 -64.839048) (xy 189.239906 -64.843406) (xy 189.322202 -64.880744)
			(xy 189.332749 -64.884753) (xy 189.355279 -64.884211) (xy 189.365636 -64.879728) (xy 189.378336 -64.873378)
			(xy 189.383162 -64.869568) (xy 189.403951 -64.852435) (xy 189.449444 -64.823583) (xy 189.498549 -64.80143)
			(xy 189.550286 -64.786419) (xy 189.603622 -64.778849) (xy 189.630558 -64.778382) (xy 189.657814 -64.778842)
			(xy 189.711771 -64.786594) (xy 189.764075 -64.801947) (xy 189.813662 -64.824588) (xy 189.859521 -64.854056)
			(xy 189.90072 -64.88975) (xy 189.936419 -64.930945) (xy 189.965892 -64.976801) (xy 189.988538 -65.026386)
			(xy 190.003897 -65.078688) (xy 190.011655 -65.132644) (xy 190.011655 -65.187156) (xy 190.003897 -65.241112)
			(xy 189.988538 -65.293414) (xy 189.965892 -65.342999) (xy 189.936419 -65.388855) (xy 189.90072 -65.43005)
			(xy 189.859521 -65.465744) (xy 189.813662 -65.495212) (xy 189.764075 -65.517853) (xy 189.711771 -65.533206)
			(xy 189.657814 -65.540958) (xy 189.630558 -65.541398) (xy 189.603626 -65.540913) (xy 189.550302 -65.533302)
			(xy 189.498574 -65.51828) (xy 189.449469 -65.496144) (xy 189.403957 -65.467332) (xy 189.383162 -65.450212)
			(xy 189.378336 -65.446402) (xy 189.365636 -65.440052) (xy 189.355295 -65.435523) (xy 189.332754 -65.435016)
			(xy 189.322202 -65.439036) (xy 189.239906 -65.476374) (xy 189.231212 -65.480778) (xy 189.217723 -65.494819)
			(xy 189.210417 -65.512868) (xy 189.209934 -65.522602) (xy 189.209934 -67.592956) (xy 189.44539 -67.592956)
			(xy 189.449461 -67.537334) (xy 189.461587 -67.482897) (xy 189.48151 -67.430806) (xy 189.508806 -67.382171)
			(xy 189.542892 -67.338028) (xy 189.583041 -67.299319) (xy 189.628399 -67.266868) (xy 189.677999 -67.241367)
			(xy 189.730783 -67.22336) (xy 189.785626 -67.21323) (xy 189.84136 -67.211193) (xy 189.896797 -67.217293)
			(xy 189.950754 -67.231399) (xy 190.002083 -67.253211) (xy 190.049689 -67.282265) (xy 190.092557 -67.31794)
			(xy 190.129774 -67.359477) (xy 190.160547 -67.40599) (xy 190.184219 -67.456487) (xy 190.200287 -67.509894)
			(xy 190.208407 -67.56507) (xy 190.208916 -67.592956) (xy 190.208407 -67.620842) (xy 190.200287 -67.676018)
			(xy 190.184219 -67.729425) (xy 190.160547 -67.779922) (xy 190.129774 -67.826435) (xy 190.092557 -67.867972)
			(xy 190.049689 -67.903647) (xy 190.002083 -67.932701) (xy 189.950754 -67.954513) (xy 189.896797 -67.968619)
			(xy 189.84136 -67.974719) (xy 189.785626 -67.972682) (xy 189.730783 -67.962552) (xy 189.677999 -67.944545)
			(xy 189.628399 -67.919044) (xy 189.583041 -67.886593) (xy 189.542892 -67.847884) (xy 189.508806 -67.803741)
			(xy 189.48151 -67.755106) (xy 189.461587 -67.703015) (xy 189.449461 -67.648578) (xy 189.44539 -67.592956)
			(xy 189.209934 -67.592956) (xy 189.209934 -70.035928) (xy 189.210359 -70.045943) (xy 189.218035 -70.064445)
			(xy 189.232208 -70.0786) (xy 189.250718 -70.086253) (xy 189.260734 -70.086728) (xy 194.832224 -70.086728)
		)
		(stroke
			(width 0)
			(type solid)
		)
		(fill yes)
		(layer "In9.Cu")
		(net "P12V_AUX")
	)
	(gr_poly
		(pts
			(xy 220.850968 -70.079108) (xy 220.85808 -70.071742) (xy 221.013274 -69.916548) (xy 221.020115 -69.909148)
			(xy 221.027834 -69.890549) (xy 221.02826 -69.88048) (xy 221.02826 -52.07508) (xy 221.02064 -52.056284)
			(xy 221.013274 -52.049172) (xy 220.62694 -51.662838) (xy 220.61954 -51.655997) (xy 220.600941 -51.648278)
			(xy 220.590872 -51.647852) (xy 215.290654 -51.647852) (xy 215.271858 -51.655472) (xy 215.264746 -51.662838)
			(xy 215.224614 -51.70297) (xy 215.217924 -51.710377) (xy 215.210329 -51.728814) (xy 215.209882 -51.738784)
			(xy 215.209882 -52.033932) (xy 215.210328 -52.044089) (xy 215.218183 -52.062824) (xy 215.225122 -52.070254)
			(xy 215.284558 -52.12842) (xy 215.303354 -52.135786) (xy 215.313514 -52.135532) (xy 215.32215 -52.135532)
			(xy 215.349402 -52.135992) (xy 215.403353 -52.143742) (xy 215.455651 -52.159092) (xy 215.505233 -52.18173)
			(xy 215.551087 -52.211193) (xy 215.592282 -52.246883) (xy 215.627977 -52.288073) (xy 215.657446 -52.333923)
			(xy 215.68009 -52.383502) (xy 215.695447 -52.435798) (xy 215.703205 -52.489748) (xy 215.703205 -52.544252)
			(xy 215.697001 -52.587398) (xy 218.855288 -52.587398) (xy 218.859359 -52.531776) (xy 218.871485 -52.477339)
			(xy 218.891408 -52.425248) (xy 218.918704 -52.376613) (xy 218.95279 -52.33247) (xy 218.992939 -52.293761)
			(xy 219.038297 -52.26131) (xy 219.087897 -52.235809) (xy 219.140681 -52.217802) (xy 219.195524 -52.207672)
			(xy 219.251258 -52.205635) (xy 219.306695 -52.211735) (xy 219.360652 -52.225841) (xy 219.411981 -52.247653)
			(xy 219.459587 -52.276707) (xy 219.502455 -52.312382) (xy 219.539672 -52.353919) (xy 219.570445 -52.400432)
			(xy 219.594117 -52.450929) (xy 219.610185 -52.504336) (xy 219.618305 -52.559512) (xy 219.618814 -52.587398)
			(xy 219.618305 -52.615284) (xy 219.610185 -52.67046) (xy 219.594117 -52.723867) (xy 219.570445 -52.774364)
			(xy 219.539672 -52.820877) (xy 219.502455 -52.862414) (xy 219.459587 -52.898089) (xy 219.411981 -52.927143)
			(xy 219.360652 -52.948955) (xy 219.306695 -52.963061) (xy 219.251258 -52.969161) (xy 219.195524 -52.967124)
			(xy 219.140681 -52.956994) (xy 219.087897 -52.938987) (xy 219.038297 -52.913486) (xy 218.992939 -52.881035)
			(xy 218.95279 -52.842326) (xy 218.918704 -52.798183) (xy 218.891408 -52.749548) (xy 218.871485 -52.697457)
			(xy 218.859359 -52.64302) (xy 218.855288 -52.587398) (xy 215.697001 -52.587398) (xy 215.695447 -52.598202)
			(xy 215.68009 -52.650498) (xy 215.657446 -52.700077) (xy 215.627977 -52.745927) (xy 215.592282 -52.787117)
			(xy 215.551087 -52.822807) (xy 215.505233 -52.85227) (xy 215.455651 -52.874908) (xy 215.403353 -52.890258)
			(xy 215.349402 -52.898008) (xy 215.32215 -52.898548) (xy 215.313514 -52.898548) (xy 215.303354 -52.898294)
			(xy 215.284558 -52.90566) (xy 215.225122 -52.963826) (xy 215.218213 -52.971199) (xy 215.210364 -52.9898)
			(xy 215.209882 -52.999894) (xy 215.209882 -53.96357) (xy 218.872052 -53.96357) (xy 218.876123 -53.907948)
			(xy 218.888249 -53.853511) (xy 218.908172 -53.80142) (xy 218.935468 -53.752785) (xy 218.969554 -53.708642)
			(xy 219.009703 -53.669933) (xy 219.055061 -53.637482) (xy 219.104661 -53.611981) (xy 219.157445 -53.593974)
			(xy 219.212288 -53.583844) (xy 219.268022 -53.581807) (xy 219.323459 -53.587907) (xy 219.377416 -53.602013)
			(xy 219.428745 -53.623825) (xy 219.476351 -53.652879) (xy 219.519219 -53.688554) (xy 219.556436 -53.730091)
			(xy 219.587209 -53.776604) (xy 219.610881 -53.827101) (xy 219.626949 -53.880508) (xy 219.635069 -53.935684)
			(xy 219.635578 -53.96357) (xy 219.635069 -53.991456) (xy 219.626949 -54.046632) (xy 219.610881 -54.100039)
			(xy 219.587209 -54.150536) (xy 219.556436 -54.197049) (xy 219.519219 -54.238586) (xy 219.476351 -54.274261)
			(xy 219.428745 -54.303315) (xy 219.377416 -54.325127) (xy 219.323459 -54.339233) (xy 219.268022 -54.345333)
			(xy 219.212288 -54.343296) (xy 219.157445 -54.333166) (xy 219.104661 -54.315159) (xy 219.055061 -54.289658)
			(xy 219.009703 -54.257207) (xy 218.969554 -54.218498) (xy 218.935468 -54.174355) (xy 218.908172 -54.12572)
			(xy 218.888249 -54.073629) (xy 218.876123 -54.019192) (xy 218.872052 -53.96357) (xy 215.209882 -53.96357)
			(xy 215.209882 -55.722266) (xy 219.934026 -55.722266) (xy 219.938097 -55.666644) (xy 219.950223 -55.612207)
			(xy 219.970146 -55.560116) (xy 219.997442 -55.511481) (xy 220.031528 -55.467338) (xy 220.071677 -55.428629)
			(xy 220.117035 -55.396178) (xy 220.166635 -55.370677) (xy 220.219419 -55.35267) (xy 220.274262 -55.34254)
			(xy 220.329996 -55.340503) (xy 220.385433 -55.346603) (xy 220.43939 -55.360709) (xy 220.490719 -55.382521)
			(xy 220.538325 -55.411575) (xy 220.581193 -55.44725) (xy 220.61841 -55.488787) (xy 220.649183 -55.5353)
			(xy 220.672855 -55.585797) (xy 220.688923 -55.639204) (xy 220.697043 -55.69438) (xy 220.697552 -55.722266)
			(xy 220.697043 -55.750152) (xy 220.688923 -55.805328) (xy 220.672855 -55.858735) (xy 220.649183 -55.909232)
			(xy 220.61841 -55.955745) (xy 220.581193 -55.997282) (xy 220.538325 -56.032957) (xy 220.490719 -56.062011)
			(xy 220.43939 -56.083823) (xy 220.385433 -56.097929) (xy 220.329996 -56.104029) (xy 220.274262 -56.101992)
			(xy 220.219419 -56.091862) (xy 220.166635 -56.073855) (xy 220.117035 -56.048354) (xy 220.071677 -56.015903)
			(xy 220.031528 -55.977194) (xy 219.997442 -55.933051) (xy 219.970146 -55.884416) (xy 219.950223 -55.832325)
			(xy 219.938097 -55.777888) (xy 219.934026 -55.722266) (xy 215.209882 -55.722266) (xy 215.209882 -57.032144)
			(xy 219.585792 -57.032144) (xy 219.589863 -56.976522) (xy 219.601989 -56.922085) (xy 219.621912 -56.869994)
			(xy 219.649208 -56.821359) (xy 219.683294 -56.777216) (xy 219.723443 -56.738507) (xy 219.768801 -56.706056)
			(xy 219.818401 -56.680555) (xy 219.871185 -56.662548) (xy 219.926028 -56.652418) (xy 219.981762 -56.650381)
			(xy 220.037199 -56.656481) (xy 220.091156 -56.670587) (xy 220.142485 -56.692399) (xy 220.190091 -56.721453)
			(xy 220.232959 -56.757128) (xy 220.270176 -56.798665) (xy 220.300949 -56.845178) (xy 220.324621 -56.895675)
			(xy 220.340689 -56.949082) (xy 220.348809 -57.004258) (xy 220.349318 -57.032144) (xy 220.348809 -57.06003)
			(xy 220.340689 -57.115206) (xy 220.324621 -57.168613) (xy 220.300949 -57.21911) (xy 220.270176 -57.265623)
			(xy 220.232959 -57.30716) (xy 220.190091 -57.342835) (xy 220.142485 -57.371889) (xy 220.091156 -57.393701)
			(xy 220.037199 -57.407807) (xy 219.981762 -57.413907) (xy 219.926028 -57.41187) (xy 219.871185 -57.40174)
			(xy 219.818401 -57.383733) (xy 219.768801 -57.358232) (xy 219.723443 -57.325781) (xy 219.683294 -57.287072)
			(xy 219.649208 -57.242929) (xy 219.621912 -57.194294) (xy 219.601989 -57.142203) (xy 219.589863 -57.087766)
			(xy 219.585792 -57.032144) (xy 215.209882 -57.032144) (xy 215.209882 -64.797178) (xy 215.210304 -64.80693)
			(xy 215.217579 -64.825025) (xy 215.231112 -64.839068) (xy 215.239854 -64.843406) (xy 215.32215 -64.880744)
			(xy 215.332698 -64.884764) (xy 215.355238 -64.884242) (xy 215.365584 -64.879728) (xy 215.378284 -64.873378)
			(xy 215.38311 -64.869568) (xy 215.403898 -64.852432) (xy 215.44939 -64.823573) (xy 215.498494 -64.801414)
			(xy 215.550232 -64.786396) (xy 215.603569 -64.778819) (xy 215.630506 -64.778382) (xy 215.657758 -64.778868)
			(xy 215.711706 -64.786626) (xy 215.764002 -64.801982) (xy 215.813579 -64.824624) (xy 215.85943 -64.854091)
			(xy 215.900621 -64.889783) (xy 215.936313 -64.930975) (xy 215.965779 -64.976826) (xy 215.98842 -65.026404)
			(xy 216.003776 -65.0787) (xy 216.011532 -65.132648) (xy 216.011532 -65.187152) (xy 216.003776 -65.2411)
			(xy 215.98842 -65.293396) (xy 215.965779 -65.342974) (xy 215.936313 -65.388825) (xy 215.900621 -65.430017)
			(xy 215.85943 -65.465709) (xy 215.813579 -65.495176) (xy 215.764002 -65.517818) (xy 215.711706 -65.533174)
			(xy 215.657758 -65.540932) (xy 215.630506 -65.541398) (xy 215.603575 -65.540909) (xy 215.550255 -65.533292)
			(xy 215.498531 -65.518264) (xy 215.44943 -65.496124) (xy 215.403924 -65.467308) (xy 215.38311 -65.450212)
			(xy 215.378284 -65.446402) (xy 215.365584 -65.440052) (xy 215.355242 -65.435512) (xy 215.332693 -65.434985)
			(xy 215.32215 -65.439036) (xy 215.239854 -65.476374) (xy 215.231167 -65.480783) (xy 215.217691 -65.494827)
			(xy 215.210393 -65.512872) (xy 215.209882 -65.522602) (xy 215.209882 -67.592956) (xy 215.445338 -67.592956)
			(xy 215.449409 -67.537334) (xy 215.461535 -67.482897) (xy 215.481458 -67.430806) (xy 215.508754 -67.382171)
			(xy 215.54284 -67.338028) (xy 215.582989 -67.299319) (xy 215.628347 -67.266868) (xy 215.677947 -67.241367)
			(xy 215.730731 -67.22336) (xy 215.785574 -67.21323) (xy 215.841308 -67.211193) (xy 215.896745 -67.217293)
			(xy 215.950702 -67.231399) (xy 216.002031 -67.253211) (xy 216.049637 -67.282265) (xy 216.092505 -67.31794)
			(xy 216.129722 -67.359477) (xy 216.160495 -67.40599) (xy 216.184167 -67.456487) (xy 216.200235 -67.509894)
			(xy 216.208355 -67.56507) (xy 216.208864 -67.592956) (xy 216.208355 -67.620842) (xy 216.200235 -67.676018)
			(xy 216.184167 -67.729425) (xy 216.160495 -67.779922) (xy 216.129722 -67.826435) (xy 216.092505 -67.867972)
			(xy 216.049637 -67.903647) (xy 216.002031 -67.932701) (xy 215.950702 -67.954513) (xy 215.896745 -67.968619)
			(xy 215.841308 -67.974719) (xy 215.785574 -67.972682) (xy 215.730731 -67.962552) (xy 215.677947 -67.944545)
			(xy 215.628347 -67.919044) (xy 215.582989 -67.886593) (xy 215.54284 -67.847884) (xy 215.508754 -67.803741)
			(xy 215.481458 -67.755106) (xy 215.461535 -67.703015) (xy 215.449409 -67.648578) (xy 215.445338 -67.592956)
			(xy 215.209882 -67.592956) (xy 215.209882 -70.035928) (xy 215.210374 -70.045933) (xy 215.218038 -70.064419)
			(xy 215.23219 -70.078567) (xy 215.250677 -70.086228) (xy 215.260682 -70.086728) (xy 220.832172 -70.086728)
		)
		(stroke
			(width 0)
			(type solid)
		)
		(fill yes)
		(layer "In9.Cu")
		(net "P12V_AUX")
	)
	(gr_poly
		(pts
			(xy 258.950968 -70.079108) (xy 258.95808 -70.071742) (xy 259.113274 -69.916548) (xy 259.120115 -69.909148)
			(xy 259.127834 -69.890549) (xy 259.12826 -69.88048) (xy 259.12826 -52.07508) (xy 259.12064 -52.056284)
			(xy 259.113274 -52.049172) (xy 258.72694 -51.662838) (xy 258.71954 -51.655997) (xy 258.700941 -51.648278)
			(xy 258.690872 -51.647852) (xy 253.390654 -51.647852) (xy 253.371858 -51.655472) (xy 253.364746 -51.662838)
			(xy 253.324614 -51.70297) (xy 253.317924 -51.710377) (xy 253.310329 -51.728814) (xy 253.309882 -51.738784)
			(xy 253.309882 -52.033932) (xy 253.310328 -52.044089) (xy 253.318183 -52.062824) (xy 253.325122 -52.070254)
			(xy 253.384558 -52.12842) (xy 253.403354 -52.135786) (xy 253.413514 -52.135532) (xy 253.42215 -52.135532)
			(xy 253.449402 -52.135992) (xy 253.503353 -52.143742) (xy 253.555651 -52.159092) (xy 253.605233 -52.18173)
			(xy 253.651087 -52.211193) (xy 253.692282 -52.246883) (xy 253.727977 -52.288073) (xy 253.757446 -52.333923)
			(xy 253.78009 -52.383502) (xy 253.795447 -52.435798) (xy 253.803205 -52.489748) (xy 253.803205 -52.544252)
			(xy 253.797001 -52.587398) (xy 256.955288 -52.587398) (xy 256.959359 -52.531776) (xy 256.971485 -52.477339)
			(xy 256.991408 -52.425248) (xy 257.018704 -52.376613) (xy 257.05279 -52.33247) (xy 257.092939 -52.293761)
			(xy 257.138297 -52.26131) (xy 257.187897 -52.235809) (xy 257.240681 -52.217802) (xy 257.295524 -52.207672)
			(xy 257.351258 -52.205635) (xy 257.406695 -52.211735) (xy 257.460652 -52.225841) (xy 257.511981 -52.247653)
			(xy 257.559587 -52.276707) (xy 257.602455 -52.312382) (xy 257.639672 -52.353919) (xy 257.670445 -52.400432)
			(xy 257.694117 -52.450929) (xy 257.710185 -52.504336) (xy 257.718305 -52.559512) (xy 257.718814 -52.587398)
			(xy 257.718305 -52.615284) (xy 257.710185 -52.67046) (xy 257.694117 -52.723867) (xy 257.670445 -52.774364)
			(xy 257.639672 -52.820877) (xy 257.602455 -52.862414) (xy 257.559587 -52.898089) (xy 257.511981 -52.927143)
			(xy 257.460652 -52.948955) (xy 257.406695 -52.963061) (xy 257.351258 -52.969161) (xy 257.295524 -52.967124)
			(xy 257.240681 -52.956994) (xy 257.187897 -52.938987) (xy 257.138297 -52.913486) (xy 257.092939 -52.881035)
			(xy 257.05279 -52.842326) (xy 257.018704 -52.798183) (xy 256.991408 -52.749548) (xy 256.971485 -52.697457)
			(xy 256.959359 -52.64302) (xy 256.955288 -52.587398) (xy 253.797001 -52.587398) (xy 253.795447 -52.598202)
			(xy 253.78009 -52.650498) (xy 253.757446 -52.700077) (xy 253.727977 -52.745927) (xy 253.692282 -52.787117)
			(xy 253.651087 -52.822807) (xy 253.605233 -52.85227) (xy 253.555651 -52.874908) (xy 253.503353 -52.890258)
			(xy 253.449402 -52.898008) (xy 253.42215 -52.898548) (xy 253.413514 -52.898548) (xy 253.403354 -52.898294)
			(xy 253.384558 -52.90566) (xy 253.325122 -52.963826) (xy 253.318213 -52.971199) (xy 253.310364 -52.9898)
			(xy 253.309882 -52.999894) (xy 253.309882 -53.96357) (xy 256.972052 -53.96357) (xy 256.976123 -53.907948)
			(xy 256.988249 -53.853511) (xy 257.008172 -53.80142) (xy 257.035468 -53.752785) (xy 257.069554 -53.708642)
			(xy 257.109703 -53.669933) (xy 257.155061 -53.637482) (xy 257.204661 -53.611981) (xy 257.257445 -53.593974)
			(xy 257.312288 -53.583844) (xy 257.368022 -53.581807) (xy 257.423459 -53.587907) (xy 257.477416 -53.602013)
			(xy 257.528745 -53.623825) (xy 257.576351 -53.652879) (xy 257.619219 -53.688554) (xy 257.656436 -53.730091)
			(xy 257.687209 -53.776604) (xy 257.710881 -53.827101) (xy 257.726949 -53.880508) (xy 257.735069 -53.935684)
			(xy 257.735578 -53.96357) (xy 257.735069 -53.991456) (xy 257.726949 -54.046632) (xy 257.710881 -54.100039)
			(xy 257.687209 -54.150536) (xy 257.656436 -54.197049) (xy 257.619219 -54.238586) (xy 257.576351 -54.274261)
			(xy 257.528745 -54.303315) (xy 257.477416 -54.325127) (xy 257.423459 -54.339233) (xy 257.368022 -54.345333)
			(xy 257.312288 -54.343296) (xy 257.257445 -54.333166) (xy 257.204661 -54.315159) (xy 257.155061 -54.289658)
			(xy 257.109703 -54.257207) (xy 257.069554 -54.218498) (xy 257.035468 -54.174355) (xy 257.008172 -54.12572)
			(xy 256.988249 -54.073629) (xy 256.976123 -54.019192) (xy 256.972052 -53.96357) (xy 253.309882 -53.96357)
			(xy 253.309882 -55.722266) (xy 258.034026 -55.722266) (xy 258.038097 -55.666644) (xy 258.050223 -55.612207)
			(xy 258.070146 -55.560116) (xy 258.097442 -55.511481) (xy 258.131528 -55.467338) (xy 258.171677 -55.428629)
			(xy 258.217035 -55.396178) (xy 258.266635 -55.370677) (xy 258.319419 -55.35267) (xy 258.374262 -55.34254)
			(xy 258.429996 -55.340503) (xy 258.485433 -55.346603) (xy 258.53939 -55.360709) (xy 258.590719 -55.382521)
			(xy 258.638325 -55.411575) (xy 258.681193 -55.44725) (xy 258.71841 -55.488787) (xy 258.749183 -55.5353)
			(xy 258.772855 -55.585797) (xy 258.788923 -55.639204) (xy 258.797043 -55.69438) (xy 258.797552 -55.722266)
			(xy 258.797043 -55.750152) (xy 258.788923 -55.805328) (xy 258.772855 -55.858735) (xy 258.749183 -55.909232)
			(xy 258.71841 -55.955745) (xy 258.681193 -55.997282) (xy 258.638325 -56.032957) (xy 258.590719 -56.062011)
			(xy 258.53939 -56.083823) (xy 258.485433 -56.097929) (xy 258.429996 -56.104029) (xy 258.374262 -56.101992)
			(xy 258.319419 -56.091862) (xy 258.266635 -56.073855) (xy 258.217035 -56.048354) (xy 258.171677 -56.015903)
			(xy 258.131528 -55.977194) (xy 258.097442 -55.933051) (xy 258.070146 -55.884416) (xy 258.050223 -55.832325)
			(xy 258.038097 -55.777888) (xy 258.034026 -55.722266) (xy 253.309882 -55.722266) (xy 253.309882 -58.072274)
			(xy 258.193538 -58.072274) (xy 258.197609 -58.016652) (xy 258.209735 -57.962215) (xy 258.229658 -57.910124)
			(xy 258.256954 -57.861489) (xy 258.29104 -57.817346) (xy 258.331189 -57.778637) (xy 258.376547 -57.746186)
			(xy 258.426147 -57.720685) (xy 258.478931 -57.702678) (xy 258.533774 -57.692548) (xy 258.589508 -57.690511)
			(xy 258.644945 -57.696611) (xy 258.698902 -57.710717) (xy 258.750231 -57.732529) (xy 258.797837 -57.761583)
			(xy 258.840705 -57.797258) (xy 258.877922 -57.838795) (xy 258.908695 -57.885308) (xy 258.932367 -57.935805)
			(xy 258.948435 -57.989212) (xy 258.956555 -58.044388) (xy 258.957064 -58.072274) (xy 258.956555 -58.10016)
			(xy 258.948435 -58.155336) (xy 258.932367 -58.208743) (xy 258.908695 -58.25924) (xy 258.877922 -58.305753)
			(xy 258.840705 -58.34729) (xy 258.797837 -58.382965) (xy 258.750231 -58.412019) (xy 258.698902 -58.433831)
			(xy 258.644945 -58.447937) (xy 258.589508 -58.454037) (xy 258.533774 -58.452) (xy 258.478931 -58.44187)
			(xy 258.426147 -58.423863) (xy 258.376547 -58.398362) (xy 258.331189 -58.365911) (xy 258.29104 -58.327202)
			(xy 258.256954 -58.283059) (xy 258.229658 -58.234424) (xy 258.209735 -58.182333) (xy 258.197609 -58.127896)
			(xy 258.193538 -58.072274) (xy 253.309882 -58.072274) (xy 253.309882 -64.797178) (xy 253.310304 -64.80693)
			(xy 253.317579 -64.825025) (xy 253.331112 -64.839068) (xy 253.339854 -64.843406) (xy 253.42215 -64.880744)
			(xy 253.432698 -64.884764) (xy 253.455238 -64.884242) (xy 253.465584 -64.879728) (xy 253.478284 -64.873378)
			(xy 253.48311 -64.869568) (xy 253.503898 -64.852432) (xy 253.54939 -64.823573) (xy 253.598494 -64.801414)
			(xy 253.650232 -64.786396) (xy 253.703569 -64.778819) (xy 253.730506 -64.778382) (xy 253.757758 -64.778868)
			(xy 253.811706 -64.786626) (xy 253.864002 -64.801982) (xy 253.913579 -64.824624) (xy 253.95943 -64.854091)
			(xy 254.000621 -64.889783) (xy 254.036313 -64.930975) (xy 254.065779 -64.976826) (xy 254.08842 -65.026404)
			(xy 254.103776 -65.0787) (xy 254.111532 -65.132648) (xy 254.111532 -65.187152) (xy 254.103776 -65.2411)
			(xy 254.08842 -65.293396) (xy 254.065779 -65.342974) (xy 254.036313 -65.388825) (xy 254.000621 -65.430017)
			(xy 253.95943 -65.465709) (xy 253.913579 -65.495176) (xy 253.864002 -65.517818) (xy 253.811706 -65.533174)
			(xy 253.757758 -65.540932) (xy 253.730506 -65.541398) (xy 253.703575 -65.540909) (xy 253.650255 -65.533292)
			(xy 253.598531 -65.518264) (xy 253.54943 -65.496124) (xy 253.503924 -65.467308) (xy 253.48311 -65.450212)
			(xy 253.478284 -65.446402) (xy 253.465584 -65.440052) (xy 253.455242 -65.435512) (xy 253.432693 -65.434985)
			(xy 253.42215 -65.439036) (xy 253.339854 -65.476374) (xy 253.331167 -65.480783) (xy 253.317691 -65.494827)
			(xy 253.310393 -65.512872) (xy 253.309882 -65.522602) (xy 253.309882 -67.592956) (xy 253.545338 -67.592956)
			(xy 253.549409 -67.537334) (xy 253.561535 -67.482897) (xy 253.581458 -67.430806) (xy 253.608754 -67.382171)
			(xy 253.64284 -67.338028) (xy 253.682989 -67.299319) (xy 253.728347 -67.266868) (xy 253.777947 -67.241367)
			(xy 253.830731 -67.22336) (xy 253.885574 -67.21323) (xy 253.941308 -67.211193) (xy 253.996745 -67.217293)
			(xy 254.050702 -67.231399) (xy 254.102031 -67.253211) (xy 254.149637 -67.282265) (xy 254.192505 -67.31794)
			(xy 254.229722 -67.359477) (xy 254.260495 -67.40599) (xy 254.284167 -67.456487) (xy 254.300235 -67.509894)
			(xy 254.308355 -67.56507) (xy 254.308864 -67.592956) (xy 254.308355 -67.620842) (xy 254.300235 -67.676018)
			(xy 254.284167 -67.729425) (xy 254.260495 -67.779922) (xy 254.229722 -67.826435) (xy 254.192505 -67.867972)
			(xy 254.149637 -67.903647) (xy 254.102031 -67.932701) (xy 254.050702 -67.954513) (xy 253.996745 -67.968619)
			(xy 253.941308 -67.974719) (xy 253.885574 -67.972682) (xy 253.830731 -67.962552) (xy 253.777947 -67.944545)
			(xy 253.728347 -67.919044) (xy 253.682989 -67.886593) (xy 253.64284 -67.847884) (xy 253.608754 -67.803741)
			(xy 253.581458 -67.755106) (xy 253.561535 -67.703015) (xy 253.549409 -67.648578) (xy 253.545338 -67.592956)
			(xy 253.309882 -67.592956) (xy 253.309882 -70.035928) (xy 253.310374 -70.045933) (xy 253.318038 -70.064419)
			(xy 253.33219 -70.078567) (xy 253.350677 -70.086228) (xy 253.360682 -70.086728) (xy 258.932172 -70.086728)
		)
		(stroke
			(width 0)
			(type solid)
		)
		(fill yes)
		(layer "In9.Cu")
		(net "P12V_AUX")
	)
	(gr_poly
		(pts
			(xy 284.950916 -70.079108) (xy 284.958028 -70.071742) (xy 285.113222 -69.916548) (xy 285.120069 -69.909151)
			(xy 285.127797 -69.890551) (xy 285.128208 -69.88048) (xy 285.128208 -52.07508) (xy 285.120588 -52.056284)
			(xy 285.113222 -52.049172) (xy 284.726888 -51.662838) (xy 284.719491 -51.655989) (xy 284.700892 -51.648253)
			(xy 284.69082 -51.647852) (xy 279.390602 -51.647852) (xy 279.371806 -51.655472) (xy 279.364694 -51.662838)
			(xy 279.324562 -51.70297) (xy 279.317877 -51.71038) (xy 279.31029 -51.728815) (xy 279.30983 -51.738784)
			(xy 279.30983 -52.033932) (xy 279.310277 -52.044088) (xy 279.318138 -52.062818) (xy 279.32507 -52.070254)
			(xy 279.384506 -52.12842) (xy 279.403302 -52.135786) (xy 279.413462 -52.135532) (xy 279.422098 -52.135532)
			(xy 279.449348 -52.135995) (xy 279.503294 -52.143751) (xy 279.555586 -52.159105) (xy 279.605161 -52.181745)
			(xy 279.65101 -52.21121) (xy 279.692199 -52.2469) (xy 279.727889 -52.288088) (xy 279.757354 -52.333937)
			(xy 279.779994 -52.383512) (xy 279.795349 -52.435804) (xy 279.803105 -52.48975) (xy 279.803105 -52.54425)
			(xy 279.796901 -52.587398) (xy 282.955236 -52.587398) (xy 282.959307 -52.531776) (xy 282.971433 -52.477339)
			(xy 282.991356 -52.425248) (xy 283.018652 -52.376613) (xy 283.052738 -52.33247) (xy 283.092887 -52.293761)
			(xy 283.138245 -52.26131) (xy 283.187845 -52.235809) (xy 283.240629 -52.217802) (xy 283.295472 -52.207672)
			(xy 283.351206 -52.205635) (xy 283.406643 -52.211735) (xy 283.4606 -52.225841) (xy 283.511929 -52.247653)
			(xy 283.559535 -52.276707) (xy 283.602403 -52.312382) (xy 283.63962 -52.353919) (xy 283.670393 -52.400432)
			(xy 283.694065 -52.450929) (xy 283.710133 -52.504336) (xy 283.718253 -52.559512) (xy 283.718762 -52.587398)
			(xy 283.718253 -52.615284) (xy 283.710133 -52.67046) (xy 283.694065 -52.723867) (xy 283.670393 -52.774364)
			(xy 283.63962 -52.820877) (xy 283.602403 -52.862414) (xy 283.559535 -52.898089) (xy 283.511929 -52.927143)
			(xy 283.4606 -52.948955) (xy 283.406643 -52.963061) (xy 283.351206 -52.969161) (xy 283.295472 -52.967124)
			(xy 283.240629 -52.956994) (xy 283.187845 -52.938987) (xy 283.138245 -52.913486) (xy 283.092887 -52.881035)
			(xy 283.052738 -52.842326) (xy 283.018652 -52.798183) (xy 282.991356 -52.749548) (xy 282.971433 -52.697457)
			(xy 282.959307 -52.64302) (xy 282.955236 -52.587398) (xy 279.796901 -52.587398) (xy 279.795349 -52.598196)
			(xy 279.779994 -52.650488) (xy 279.757354 -52.700063) (xy 279.727889 -52.745912) (xy 279.692199 -52.7871)
			(xy 279.65101 -52.82279) (xy 279.605161 -52.852255) (xy 279.555586 -52.874895) (xy 279.503294 -52.890249)
			(xy 279.449348 -52.898005) (xy 279.422098 -52.898548) (xy 279.413462 -52.898548) (xy 279.403302 -52.898294)
			(xy 279.384506 -52.90566) (xy 279.32507 -52.963826) (xy 279.318167 -52.971202) (xy 279.310326 -52.989802)
			(xy 279.30983 -52.999894) (xy 279.30983 -53.96357) (xy 282.972 -53.96357) (xy 282.976071 -53.907948)
			(xy 282.988197 -53.853511) (xy 283.00812 -53.80142) (xy 283.035416 -53.752785) (xy 283.069502 -53.708642)
			(xy 283.109651 -53.669933) (xy 283.155009 -53.637482) (xy 283.204609 -53.611981) (xy 283.257393 -53.593974)
			(xy 283.312236 -53.583844) (xy 283.36797 -53.581807) (xy 283.423407 -53.587907) (xy 283.477364 -53.602013)
			(xy 283.528693 -53.623825) (xy 283.576299 -53.652879) (xy 283.619167 -53.688554) (xy 283.656384 -53.730091)
			(xy 283.687157 -53.776604) (xy 283.710829 -53.827101) (xy 283.726897 -53.880508) (xy 283.735017 -53.935684)
			(xy 283.735526 -53.96357) (xy 283.735017 -53.991456) (xy 283.726897 -54.046632) (xy 283.710829 -54.100039)
			(xy 283.687157 -54.150536) (xy 283.656384 -54.197049) (xy 283.619167 -54.238586) (xy 283.576299 -54.274261)
			(xy 283.528693 -54.303315) (xy 283.477364 -54.325127) (xy 283.423407 -54.339233) (xy 283.36797 -54.345333)
			(xy 283.312236 -54.343296) (xy 283.257393 -54.333166) (xy 283.204609 -54.315159) (xy 283.155009 -54.289658)
			(xy 283.109651 -54.257207) (xy 283.069502 -54.218498) (xy 283.035416 -54.174355) (xy 283.00812 -54.12572)
			(xy 282.988197 -54.073629) (xy 282.976071 -54.019192) (xy 282.972 -53.96357) (xy 279.30983 -53.96357)
			(xy 279.30983 -55.722266) (xy 284.033974 -55.722266) (xy 284.038045 -55.666644) (xy 284.050171 -55.612207)
			(xy 284.070094 -55.560116) (xy 284.09739 -55.511481) (xy 284.131476 -55.467338) (xy 284.171625 -55.428629)
			(xy 284.216983 -55.396178) (xy 284.266583 -55.370677) (xy 284.319367 -55.35267) (xy 284.37421 -55.34254)
			(xy 284.429944 -55.340503) (xy 284.485381 -55.346603) (xy 284.539338 -55.360709) (xy 284.590667 -55.382521)
			(xy 284.638273 -55.411575) (xy 284.681141 -55.44725) (xy 284.718358 -55.488787) (xy 284.749131 -55.5353)
			(xy 284.772803 -55.585797) (xy 284.788871 -55.639204) (xy 284.796991 -55.69438) (xy 284.7975 -55.722266)
			(xy 284.796991 -55.750152) (xy 284.788871 -55.805328) (xy 284.772803 -55.858735) (xy 284.749131 -55.909232)
			(xy 284.718358 -55.955745) (xy 284.681141 -55.997282) (xy 284.638273 -56.032957) (xy 284.590667 -56.062011)
			(xy 284.539338 -56.083823) (xy 284.485381 -56.097929) (xy 284.429944 -56.104029) (xy 284.37421 -56.101992)
			(xy 284.319367 -56.091862) (xy 284.266583 -56.073855) (xy 284.216983 -56.048354) (xy 284.171625 -56.015903)
			(xy 284.131476 -55.977194) (xy 284.09739 -55.933051) (xy 284.070094 -55.884416) (xy 284.050171 -55.832325)
			(xy 284.038045 -55.777888) (xy 284.033974 -55.722266) (xy 279.30983 -55.722266) (xy 279.30983 -58.072274)
			(xy 284.193486 -58.072274) (xy 284.197557 -58.016652) (xy 284.209683 -57.962215) (xy 284.229606 -57.910124)
			(xy 284.256902 -57.861489) (xy 284.290988 -57.817346) (xy 284.331137 -57.778637) (xy 284.376495 -57.746186)
			(xy 284.426095 -57.720685) (xy 284.478879 -57.702678) (xy 284.533722 -57.692548) (xy 284.589456 -57.690511)
			(xy 284.644893 -57.696611) (xy 284.69885 -57.710717) (xy 284.750179 -57.732529) (xy 284.797785 -57.761583)
			(xy 284.840653 -57.797258) (xy 284.87787 -57.838795) (xy 284.908643 -57.885308) (xy 284.932315 -57.935805)
			(xy 284.948383 -57.989212) (xy 284.956503 -58.044388) (xy 284.957012 -58.072274) (xy 284.956503 -58.10016)
			(xy 284.948383 -58.155336) (xy 284.932315 -58.208743) (xy 284.908643 -58.25924) (xy 284.87787 -58.305753)
			(xy 284.840653 -58.34729) (xy 284.797785 -58.382965) (xy 284.750179 -58.412019) (xy 284.69885 -58.433831)
			(xy 284.644893 -58.447937) (xy 284.589456 -58.454037) (xy 284.533722 -58.452) (xy 284.478879 -58.44187)
			(xy 284.426095 -58.423863) (xy 284.376495 -58.398362) (xy 284.331137 -58.365911) (xy 284.290988 -58.327202)
			(xy 284.256902 -58.283059) (xy 284.229606 -58.234424) (xy 284.209683 -58.182333) (xy 284.197557 -58.127896)
			(xy 284.193486 -58.072274) (xy 279.30983 -58.072274) (xy 279.30983 -64.797178) (xy 279.310253 -64.806928)
			(xy 279.317531 -64.825017) (xy 279.33107 -64.839049) (xy 279.339802 -64.843406) (xy 279.422098 -64.880744)
			(xy 279.432645 -64.884753) (xy 279.455176 -64.884213) (xy 279.465532 -64.879728) (xy 279.478232 -64.873378)
			(xy 279.483058 -64.869568) (xy 279.503847 -64.852435) (xy 279.54934 -64.823582) (xy 279.598445 -64.801429)
			(xy 279.650182 -64.786417) (xy 279.703518 -64.778846) (xy 279.730454 -64.778382) (xy 279.75771 -64.778842)
			(xy 279.811667 -64.786594) (xy 279.863972 -64.801946) (xy 279.913559 -64.824587) (xy 279.959419 -64.854054)
			(xy 280.000619 -64.889749) (xy 280.036318 -64.930944) (xy 280.065791 -64.9768) (xy 280.088438 -65.026385)
			(xy 280.103797 -65.078688) (xy 280.111555 -65.132644) (xy 280.111555 -65.187156) (xy 280.103797 -65.241112)
			(xy 280.088438 -65.293415) (xy 280.065791 -65.343) (xy 280.036318 -65.388856) (xy 280.000619 -65.430051)
			(xy 279.959419 -65.465746) (xy 279.913559 -65.495213) (xy 279.863972 -65.517854) (xy 279.811667 -65.533206)
			(xy 279.75771 -65.540958) (xy 279.730454 -65.541398) (xy 279.703522 -65.540913) (xy 279.650198 -65.533302)
			(xy 279.598471 -65.518279) (xy 279.549366 -65.496142) (xy 279.503855 -65.467331) (xy 279.483058 -65.450212)
			(xy 279.478232 -65.446402) (xy 279.465532 -65.440052) (xy 279.45519 -65.435502) (xy 279.432632 -65.434955)
			(xy 279.422098 -65.439036) (xy 279.339802 -65.476374) (xy 279.331109 -65.480778) (xy 279.31762 -65.49482)
			(xy 279.310315 -65.512868) (xy 279.30983 -65.522602) (xy 279.30983 -67.592956) (xy 279.545286 -67.592956)
			(xy 279.549357 -67.537334) (xy 279.561483 -67.482897) (xy 279.581406 -67.430806) (xy 279.608702 -67.382171)
			(xy 279.642788 -67.338028) (xy 279.682937 -67.299319) (xy 279.728295 -67.266868) (xy 279.777895 -67.241367)
			(xy 279.830679 -67.22336) (xy 279.885522 -67.21323) (xy 279.941256 -67.211193) (xy 279.996693 -67.217293)
			(xy 280.05065 -67.231399) (xy 280.101979 -67.253211) (xy 280.149585 -67.282265) (xy 280.192453 -67.31794)
			(xy 280.22967 -67.359477) (xy 280.260443 -67.40599) (xy 280.284115 -67.456487) (xy 280.300183 -67.509894)
			(xy 280.308303 -67.56507) (xy 280.308812 -67.592956) (xy 280.308303 -67.620842) (xy 280.300183 -67.676018)
			(xy 280.284115 -67.729425) (xy 280.260443 -67.779922) (xy 280.22967 -67.826435) (xy 280.192453 -67.867972)
			(xy 280.149585 -67.903647) (xy 280.101979 -67.932701) (xy 280.05065 -67.954513) (xy 279.996693 -67.968619)
			(xy 279.941256 -67.974719) (xy 279.885522 -67.972682) (xy 279.830679 -67.962552) (xy 279.777895 -67.944545)
			(xy 279.728295 -67.919044) (xy 279.682937 -67.886593) (xy 279.642788 -67.847884) (xy 279.608702 -67.803741)
			(xy 279.581406 -67.755106) (xy 279.561483 -67.703015) (xy 279.549357 -67.648578) (xy 279.545286 -67.592956)
			(xy 279.30983 -67.592956) (xy 279.30983 -70.035928) (xy 279.310255 -70.045943) (xy 279.317931 -70.064445)
			(xy 279.332103 -70.078602) (xy 279.350614 -70.086256) (xy 279.36063 -70.086728) (xy 284.93212 -70.086728)
		)
		(stroke
			(width 0)
			(type solid)
		)
		(fill yes)
		(layer "In9.Cu")
		(net "P12V_AUX")
	)
	(gr_poly
		(pts
			(xy 310.950864 -70.079108) (xy 310.957976 -70.071742) (xy 311.11317 -69.916548) (xy 311.120011 -69.909148)
			(xy 311.127732 -69.89055) (xy 311.128156 -69.88048) (xy 311.128156 -52.07508) (xy 311.120536 -52.056284)
			(xy 311.11317 -52.049172) (xy 310.726836 -51.662838) (xy 310.719436 -51.655998) (xy 310.700837 -51.64828)
			(xy 310.690768 -51.647852) (xy 305.39055 -51.647852) (xy 305.371754 -51.655472) (xy 305.364642 -51.662838)
			(xy 305.32451 -51.70297) (xy 305.31782 -51.710378) (xy 305.310226 -51.728814) (xy 305.309778 -51.738784)
			(xy 305.309778 -52.033932) (xy 305.310224 -52.044089) (xy 305.318079 -52.062824) (xy 305.325018 -52.070254)
			(xy 305.384454 -52.12842) (xy 305.40325 -52.135786) (xy 305.41341 -52.135532) (xy 305.422046 -52.135532)
			(xy 305.449292 -52.136021) (xy 305.503229 -52.143782) (xy 305.555513 -52.15914) (xy 305.605079 -52.181781)
			(xy 305.650919 -52.211246) (xy 305.692099 -52.246933) (xy 305.727782 -52.288118) (xy 305.757241 -52.333961)
			(xy 305.779876 -52.38353) (xy 305.795227 -52.435816) (xy 305.802982 -52.489754) (xy 305.802982 -52.544246)
			(xy 305.796778 -52.587398) (xy 308.955184 -52.587398) (xy 308.959255 -52.531776) (xy 308.971381 -52.477339)
			(xy 308.991304 -52.425248) (xy 309.0186 -52.376613) (xy 309.052686 -52.33247) (xy 309.092835 -52.293761)
			(xy 309.138193 -52.26131) (xy 309.187793 -52.235809) (xy 309.240577 -52.217802) (xy 309.29542 -52.207672)
			(xy 309.351154 -52.205635) (xy 309.406591 -52.211735) (xy 309.460548 -52.225841) (xy 309.511877 -52.247653)
			(xy 309.559483 -52.276707) (xy 309.602351 -52.312382) (xy 309.639568 -52.353919) (xy 309.670341 -52.400432)
			(xy 309.694013 -52.450929) (xy 309.710081 -52.504336) (xy 309.718201 -52.559512) (xy 309.71871 -52.587398)
			(xy 309.718201 -52.615284) (xy 309.710081 -52.67046) (xy 309.694013 -52.723867) (xy 309.670341 -52.774364)
			(xy 309.639568 -52.820877) (xy 309.602351 -52.862414) (xy 309.559483 -52.898089) (xy 309.511877 -52.927143)
			(xy 309.460548 -52.948955) (xy 309.406591 -52.963061) (xy 309.351154 -52.969161) (xy 309.29542 -52.967124)
			(xy 309.240577 -52.956994) (xy 309.187793 -52.938987) (xy 309.138193 -52.913486) (xy 309.092835 -52.881035)
			(xy 309.052686 -52.842326) (xy 309.0186 -52.798183) (xy 308.991304 -52.749548) (xy 308.971381 -52.697457)
			(xy 308.959255 -52.64302) (xy 308.955184 -52.587398) (xy 305.796778 -52.587398) (xy 305.795227 -52.598184)
			(xy 305.779876 -52.65047) (xy 305.757241 -52.700039) (xy 305.727782 -52.745882) (xy 305.692099 -52.787067)
			(xy 305.650919 -52.822754) (xy 305.605079 -52.852219) (xy 305.555513 -52.87486) (xy 305.503229 -52.890218)
			(xy 305.449292 -52.897979) (xy 305.422046 -52.898548) (xy 305.41341 -52.898548) (xy 305.40325 -52.898294)
			(xy 305.384454 -52.90566) (xy 305.325018 -52.963826) (xy 305.31811 -52.971199) (xy 305.310261 -52.9898)
			(xy 305.309778 -52.999894) (xy 305.309778 -53.96357) (xy 308.971948 -53.96357) (xy 308.976019 -53.907948)
			(xy 308.988145 -53.853511) (xy 309.008068 -53.80142) (xy 309.035364 -53.752785) (xy 309.06945 -53.708642)
			(xy 309.109599 -53.669933) (xy 309.154957 -53.637482) (xy 309.204557 -53.611981) (xy 309.257341 -53.593974)
			(xy 309.312184 -53.583844) (xy 309.367918 -53.581807) (xy 309.423355 -53.587907) (xy 309.477312 -53.602013)
			(xy 309.528641 -53.623825) (xy 309.576247 -53.652879) (xy 309.619115 -53.688554) (xy 309.656332 -53.730091)
			(xy 309.687105 -53.776604) (xy 309.710777 -53.827101) (xy 309.726845 -53.880508) (xy 309.734965 -53.935684)
			(xy 309.735474 -53.96357) (xy 309.734965 -53.991456) (xy 309.726845 -54.046632) (xy 309.710777 -54.100039)
			(xy 309.687105 -54.150536) (xy 309.656332 -54.197049) (xy 309.619115 -54.238586) (xy 309.576247 -54.274261)
			(xy 309.528641 -54.303315) (xy 309.477312 -54.325127) (xy 309.423355 -54.339233) (xy 309.367918 -54.345333)
			(xy 309.312184 -54.343296) (xy 309.257341 -54.333166) (xy 309.204557 -54.315159) (xy 309.154957 -54.289658)
			(xy 309.109599 -54.257207) (xy 309.06945 -54.218498) (xy 309.035364 -54.174355) (xy 309.008068 -54.12572)
			(xy 308.988145 -54.073629) (xy 308.976019 -54.019192) (xy 308.971948 -53.96357) (xy 305.309778 -53.96357)
			(xy 305.309778 -55.722266) (xy 310.033922 -55.722266) (xy 310.037993 -55.666644) (xy 310.050119 -55.612207)
			(xy 310.070042 -55.560116) (xy 310.097338 -55.511481) (xy 310.131424 -55.467338) (xy 310.171573 -55.428629)
			(xy 310.216931 -55.396178) (xy 310.266531 -55.370677) (xy 310.319315 -55.35267) (xy 310.374158 -55.34254)
			(xy 310.429892 -55.340503) (xy 310.485329 -55.346603) (xy 310.539286 -55.360709) (xy 310.590615 -55.382521)
			(xy 310.638221 -55.411575) (xy 310.681089 -55.44725) (xy 310.718306 -55.488787) (xy 310.749079 -55.5353)
			(xy 310.772751 -55.585797) (xy 310.788819 -55.639204) (xy 310.796939 -55.69438) (xy 310.797448 -55.722266)
			(xy 310.796939 -55.750152) (xy 310.788819 -55.805328) (xy 310.772751 -55.858735) (xy 310.749079 -55.909232)
			(xy 310.718306 -55.955745) (xy 310.681089 -55.997282) (xy 310.638221 -56.032957) (xy 310.590615 -56.062011)
			(xy 310.539286 -56.083823) (xy 310.485329 -56.097929) (xy 310.429892 -56.104029) (xy 310.374158 -56.101992)
			(xy 310.319315 -56.091862) (xy 310.266531 -56.073855) (xy 310.216931 -56.048354) (xy 310.171573 -56.015903)
			(xy 310.131424 -55.977194) (xy 310.097338 -55.933051) (xy 310.070042 -55.884416) (xy 310.050119 -55.832325)
			(xy 310.037993 -55.777888) (xy 310.033922 -55.722266) (xy 305.309778 -55.722266) (xy 305.309778 -58.072274)
			(xy 310.193434 -58.072274) (xy 310.197505 -58.016652) (xy 310.209631 -57.962215) (xy 310.229554 -57.910124)
			(xy 310.25685 -57.861489) (xy 310.290936 -57.817346) (xy 310.331085 -57.778637) (xy 310.376443 -57.746186)
			(xy 310.426043 -57.720685) (xy 310.478827 -57.702678) (xy 310.53367 -57.692548) (xy 310.589404 -57.690511)
			(xy 310.644841 -57.696611) (xy 310.698798 -57.710717) (xy 310.750127 -57.732529) (xy 310.797733 -57.761583)
			(xy 310.840601 -57.797258) (xy 310.877818 -57.838795) (xy 310.908591 -57.885308) (xy 310.932263 -57.935805)
			(xy 310.948331 -57.989212) (xy 310.956451 -58.044388) (xy 310.95696 -58.072274) (xy 310.956451 -58.10016)
			(xy 310.948331 -58.155336) (xy 310.932263 -58.208743) (xy 310.908591 -58.25924) (xy 310.877818 -58.305753)
			(xy 310.840601 -58.34729) (xy 310.797733 -58.382965) (xy 310.750127 -58.412019) (xy 310.698798 -58.433831)
			(xy 310.644841 -58.447937) (xy 310.589404 -58.454037) (xy 310.53367 -58.452) (xy 310.478827 -58.44187)
			(xy 310.426043 -58.423863) (xy 310.376443 -58.398362) (xy 310.331085 -58.365911) (xy 310.290936 -58.327202)
			(xy 310.25685 -58.283059) (xy 310.229554 -58.234424) (xy 310.209631 -58.182333) (xy 310.197505 -58.127896)
			(xy 310.193434 -58.072274) (xy 305.309778 -58.072274) (xy 305.309778 -64.797178) (xy 305.3102 -64.80693)
			(xy 305.317474 -64.825026) (xy 305.331007 -64.839069) (xy 305.33975 -64.843406) (xy 305.422046 -64.880744)
			(xy 305.432594 -64.884765) (xy 305.455135 -64.884245) (xy 305.46548 -64.879728) (xy 305.47818 -64.873378)
			(xy 305.483006 -64.869568) (xy 305.503794 -64.852432) (xy 305.549286 -64.823573) (xy 305.59839 -64.801413)
			(xy 305.650128 -64.786394) (xy 305.703465 -64.778816) (xy 305.730402 -64.778382) (xy 305.757654 -64.778868)
			(xy 305.811603 -64.786625) (xy 305.863899 -64.801981) (xy 305.913477 -64.824622) (xy 305.959328 -64.85409)
			(xy 306.000519 -64.889782) (xy 306.036212 -64.930973) (xy 306.065679 -64.976825) (xy 306.08832 -65.026403)
			(xy 306.103676 -65.078699) (xy 306.111432 -65.132648) (xy 306.111432 -65.187152) (xy 306.103676 -65.241101)
			(xy 306.08832 -65.293397) (xy 306.065679 -65.342975) (xy 306.036212 -65.388827) (xy 306.000519 -65.430018)
			(xy 305.959328 -65.46571) (xy 305.913477 -65.495178) (xy 305.863899 -65.517819) (xy 305.811603 -65.533175)
			(xy 305.757654 -65.540932) (xy 305.730402 -65.541398) (xy 305.703472 -65.540909) (xy 305.650151 -65.533292)
			(xy 305.598428 -65.518263) (xy 305.549327 -65.496122) (xy 305.503822 -65.467306) (xy 305.483006 -65.450212)
			(xy 305.47818 -65.446402) (xy 305.46548 -65.440052) (xy 305.455138 -65.435514) (xy 305.43259 -65.434988)
			(xy 305.422046 -65.439036) (xy 305.33975 -65.476374) (xy 305.331064 -65.480783) (xy 305.317589 -65.494828)
			(xy 305.310292 -65.512872) (xy 305.309778 -65.522602) (xy 305.309778 -67.592956) (xy 305.545234 -67.592956)
			(xy 305.549305 -67.537334) (xy 305.561431 -67.482897) (xy 305.581354 -67.430806) (xy 305.60865 -67.382171)
			(xy 305.642736 -67.338028) (xy 305.682885 -67.299319) (xy 305.728243 -67.266868) (xy 305.777843 -67.241367)
			(xy 305.830627 -67.22336) (xy 305.88547 -67.21323) (xy 305.941204 -67.211193) (xy 305.996641 -67.217293)
			(xy 306.050598 -67.231399) (xy 306.101927 -67.253211) (xy 306.149533 -67.282265) (xy 306.192401 -67.31794)
			(xy 306.229618 -67.359477) (xy 306.260391 -67.40599) (xy 306.284063 -67.456487) (xy 306.300131 -67.509894)
			(xy 306.308251 -67.56507) (xy 306.30876 -67.592956) (xy 306.308251 -67.620842) (xy 306.300131 -67.676018)
			(xy 306.284063 -67.729425) (xy 306.260391 -67.779922) (xy 306.229618 -67.826435) (xy 306.192401 -67.867972)
			(xy 306.149533 -67.903647) (xy 306.101927 -67.932701) (xy 306.050598 -67.954513) (xy 305.996641 -67.968619)
			(xy 305.941204 -67.974719) (xy 305.88547 -67.972682) (xy 305.830627 -67.962552) (xy 305.777843 -67.944545)
			(xy 305.728243 -67.919044) (xy 305.682885 -67.886593) (xy 305.642736 -67.847884) (xy 305.60865 -67.803741)
			(xy 305.581354 -67.755106) (xy 305.561431 -67.703015) (xy 305.549305 -67.648578) (xy 305.545234 -67.592956)
			(xy 305.309778 -67.592956) (xy 305.309778 -70.035928) (xy 305.31027 -70.045934) (xy 305.317934 -70.06442)
			(xy 305.332085 -70.078569) (xy 305.350572 -70.086231) (xy 305.360578 -70.086728) (xy 310.932068 -70.086728)
		)
		(stroke
			(width 0)
			(type solid)
		)
		(fill yes)
		(layer "In9.Cu")
		(net "P12V_AUX")
	)
	(gr_poly
		(pts
			(xy 336.950812 -70.079108) (xy 336.957924 -70.071742) (xy 337.113118 -69.916548) (xy 337.119965 -69.909151)
			(xy 337.127694 -69.890552) (xy 337.128104 -69.88048) (xy 337.128104 -52.07508) (xy 337.120484 -52.056284)
			(xy 337.113118 -52.049172) (xy 336.726784 -51.662838) (xy 336.719386 -51.65599) (xy 336.700788 -51.648255)
			(xy 336.690716 -51.647852) (xy 331.390498 -51.647852) (xy 331.371702 -51.655472) (xy 331.36459 -51.662838)
			(xy 331.324458 -51.70297) (xy 331.317774 -51.71038) (xy 331.310187 -51.728816) (xy 331.309726 -51.738784)
			(xy 331.309726 -52.033932) (xy 331.310173 -52.044088) (xy 331.318033 -52.062819) (xy 331.324966 -52.070254)
			(xy 331.384402 -52.12842) (xy 331.403198 -52.135786) (xy 331.413358 -52.135532) (xy 331.421994 -52.135532)
			(xy 331.449244 -52.135995) (xy 331.50319 -52.14375) (xy 331.555483 -52.159104) (xy 331.605059 -52.181744)
			(xy 331.650908 -52.211209) (xy 331.692097 -52.246899) (xy 331.727788 -52.288087) (xy 331.757253 -52.333936)
			(xy 331.779894 -52.383511) (xy 331.795248 -52.435804) (xy 331.803005 -52.48975) (xy 331.803005 -52.54425)
			(xy 331.796801 -52.587398) (xy 334.955132 -52.587398) (xy 334.959203 -52.531776) (xy 334.971329 -52.477339)
			(xy 334.991252 -52.425248) (xy 335.018548 -52.376613) (xy 335.052634 -52.33247) (xy 335.092783 -52.293761)
			(xy 335.138141 -52.26131) (xy 335.187741 -52.235809) (xy 335.240525 -52.217802) (xy 335.295368 -52.207672)
			(xy 335.351102 -52.205635) (xy 335.406539 -52.211735) (xy 335.460496 -52.225841) (xy 335.511825 -52.247653)
			(xy 335.559431 -52.276707) (xy 335.602299 -52.312382) (xy 335.639516 -52.353919) (xy 335.670289 -52.400432)
			(xy 335.693961 -52.450929) (xy 335.710029 -52.504336) (xy 335.718149 -52.559512) (xy 335.718658 -52.587398)
			(xy 335.718149 -52.615284) (xy 335.710029 -52.67046) (xy 335.693961 -52.723867) (xy 335.670289 -52.774364)
			(xy 335.639516 -52.820877) (xy 335.602299 -52.862414) (xy 335.559431 -52.898089) (xy 335.511825 -52.927143)
			(xy 335.460496 -52.948955) (xy 335.406539 -52.963061) (xy 335.351102 -52.969161) (xy 335.295368 -52.967124)
			(xy 335.240525 -52.956994) (xy 335.187741 -52.938987) (xy 335.138141 -52.913486) (xy 335.092783 -52.881035)
			(xy 335.052634 -52.842326) (xy 335.018548 -52.798183) (xy 334.991252 -52.749548) (xy 334.971329 -52.697457)
			(xy 334.959203 -52.64302) (xy 334.955132 -52.587398) (xy 331.796801 -52.587398) (xy 331.795248 -52.598196)
			(xy 331.779894 -52.650489) (xy 331.757253 -52.700064) (xy 331.727788 -52.745913) (xy 331.692097 -52.787101)
			(xy 331.650908 -52.822791) (xy 331.605059 -52.852256) (xy 331.555483 -52.874896) (xy 331.50319 -52.89025)
			(xy 331.449244 -52.898005) (xy 331.421994 -52.898548) (xy 331.413358 -52.898548) (xy 331.403198 -52.898294)
			(xy 331.384402 -52.90566) (xy 331.324966 -52.963826) (xy 331.318063 -52.971202) (xy 331.310223 -52.989802)
			(xy 331.309726 -52.999894) (xy 331.309726 -53.96357) (xy 334.971896 -53.96357) (xy 334.975967 -53.907948)
			(xy 334.988093 -53.853511) (xy 335.008016 -53.80142) (xy 335.035312 -53.752785) (xy 335.069398 -53.708642)
			(xy 335.109547 -53.669933) (xy 335.154905 -53.637482) (xy 335.204505 -53.611981) (xy 335.257289 -53.593974)
			(xy 335.312132 -53.583844) (xy 335.367866 -53.581807) (xy 335.423303 -53.587907) (xy 335.47726 -53.602013)
			(xy 335.528589 -53.623825) (xy 335.576195 -53.652879) (xy 335.619063 -53.688554) (xy 335.65628 -53.730091)
			(xy 335.687053 -53.776604) (xy 335.710725 -53.827101) (xy 335.726793 -53.880508) (xy 335.734913 -53.935684)
			(xy 335.735422 -53.96357) (xy 335.734913 -53.991456) (xy 335.726793 -54.046632) (xy 335.710725 -54.100039)
			(xy 335.687053 -54.150536) (xy 335.65628 -54.197049) (xy 335.619063 -54.238586) (xy 335.576195 -54.274261)
			(xy 335.528589 -54.303315) (xy 335.47726 -54.325127) (xy 335.423303 -54.339233) (xy 335.367866 -54.345333)
			(xy 335.312132 -54.343296) (xy 335.257289 -54.333166) (xy 335.204505 -54.315159) (xy 335.154905 -54.289658)
			(xy 335.109547 -54.257207) (xy 335.069398 -54.218498) (xy 335.035312 -54.174355) (xy 335.008016 -54.12572)
			(xy 334.988093 -54.073629) (xy 334.975967 -54.019192) (xy 334.971896 -53.96357) (xy 331.309726 -53.96357)
			(xy 331.309726 -55.722266) (xy 336.03387 -55.722266) (xy 336.037941 -55.666644) (xy 336.050067 -55.612207)
			(xy 336.06999 -55.560116) (xy 336.097286 -55.511481) (xy 336.131372 -55.467338) (xy 336.171521 -55.428629)
			(xy 336.216879 -55.396178) (xy 336.266479 -55.370677) (xy 336.319263 -55.35267) (xy 336.374106 -55.34254)
			(xy 336.42984 -55.340503) (xy 336.485277 -55.346603) (xy 336.539234 -55.360709) (xy 336.590563 -55.382521)
			(xy 336.638169 -55.411575) (xy 336.681037 -55.44725) (xy 336.718254 -55.488787) (xy 336.749027 -55.5353)
			(xy 336.772699 -55.585797) (xy 336.788767 -55.639204) (xy 336.796887 -55.69438) (xy 336.797396 -55.722266)
			(xy 336.796887 -55.750152) (xy 336.788767 -55.805328) (xy 336.772699 -55.858735) (xy 336.749027 -55.909232)
			(xy 336.718254 -55.955745) (xy 336.681037 -55.997282) (xy 336.638169 -56.032957) (xy 336.590563 -56.062011)
			(xy 336.539234 -56.083823) (xy 336.485277 -56.097929) (xy 336.42984 -56.104029) (xy 336.374106 -56.101992)
			(xy 336.319263 -56.091862) (xy 336.266479 -56.073855) (xy 336.216879 -56.048354) (xy 336.171521 -56.015903)
			(xy 336.131372 -55.977194) (xy 336.097286 -55.933051) (xy 336.06999 -55.884416) (xy 336.050067 -55.832325)
			(xy 336.037941 -55.777888) (xy 336.03387 -55.722266) (xy 331.309726 -55.722266) (xy 331.309726 -58.072274)
			(xy 336.193382 -58.072274) (xy 336.197453 -58.016652) (xy 336.209579 -57.962215) (xy 336.229502 -57.910124)
			(xy 336.256798 -57.861489) (xy 336.290884 -57.817346) (xy 336.331033 -57.778637) (xy 336.376391 -57.746186)
			(xy 336.425991 -57.720685) (xy 336.478775 -57.702678) (xy 336.533618 -57.692548) (xy 336.589352 -57.690511)
			(xy 336.644789 -57.696611) (xy 336.698746 -57.710717) (xy 336.750075 -57.732529) (xy 336.797681 -57.761583)
			(xy 336.840549 -57.797258) (xy 336.877766 -57.838795) (xy 336.908539 -57.885308) (xy 336.932211 -57.935805)
			(xy 336.948279 -57.989212) (xy 336.956399 -58.044388) (xy 336.956908 -58.072274) (xy 336.956399 -58.10016)
			(xy 336.948279 -58.155336) (xy 336.932211 -58.208743) (xy 336.908539 -58.25924) (xy 336.877766 -58.305753)
			(xy 336.840549 -58.34729) (xy 336.797681 -58.382965) (xy 336.750075 -58.412019) (xy 336.698746 -58.433831)
			(xy 336.644789 -58.447937) (xy 336.589352 -58.454037) (xy 336.533618 -58.452) (xy 336.478775 -58.44187)
			(xy 336.425991 -58.423863) (xy 336.376391 -58.398362) (xy 336.331033 -58.365911) (xy 336.290884 -58.327202)
			(xy 336.256798 -58.283059) (xy 336.229502 -58.234424) (xy 336.209579 -58.182333) (xy 336.197453 -58.127896)
			(xy 336.193382 -58.072274) (xy 331.309726 -58.072274) (xy 331.309726 -64.797178) (xy 331.310149 -64.806928)
			(xy 331.317427 -64.825018) (xy 331.330965 -64.839051) (xy 331.339698 -64.843406) (xy 331.421994 -64.880744)
			(xy 331.432542 -64.884754) (xy 331.455073 -64.884215) (xy 331.465428 -64.879728) (xy 331.478128 -64.873378)
			(xy 331.482954 -64.869568) (xy 331.503743 -64.852434) (xy 331.549236 -64.823581) (xy 331.598341 -64.801427)
			(xy 331.650078 -64.786415) (xy 331.703414 -64.778844) (xy 331.73035 -64.778382) (xy 331.757606 -64.778841)
			(xy 331.811564 -64.786593) (xy 331.863869 -64.801945) (xy 331.913457 -64.824585) (xy 331.959317 -64.854053)
			(xy 332.000517 -64.889747) (xy 332.036217 -64.930942) (xy 332.065691 -64.976799) (xy 332.088338 -65.026384)
			(xy 332.103697 -65.078687) (xy 332.111455 -65.132644) (xy 332.111455 -65.187156) (xy 332.103697 -65.241113)
			(xy 332.088338 -65.293416) (xy 332.065691 -65.343001) (xy 332.036217 -65.388858) (xy 332.000517 -65.430053)
			(xy 331.959317 -65.465747) (xy 331.913457 -65.495215) (xy 331.863869 -65.517855) (xy 331.811564 -65.533207)
			(xy 331.757606 -65.540959) (xy 331.73035 -65.541398) (xy 331.703418 -65.540912) (xy 331.650095 -65.533301)
			(xy 331.598368 -65.518278) (xy 331.549263 -65.496141) (xy 331.503752 -65.467329) (xy 331.482954 -65.450212)
			(xy 331.478128 -65.446402) (xy 331.465428 -65.440052) (xy 331.455086 -65.435503) (xy 331.432529 -65.434958)
			(xy 331.421994 -65.439036) (xy 331.339698 -65.476374) (xy 331.331006 -65.480779) (xy 331.317518 -65.49482)
			(xy 331.310213 -65.512869) (xy 331.309726 -65.522602) (xy 331.309726 -67.592956) (xy 331.545182 -67.592956)
			(xy 331.549253 -67.537334) (xy 331.561379 -67.482897) (xy 331.581302 -67.430806) (xy 331.608598 -67.382171)
			(xy 331.642684 -67.338028) (xy 331.682833 -67.299319) (xy 331.728191 -67.266868) (xy 331.777791 -67.241367)
			(xy 331.830575 -67.22336) (xy 331.885418 -67.21323) (xy 331.941152 -67.211193) (xy 331.996589 -67.217293)
			(xy 332.050546 -67.231399) (xy 332.101875 -67.253211) (xy 332.149481 -67.282265) (xy 332.192349 -67.31794)
			(xy 332.229566 -67.359477) (xy 332.260339 -67.40599) (xy 332.284011 -67.456487) (xy 332.300079 -67.509894)
			(xy 332.308199 -67.56507) (xy 332.308708 -67.592956) (xy 332.308199 -67.620842) (xy 332.300079 -67.676018)
			(xy 332.284011 -67.729425) (xy 332.260339 -67.779922) (xy 332.229566 -67.826435) (xy 332.192349 -67.867972)
			(xy 332.149481 -67.903647) (xy 332.101875 -67.932701) (xy 332.050546 -67.954513) (xy 331.996589 -67.968619)
			(xy 331.941152 -67.974719) (xy 331.885418 -67.972682) (xy 331.830575 -67.962552) (xy 331.777791 -67.944545)
			(xy 331.728191 -67.919044) (xy 331.682833 -67.886593) (xy 331.642684 -67.847884) (xy 331.608598 -67.803741)
			(xy 331.581302 -67.755106) (xy 331.561379 -67.703015) (xy 331.549253 -67.648578) (xy 331.545182 -67.592956)
			(xy 331.309726 -67.592956) (xy 331.309726 -70.035928) (xy 331.310219 -70.04593) (xy 331.317885 -70.064408)
			(xy 331.332038 -70.078546) (xy 331.350523 -70.086191) (xy 331.360526 -70.086728) (xy 336.932016 -70.086728)
		)
		(stroke
			(width 0)
			(type solid)
		)
		(fill yes)
		(layer "In9.Cu")
		(net "P12V_AUX")
	)
	(gr_poly
		(pts
			(xy 375.051066 -70.079108) (xy 375.058178 -70.071742) (xy 375.213372 -69.916548) (xy 375.220213 -69.909148)
			(xy 375.227933 -69.89055) (xy 375.228358 -69.88048) (xy 375.228358 -52.07508) (xy 375.220738 -52.056284)
			(xy 375.213372 -52.049172) (xy 374.827038 -51.662838) (xy 374.819638 -51.655997) (xy 374.801039 -51.648279)
			(xy 374.79097 -51.647852) (xy 369.490752 -51.647852) (xy 369.471956 -51.655472) (xy 369.464844 -51.662838)
			(xy 369.424712 -51.70297) (xy 369.418022 -51.710377) (xy 369.410427 -51.728814) (xy 369.40998 -51.738784)
			(xy 369.40998 -52.033932) (xy 369.410426 -52.044089) (xy 369.418281 -52.062824) (xy 369.42522 -52.070254)
			(xy 369.484656 -52.12842) (xy 369.503452 -52.135786) (xy 369.513612 -52.135532) (xy 369.522248 -52.135532)
			(xy 369.549494 -52.136021) (xy 369.603431 -52.143783) (xy 369.655714 -52.15914) (xy 369.70528 -52.181782)
			(xy 369.75112 -52.211246) (xy 369.7923 -52.246934) (xy 369.827983 -52.288119) (xy 369.857441 -52.333962)
			(xy 369.880076 -52.383531) (xy 369.895428 -52.435816) (xy 369.903182 -52.489754) (xy 369.903182 -52.544246)
			(xy 369.896979 -52.587398) (xy 373.055386 -52.587398) (xy 373.059457 -52.531776) (xy 373.071583 -52.477339)
			(xy 373.091506 -52.425248) (xy 373.118802 -52.376613) (xy 373.152888 -52.33247) (xy 373.193037 -52.293761)
			(xy 373.238395 -52.26131) (xy 373.287995 -52.235809) (xy 373.340779 -52.217802) (xy 373.395622 -52.207672)
			(xy 373.451356 -52.205635) (xy 373.506793 -52.211735) (xy 373.56075 -52.225841) (xy 373.612079 -52.247653)
			(xy 373.659685 -52.276707) (xy 373.702553 -52.312382) (xy 373.73977 -52.353919) (xy 373.770543 -52.400432)
			(xy 373.794215 -52.450929) (xy 373.810283 -52.504336) (xy 373.818403 -52.559512) (xy 373.818912 -52.587398)
			(xy 373.818403 -52.615284) (xy 373.810283 -52.67046) (xy 373.794215 -52.723867) (xy 373.770543 -52.774364)
			(xy 373.73977 -52.820877) (xy 373.702553 -52.862414) (xy 373.659685 -52.898089) (xy 373.612079 -52.927143)
			(xy 373.56075 -52.948955) (xy 373.506793 -52.963061) (xy 373.451356 -52.969161) (xy 373.395622 -52.967124)
			(xy 373.340779 -52.956994) (xy 373.287995 -52.938987) (xy 373.238395 -52.913486) (xy 373.193037 -52.881035)
			(xy 373.152888 -52.842326) (xy 373.118802 -52.798183) (xy 373.091506 -52.749548) (xy 373.071583 -52.697457)
			(xy 373.059457 -52.64302) (xy 373.055386 -52.587398) (xy 369.896979 -52.587398) (xy 369.895428 -52.598184)
			(xy 369.880076 -52.650469) (xy 369.857441 -52.700038) (xy 369.827983 -52.745881) (xy 369.7923 -52.787066)
			(xy 369.75112 -52.822754) (xy 369.70528 -52.852218) (xy 369.655714 -52.87486) (xy 369.603431 -52.890217)
			(xy 369.549494 -52.897979) (xy 369.522248 -52.898548) (xy 369.513612 -52.898548) (xy 369.503452 -52.898294)
			(xy 369.484656 -52.90566) (xy 369.42522 -52.963826) (xy 369.418311 -52.971199) (xy 369.410463 -52.9898)
			(xy 369.40998 -52.999894) (xy 369.40998 -53.96357) (xy 373.07215 -53.96357) (xy 373.076221 -53.907948)
			(xy 373.088347 -53.853511) (xy 373.10827 -53.80142) (xy 373.135566 -53.752785) (xy 373.169652 -53.708642)
			(xy 373.209801 -53.669933) (xy 373.255159 -53.637482) (xy 373.304759 -53.611981) (xy 373.357543 -53.593974)
			(xy 373.412386 -53.583844) (xy 373.46812 -53.581807) (xy 373.523557 -53.587907) (xy 373.577514 -53.602013)
			(xy 373.628843 -53.623825) (xy 373.676449 -53.652879) (xy 373.719317 -53.688554) (xy 373.756534 -53.730091)
			(xy 373.787307 -53.776604) (xy 373.810979 -53.827101) (xy 373.827047 -53.880508) (xy 373.835167 -53.935684)
			(xy 373.835676 -53.96357) (xy 373.835167 -53.991456) (xy 373.827047 -54.046632) (xy 373.810979 -54.100039)
			(xy 373.787307 -54.150536) (xy 373.756534 -54.197049) (xy 373.719317 -54.238586) (xy 373.676449 -54.274261)
			(xy 373.628843 -54.303315) (xy 373.577514 -54.325127) (xy 373.523557 -54.339233) (xy 373.46812 -54.345333)
			(xy 373.412386 -54.343296) (xy 373.357543 -54.333166) (xy 373.304759 -54.315159) (xy 373.255159 -54.289658)
			(xy 373.209801 -54.257207) (xy 373.169652 -54.218498) (xy 373.135566 -54.174355) (xy 373.10827 -54.12572)
			(xy 373.088347 -54.073629) (xy 373.076221 -54.019192) (xy 373.07215 -53.96357) (xy 369.40998 -53.96357)
			(xy 369.40998 -55.722266) (xy 374.134124 -55.722266) (xy 374.138195 -55.666644) (xy 374.150321 -55.612207)
			(xy 374.170244 -55.560116) (xy 374.19754 -55.511481) (xy 374.231626 -55.467338) (xy 374.271775 -55.428629)
			(xy 374.317133 -55.396178) (xy 374.366733 -55.370677) (xy 374.419517 -55.35267) (xy 374.47436 -55.34254)
			(xy 374.530094 -55.340503) (xy 374.585531 -55.346603) (xy 374.639488 -55.360709) (xy 374.690817 -55.382521)
			(xy 374.738423 -55.411575) (xy 374.781291 -55.44725) (xy 374.818508 -55.488787) (xy 374.849281 -55.5353)
			(xy 374.872953 -55.585797) (xy 374.889021 -55.639204) (xy 374.897141 -55.69438) (xy 374.89765 -55.722266)
			(xy 374.897141 -55.750152) (xy 374.889021 -55.805328) (xy 374.872953 -55.858735) (xy 374.849281 -55.909232)
			(xy 374.818508 -55.955745) (xy 374.781291 -55.997282) (xy 374.738423 -56.032957) (xy 374.690817 -56.062011)
			(xy 374.639488 -56.083823) (xy 374.585531 -56.097929) (xy 374.530094 -56.104029) (xy 374.47436 -56.101992)
			(xy 374.419517 -56.091862) (xy 374.366733 -56.073855) (xy 374.317133 -56.048354) (xy 374.271775 -56.015903)
			(xy 374.231626 -55.977194) (xy 374.19754 -55.933051) (xy 374.170244 -55.884416) (xy 374.150321 -55.832325)
			(xy 374.138195 -55.777888) (xy 374.134124 -55.722266) (xy 369.40998 -55.722266) (xy 369.40998 -58.072274)
			(xy 374.293636 -58.072274) (xy 374.297707 -58.016652) (xy 374.309833 -57.962215) (xy 374.329756 -57.910124)
			(xy 374.357052 -57.861489) (xy 374.391138 -57.817346) (xy 374.431287 -57.778637) (xy 374.476645 -57.746186)
			(xy 374.526245 -57.720685) (xy 374.579029 -57.702678) (xy 374.633872 -57.692548) (xy 374.689606 -57.690511)
			(xy 374.745043 -57.696611) (xy 374.799 -57.710717) (xy 374.850329 -57.732529) (xy 374.897935 -57.761583)
			(xy 374.940803 -57.797258) (xy 374.97802 -57.838795) (xy 375.008793 -57.885308) (xy 375.032465 -57.935805)
			(xy 375.048533 -57.989212) (xy 375.056653 -58.044388) (xy 375.057162 -58.072274) (xy 375.056653 -58.10016)
			(xy 375.048533 -58.155336) (xy 375.032465 -58.208743) (xy 375.008793 -58.25924) (xy 374.97802 -58.305753)
			(xy 374.940803 -58.34729) (xy 374.897935 -58.382965) (xy 374.850329 -58.412019) (xy 374.799 -58.433831)
			(xy 374.745043 -58.447937) (xy 374.689606 -58.454037) (xy 374.633872 -58.452) (xy 374.579029 -58.44187)
			(xy 374.526245 -58.423863) (xy 374.476645 -58.398362) (xy 374.431287 -58.365911) (xy 374.391138 -58.327202)
			(xy 374.357052 -58.283059) (xy 374.329756 -58.234424) (xy 374.309833 -58.182333) (xy 374.297707 -58.127896)
			(xy 374.293636 -58.072274) (xy 369.40998 -58.072274) (xy 369.40998 -64.797178) (xy 369.410402 -64.80693)
			(xy 369.417676 -64.825025) (xy 369.431209 -64.839068) (xy 369.439952 -64.843406) (xy 369.522248 -64.880744)
			(xy 369.532796 -64.884764) (xy 369.555337 -64.884244) (xy 369.565682 -64.879728) (xy 369.578382 -64.873378)
			(xy 369.583208 -64.869568) (xy 369.603996 -64.852432) (xy 369.649488 -64.823573) (xy 369.698592 -64.801413)
			(xy 369.75033 -64.786395) (xy 369.803667 -64.778818) (xy 369.830604 -64.778382) (xy 369.857856 -64.778868)
			(xy 369.911804 -64.786625) (xy 369.9641 -64.801981) (xy 370.013678 -64.824623) (xy 370.059529 -64.85409)
			(xy 370.10072 -64.889783) (xy 370.136412 -64.930974) (xy 370.165879 -64.976825) (xy 370.18852 -65.026404)
			(xy 370.203876 -65.078699) (xy 370.211632 -65.132648) (xy 370.211632 -65.187152) (xy 370.203876 -65.241101)
			(xy 370.18852 -65.293396) (xy 370.165879 -65.342975) (xy 370.136412 -65.388826) (xy 370.10072 -65.430017)
			(xy 370.059529 -65.46571) (xy 370.013678 -65.495177) (xy 369.9641 -65.517819) (xy 369.911804 -65.533175)
			(xy 369.857856 -65.540932) (xy 369.830604 -65.541398) (xy 369.803673 -65.540909) (xy 369.750353 -65.533292)
			(xy 369.69863 -65.518264) (xy 369.649529 -65.496123) (xy 369.604023 -65.467307) (xy 369.583208 -65.450212)
			(xy 369.578382 -65.446402) (xy 369.565682 -65.440052) (xy 369.55534 -65.435513) (xy 369.532791 -65.434987)
			(xy 369.522248 -65.439036) (xy 369.439952 -65.476374) (xy 369.431265 -65.480783) (xy 369.41779 -65.494828)
			(xy 369.410493 -65.512872) (xy 369.40998 -65.522602) (xy 369.40998 -67.592956) (xy 369.645436 -67.592956)
			(xy 369.649507 -67.537334) (xy 369.661633 -67.482897) (xy 369.681556 -67.430806) (xy 369.708852 -67.382171)
			(xy 369.742938 -67.338028) (xy 369.783087 -67.299319) (xy 369.828445 -67.266868) (xy 369.878045 -67.241367)
			(xy 369.930829 -67.22336) (xy 369.985672 -67.21323) (xy 370.041406 -67.211193) (xy 370.096843 -67.217293)
			(xy 370.1508 -67.231399) (xy 370.202129 -67.253211) (xy 370.249735 -67.282265) (xy 370.292603 -67.31794)
			(xy 370.32982 -67.359477) (xy 370.360593 -67.40599) (xy 370.384265 -67.456487) (xy 370.400333 -67.509894)
			(xy 370.408453 -67.56507) (xy 370.408962 -67.592956) (xy 370.408453 -67.620842) (xy 370.400333 -67.676018)
			(xy 370.384265 -67.729425) (xy 370.360593 -67.779922) (xy 370.32982 -67.826435) (xy 370.292603 -67.867972)
			(xy 370.249735 -67.903647) (xy 370.202129 -67.932701) (xy 370.1508 -67.954513) (xy 370.096843 -67.968619)
			(xy 370.041406 -67.974719) (xy 369.985672 -67.972682) (xy 369.930829 -67.962552) (xy 369.878045 -67.944545)
			(xy 369.828445 -67.919044) (xy 369.783087 -67.886593) (xy 369.742938 -67.847884) (xy 369.708852 -67.803741)
			(xy 369.681556 -67.755106) (xy 369.661633 -67.703015) (xy 369.649507 -67.648578) (xy 369.645436 -67.592956)
			(xy 369.40998 -67.592956) (xy 369.40998 -70.035928) (xy 369.410472 -70.045933) (xy 369.418136 -70.064419)
			(xy 369.432288 -70.078568) (xy 369.450774 -70.086229) (xy 369.46078 -70.086728) (xy 375.03227 -70.086728)
		)
		(stroke
			(width 0)
			(type solid)
		)
		(fill yes)
		(layer "In9.Cu")
		(net "P12V_AUX")
	)
	(gr_poly
		(pts
			(xy 401.051014 -70.079108) (xy 401.058126 -70.071742) (xy 401.21332 -69.916548) (xy 401.220167 -69.909151)
			(xy 401.227895 -69.890551) (xy 401.228306 -69.88048) (xy 401.228306 -52.07508) (xy 401.220686 -52.056284)
			(xy 401.21332 -52.049172) (xy 400.826986 -51.662838) (xy 400.819589 -51.65599) (xy 400.80099 -51.648254)
			(xy 400.790918 -51.647852) (xy 395.4907 -51.647852) (xy 395.471904 -51.655472) (xy 395.464792 -51.662838)
			(xy 395.42466 -51.70297) (xy 395.417975 -51.71038) (xy 395.410389 -51.728815) (xy 395.409928 -51.738784)
			(xy 395.409928 -52.033932) (xy 395.410375 -52.044088) (xy 395.418236 -52.062818) (xy 395.425168 -52.070254)
			(xy 395.484604 -52.12842) (xy 395.5034 -52.135786) (xy 395.51356 -52.135532) (xy 395.522196 -52.135532)
			(xy 395.549446 -52.135995) (xy 395.603392 -52.143751) (xy 395.655685 -52.159105) (xy 395.70526 -52.181745)
			(xy 395.751109 -52.211209) (xy 395.792298 -52.246899) (xy 395.827988 -52.288088) (xy 395.857453 -52.333936)
			(xy 395.880094 -52.383512) (xy 395.895448 -52.435804) (xy 395.903205 -52.48975) (xy 395.903205 -52.54425)
			(xy 395.897001 -52.587398) (xy 399.055334 -52.587398) (xy 399.059405 -52.531776) (xy 399.071531 -52.477339)
			(xy 399.091454 -52.425248) (xy 399.11875 -52.376613) (xy 399.152836 -52.33247) (xy 399.192985 -52.293761)
			(xy 399.238343 -52.26131) (xy 399.287943 -52.235809) (xy 399.340727 -52.217802) (xy 399.39557 -52.207672)
			(xy 399.451304 -52.205635) (xy 399.506741 -52.211735) (xy 399.560698 -52.225841) (xy 399.612027 -52.247653)
			(xy 399.659633 -52.276707) (xy 399.702501 -52.312382) (xy 399.739718 -52.353919) (xy 399.770491 -52.400432)
			(xy 399.794163 -52.450929) (xy 399.810231 -52.504336) (xy 399.818351 -52.559512) (xy 399.81886 -52.587398)
			(xy 399.818351 -52.615284) (xy 399.810231 -52.67046) (xy 399.794163 -52.723867) (xy 399.770491 -52.774364)
			(xy 399.739718 -52.820877) (xy 399.702501 -52.862414) (xy 399.659633 -52.898089) (xy 399.612027 -52.927143)
			(xy 399.560698 -52.948955) (xy 399.506741 -52.963061) (xy 399.451304 -52.969161) (xy 399.39557 -52.967124)
			(xy 399.340727 -52.956994) (xy 399.287943 -52.938987) (xy 399.238343 -52.913486) (xy 399.192985 -52.881035)
			(xy 399.152836 -52.842326) (xy 399.11875 -52.798183) (xy 399.091454 -52.749548) (xy 399.071531 -52.697457)
			(xy 399.059405 -52.64302) (xy 399.055334 -52.587398) (xy 395.897001 -52.587398) (xy 395.895448 -52.598196)
			(xy 395.880094 -52.650488) (xy 395.857453 -52.700064) (xy 395.827988 -52.745912) (xy 395.792298 -52.787101)
			(xy 395.751109 -52.822791) (xy 395.70526 -52.852255) (xy 395.655685 -52.874895) (xy 395.603392 -52.890249)
			(xy 395.549446 -52.898005) (xy 395.522196 -52.898548) (xy 395.51356 -52.898548) (xy 395.5034 -52.898294)
			(xy 395.484604 -52.90566) (xy 395.425168 -52.963826) (xy 395.418265 -52.971202) (xy 395.410424 -52.989802)
			(xy 395.409928 -52.999894) (xy 395.409928 -53.96357) (xy 399.072098 -53.96357) (xy 399.076169 -53.907948)
			(xy 399.088295 -53.853511) (xy 399.108218 -53.80142) (xy 399.135514 -53.752785) (xy 399.1696 -53.708642)
			(xy 399.209749 -53.669933) (xy 399.255107 -53.637482) (xy 399.304707 -53.611981) (xy 399.357491 -53.593974)
			(xy 399.412334 -53.583844) (xy 399.468068 -53.581807) (xy 399.523505 -53.587907) (xy 399.577462 -53.602013)
			(xy 399.628791 -53.623825) (xy 399.676397 -53.652879) (xy 399.719265 -53.688554) (xy 399.756482 -53.730091)
			(xy 399.787255 -53.776604) (xy 399.810927 -53.827101) (xy 399.826995 -53.880508) (xy 399.835115 -53.935684)
			(xy 399.835624 -53.96357) (xy 399.835115 -53.991456) (xy 399.826995 -54.046632) (xy 399.810927 -54.100039)
			(xy 399.787255 -54.150536) (xy 399.756482 -54.197049) (xy 399.719265 -54.238586) (xy 399.676397 -54.274261)
			(xy 399.628791 -54.303315) (xy 399.577462 -54.325127) (xy 399.523505 -54.339233) (xy 399.468068 -54.345333)
			(xy 399.412334 -54.343296) (xy 399.357491 -54.333166) (xy 399.304707 -54.315159) (xy 399.255107 -54.289658)
			(xy 399.209749 -54.257207) (xy 399.1696 -54.218498) (xy 399.135514 -54.174355) (xy 399.108218 -54.12572)
			(xy 399.088295 -54.073629) (xy 399.076169 -54.019192) (xy 399.072098 -53.96357) (xy 395.409928 -53.96357)
			(xy 395.409928 -55.722266) (xy 400.134072 -55.722266) (xy 400.138143 -55.666644) (xy 400.150269 -55.612207)
			(xy 400.170192 -55.560116) (xy 400.197488 -55.511481) (xy 400.231574 -55.467338) (xy 400.271723 -55.428629)
			(xy 400.317081 -55.396178) (xy 400.366681 -55.370677) (xy 400.419465 -55.35267) (xy 400.474308 -55.34254)
			(xy 400.530042 -55.340503) (xy 400.585479 -55.346603) (xy 400.639436 -55.360709) (xy 400.690765 -55.382521)
			(xy 400.738371 -55.411575) (xy 400.781239 -55.44725) (xy 400.818456 -55.488787) (xy 400.849229 -55.5353)
			(xy 400.872901 -55.585797) (xy 400.888969 -55.639204) (xy 400.897089 -55.69438) (xy 400.897598 -55.722266)
			(xy 400.897089 -55.750152) (xy 400.888969 -55.805328) (xy 400.872901 -55.858735) (xy 400.849229 -55.909232)
			(xy 400.818456 -55.955745) (xy 400.781239 -55.997282) (xy 400.738371 -56.032957) (xy 400.690765 -56.062011)
			(xy 400.639436 -56.083823) (xy 400.585479 -56.097929) (xy 400.530042 -56.104029) (xy 400.474308 -56.101992)
			(xy 400.419465 -56.091862) (xy 400.366681 -56.073855) (xy 400.317081 -56.048354) (xy 400.271723 -56.015903)
			(xy 400.231574 -55.977194) (xy 400.197488 -55.933051) (xy 400.170192 -55.884416) (xy 400.150269 -55.832325)
			(xy 400.138143 -55.777888) (xy 400.134072 -55.722266) (xy 395.409928 -55.722266) (xy 395.409928 -58.072274)
			(xy 400.293584 -58.072274) (xy 400.297655 -58.016652) (xy 400.309781 -57.962215) (xy 400.329704 -57.910124)
			(xy 400.357 -57.861489) (xy 400.391086 -57.817346) (xy 400.431235 -57.778637) (xy 400.476593 -57.746186)
			(xy 400.526193 -57.720685) (xy 400.578977 -57.702678) (xy 400.63382 -57.692548) (xy 400.689554 -57.690511)
			(xy 400.744991 -57.696611) (xy 400.798948 -57.710717) (xy 400.850277 -57.732529) (xy 400.897883 -57.761583)
			(xy 400.940751 -57.797258) (xy 400.977968 -57.838795) (xy 401.008741 -57.885308) (xy 401.032413 -57.935805)
			(xy 401.048481 -57.989212) (xy 401.056601 -58.044388) (xy 401.05711 -58.072274) (xy 401.056601 -58.10016)
			(xy 401.048481 -58.155336) (xy 401.032413 -58.208743) (xy 401.008741 -58.25924) (xy 400.977968 -58.305753)
			(xy 400.940751 -58.34729) (xy 400.897883 -58.382965) (xy 400.850277 -58.412019) (xy 400.798948 -58.433831)
			(xy 400.744991 -58.447937) (xy 400.689554 -58.454037) (xy 400.63382 -58.452) (xy 400.578977 -58.44187)
			(xy 400.526193 -58.423863) (xy 400.476593 -58.398362) (xy 400.431235 -58.365911) (xy 400.391086 -58.327202)
			(xy 400.357 -58.283059) (xy 400.329704 -58.234424) (xy 400.309781 -58.182333) (xy 400.297655 -58.127896)
			(xy 400.293584 -58.072274) (xy 395.409928 -58.072274) (xy 395.409928 -64.797178) (xy 395.410351 -64.806928)
			(xy 395.417629 -64.825017) (xy 395.431167 -64.83905) (xy 395.4399 -64.843406) (xy 395.522196 -64.880744)
			(xy 395.532743 -64.884754) (xy 395.555275 -64.884214) (xy 395.56563 -64.879728) (xy 395.57833 -64.873378)
			(xy 395.583156 -64.869568) (xy 395.603945 -64.852434) (xy 395.649438 -64.823582) (xy 395.698543 -64.801428)
			(xy 395.75028 -64.786416) (xy 395.803616 -64.778845) (xy 395.830552 -64.778382) (xy 395.857808 -64.778842)
			(xy 395.911765 -64.786593) (xy 395.96407 -64.801946) (xy 396.013658 -64.824586) (xy 396.059518 -64.854053)
			(xy 396.100718 -64.889748) (xy 396.136418 -64.930943) (xy 396.165891 -64.9768) (xy 396.188538 -65.026384)
			(xy 396.203897 -65.078688) (xy 396.211655 -65.132644) (xy 396.211655 -65.187156) (xy 396.203897 -65.241112)
			(xy 396.188538 -65.293416) (xy 396.165891 -65.343) (xy 396.136418 -65.388857) (xy 396.100718 -65.430052)
			(xy 396.059518 -65.465747) (xy 396.013658 -65.495214) (xy 395.96407 -65.517854) (xy 395.911765 -65.533207)
			(xy 395.857808 -65.540958) (xy 395.830552 -65.541398) (xy 395.80362 -65.540913) (xy 395.750296 -65.533301)
			(xy 395.698569 -65.518278) (xy 395.649464 -65.496142) (xy 395.603953 -65.46733) (xy 395.583156 -65.450212)
			(xy 395.57833 -65.446402) (xy 395.56563 -65.440052) (xy 395.555288 -65.435502) (xy 395.53273 -65.434957)
			(xy 395.522196 -65.439036) (xy 395.4399 -65.476374) (xy 395.431207 -65.480778) (xy 395.417719 -65.49482)
			(xy 395.410414 -65.512868) (xy 395.409928 -65.522602) (xy 395.409928 -67.592956) (xy 395.645384 -67.592956)
			(xy 395.649455 -67.537334) (xy 395.661581 -67.482897) (xy 395.681504 -67.430806) (xy 395.7088 -67.382171)
			(xy 395.742886 -67.338028) (xy 395.783035 -67.299319) (xy 395.828393 -67.266868) (xy 395.877993 -67.241367)
			(xy 395.930777 -67.22336) (xy 395.98562 -67.21323) (xy 396.041354 -67.211193) (xy 396.096791 -67.217293)
			(xy 396.150748 -67.231399) (xy 396.202077 -67.253211) (xy 396.249683 -67.282265) (xy 396.292551 -67.31794)
			(xy 396.329768 -67.359477) (xy 396.360541 -67.40599) (xy 396.384213 -67.456487) (xy 396.400281 -67.509894)
			(xy 396.408401 -67.56507) (xy 396.40891 -67.592956) (xy 396.408401 -67.620842) (xy 396.400281 -67.676018)
			(xy 396.384213 -67.729425) (xy 396.360541 -67.779922) (xy 396.329768 -67.826435) (xy 396.292551 -67.867972)
			(xy 396.249683 -67.903647) (xy 396.202077 -67.932701) (xy 396.150748 -67.954513) (xy 396.096791 -67.968619)
			(xy 396.041354 -67.974719) (xy 395.98562 -67.972682) (xy 395.930777 -67.962552) (xy 395.877993 -67.944545)
			(xy 395.828393 -67.919044) (xy 395.783035 -67.886593) (xy 395.742886 -67.847884) (xy 395.7088 -67.803741)
			(xy 395.681504 -67.755106) (xy 395.661581 -67.703015) (xy 395.649455 -67.648578) (xy 395.645384 -67.592956)
			(xy 395.409928 -67.592956) (xy 395.409928 -70.035928) (xy 395.410421 -70.04593) (xy 395.418087 -70.064407)
			(xy 395.43224 -70.078545) (xy 395.450726 -70.08619) (xy 395.460728 -70.086728) (xy 401.032218 -70.086728)
		)
		(stroke
			(width 0)
			(type solid)
		)
		(fill yes)
		(layer "In9.Cu")
		(net "P12V_AUX")
	)
	(gr_poly
		(pts
			(xy 427.050962 -70.079108) (xy 427.058074 -70.071742) (xy 427.213268 -69.916548) (xy 427.22011 -69.909148)
			(xy 427.22783 -69.89055) (xy 427.228254 -69.88048) (xy 427.228254 -52.07508) (xy 427.220634 -52.056284)
			(xy 427.213268 -52.049172) (xy 426.826934 -51.662838) (xy 426.819534 -51.655998) (xy 426.800935 -51.648281)
			(xy 426.790866 -51.647852) (xy 421.490648 -51.647852) (xy 421.471852 -51.655472) (xy 421.46474 -51.662838)
			(xy 421.424608 -51.70297) (xy 421.417918 -51.710378) (xy 421.410324 -51.728814) (xy 421.409876 -51.738784)
			(xy 421.409876 -52.033932) (xy 421.410322 -52.044089) (xy 421.418176 -52.062825) (xy 421.425116 -52.070254)
			(xy 421.484552 -52.12842) (xy 421.503348 -52.135786) (xy 421.513508 -52.135532) (xy 421.522144 -52.135532)
			(xy 421.54939 -52.136021) (xy 421.603328 -52.143782) (xy 421.655611 -52.159139) (xy 421.705178 -52.181781)
			(xy 421.751018 -52.211245) (xy 421.792199 -52.246933) (xy 421.827882 -52.288117) (xy 421.857341 -52.333961)
			(xy 421.879976 -52.38353) (xy 421.895327 -52.435815) (xy 421.903082 -52.489754) (xy 421.903082 -52.544246)
			(xy 421.896878 -52.587398) (xy 425.055282 -52.587398) (xy 425.059353 -52.531776) (xy 425.071479 -52.477339)
			(xy 425.091402 -52.425248) (xy 425.118698 -52.376613) (xy 425.152784 -52.33247) (xy 425.192933 -52.293761)
			(xy 425.238291 -52.26131) (xy 425.287891 -52.235809) (xy 425.340675 -52.217802) (xy 425.395518 -52.207672)
			(xy 425.451252 -52.205635) (xy 425.506689 -52.211735) (xy 425.560646 -52.225841) (xy 425.611975 -52.247653)
			(xy 425.659581 -52.276707) (xy 425.702449 -52.312382) (xy 425.739666 -52.353919) (xy 425.770439 -52.400432)
			(xy 425.794111 -52.450929) (xy 425.810179 -52.504336) (xy 425.818299 -52.559512) (xy 425.818808 -52.587398)
			(xy 425.818299 -52.615284) (xy 425.810179 -52.67046) (xy 425.794111 -52.723867) (xy 425.770439 -52.774364)
			(xy 425.739666 -52.820877) (xy 425.702449 -52.862414) (xy 425.659581 -52.898089) (xy 425.611975 -52.927143)
			(xy 425.560646 -52.948955) (xy 425.506689 -52.963061) (xy 425.451252 -52.969161) (xy 425.395518 -52.967124)
			(xy 425.340675 -52.956994) (xy 425.287891 -52.938987) (xy 425.238291 -52.913486) (xy 425.192933 -52.881035)
			(xy 425.152784 -52.842326) (xy 425.118698 -52.798183) (xy 425.091402 -52.749548) (xy 425.071479 -52.697457)
			(xy 425.059353 -52.64302) (xy 425.055282 -52.587398) (xy 421.896878 -52.587398) (xy 421.895327 -52.598185)
			(xy 421.879976 -52.65047) (xy 421.857341 -52.700039) (xy 421.827882 -52.745883) (xy 421.792199 -52.787067)
			(xy 421.751018 -52.822755) (xy 421.705178 -52.852219) (xy 421.655611 -52.874861) (xy 421.603328 -52.890218)
			(xy 421.54939 -52.897979) (xy 421.522144 -52.898548) (xy 421.513508 -52.898548) (xy 421.503348 -52.898294)
			(xy 421.484552 -52.90566) (xy 421.425116 -52.963826) (xy 421.418208 -52.9712) (xy 421.41036 -52.989801)
			(xy 421.409876 -52.999894) (xy 421.409876 -53.96357) (xy 425.072046 -53.96357) (xy 425.076117 -53.907948)
			(xy 425.088243 -53.853511) (xy 425.108166 -53.80142) (xy 425.135462 -53.752785) (xy 425.169548 -53.708642)
			(xy 425.209697 -53.669933) (xy 425.255055 -53.637482) (xy 425.304655 -53.611981) (xy 425.357439 -53.593974)
			(xy 425.412282 -53.583844) (xy 425.468016 -53.581807) (xy 425.523453 -53.587907) (xy 425.57741 -53.602013)
			(xy 425.628739 -53.623825) (xy 425.676345 -53.652879) (xy 425.719213 -53.688554) (xy 425.75643 -53.730091)
			(xy 425.787203 -53.776604) (xy 425.810875 -53.827101) (xy 425.826943 -53.880508) (xy 425.835063 -53.935684)
			(xy 425.835572 -53.96357) (xy 425.835063 -53.991456) (xy 425.826943 -54.046632) (xy 425.810875 -54.100039)
			(xy 425.787203 -54.150536) (xy 425.75643 -54.197049) (xy 425.719213 -54.238586) (xy 425.676345 -54.274261)
			(xy 425.628739 -54.303315) (xy 425.57741 -54.325127) (xy 425.523453 -54.339233) (xy 425.468016 -54.345333)
			(xy 425.412282 -54.343296) (xy 425.357439 -54.333166) (xy 425.304655 -54.315159) (xy 425.255055 -54.289658)
			(xy 425.209697 -54.257207) (xy 425.169548 -54.218498) (xy 425.135462 -54.174355) (xy 425.108166 -54.12572)
			(xy 425.088243 -54.073629) (xy 425.076117 -54.019192) (xy 425.072046 -53.96357) (xy 421.409876 -53.96357)
			(xy 421.409876 -55.722266) (xy 426.13402 -55.722266) (xy 426.138091 -55.666644) (xy 426.150217 -55.612207)
			(xy 426.17014 -55.560116) (xy 426.197436 -55.511481) (xy 426.231522 -55.467338) (xy 426.271671 -55.428629)
			(xy 426.317029 -55.396178) (xy 426.366629 -55.370677) (xy 426.419413 -55.35267) (xy 426.474256 -55.34254)
			(xy 426.52999 -55.340503) (xy 426.585427 -55.346603) (xy 426.639384 -55.360709) (xy 426.690713 -55.382521)
			(xy 426.738319 -55.411575) (xy 426.781187 -55.44725) (xy 426.818404 -55.488787) (xy 426.849177 -55.5353)
			(xy 426.872849 -55.585797) (xy 426.888917 -55.639204) (xy 426.897037 -55.69438) (xy 426.897546 -55.722266)
			(xy 426.897037 -55.750152) (xy 426.888917 -55.805328) (xy 426.872849 -55.858735) (xy 426.849177 -55.909232)
			(xy 426.818404 -55.955745) (xy 426.781187 -55.997282) (xy 426.738319 -56.032957) (xy 426.690713 -56.062011)
			(xy 426.639384 -56.083823) (xy 426.585427 -56.097929) (xy 426.52999 -56.104029) (xy 426.474256 -56.101992)
			(xy 426.419413 -56.091862) (xy 426.366629 -56.073855) (xy 426.317029 -56.048354) (xy 426.271671 -56.015903)
			(xy 426.231522 -55.977194) (xy 426.197436 -55.933051) (xy 426.17014 -55.884416) (xy 426.150217 -55.832325)
			(xy 426.138091 -55.777888) (xy 426.13402 -55.722266) (xy 421.409876 -55.722266) (xy 421.409876 -58.072274)
			(xy 426.293532 -58.072274) (xy 426.297603 -58.016652) (xy 426.309729 -57.962215) (xy 426.329652 -57.910124)
			(xy 426.356948 -57.861489) (xy 426.391034 -57.817346) (xy 426.431183 -57.778637) (xy 426.476541 -57.746186)
			(xy 426.526141 -57.720685) (xy 426.578925 -57.702678) (xy 426.633768 -57.692548) (xy 426.689502 -57.690511)
			(xy 426.744939 -57.696611) (xy 426.798896 -57.710717) (xy 426.850225 -57.732529) (xy 426.897831 -57.761583)
			(xy 426.940699 -57.797258) (xy 426.977916 -57.838795) (xy 427.008689 -57.885308) (xy 427.032361 -57.935805)
			(xy 427.048429 -57.989212) (xy 427.056549 -58.044388) (xy 427.057058 -58.072274) (xy 427.056549 -58.10016)
			(xy 427.048429 -58.155336) (xy 427.032361 -58.208743) (xy 427.008689 -58.25924) (xy 426.977916 -58.305753)
			(xy 426.940699 -58.34729) (xy 426.897831 -58.382965) (xy 426.850225 -58.412019) (xy 426.798896 -58.433831)
			(xy 426.744939 -58.447937) (xy 426.689502 -58.454037) (xy 426.633768 -58.452) (xy 426.578925 -58.44187)
			(xy 426.526141 -58.423863) (xy 426.476541 -58.398362) (xy 426.431183 -58.365911) (xy 426.391034 -58.327202)
			(xy 426.356948 -58.283059) (xy 426.329652 -58.234424) (xy 426.309729 -58.182333) (xy 426.297603 -58.127896)
			(xy 426.293532 -58.072274) (xy 421.409876 -58.072274) (xy 421.409876 -64.797178) (xy 421.410298 -64.80693)
			(xy 421.417572 -64.825026) (xy 421.431105 -64.83907) (xy 421.439848 -64.843406) (xy 421.522144 -64.880744)
			(xy 421.532692 -64.884765) (xy 421.555234 -64.884246) (xy 421.565578 -64.879728) (xy 421.578278 -64.873378)
			(xy 421.583104 -64.869568) (xy 421.603892 -64.852431) (xy 421.649384 -64.823572) (xy 421.698488 -64.801412)
			(xy 421.750226 -64.786393) (xy 421.803563 -64.778815) (xy 421.8305 -64.778382) (xy 421.857752 -64.778868)
			(xy 421.911701 -64.786625) (xy 421.963997 -64.80198) (xy 422.013576 -64.824622) (xy 422.059427 -64.854089)
			(xy 422.100619 -64.889781) (xy 422.136311 -64.930973) (xy 422.165778 -64.976824) (xy 422.18842 -65.026403)
			(xy 422.203775 -65.078699) (xy 422.211532 -65.132648) (xy 422.211532 -65.187152) (xy 422.203775 -65.241101)
			(xy 422.18842 -65.293397) (xy 422.165778 -65.342976) (xy 422.136311 -65.388827) (xy 422.100619 -65.430019)
			(xy 422.059427 -65.465711) (xy 422.013576 -65.495178) (xy 421.963997 -65.51782) (xy 421.911701 -65.533175)
			(xy 421.857752 -65.540932) (xy 421.8305 -65.541398) (xy 421.80357 -65.540909) (xy 421.750249 -65.533291)
			(xy 421.698526 -65.518263) (xy 421.649426 -65.496121) (xy 421.60392 -65.467305) (xy 421.583104 -65.450212)
			(xy 421.578278 -65.446402) (xy 421.565578 -65.440052) (xy 421.555236 -65.435514) (xy 421.532688 -65.43499)
			(xy 421.522144 -65.439036) (xy 421.439848 -65.476374) (xy 421.431162 -65.480783) (xy 421.417687 -65.494828)
			(xy 421.410391 -65.512872) (xy 421.409876 -65.522602) (xy 421.409876 -67.592956) (xy 421.645332 -67.592956)
			(xy 421.649403 -67.537334) (xy 421.661529 -67.482897) (xy 421.681452 -67.430806) (xy 421.708748 -67.382171)
			(xy 421.742834 -67.338028) (xy 421.782983 -67.299319) (xy 421.828341 -67.266868) (xy 421.877941 -67.241367)
			(xy 421.930725 -67.22336) (xy 421.985568 -67.21323) (xy 422.041302 -67.211193) (xy 422.096739 -67.217293)
			(xy 422.150696 -67.231399) (xy 422.202025 -67.253211) (xy 422.249631 -67.282265) (xy 422.292499 -67.31794)
			(xy 422.329716 -67.359477) (xy 422.360489 -67.40599) (xy 422.384161 -67.456487) (xy 422.400229 -67.509894)
			(xy 422.408349 -67.56507) (xy 422.408858 -67.592956) (xy 422.408349 -67.620842) (xy 422.400229 -67.676018)
			(xy 422.384161 -67.729425) (xy 422.360489 -67.779922) (xy 422.329716 -67.826435) (xy 422.292499 -67.867972)
			(xy 422.249631 -67.903647) (xy 422.202025 -67.932701) (xy 422.150696 -67.954513) (xy 422.096739 -67.968619)
			(xy 422.041302 -67.974719) (xy 421.985568 -67.972682) (xy 421.930725 -67.962552) (xy 421.877941 -67.944545)
			(xy 421.828341 -67.919044) (xy 421.782983 -67.886593) (xy 421.742834 -67.847884) (xy 421.708748 -67.803741)
			(xy 421.681452 -67.755106) (xy 421.661529 -67.703015) (xy 421.649403 -67.648578) (xy 421.645332 -67.592956)
			(xy 421.409876 -67.592956) (xy 421.409876 -70.035928) (xy 421.410368 -70.045934) (xy 421.418032 -70.06442)
			(xy 421.432183 -70.07857) (xy 421.45067 -70.086232) (xy 421.460676 -70.086728) (xy 427.032166 -70.086728)
		)
		(stroke
			(width 0)
			(type solid)
		)
		(fill yes)
		(layer "In9.Cu")
		(net "P12V_AUX")
	)
	(gr_poly
		(pts
			(xy 16.670274 -319.15608) (xy 16.680338 -319.155643) (xy 16.698921 -319.147907) (xy 16.706342 -319.141094)
			(xy 17.037304 -318.810132) (xy 17.044139 -318.80273) (xy 17.051848 -318.784132) (xy 17.05229 -318.774064)
			(xy 17.05229 -308.137814) (xy 17.05191 -308.128982) (xy 17.045933 -308.112358) (xy 17.040606 -308.105302)
			(xy 17.024074 -308.084673) (xy 16.996258 -308.039717) (xy 16.974915 -307.991352) (xy 16.960455 -307.940503)
			(xy 16.953154 -307.888145) (xy 16.953153 -307.83528) (xy 16.96045 -307.782921) (xy 16.974907 -307.732071)
			(xy 16.996246 -307.683704) (xy 17.024059 -307.638747) (xy 17.040606 -307.61813) (xy 17.046013 -307.611119)
			(xy 17.051998 -307.594467) (xy 17.05229 -307.585618) (xy 17.05229 -302.769524) (xy 17.052194 -302.764364)
			(xy 17.050143 -302.75425) (xy 17.048226 -302.749458) (xy 17.014596 -302.670219) (xy 16.954475 -302.508901)
			(xy 16.90265 -302.34473) (xy 16.859256 -302.178132) (xy 16.824406 -302.00954) (xy 16.79819 -301.839391)
			(xy 16.780676 -301.668128) (xy 16.77191 -301.496194) (xy 16.771366 -301.410116) (xy 16.77192 -301.324039)
			(xy 16.780705 -301.152108) (xy 16.79823 -300.980847) (xy 16.824453 -300.810701) (xy 16.859303 -300.64211)
			(xy 16.902692 -300.475513) (xy 16.954506 -300.31134) (xy 17.014611 -300.150018) (xy 17.048226 -300.070774)
			(xy 17.050112 -300.065973) (xy 17.052152 -300.055864) (xy 17.05229 -300.050708) (xy 17.05229 -295.436544)
			(xy 17.051856 -295.426479) (xy 17.044127 -295.40789) (xy 17.037304 -295.400476) (xy 16.514064 -294.877236)
			(xy 16.506665 -294.870391) (xy 16.488067 -294.862664) (xy 16.477996 -294.86225) (xy 1.444752 -294.86225)
			(xy 1.434687 -294.862683) (xy 1.4161 -294.870416) (xy 1.408684 -294.877236) (xy 0.620014 -295.665906)
			(xy 0.613167 -295.673304) (xy 0.605433 -295.691902) (xy 0.605028 -295.701974) (xy 0.605028 -304.457354)
			(xy 7.652256 -304.457354) (xy 7.656327 -304.401732) (xy 7.668453 -304.347295) (xy 7.688376 -304.295204)
			(xy 7.715672 -304.246569) (xy 7.749758 -304.202426) (xy 7.789907 -304.163717) (xy 7.835265 -304.131266)
			(xy 7.884865 -304.105765) (xy 7.937649 -304.087758) (xy 7.992492 -304.077628) (xy 8.048226 -304.075591)
			(xy 8.103663 -304.081691) (xy 8.15762 -304.095797) (xy 8.208949 -304.117609) (xy 8.256555 -304.146663)
			(xy 8.299423 -304.182338) (xy 8.33664 -304.223875) (xy 8.367413 -304.270388) (xy 8.391085 -304.320885)
			(xy 8.407153 -304.374292) (xy 8.415273 -304.429468) (xy 8.415782 -304.457354) (xy 8.415273 -304.48524)
			(xy 8.41306 -304.50028) (xy 14.926308 -304.50028) (xy 14.930379 -304.444658) (xy 14.942505 -304.390221)
			(xy 14.962428 -304.33813) (xy 14.989724 -304.289495) (xy 15.02381 -304.245352) (xy 15.063959 -304.206643)
			(xy 15.109317 -304.174192) (xy 15.158917 -304.148691) (xy 15.211701 -304.130684) (xy 15.266544 -304.120554)
			(xy 15.322278 -304.118517) (xy 15.377715 -304.124617) (xy 15.431672 -304.138723) (xy 15.483001 -304.160535)
			(xy 15.530607 -304.189589) (xy 15.573475 -304.225264) (xy 15.610692 -304.266801) (xy 15.641465 -304.313314)
			(xy 15.665137 -304.363811) (xy 15.681205 -304.417218) (xy 15.689325 -304.472394) (xy 15.689834 -304.50028)
			(xy 15.689325 -304.528166) (xy 15.681205 -304.583342) (xy 15.665137 -304.636749) (xy 15.641465 -304.687246)
			(xy 15.610692 -304.733759) (xy 15.573475 -304.775296) (xy 15.530607 -304.810971) (xy 15.483001 -304.840025)
			(xy 15.431672 -304.861837) (xy 15.377715 -304.875943) (xy 15.322278 -304.882043) (xy 15.266544 -304.880006)
			(xy 15.211701 -304.869876) (xy 15.158917 -304.851869) (xy 15.109317 -304.826368) (xy 15.063959 -304.793917)
			(xy 15.02381 -304.755208) (xy 14.989724 -304.711065) (xy 14.962428 -304.66243) (xy 14.942505 -304.610339)
			(xy 14.930379 -304.555902) (xy 14.926308 -304.50028) (xy 8.41306 -304.50028) (xy 8.407153 -304.540416)
			(xy 8.391085 -304.593823) (xy 8.367413 -304.64432) (xy 8.33664 -304.690833) (xy 8.299423 -304.73237)
			(xy 8.256555 -304.768045) (xy 8.208949 -304.797099) (xy 8.15762 -304.818911) (xy 8.103663 -304.833017)
			(xy 8.048226 -304.839117) (xy 7.992492 -304.83708) (xy 7.937649 -304.82695) (xy 7.884865 -304.808943)
			(xy 7.835265 -304.783442) (xy 7.789907 -304.750991) (xy 7.749758 -304.712282) (xy 7.715672 -304.668139)
			(xy 7.688376 -304.619504) (xy 7.668453 -304.567413) (xy 7.656327 -304.512976) (xy 7.652256 -304.457354)
			(xy 0.605028 -304.457354) (xy 0.605028 -305.159664) (xy 12.577824 -305.159664) (xy 12.581895 -305.104042)
			(xy 12.594021 -305.049605) (xy 12.613944 -304.997514) (xy 12.64124 -304.948879) (xy 12.675326 -304.904736)
			(xy 12.715475 -304.866027) (xy 12.760833 -304.833576) (xy 12.810433 -304.808075) (xy 12.863217 -304.790068)
			(xy 12.91806 -304.779938) (xy 12.973794 -304.777901) (xy 13.029231 -304.784001) (xy 13.083188 -304.798107)
			(xy 13.134517 -304.819919) (xy 13.182123 -304.848973) (xy 13.224991 -304.884648) (xy 13.262208 -304.926185)
			(xy 13.292981 -304.972698) (xy 13.316653 -305.023195) (xy 13.332721 -305.076602) (xy 13.340841 -305.131778)
			(xy 13.34135 -305.159664) (xy 13.340841 -305.18755) (xy 13.332721 -305.242726) (xy 13.316653 -305.296133)
			(xy 13.292981 -305.34663) (xy 13.262208 -305.393143) (xy 13.224991 -305.43468) (xy 13.182123 -305.470355)
			(xy 13.134517 -305.499409) (xy 13.083188 -305.521221) (xy 13.029231 -305.535327) (xy 12.973794 -305.541427)
			(xy 12.91806 -305.53939) (xy 12.863217 -305.52926) (xy 12.810433 -305.511253) (xy 12.760833 -305.485752)
			(xy 12.715475 -305.453301) (xy 12.675326 -305.414592) (xy 12.64124 -305.370449) (xy 12.613944 -305.321814)
			(xy 12.594021 -305.269723) (xy 12.581895 -305.215286) (xy 12.577824 -305.159664) (xy 0.605028 -305.159664)
			(xy 0.605028 -306.115466) (xy 13.635734 -306.115466) (xy 13.639805 -306.059844) (xy 13.651931 -306.005407)
			(xy 13.671854 -305.953316) (xy 13.69915 -305.904681) (xy 13.733236 -305.860538) (xy 13.773385 -305.821829)
			(xy 13.818743 -305.789378) (xy 13.868343 -305.763877) (xy 13.921127 -305.74587) (xy 13.97597 -305.73574)
			(xy 14.031704 -305.733703) (xy 14.087141 -305.739803) (xy 14.141098 -305.753909) (xy 14.192427 -305.775721)
			(xy 14.240033 -305.804775) (xy 14.282901 -305.84045) (xy 14.320118 -305.881987) (xy 14.350891 -305.9285)
			(xy 14.374563 -305.978997) (xy 14.390631 -306.032404) (xy 14.398751 -306.08758) (xy 14.39926 -306.115466)
			(xy 14.398751 -306.143352) (xy 14.390631 -306.198528) (xy 14.374563 -306.251935) (xy 14.350891 -306.302432)
			(xy 14.320118 -306.348945) (xy 14.282901 -306.390482) (xy 14.240033 -306.426157) (xy 14.192427 -306.455211)
			(xy 14.141098 -306.477023) (xy 14.087141 -306.491129) (xy 14.031704 -306.497229) (xy 13.97597 -306.495192)
			(xy 13.921127 -306.485062) (xy 13.868343 -306.467055) (xy 13.818743 -306.441554) (xy 13.773385 -306.409103)
			(xy 13.733236 -306.370394) (xy 13.69915 -306.326251) (xy 13.671854 -306.277616) (xy 13.651931 -306.225525)
			(xy 13.639805 -306.171088) (xy 13.635734 -306.115466) (xy 0.605028 -306.115466) (xy 0.605028 -306.731416)
			(xy 15.643858 -306.731416) (xy 15.647929 -306.675794) (xy 15.660055 -306.621357) (xy 15.679978 -306.569266)
			(xy 15.707274 -306.520631) (xy 15.74136 -306.476488) (xy 15.781509 -306.437779) (xy 15.826867 -306.405328)
			(xy 15.876467 -306.379827) (xy 15.929251 -306.36182) (xy 15.984094 -306.35169) (xy 16.039828 -306.349653)
			(xy 16.095265 -306.355753) (xy 16.149222 -306.369859) (xy 16.200551 -306.391671) (xy 16.248157 -306.420725)
			(xy 16.291025 -306.4564) (xy 16.328242 -306.497937) (xy 16.359015 -306.54445) (xy 16.382687 -306.594947)
			(xy 16.398755 -306.648354) (xy 16.406875 -306.70353) (xy 16.407384 -306.731416) (xy 16.406875 -306.759302)
			(xy 16.398755 -306.814478) (xy 16.382687 -306.867885) (xy 16.359015 -306.918382) (xy 16.328242 -306.964895)
			(xy 16.291025 -307.006432) (xy 16.248157 -307.042107) (xy 16.200551 -307.071161) (xy 16.149222 -307.092973)
			(xy 16.095265 -307.107079) (xy 16.039828 -307.113179) (xy 15.984094 -307.111142) (xy 15.929251 -307.101012)
			(xy 15.876467 -307.083005) (xy 15.826867 -307.057504) (xy 15.781509 -307.025053) (xy 15.74136 -306.986344)
			(xy 15.707274 -306.942201) (xy 15.679978 -306.893566) (xy 15.660055 -306.841475) (xy 15.647929 -306.787038)
			(xy 15.643858 -306.731416) (xy 0.605028 -306.731416) (xy 0.605028 -307.621686) (xy 12.02385 -307.621686)
			(xy 12.027921 -307.566064) (xy 12.040047 -307.511627) (xy 12.05997 -307.459536) (xy 12.087266 -307.410901)
			(xy 12.121352 -307.366758) (xy 12.161501 -307.328049) (xy 12.206859 -307.295598) (xy 12.256459 -307.270097)
			(xy 12.309243 -307.25209) (xy 12.364086 -307.24196) (xy 12.41982 -307.239923) (xy 12.475257 -307.246023)
			(xy 12.529214 -307.260129) (xy 12.580543 -307.281941) (xy 12.628149 -307.310995) (xy 12.671017 -307.34667)
			(xy 12.708234 -307.388207) (xy 12.739007 -307.43472) (xy 12.750091 -307.458364) (xy 13.739366 -307.458364)
			(xy 13.743437 -307.402742) (xy 13.755563 -307.348305) (xy 13.775486 -307.296214) (xy 13.802782 -307.247579)
			(xy 13.836868 -307.203436) (xy 13.877017 -307.164727) (xy 13.922375 -307.132276) (xy 13.971975 -307.106775)
			(xy 14.024759 -307.088768) (xy 14.079602 -307.078638) (xy 14.135336 -307.076601) (xy 14.190773 -307.082701)
			(xy 14.24473 -307.096807) (xy 14.296059 -307.118619) (xy 14.343665 -307.147673) (xy 14.386533 -307.183348)
			(xy 14.42375 -307.224885) (xy 14.454523 -307.271398) (xy 14.478195 -307.321895) (xy 14.494263 -307.375302)
			(xy 14.502383 -307.430478) (xy 14.502892 -307.458364) (xy 14.502383 -307.48625) (xy 14.494263 -307.541426)
			(xy 14.478195 -307.594833) (xy 14.454523 -307.64533) (xy 14.42375 -307.691843) (xy 14.386533 -307.73338)
			(xy 14.343665 -307.769055) (xy 14.296059 -307.798109) (xy 14.24473 -307.819921) (xy 14.190773 -307.834027)
			(xy 14.135336 -307.840127) (xy 14.079602 -307.83809) (xy 14.024759 -307.82796) (xy 13.971975 -307.809953)
			(xy 13.922375 -307.784452) (xy 13.877017 -307.752001) (xy 13.836868 -307.713292) (xy 13.802782 -307.669149)
			(xy 13.775486 -307.620514) (xy 13.755563 -307.568423) (xy 13.743437 -307.513986) (xy 13.739366 -307.458364)
			(xy 12.750091 -307.458364) (xy 12.762679 -307.485217) (xy 12.778747 -307.538624) (xy 12.786867 -307.5938)
			(xy 12.787376 -307.621686) (xy 12.786867 -307.649572) (xy 12.778747 -307.704748) (xy 12.762679 -307.758155)
			(xy 12.739007 -307.808652) (xy 12.708234 -307.855165) (xy 12.671017 -307.896702) (xy 12.628149 -307.932377)
			(xy 12.580543 -307.961431) (xy 12.529214 -307.983243) (xy 12.475257 -307.997349) (xy 12.41982 -308.003449)
			(xy 12.364086 -308.001412) (xy 12.309243 -307.991282) (xy 12.256459 -307.973275) (xy 12.206859 -307.947774)
			(xy 12.161501 -307.915323) (xy 12.121352 -307.876614) (xy 12.087266 -307.832471) (xy 12.05997 -307.783836)
			(xy 12.040047 -307.731745) (xy 12.027921 -307.677308) (xy 12.02385 -307.621686) (xy 0.605028 -307.621686)
			(xy 0.605028 -308.929024) (xy 13.201648 -308.929024) (xy 13.205719 -308.873402) (xy 13.217845 -308.818965)
			(xy 13.237768 -308.766874) (xy 13.265064 -308.718239) (xy 13.29915 -308.674096) (xy 13.339299 -308.635387)
			(xy 13.384657 -308.602936) (xy 13.434257 -308.577435) (xy 13.487041 -308.559428) (xy 13.541884 -308.549298)
			(xy 13.597618 -308.547261) (xy 13.653055 -308.553361) (xy 13.707012 -308.567467) (xy 13.758341 -308.589279)
			(xy 13.805947 -308.618333) (xy 13.848815 -308.654008) (xy 13.886032 -308.695545) (xy 13.916805 -308.742058)
			(xy 13.940477 -308.792555) (xy 13.956545 -308.845962) (xy 13.964665 -308.901138) (xy 13.965174 -308.929024)
			(xy 13.964665 -308.95691) (xy 13.956545 -309.012086) (xy 13.940477 -309.065493) (xy 13.916805 -309.11599)
			(xy 13.886032 -309.162503) (xy 13.848815 -309.20404) (xy 13.805947 -309.239715) (xy 13.758341 -309.268769)
			(xy 13.707012 -309.290581) (xy 13.653055 -309.304687) (xy 13.597618 -309.310787) (xy 13.541884 -309.30875)
			(xy 13.487041 -309.29862) (xy 13.434257 -309.280613) (xy 13.384657 -309.255112) (xy 13.339299 -309.222661)
			(xy 13.29915 -309.183952) (xy 13.265064 -309.139809) (xy 13.237768 -309.091174) (xy 13.217845 -309.039083)
			(xy 13.205719 -308.984646) (xy 13.201648 -308.929024) (xy 0.605028 -308.929024) (xy 0.605028 -318.52997)
			(xy 10.590784 -318.52997) (xy 10.591212 -318.502598) (xy 10.599036 -318.448417) (xy 10.614533 -318.395912)
			(xy 10.637383 -318.346166) (xy 10.667118 -318.300202) (xy 10.684764 -318.279272) (xy 10.69086 -318.27216)
			(xy 10.69721 -318.255142) (xy 10.69721 -318.169798) (xy 10.69086 -318.15278) (xy 10.684764 -318.145668)
			(xy 10.667138 -318.124726) (xy 10.637425 -318.078755) (xy 10.614587 -318.02901) (xy 10.599093 -317.976512)
			(xy 10.591261 -317.922338) (xy 10.590784 -317.89497) (xy 10.59125 -317.867718) (xy 10.59901 -317.81377)
			(xy 10.614369 -317.761476) (xy 10.637013 -317.711899) (xy 10.666482 -317.666049) (xy 10.702175 -317.624859)
			(xy 10.743367 -317.589168) (xy 10.789218 -317.559702) (xy 10.838796 -317.537061) (xy 10.891092 -317.521706)
			(xy 10.94504 -317.513948) (xy 10.972292 -317.513462) (xy 10.999663 -317.513918) (xy 11.053843 -317.521736)
			(xy 11.106347 -317.537226) (xy 11.156093 -317.560071) (xy 11.202059 -317.589799) (xy 11.22299 -317.607442)
			(xy 11.230102 -317.613538) (xy 11.24712 -317.619888) (xy 11.332464 -317.619888) (xy 11.349482 -317.613538)
			(xy 11.356594 -317.607442) (xy 11.377527 -317.589801) (xy 11.423495 -317.560077) (xy 11.473241 -317.537231)
			(xy 11.525743 -317.521735) (xy 11.579921 -317.513906) (xy 11.634663 -317.513906) (xy 11.688841 -317.521735)
			(xy 11.741343 -317.537231) (xy 11.791089 -317.560077) (xy 11.837057 -317.589801) (xy 11.85799 -317.607442)
			(xy 11.865102 -317.613538) (xy 11.88212 -317.619888) (xy 11.967464 -317.619888) (xy 11.984482 -317.613538)
			(xy 11.991594 -317.607442) (xy 12.012523 -317.589799) (xy 12.058496 -317.560086) (xy 12.108244 -317.53725)
			(xy 12.160746 -317.52176) (xy 12.214922 -317.513934) (xy 12.242292 -317.513462) (xy 12.269542 -317.513985)
			(xy 12.323487 -317.52174) (xy 12.375779 -317.537092) (xy 12.425354 -317.55973) (xy 12.471203 -317.589193)
			(xy 12.512393 -317.624881) (xy 12.548084 -317.666067) (xy 12.577551 -317.711913) (xy 12.600194 -317.761486)
			(xy 12.615552 -317.813776) (xy 12.623312 -317.86772) (xy 12.6238 -317.89497) (xy 12.623316 -317.92234)
			(xy 12.615503 -317.976518) (xy 12.600018 -318.029021) (xy 12.57718 -318.078768) (xy 12.547459 -318.124736)
			(xy 12.52982 -318.145668) (xy 12.523724 -318.15278) (xy 12.517374 -318.169798) (xy 12.517374 -318.255142)
			(xy 12.523724 -318.27216) (xy 12.52982 -318.279272) (xy 12.547463 -318.300201) (xy 12.577173 -318.346175)
			(xy 12.600008 -318.395923) (xy 12.615498 -318.448425) (xy 12.623326 -318.502601) (xy 12.6238 -318.52997)
			(xy 12.623317 -318.557222) (xy 12.615564 -318.611173) (xy 12.600211 -318.663471) (xy 12.577571 -318.713052)
			(xy 12.548106 -318.758905) (xy 12.512414 -318.800099) (xy 12.471223 -318.835793) (xy 12.425371 -318.865261)
			(xy 12.375792 -318.887903) (xy 12.323495 -318.903259) (xy 12.269544 -318.911015) (xy 12.242292 -318.911478)
			(xy 12.214921 -318.911022) (xy 12.160742 -318.903203) (xy 12.108238 -318.887711) (xy 12.058491 -318.864867)
			(xy 12.012525 -318.83514) (xy 11.991594 -318.817498) (xy 11.984482 -318.811402) (xy 11.967464 -318.805052)
			(xy 11.88212 -318.805052) (xy 11.865102 -318.811402) (xy 11.85799 -318.817498) (xy 11.837057 -318.835139)
			(xy 11.791089 -318.864863) (xy 11.741343 -318.887709) (xy 11.688841 -318.903205) (xy 11.634663 -318.911034)
			(xy 11.579921 -318.911034) (xy 11.525743 -318.903205) (xy 11.473241 -318.887709) (xy 11.423495 -318.864863)
			(xy 11.377527 -318.835139) (xy 11.356594 -318.817498) (xy 11.349482 -318.811402) (xy 11.332464 -318.805052)
			(xy 11.24712 -318.805052) (xy 11.230102 -318.811402) (xy 11.22299 -318.817498) (xy 11.202072 -318.835155)
			(xy 11.156096 -318.864864) (xy 11.106344 -318.887697) (xy 11.053841 -318.903184) (xy 10.999662 -318.911007)
			(xy 10.972292 -318.911478) (xy 10.945038 -318.911052) (xy 10.891084 -318.903293) (xy 10.838783 -318.887935)
			(xy 10.789201 -318.865289) (xy 10.743347 -318.835817) (xy 10.702153 -318.80012) (xy 10.66646 -318.758923)
			(xy 10.636993 -318.713065) (xy 10.614352 -318.663481) (xy 10.598999 -318.611179) (xy 10.591245 -318.557224)
			(xy 10.590784 -318.52997) (xy 0.605028 -318.52997) (xy 0.605028 -318.608202) (xy 0.605457 -318.618269)
			(xy 0.613182 -318.636864) (xy 0.620014 -318.64427) (xy 1.116838 -319.141094) (xy 1.124238 -319.147935)
			(xy 1.142836 -319.155657) (xy 1.152906 -319.15608)
		)
		(stroke
			(width 0)
			(type solid)
		)
		(fill yes)
		(layer "In9.Cu")
		(net "GND")
	)
	(gr_poly
		(pts
			(arc
				(start 200.481692 -418.081968)
				(mid 201.086106 -417.953924)
				(end 201.586846 -417.592002)
			)
			(arc
				(start 201.586846 -417.592002)
				(mid 202.42889 -416.98332)
				(end 203.445364 -416.768026)
			)
			(arc
				(start 271.794732 -416.768026)
				(mid 272.811071 -416.983322)
				(end 273.652996 -417.592002)
			)
			(arc
				(start 273.652996 -417.592002)
				(mid 274.153727 -417.953921)
				(end 274.75815 -418.081968)
			)
			(arc
				(start 465.600034 -418.081968)
				(mid 466.655034 -417.644972)
				(end 467.09203 -416.589972)
			)
			(arc
				(start 467.09203 -246.488204)
				(mid 466.978493 -245.917325)
				(end 466.65515 -245.433342)
			)
			(arc
				(start 464.026504 -242.80495)
				(mid 463.482885 -241.991412)
				(end 463.291936 -241.031776)
			)
			(arc
				(start 463.291936 -87.588344)
				(mid 463.482826 -86.628673)
				(end 464.026504 -85.81517)
			)
			(arc
				(start 466.65515 -83.186524)
				(mid 466.978483 -82.702667)
				(end 467.09203 -82.131916)
			)
			(arc
				(start 467.09203 -1.999996)
				(mid 466.655034 -0.944996)
				(end 465.600034 -0.508)
			)
			(arc
				(start 446.265046 -0.508)
				(mid 445.210046 -0.944996)
				(end 444.77305 -1.999996)
			)
			(arc
				(start 444.77305 -11.850116)
				(mid 444.676277 -12.381671)
				(end 444.3984 -12.845034)
			)
			(xy 444.3984 -12.869164) (xy 444.399924 -12.870688)
			(arc
				(start 445.002666 -12.870688)
				(mid 445.20965 -12.378943)
				(end 445.280288 -11.850116)
			)
			(arc
				(start 445.280288 -1.999996)
				(mid 445.568553 -1.303936)
				(end 446.264538 -1.015492)
			)
			(arc
				(start 465.600034 -1.015492)
				(mid 466.296273 -1.303831)
				(end 466.584792 -1.999996)
			)
			(arc
				(start 466.584792 -82.131916)
				(mid 466.509885 -82.508586)
				(end 466.296502 -82.827876)
			)
			(arc
				(start 463.667856 -85.456522)
				(mid 463.014235 -86.434595)
				(end 462.784698 -87.588344)
			)
			(xy 462.784444 -87.588344) (xy 462.784444 -241.031776)
			(arc
				(start 462.784698 -241.031776)
				(mid 463.014268 -242.185519)
				(end 463.667856 -243.163598)
			)
			(arc
				(start 466.296502 -245.79199)
				(mid 466.509882 -246.11143)
				(end 466.584792 -246.488204)
			)
			(arc
				(start 466.584792 -416.589972)
				(mid 466.296527 -417.286032)
				(end 465.600542 -417.574476)
			)
			(xy 414.915604 -417.574476) (xy 414.915604 -417.797742) (xy 400.95424 -417.797742) (xy 400.95424 -417.574476)
			(xy 326.621648 -417.574476) (xy 326.621648 -417.747958) (xy 313.065922 -417.747958) (xy 313.065922 -417.574476)
			(arc
				(start 274.757896 -417.574476)
				(mid 274.359217 -417.490052)
				(end 274.028916 -417.251388)
			)
			(arc
				(start 274.028916 -417.251388)
				(mid 273.01669 -416.519565)
				(end 271.794732 -416.260788)
			)
			(arc
				(start 203.445364 -416.260788)
				(mid 202.223266 -416.519531)
				(end 201.210926 -417.251388)
			)
			(arc
				(start 201.210926 -417.251388)
				(mid 200.880626 -417.490098)
				(end 200.481946 -417.574476)
			)
			(xy 154.673554 -417.574476) (xy 154.673554 -417.693856) (xy 141.027912 -417.693856) (xy 141.027912 -417.574476)
			(xy 66.745104 -417.574476) (xy 66.745104 -417.671758) (xy 53.039772 -417.671758) (xy 53.039772 -417.574476)
			(arc
				(start 1.999996 -417.574476)
				(mid 1.303847 -417.286121)
				(end 1.015492 -416.589972)
			)
			(xy 1.015492 -388.54888) (xy 0.614934 -388.148322) (xy 0.614934 -384.796792) (xy 1.015492 -384.396234)
			(arc
				(start 1.015492 -246.48795)
				(mid 1.090466 -246.111319)
				(end 1.303782 -245.79199)
			)
			(arc
				(start 3.93192 -243.163852)
				(mid 4.58575 -242.18556)
				(end 4.815332 -241.031522)
			)
			(arc
				(start 4.815332 -87.588344)
				(mid 4.585694 -86.434435)
				(end 3.93192 -85.456268)
			)
			(arc
				(start 1.303528 -82.827876)
				(mid 1.090411 -82.508641)
				(end 1.015492 -82.13217)
			)
			(arc
				(start 1.015492 -1.999996)
				(mid 1.303847 -1.303847)
				(end 1.999996 -1.015492)
			)
			(arc
				(start 5.964936 -1.015492)
				(mid 6.661085 -1.303847)
				(end 6.94944 -1.999996)
			)
			(arc
				(start 6.94944 -11.850116)
				(mid 7.539853 -13.275118)
				(end 8.96493 -13.865352)
			)
			(xy 16.2814 -13.865352) (xy 16.371316 -13.775436) (xy 16.371316 -13.44803) (xy 16.2814 -13.358114)
			(arc
				(start 8.96493 -13.358114)
				(mid 7.898614 -12.916432)
				(end 7.456932 -11.850116)
			)
			(arc
				(start 7.456932 -1.999996)
				(mid 7.019936 -0.944996)
				(end 5.964936 -0.508)
			)
			(arc
				(start 1.999996 -0.508)
				(mid 0.944996 -0.944996)
				(end 0.508 -1.999996)
			)
			(arc
				(start 0.508 -82.131916)
				(mid 0.621601 -82.702644)
				(end 0.94488 -83.186524)
			)
			(arc
				(start 3.573272 -85.81517)
				(mid 4.117081 -86.628665)
				(end 4.308094 -87.588344)
			)
			(arc
				(start 4.308094 -241.031522)
				(mid 4.117082 -241.991334)
				(end 3.573272 -242.80495)
			)
			(arc
				(start 0.94488 -245.433342)
				(mid 0.621552 -245.917331)
				(end 0.508 -246.488204)
			)
			(arc
				(start 0.508 -416.589972)
				(mid 0.944996 -417.644972)
				(end 1.999996 -418.081968)
			)
		)
		(stroke
			(width 0)
			(type solid)
		)
		(fill yes)
		(layer "In9.Cu")
		(net "GND")
	)
	(gr_poly
		(pts
			(xy 142.532608 -301.3964) (xy 142.537562 -301.396281) (xy 142.547283 -301.39436) (xy 142.551912 -301.39259)
			(xy 143.380206 -301.04969) (xy 143.39697 -301.025814) (xy 143.397732 -301.011082) (xy 143.399826 -300.982201)
			(xy 143.411645 -300.925517) (xy 143.431895 -300.87127) (xy 143.460113 -300.820708) (xy 143.495649 -300.774991)
			(xy 143.537686 -300.735171) (xy 143.58526 -300.702162) (xy 143.637276 -300.676724) (xy 143.692539 -300.65944)
			(xy 143.74978 -300.650707) (xy 143.778732 -300.650148) (xy 143.804752 -300.650572) (xy 143.856313 -300.65761)
			(xy 143.906439 -300.671593) (xy 143.954199 -300.692261) (xy 143.998705 -300.719229) (xy 144.039132 -300.751998)
			(xy 144.074728 -300.789958) (xy 144.090136 -300.81093) (xy 144.099026 -300.823884) (xy 144.127982 -300.834552)
			(xy 144.771618 -300.682406) (xy 144.778392 -300.680582) (xy 144.790636 -300.673749) (xy 144.795748 -300.668944)
			(xy 147.095464 -298.369228) (xy 147.102303 -298.361827) (xy 147.110017 -298.343229) (xy 147.11045 -298.33316)
			(xy 147.11045 -281.79141) (xy 147.110027 -281.78134) (xy 147.10231 -281.762738) (xy 147.095464 -281.755342)
			(xy 146.46148 -281.121358) (xy 146.454368 -281.113992) (xy 146.435572 -281.106372) (xy 142.653512 -281.106372)
			(xy 142.64344 -281.106792) (xy 142.62483 -281.1145) (xy 142.617444 -281.121358) (xy 142.069312 -281.66949)
			(xy 142.061946 -281.676602) (xy 142.054326 -281.695398) (xy 142.054326 -282.668472) (xy 142.05494 -282.68032)
			(xy 142.065532 -282.701517) (xy 142.074646 -282.709112) (xy 142.149576 -282.764992) (xy 142.172944 -282.76931)
			(xy 142.184628 -282.765754) (xy 142.211137 -282.758399) (xy 142.26558 -282.750502) (xy 142.293086 -282.750006)
			(xy 142.293594 -282.750006) (xy 142.320846 -282.750469) (xy 142.374796 -282.758225) (xy 142.427092 -282.77358)
			(xy 142.476671 -282.796221) (xy 142.522524 -282.825688) (xy 142.563715 -282.86138) (xy 142.599408 -282.902572)
			(xy 142.628876 -282.948423) (xy 142.651518 -282.998002) (xy 142.666874 -283.050298) (xy 142.674631 -283.104248)
			(xy 142.674631 -283.131514) (xy 143.387062 -283.131514) (xy 143.391133 -283.075892) (xy 143.403259 -283.021455)
			(xy 143.423182 -282.969364) (xy 143.450478 -282.920729) (xy 143.484564 -282.876586) (xy 143.524713 -282.837877)
			(xy 143.570071 -282.805426) (xy 143.619671 -282.779925) (xy 143.672455 -282.761918) (xy 143.727298 -282.751788)
			(xy 143.783032 -282.749751) (xy 143.838469 -282.755851) (xy 143.892426 -282.769957) (xy 143.943755 -282.791769)
			(xy 143.991361 -282.820823) (xy 144.034229 -282.856498) (xy 144.071446 -282.898035) (xy 144.102219 -282.944548)
			(xy 144.125891 -282.995045) (xy 144.141959 -283.048452) (xy 144.150079 -283.103628) (xy 144.150588 -283.131514)
			(xy 144.276062 -283.131514) (xy 144.280133 -283.075892) (xy 144.292259 -283.021455) (xy 144.312182 -282.969364)
			(xy 144.339478 -282.920729) (xy 144.373564 -282.876586) (xy 144.413713 -282.837877) (xy 144.459071 -282.805426)
			(xy 144.508671 -282.779925) (xy 144.561455 -282.761918) (xy 144.616298 -282.751788) (xy 144.672032 -282.749751)
			(xy 144.727469 -282.755851) (xy 144.781426 -282.769957) (xy 144.832755 -282.791769) (xy 144.880361 -282.820823)
			(xy 144.923229 -282.856498) (xy 144.960446 -282.898035) (xy 144.991219 -282.944548) (xy 145.014891 -282.995045)
			(xy 145.030959 -283.048452) (xy 145.039079 -283.103628) (xy 145.039588 -283.131514) (xy 145.039079 -283.1594)
			(xy 145.030959 -283.214576) (xy 145.014891 -283.267983) (xy 144.991219 -283.31848) (xy 144.960446 -283.364993)
			(xy 144.923229 -283.40653) (xy 144.880361 -283.442205) (xy 144.832755 -283.471259) (xy 144.781426 -283.493071)
			(xy 144.727469 -283.507177) (xy 144.672032 -283.513277) (xy 144.616298 -283.51124) (xy 144.561455 -283.50111)
			(xy 144.508671 -283.483103) (xy 144.459071 -283.457602) (xy 144.413713 -283.425151) (xy 144.373564 -283.386442)
			(xy 144.339478 -283.342299) (xy 144.312182 -283.293664) (xy 144.292259 -283.241573) (xy 144.280133 -283.187136)
			(xy 144.276062 -283.131514) (xy 144.150588 -283.131514) (xy 144.150079 -283.1594) (xy 144.141959 -283.214576)
			(xy 144.125891 -283.267983) (xy 144.102219 -283.31848) (xy 144.071446 -283.364993) (xy 144.034229 -283.40653)
			(xy 143.991361 -283.442205) (xy 143.943755 -283.471259) (xy 143.892426 -283.493071) (xy 143.838469 -283.507177)
			(xy 143.783032 -283.513277) (xy 143.727298 -283.51124) (xy 143.672455 -283.50111) (xy 143.619671 -283.483103)
			(xy 143.570071 -283.457602) (xy 143.524713 -283.425151) (xy 143.484564 -283.386442) (xy 143.450478 -283.342299)
			(xy 143.423182 -283.293664) (xy 143.403259 -283.241573) (xy 143.391133 -283.187136) (xy 143.387062 -283.131514)
			(xy 142.674631 -283.131514) (xy 142.674631 -283.158752) (xy 142.666874 -283.212702) (xy 142.651518 -283.264998)
			(xy 142.628876 -283.314577) (xy 142.599408 -283.360428) (xy 142.563715 -283.40162) (xy 142.522524 -283.437312)
			(xy 142.476671 -283.466779) (xy 142.427092 -283.48942) (xy 142.374796 -283.504775) (xy 142.320846 -283.512531)
			(xy 142.293594 -283.513022) (xy 142.293086 -283.513022) (xy 142.265579 -283.512539) (xy 142.211138 -283.504629)
			(xy 142.184628 -283.497274) (xy 142.172944 -283.493718) (xy 142.149576 -283.498036) (xy 142.074646 -283.553916)
			(xy 142.065529 -283.561514) (xy 142.05491 -283.582705) (xy 142.054326 -283.594556) (xy 142.054326 -285.868872)
			(xy 142.05494 -285.88072) (xy 142.065532 -285.901917) (xy 142.074646 -285.909512) (xy 142.149576 -285.965392)
			(xy 142.172944 -285.96971) (xy 142.184628 -285.966154) (xy 142.211137 -285.958799) (xy 142.26558 -285.950902)
			(xy 142.293086 -285.950406) (xy 142.293594 -285.950406) (xy 142.320846 -285.950869) (xy 142.374796 -285.958625)
			(xy 142.427092 -285.97398) (xy 142.476671 -285.996621) (xy 142.522524 -286.026088) (xy 142.563715 -286.06178)
			(xy 142.599408 -286.102972) (xy 142.628876 -286.148823) (xy 142.651518 -286.198402) (xy 142.666874 -286.250698)
			(xy 142.674631 -286.304648) (xy 142.674631 -286.331914) (xy 143.387062 -286.331914) (xy 143.391133 -286.276292)
			(xy 143.403259 -286.221855) (xy 143.423182 -286.169764) (xy 143.450478 -286.121129) (xy 143.484564 -286.076986)
			(xy 143.524713 -286.038277) (xy 143.570071 -286.005826) (xy 143.619671 -285.980325) (xy 143.672455 -285.962318)
			(xy 143.727298 -285.952188) (xy 143.783032 -285.950151) (xy 143.838469 -285.956251) (xy 143.892426 -285.970357)
			(xy 143.943755 -285.992169) (xy 143.991361 -286.021223) (xy 144.034229 -286.056898) (xy 144.071446 -286.098435)
			(xy 144.102219 -286.144948) (xy 144.125891 -286.195445) (xy 144.141959 -286.248852) (xy 144.150079 -286.304028)
			(xy 144.150588 -286.331914) (xy 144.276062 -286.331914) (xy 144.280133 -286.276292) (xy 144.292259 -286.221855)
			(xy 144.312182 -286.169764) (xy 144.339478 -286.121129) (xy 144.373564 -286.076986) (xy 144.413713 -286.038277)
			(xy 144.459071 -286.005826) (xy 144.508671 -285.980325) (xy 144.561455 -285.962318) (xy 144.616298 -285.952188)
			(xy 144.672032 -285.950151) (xy 144.727469 -285.956251) (xy 144.781426 -285.970357) (xy 144.832755 -285.992169)
			(xy 144.880361 -286.021223) (xy 144.923229 -286.056898) (xy 144.960446 -286.098435) (xy 144.991219 -286.144948)
			(xy 145.014891 -286.195445) (xy 145.030959 -286.248852) (xy 145.039079 -286.304028) (xy 145.039588 -286.331914)
			(xy 145.039079 -286.3598) (xy 145.030959 -286.414976) (xy 145.014891 -286.468383) (xy 144.991219 -286.51888)
			(xy 144.960446 -286.565393) (xy 144.923229 -286.60693) (xy 144.880361 -286.642605) (xy 144.832755 -286.671659)
			(xy 144.781426 -286.693471) (xy 144.727469 -286.707577) (xy 144.672032 -286.713677) (xy 144.616298 -286.71164)
			(xy 144.561455 -286.70151) (xy 144.508671 -286.683503) (xy 144.459071 -286.658002) (xy 144.413713 -286.625551)
			(xy 144.373564 -286.586842) (xy 144.339478 -286.542699) (xy 144.312182 -286.494064) (xy 144.292259 -286.441973)
			(xy 144.280133 -286.387536) (xy 144.276062 -286.331914) (xy 144.150588 -286.331914) (xy 144.150079 -286.3598)
			(xy 144.141959 -286.414976) (xy 144.125891 -286.468383) (xy 144.102219 -286.51888) (xy 144.071446 -286.565393)
			(xy 144.034229 -286.60693) (xy 143.991361 -286.642605) (xy 143.943755 -286.671659) (xy 143.892426 -286.693471)
			(xy 143.838469 -286.707577) (xy 143.783032 -286.713677) (xy 143.727298 -286.71164) (xy 143.672455 -286.70151)
			(xy 143.619671 -286.683503) (xy 143.570071 -286.658002) (xy 143.524713 -286.625551) (xy 143.484564 -286.586842)
			(xy 143.450478 -286.542699) (xy 143.423182 -286.494064) (xy 143.403259 -286.441973) (xy 143.391133 -286.387536)
			(xy 143.387062 -286.331914) (xy 142.674631 -286.331914) (xy 142.674631 -286.359152) (xy 142.666874 -286.413102)
			(xy 142.651518 -286.465398) (xy 142.628876 -286.514977) (xy 142.599408 -286.560828) (xy 142.563715 -286.60202)
			(xy 142.522524 -286.637712) (xy 142.476671 -286.667179) (xy 142.427092 -286.68982) (xy 142.374796 -286.705175)
			(xy 142.320846 -286.712931) (xy 142.293594 -286.713422) (xy 142.293086 -286.713422) (xy 142.265579 -286.712939)
			(xy 142.211138 -286.705029) (xy 142.184628 -286.697674) (xy 142.172944 -286.694118) (xy 142.149576 -286.698436)
			(xy 142.074646 -286.754316) (xy 142.065529 -286.761914) (xy 142.05491 -286.783105) (xy 142.054326 -286.794956)
			(xy 142.054326 -289.069272) (xy 142.05494 -289.08112) (xy 142.065532 -289.102317) (xy 142.074646 -289.109912)
			(xy 142.149576 -289.165792) (xy 142.172944 -289.17011) (xy 142.184628 -289.166554) (xy 142.211137 -289.159199)
			(xy 142.26558 -289.151302) (xy 142.293086 -289.150806) (xy 142.293594 -289.150806) (xy 142.320846 -289.151269)
			(xy 142.374796 -289.159025) (xy 142.427092 -289.17438) (xy 142.476671 -289.197021) (xy 142.522524 -289.226488)
			(xy 142.563715 -289.26218) (xy 142.599408 -289.303372) (xy 142.628876 -289.349223) (xy 142.651518 -289.398802)
			(xy 142.666874 -289.451098) (xy 142.674631 -289.505048) (xy 142.674631 -289.532314) (xy 143.387062 -289.532314)
			(xy 143.391133 -289.476692) (xy 143.403259 -289.422255) (xy 143.423182 -289.370164) (xy 143.450478 -289.321529)
			(xy 143.484564 -289.277386) (xy 143.524713 -289.238677) (xy 143.570071 -289.206226) (xy 143.619671 -289.180725)
			(xy 143.672455 -289.162718) (xy 143.727298 -289.152588) (xy 143.783032 -289.150551) (xy 143.838469 -289.156651)
			(xy 143.892426 -289.170757) (xy 143.943755 -289.192569) (xy 143.991361 -289.221623) (xy 144.034229 -289.257298)
			(xy 144.071446 -289.298835) (xy 144.102219 -289.345348) (xy 144.125891 -289.395845) (xy 144.141959 -289.449252)
			(xy 144.150079 -289.504428) (xy 144.150588 -289.532314) (xy 144.276062 -289.532314) (xy 144.280133 -289.476692)
			(xy 144.292259 -289.422255) (xy 144.312182 -289.370164) (xy 144.339478 -289.321529) (xy 144.373564 -289.277386)
			(xy 144.413713 -289.238677) (xy 144.459071 -289.206226) (xy 144.508671 -289.180725) (xy 144.561455 -289.162718)
			(xy 144.616298 -289.152588) (xy 144.672032 -289.150551) (xy 144.727469 -289.156651) (xy 144.781426 -289.170757)
			(xy 144.832755 -289.192569) (xy 144.880361 -289.221623) (xy 144.923229 -289.257298) (xy 144.960446 -289.298835)
			(xy 144.991219 -289.345348) (xy 145.014891 -289.395845) (xy 145.030959 -289.449252) (xy 145.039079 -289.504428)
			(xy 145.039588 -289.532314) (xy 145.039079 -289.5602) (xy 145.030959 -289.615376) (xy 145.014891 -289.668783)
			(xy 144.991219 -289.71928) (xy 144.960446 -289.765793) (xy 144.923229 -289.80733) (xy 144.880361 -289.843005)
			(xy 144.832755 -289.872059) (xy 144.781426 -289.893871) (xy 144.727469 -289.907977) (xy 144.672032 -289.914077)
			(xy 144.616298 -289.91204) (xy 144.561455 -289.90191) (xy 144.508671 -289.883903) (xy 144.459071 -289.858402)
			(xy 144.413713 -289.825951) (xy 144.373564 -289.787242) (xy 144.339478 -289.743099) (xy 144.312182 -289.694464)
			(xy 144.292259 -289.642373) (xy 144.280133 -289.587936) (xy 144.276062 -289.532314) (xy 144.150588 -289.532314)
			(xy 144.150079 -289.5602) (xy 144.141959 -289.615376) (xy 144.125891 -289.668783) (xy 144.102219 -289.71928)
			(xy 144.071446 -289.765793) (xy 144.034229 -289.80733) (xy 143.991361 -289.843005) (xy 143.943755 -289.872059)
			(xy 143.892426 -289.893871) (xy 143.838469 -289.907977) (xy 143.783032 -289.914077) (xy 143.727298 -289.91204)
			(xy 143.672455 -289.90191) (xy 143.619671 -289.883903) (xy 143.570071 -289.858402) (xy 143.524713 -289.825951)
			(xy 143.484564 -289.787242) (xy 143.450478 -289.743099) (xy 143.423182 -289.694464) (xy 143.403259 -289.642373)
			(xy 143.391133 -289.587936) (xy 143.387062 -289.532314) (xy 142.674631 -289.532314) (xy 142.674631 -289.559552)
			(xy 142.666874 -289.613502) (xy 142.651518 -289.665798) (xy 142.628876 -289.715377) (xy 142.599408 -289.761228)
			(xy 142.563715 -289.80242) (xy 142.522524 -289.838112) (xy 142.476671 -289.867579) (xy 142.427092 -289.89022)
			(xy 142.374796 -289.905575) (xy 142.320846 -289.913331) (xy 142.293594 -289.913822) (xy 142.293086 -289.913822)
			(xy 142.265579 -289.913339) (xy 142.211138 -289.905429) (xy 142.184628 -289.898074) (xy 142.172944 -289.894518)
			(xy 142.149576 -289.898836) (xy 142.074646 -289.954716) (xy 142.065529 -289.962314) (xy 142.05491 -289.983505)
			(xy 142.054326 -289.995356) (xy 142.054326 -292.269672) (xy 142.05494 -292.28152) (xy 142.065532 -292.302717)
			(xy 142.074646 -292.310312) (xy 142.149576 -292.366192) (xy 142.172944 -292.37051) (xy 142.184628 -292.366954)
			(xy 142.211137 -292.359599) (xy 142.26558 -292.351702) (xy 142.293086 -292.351206) (xy 142.293594 -292.351206)
			(xy 142.320846 -292.351669) (xy 142.374796 -292.359425) (xy 142.427092 -292.37478) (xy 142.476671 -292.397421)
			(xy 142.522524 -292.426888) (xy 142.563715 -292.46258) (xy 142.599408 -292.503772) (xy 142.628876 -292.549623)
			(xy 142.651518 -292.599202) (xy 142.666874 -292.651498) (xy 142.674631 -292.705448) (xy 142.674631 -292.732714)
			(xy 143.387062 -292.732714) (xy 143.391133 -292.677092) (xy 143.403259 -292.622655) (xy 143.423182 -292.570564)
			(xy 143.450478 -292.521929) (xy 143.484564 -292.477786) (xy 143.524713 -292.439077) (xy 143.570071 -292.406626)
			(xy 143.619671 -292.381125) (xy 143.672455 -292.363118) (xy 143.727298 -292.352988) (xy 143.783032 -292.350951)
			(xy 143.838469 -292.357051) (xy 143.892426 -292.371157) (xy 143.943755 -292.392969) (xy 143.991361 -292.422023)
			(xy 144.034229 -292.457698) (xy 144.071446 -292.499235) (xy 144.102219 -292.545748) (xy 144.125891 -292.596245)
			(xy 144.141959 -292.649652) (xy 144.150079 -292.704828) (xy 144.150588 -292.732714) (xy 144.276062 -292.732714)
			(xy 144.280133 -292.677092) (xy 144.292259 -292.622655) (xy 144.312182 -292.570564) (xy 144.339478 -292.521929)
			(xy 144.373564 -292.477786) (xy 144.413713 -292.439077) (xy 144.459071 -292.406626) (xy 144.508671 -292.381125)
			(xy 144.561455 -292.363118) (xy 144.616298 -292.352988) (xy 144.672032 -292.350951) (xy 144.727469 -292.357051)
			(xy 144.781426 -292.371157) (xy 144.832755 -292.392969) (xy 144.880361 -292.422023) (xy 144.923229 -292.457698)
			(xy 144.960446 -292.499235) (xy 144.991219 -292.545748) (xy 145.014891 -292.596245) (xy 145.030959 -292.649652)
			(xy 145.039079 -292.704828) (xy 145.039588 -292.732714) (xy 145.039079 -292.7606) (xy 145.030959 -292.815776)
			(xy 145.014891 -292.869183) (xy 144.991219 -292.91968) (xy 144.960446 -292.966193) (xy 144.923229 -293.00773)
			(xy 144.880361 -293.043405) (xy 144.832755 -293.072459) (xy 144.781426 -293.094271) (xy 144.727469 -293.108377)
			(xy 144.672032 -293.114477) (xy 144.616298 -293.11244) (xy 144.561455 -293.10231) (xy 144.508671 -293.084303)
			(xy 144.459071 -293.058802) (xy 144.413713 -293.026351) (xy 144.373564 -292.987642) (xy 144.339478 -292.943499)
			(xy 144.312182 -292.894864) (xy 144.292259 -292.842773) (xy 144.280133 -292.788336) (xy 144.276062 -292.732714)
			(xy 144.150588 -292.732714) (xy 144.150079 -292.7606) (xy 144.141959 -292.815776) (xy 144.125891 -292.869183)
			(xy 144.102219 -292.91968) (xy 144.071446 -292.966193) (xy 144.034229 -293.00773) (xy 143.991361 -293.043405)
			(xy 143.943755 -293.072459) (xy 143.892426 -293.094271) (xy 143.838469 -293.108377) (xy 143.783032 -293.114477)
			(xy 143.727298 -293.11244) (xy 143.672455 -293.10231) (xy 143.619671 -293.084303) (xy 143.570071 -293.058802)
			(xy 143.524713 -293.026351) (xy 143.484564 -292.987642) (xy 143.450478 -292.943499) (xy 143.423182 -292.894864)
			(xy 143.403259 -292.842773) (xy 143.391133 -292.788336) (xy 143.387062 -292.732714) (xy 142.674631 -292.732714)
			(xy 142.674631 -292.759952) (xy 142.666874 -292.813902) (xy 142.651518 -292.866198) (xy 142.628876 -292.915777)
			(xy 142.599408 -292.961628) (xy 142.563715 -293.00282) (xy 142.522524 -293.038512) (xy 142.476671 -293.067979)
			(xy 142.427092 -293.09062) (xy 142.374796 -293.105975) (xy 142.320846 -293.113731) (xy 142.293594 -293.114222)
			(xy 142.293086 -293.114222) (xy 142.265579 -293.113739) (xy 142.211138 -293.105829) (xy 142.184628 -293.098474)
			(xy 142.172944 -293.094918) (xy 142.149576 -293.099236) (xy 142.074646 -293.155116) (xy 142.065529 -293.162714)
			(xy 142.05491 -293.183905) (xy 142.054326 -293.195756) (xy 142.054326 -295.470072) (xy 142.05494 -295.48192)
			(xy 142.065532 -295.503117) (xy 142.074646 -295.510712) (xy 142.149576 -295.566592) (xy 142.172944 -295.57091)
			(xy 142.184628 -295.567354) (xy 142.211137 -295.559999) (xy 142.26558 -295.552102) (xy 142.293086 -295.551606)
			(xy 142.293594 -295.551606) (xy 142.320846 -295.552069) (xy 142.374796 -295.559825) (xy 142.427092 -295.57518)
			(xy 142.476671 -295.597821) (xy 142.522524 -295.627288) (xy 142.563715 -295.66298) (xy 142.599408 -295.704172)
			(xy 142.628876 -295.750023) (xy 142.651518 -295.799602) (xy 142.666874 -295.851898) (xy 142.674631 -295.905848)
			(xy 142.674631 -295.933114) (xy 143.387062 -295.933114) (xy 143.391133 -295.877492) (xy 143.403259 -295.823055)
			(xy 143.423182 -295.770964) (xy 143.450478 -295.722329) (xy 143.484564 -295.678186) (xy 143.524713 -295.639477)
			(xy 143.570071 -295.607026) (xy 143.619671 -295.581525) (xy 143.672455 -295.563518) (xy 143.727298 -295.553388)
			(xy 143.783032 -295.551351) (xy 143.838469 -295.557451) (xy 143.892426 -295.571557) (xy 143.943755 -295.593369)
			(xy 143.991361 -295.622423) (xy 144.034229 -295.658098) (xy 144.071446 -295.699635) (xy 144.102219 -295.746148)
			(xy 144.125891 -295.796645) (xy 144.141959 -295.850052) (xy 144.150079 -295.905228) (xy 144.150588 -295.933114)
			(xy 144.276062 -295.933114) (xy 144.280133 -295.877492) (xy 144.292259 -295.823055) (xy 144.312182 -295.770964)
			(xy 144.339478 -295.722329) (xy 144.373564 -295.678186) (xy 144.413713 -295.639477) (xy 144.459071 -295.607026)
			(xy 144.508671 -295.581525) (xy 144.561455 -295.563518) (xy 144.616298 -295.553388) (xy 144.672032 -295.551351)
			(xy 144.727469 -295.557451) (xy 144.781426 -295.571557) (xy 144.832755 -295.593369) (xy 144.880361 -295.622423)
			(xy 144.923229 -295.658098) (xy 144.960446 -295.699635) (xy 144.991219 -295.746148) (xy 145.014891 -295.796645)
			(xy 145.030959 -295.850052) (xy 145.039079 -295.905228) (xy 145.039588 -295.933114) (xy 145.039079 -295.961)
			(xy 145.030959 -296.016176) (xy 145.014891 -296.069583) (xy 144.991219 -296.12008) (xy 144.960446 -296.166593)
			(xy 144.923229 -296.20813) (xy 144.880361 -296.243805) (xy 144.832755 -296.272859) (xy 144.781426 -296.294671)
			(xy 144.727469 -296.308777) (xy 144.672032 -296.314877) (xy 144.616298 -296.31284) (xy 144.561455 -296.30271)
			(xy 144.508671 -296.284703) (xy 144.459071 -296.259202) (xy 144.413713 -296.226751) (xy 144.373564 -296.188042)
			(xy 144.339478 -296.143899) (xy 144.312182 -296.095264) (xy 144.292259 -296.043173) (xy 144.280133 -295.988736)
			(xy 144.276062 -295.933114) (xy 144.150588 -295.933114) (xy 144.150079 -295.961) (xy 144.141959 -296.016176)
			(xy 144.125891 -296.069583) (xy 144.102219 -296.12008) (xy 144.071446 -296.166593) (xy 144.034229 -296.20813)
			(xy 143.991361 -296.243805) (xy 143.943755 -296.272859) (xy 143.892426 -296.294671) (xy 143.838469 -296.308777)
			(xy 143.783032 -296.314877) (xy 143.727298 -296.31284) (xy 143.672455 -296.30271) (xy 143.619671 -296.284703)
			(xy 143.570071 -296.259202) (xy 143.524713 -296.226751) (xy 143.484564 -296.188042) (xy 143.450478 -296.143899)
			(xy 143.423182 -296.095264) (xy 143.403259 -296.043173) (xy 143.391133 -295.988736) (xy 143.387062 -295.933114)
			(xy 142.674631 -295.933114) (xy 142.674631 -295.960352) (xy 142.666874 -296.014302) (xy 142.651518 -296.066598)
			(xy 142.628876 -296.116177) (xy 142.599408 -296.162028) (xy 142.563715 -296.20322) (xy 142.522524 -296.238912)
			(xy 142.476671 -296.268379) (xy 142.427092 -296.29102) (xy 142.374796 -296.306375) (xy 142.320846 -296.314131)
			(xy 142.293594 -296.314622) (xy 142.293086 -296.314622) (xy 142.265579 -296.314139) (xy 142.211138 -296.306229)
			(xy 142.184628 -296.298874) (xy 142.172944 -296.295318) (xy 142.149576 -296.299636) (xy 142.074646 -296.355516)
			(xy 142.065529 -296.363114) (xy 142.05491 -296.384305) (xy 142.054326 -296.396156) (xy 142.054326 -298.670472)
			(xy 142.05494 -298.68232) (xy 142.065532 -298.703517) (xy 142.074646 -298.711112) (xy 142.149576 -298.766992)
			(xy 142.172944 -298.77131) (xy 142.184628 -298.767754) (xy 142.211137 -298.760399) (xy 142.26558 -298.752502)
			(xy 142.293086 -298.752006) (xy 142.293594 -298.752006) (xy 142.320846 -298.752469) (xy 142.374796 -298.760225)
			(xy 142.427092 -298.77558) (xy 142.476671 -298.798221) (xy 142.522524 -298.827688) (xy 142.563715 -298.86338)
			(xy 142.599408 -298.904572) (xy 142.628876 -298.950423) (xy 142.651518 -299.000002) (xy 142.666874 -299.052298)
			(xy 142.674631 -299.106248) (xy 142.674631 -299.133514) (xy 143.387062 -299.133514) (xy 143.391133 -299.077892)
			(xy 143.403259 -299.023455) (xy 143.423182 -298.971364) (xy 143.450478 -298.922729) (xy 143.484564 -298.878586)
			(xy 143.524713 -298.839877) (xy 143.570071 -298.807426) (xy 143.619671 -298.781925) (xy 143.672455 -298.763918)
			(xy 143.727298 -298.753788) (xy 143.783032 -298.751751) (xy 143.838469 -298.757851) (xy 143.892426 -298.771957)
			(xy 143.943755 -298.793769) (xy 143.991361 -298.822823) (xy 144.034229 -298.858498) (xy 144.071446 -298.900035)
			(xy 144.102219 -298.946548) (xy 144.125891 -298.997045) (xy 144.141959 -299.050452) (xy 144.150079 -299.105628)
			(xy 144.150588 -299.133514) (xy 144.276062 -299.133514) (xy 144.280133 -299.077892) (xy 144.292259 -299.023455)
			(xy 144.312182 -298.971364) (xy 144.339478 -298.922729) (xy 144.373564 -298.878586) (xy 144.413713 -298.839877)
			(xy 144.459071 -298.807426) (xy 144.508671 -298.781925) (xy 144.561455 -298.763918) (xy 144.616298 -298.753788)
			(xy 144.672032 -298.751751) (xy 144.727469 -298.757851) (xy 144.781426 -298.771957) (xy 144.832755 -298.793769)
			(xy 144.880361 -298.822823) (xy 144.923229 -298.858498) (xy 144.960446 -298.900035) (xy 144.991219 -298.946548)
			(xy 145.014891 -298.997045) (xy 145.030959 -299.050452) (xy 145.039079 -299.105628) (xy 145.039588 -299.133514)
			(xy 145.039079 -299.1614) (xy 145.030959 -299.216576) (xy 145.014891 -299.269983) (xy 144.991219 -299.32048)
			(xy 144.960446 -299.366993) (xy 144.923229 -299.40853) (xy 144.880361 -299.444205) (xy 144.832755 -299.473259)
			(xy 144.781426 -299.495071) (xy 144.727469 -299.509177) (xy 144.672032 -299.515277) (xy 144.616298 -299.51324)
			(xy 144.561455 -299.50311) (xy 144.508671 -299.485103) (xy 144.459071 -299.459602) (xy 144.413713 -299.427151)
			(xy 144.373564 -299.388442) (xy 144.339478 -299.344299) (xy 144.312182 -299.295664) (xy 144.292259 -299.243573)
			(xy 144.280133 -299.189136) (xy 144.276062 -299.133514) (xy 144.150588 -299.133514) (xy 144.150079 -299.1614)
			(xy 144.141959 -299.216576) (xy 144.125891 -299.269983) (xy 144.102219 -299.32048) (xy 144.071446 -299.366993)
			(xy 144.034229 -299.40853) (xy 143.991361 -299.444205) (xy 143.943755 -299.473259) (xy 143.892426 -299.495071)
			(xy 143.838469 -299.509177) (xy 143.783032 -299.515277) (xy 143.727298 -299.51324) (xy 143.672455 -299.50311)
			(xy 143.619671 -299.485103) (xy 143.570071 -299.459602) (xy 143.524713 -299.427151) (xy 143.484564 -299.388442)
			(xy 143.450478 -299.344299) (xy 143.423182 -299.295664) (xy 143.403259 -299.243573) (xy 143.391133 -299.189136)
			(xy 143.387062 -299.133514) (xy 142.674631 -299.133514) (xy 142.674631 -299.160752) (xy 142.666874 -299.214702)
			(xy 142.651518 -299.266998) (xy 142.628876 -299.316577) (xy 142.599408 -299.362428) (xy 142.563715 -299.40362)
			(xy 142.522524 -299.439312) (xy 142.476671 -299.468779) (xy 142.427092 -299.49142) (xy 142.374796 -299.506775)
			(xy 142.320846 -299.514531) (xy 142.293594 -299.515022) (xy 142.293086 -299.515022) (xy 142.265579 -299.514539)
			(xy 142.211138 -299.506629) (xy 142.184628 -299.499274) (xy 142.172944 -299.495718) (xy 142.149576 -299.500036)
			(xy 142.074646 -299.555916) (xy 142.065529 -299.563514) (xy 142.05491 -299.584705) (xy 142.054326 -299.596556)
			(xy 142.054326 -301.246794) (xy 142.054749 -301.256864) (xy 142.062464 -301.275468) (xy 142.069312 -301.282862)
			(xy 142.167864 -301.381414) (xy 142.175262 -301.38826) (xy 142.193861 -301.395984) (xy 142.203932 -301.3964)
		)
		(stroke
			(width 0)
			(type solid)
		)
		(fill yes)
		(layer "In9.Cu")
		(net "P1V8_PLL0_PEX1")
	)
	(gr_poly
		(pts
			(xy 102.732586 -51.393344) (xy 102.741785 -51.392945) (xy 102.759004 -51.386458) (xy 102.77285 -51.374342)
			(xy 102.777544 -51.36642) (xy 102.826058 -51.274726) (xy 102.824534 -51.246532) (xy 102.816406 -51.234848)
			(xy 102.800678 -51.210929) (xy 102.775799 -51.159374) (xy 102.758898 -51.104681) (xy 102.750355 -51.048078)
			(xy 102.749858 -51.019456) (xy 102.750347 -50.992206) (xy 102.758108 -50.938261) (xy 102.773467 -50.88597)
			(xy 102.79611 -50.836396) (xy 102.825577 -50.790549) (xy 102.861268 -50.749361) (xy 102.902457 -50.713671)
			(xy 102.948305 -50.684205) (xy 102.997879 -50.661563) (xy 103.050171 -50.646206) (xy 103.104116 -50.638446)
			(xy 103.131366 -50.637948) (xy 103.13162 -50.637948) (xy 103.158871 -50.638435) (xy 103.212819 -50.646194)
			(xy 103.265114 -50.66155) (xy 103.314692 -50.684192) (xy 103.360543 -50.713658) (xy 103.401734 -50.749349)
			(xy 103.437428 -50.790538) (xy 103.466897 -50.836387) (xy 103.489541 -50.885963) (xy 103.504901 -50.938257)
			(xy 103.512663 -50.992205) (xy 103.513128 -51.019456) (xy 103.512874 -51.03495) (xy 103.511858 -51.049428)
			(xy 103.509505 -51.07412) (xy 103.499208 -51.122641) (xy 103.482698 -51.169414) (xy 103.460256 -51.213648)
			(xy 103.44658 -51.23434) (xy 103.43896 -51.24577) (xy 103.437944 -51.259994) (xy 103.437676 -51.267112)
			(xy 103.440633 -51.28104) (xy 103.443786 -51.287426) (xy 103.485696 -51.36642) (xy 103.490354 -51.374377)
			(xy 103.504187 -51.386546) (xy 103.521441 -51.393005) (xy 103.530654 -51.393344) (xy 104.422448 -51.393344)
			(xy 104.432413 -51.392862) (xy 104.450846 -51.385284) (xy 104.458262 -51.378612) (xy 104.975914 -50.86096)
			(xy 104.97947 -50.85334) (xy 104.985566 -50.841402) (xy 104.986074 -50.840894) (xy 104.994456 -50.825654)
			(xy 104.997758 -50.820066) (xy 105.002838 -50.802032) (xy 105.00487 -50.788062) (xy 105.00487 -50.1904)
			(xy 104.996488 -50.163222) (xy 104.992678 -50.15738) (xy 104.978606 -50.134347) (xy 104.956385 -50.085159)
			(xy 104.94132 -50.033331) (xy 104.93371 -49.979896) (xy 104.933709 -49.925921) (xy 104.941316 -49.872486)
			(xy 104.956379 -49.820656) (xy 104.978598 -49.771468) (xy 104.992678 -49.74844) (xy 104.996488 -49.742598)
			(xy 105.00487 -49.71542) (xy 105.00487 -49.1744) (xy 104.996488 -49.147222) (xy 104.992678 -49.14138)
			(xy 104.978606 -49.118347) (xy 104.956385 -49.069159) (xy 104.94132 -49.017331) (xy 104.93371 -48.963896)
			(xy 104.933709 -48.909921) (xy 104.941316 -48.856486) (xy 104.956379 -48.804656) (xy 104.978598 -48.755468)
			(xy 104.992678 -48.73244) (xy 104.996488 -48.726598) (xy 105.00487 -48.69942) (xy 105.00487 -47.623222)
			(xy 105.00233 -47.6123) (xy 104.99979 -47.606966) (xy 104.988898 -47.583246) (xy 104.972926 -47.533555)
			(xy 104.963866 -47.482153) (xy 104.962452 -47.45609) (xy 104.962198 -47.448216) (xy 104.962198 -47.441612)
			(xy 104.962738 -47.413182) (xy 104.971211 -47.356957) (xy 104.987942 -47.302615) (xy 104.99979 -47.276766)
			(xy 105.001822 -47.27194) (xy 105.00487 -47.260256) (xy 105.00487 -46.1264) (xy 104.996488 -46.099222)
			(xy 104.992678 -46.09338) (xy 104.978606 -46.070347) (xy 104.956385 -46.021159) (xy 104.94132 -45.969331)
			(xy 104.93371 -45.915896) (xy 104.933709 -45.861921) (xy 104.941316 -45.808486) (xy 104.956379 -45.756656)
			(xy 104.978598 -45.707468) (xy 104.992678 -45.68444) (xy 104.996488 -45.678598) (xy 105.00487 -45.65142)
			(xy 105.00487 -45.1104) (xy 104.996488 -45.083222) (xy 104.992678 -45.07738) (xy 104.978606 -45.054347)
			(xy 104.956385 -45.005159) (xy 104.94132 -44.953331) (xy 104.93371 -44.899896) (xy 104.933709 -44.845921)
			(xy 104.941316 -44.792486) (xy 104.956379 -44.740656) (xy 104.978598 -44.691468) (xy 104.992678 -44.66844)
			(xy 104.996488 -44.662598) (xy 105.00487 -44.63542) (xy 105.00487 -44.0944) (xy 104.996488 -44.067222)
			(xy 104.992678 -44.06138) (xy 104.978606 -44.038347) (xy 104.956385 -43.989159) (xy 104.94132 -43.937331)
			(xy 104.93371 -43.883896) (xy 104.933709 -43.829921) (xy 104.941316 -43.776486) (xy 104.956379 -43.724656)
			(xy 104.978598 -43.675468) (xy 104.992678 -43.65244) (xy 104.996488 -43.646598) (xy 105.00487 -43.61942)
			(xy 105.00487 -43.0784) (xy 104.996488 -43.051222) (xy 104.992678 -43.04538) (xy 104.978606 -43.022347)
			(xy 104.956385 -42.973159) (xy 104.94132 -42.921331) (xy 104.93371 -42.867896) (xy 104.933709 -42.813921)
			(xy 104.941316 -42.760486) (xy 104.956379 -42.708656) (xy 104.978598 -42.659468) (xy 104.992678 -42.63644)
			(xy 104.996488 -42.630598) (xy 105.00487 -42.60342) (xy 105.00487 -29.76753) (xy 105.004672 -29.760427)
			(xy 105.000801 -29.746761) (xy 104.99725 -29.740606) (xy 104.984042 -29.719778) (xy 104.98052 -29.713612)
			(xy 104.976666 -29.699951) (xy 104.976422 -29.692854) (xy 104.976422 -28.38323) (xy 104.97664 -28.376189)
			(xy 104.980497 -28.362647) (xy 104.984042 -28.35656) (xy 104.996996 -28.336494) (xy 104.99886 -28.333385)
			(xy 105.001797 -28.326758) (xy 105.002838 -28.323286) (xy 105.00487 -28.316174) (xy 105.00487 -27.872436)
			(xy 105.004435 -27.862372) (xy 104.9967 -27.843787) (xy 104.989884 -27.836368) (xy 104.750362 -27.596846)
			(xy 104.74325 -27.58948) (xy 104.724454 -27.58186) (xy 95.399352 -27.58186) (xy 95.386955 -27.582398)
			(xy 95.364966 -27.593838) (xy 95.357442 -27.603704) (xy 95.339034 -27.629339) (xy 95.296303 -27.675783)
			(xy 95.247599 -27.715918) (xy 95.193843 -27.748984) (xy 95.136056 -27.774354) (xy 95.075333 -27.791547)
			(xy 95.012823 -27.800238) (xy 94.981268 -27.800808) (xy 94.949712 -27.800264) (xy 94.887201 -27.791567)
			(xy 94.826476 -27.774368) (xy 94.768688 -27.748996) (xy 94.714931 -27.715928) (xy 94.666223 -27.675793)
			(xy 94.623488 -27.62935) (xy 94.605094 -27.603704) (xy 94.597434 -27.593988) (xy 94.575535 -27.582561)
			(xy 94.563184 -27.58186) (xy 90.428064 -27.58186) (xy 90.417998 -27.582291) (xy 90.399409 -27.590022)
			(xy 90.391996 -27.596846) (xy 90.122756 -27.866086) (xy 90.116152 -27.877516) (xy 90.114374 -27.884374)
			(xy 90.106616 -27.912533) (xy 90.083721 -27.966264) (xy 90.052901 -28.015876) (xy 90.014878 -28.060209)
			(xy 89.97054 -28.098227) (xy 89.920925 -28.129041) (xy 89.867191 -28.15193) (xy 89.839038 -28.15971)
			(xy 89.83218 -28.161488) (xy 89.82075 -28.168092) (xy 89.805002 -28.18384) (xy 89.797636 -28.190952)
			(xy 89.790016 -28.209748) (xy 89.790016 -29.114242) (xy 96.847152 -29.114242) (xy 96.847152 -28.250642)
			(xy 96.847642 -28.220658) (xy 96.85547 -28.161202) (xy 96.870991 -28.103277) (xy 96.89394 -28.047873)
			(xy 96.923924 -27.995939) (xy 96.96043 -27.948363) (xy 97.002835 -27.905958) (xy 97.050411 -27.869452)
			(xy 97.102345 -27.839468) (xy 97.157749 -27.816519) (xy 97.215674 -27.800998) (xy 97.27513 -27.79317)
			(xy 97.335098 -27.79317) (xy 97.394554 -27.800998) (xy 97.452479 -27.816519) (xy 97.507883 -27.839468)
			(xy 97.559817 -27.869452) (xy 97.607393 -27.905958) (xy 97.649798 -27.948363) (xy 97.686304 -27.995939)
			(xy 97.716288 -28.047873) (xy 97.739237 -28.103277) (xy 97.754758 -28.161202) (xy 97.762586 -28.220658)
			(xy 97.763076 -28.250642) (xy 97.763076 -28.469082) (xy 101.752398 -28.469082) (xy 101.756469 -28.41346)
			(xy 101.768595 -28.359023) (xy 101.788518 -28.306932) (xy 101.815814 -28.258297) (xy 101.8499 -28.214154)
			(xy 101.890049 -28.175445) (xy 101.935407 -28.142994) (xy 101.985007 -28.117493) (xy 102.037791 -28.099486)
			(xy 102.092634 -28.089356) (xy 102.148368 -28.087319) (xy 102.203805 -28.093419) (xy 102.257762 -28.107525)
			(xy 102.309091 -28.129337) (xy 102.356697 -28.158391) (xy 102.399565 -28.194066) (xy 102.436782 -28.235603)
			(xy 102.467555 -28.282116) (xy 102.491227 -28.332613) (xy 102.507295 -28.38602) (xy 102.515415 -28.441196)
			(xy 102.515924 -28.469082) (xy 102.515415 -28.496968) (xy 102.507295 -28.552144) (xy 102.491227 -28.605551)
			(xy 102.467555 -28.656048) (xy 102.436782 -28.702561) (xy 102.399565 -28.744098) (xy 102.356697 -28.779773)
			(xy 102.309091 -28.808827) (xy 102.257762 -28.830639) (xy 102.203805 -28.844745) (xy 102.148368 -28.850845)
			(xy 102.092634 -28.848808) (xy 102.037791 -28.838678) (xy 101.985007 -28.820671) (xy 101.935407 -28.79517)
			(xy 101.890049 -28.762719) (xy 101.8499 -28.72401) (xy 101.815814 -28.679867) (xy 101.788518 -28.631232)
			(xy 101.768595 -28.579141) (xy 101.756469 -28.524704) (xy 101.752398 -28.469082) (xy 97.763076 -28.469082)
			(xy 97.763076 -29.114242) (xy 97.762586 -29.144226) (xy 97.754758 -29.203682) (xy 97.739237 -29.261607)
			(xy 97.716288 -29.317011) (xy 97.686304 -29.368945) (xy 97.649798 -29.416521) (xy 97.607393 -29.458926)
			(xy 97.559817 -29.495432) (xy 97.507883 -29.525416) (xy 97.452479 -29.548365) (xy 97.394554 -29.563886)
			(xy 97.335098 -29.571714) (xy 97.27513 -29.571714) (xy 97.215674 -29.563886) (xy 97.157749 -29.548365)
			(xy 97.102345 -29.525416) (xy 97.050411 -29.495432) (xy 97.002835 -29.458926) (xy 96.96043 -29.416521)
			(xy 96.923924 -29.368945) (xy 96.89394 -29.317011) (xy 96.870991 -29.261607) (xy 96.85547 -29.203682)
			(xy 96.847642 -29.144226) (xy 96.847152 -29.114242) (xy 89.790016 -29.114242) (xy 89.790016 -29.186378)
			(xy 89.812114 -29.214064) (xy 89.82964 -29.218128) (xy 89.8559 -29.224603) (xy 89.906403 -29.243961)
			(xy 89.953664 -29.270259) (xy 89.996736 -29.30297) (xy 90.034756 -29.341437) (xy 90.066961 -29.384889)
			(xy 90.092705 -29.432454) (xy 90.111471 -29.483179) (xy 90.122884 -29.536047) (xy 90.126714 -29.589996)
			(xy 90.122885 -29.643946) (xy 90.111473 -29.696814) (xy 90.092708 -29.747539) (xy 90.066965 -29.795105)
			(xy 90.034761 -29.838558) (xy 89.996742 -29.877026) (xy 89.95367 -29.909737) (xy 89.906409 -29.936036)
			(xy 89.855907 -29.955395) (xy 89.82964 -29.96184) (xy 89.812114 -29.965904) (xy 89.790016 -29.99359)
			(xy 89.790016 -30.92069) (xy 99.48926 -30.92069) (xy 99.48926 -30.05709) (xy 99.48975 -30.027106)
			(xy 99.497578 -29.96765) (xy 99.513099 -29.909725) (xy 99.536048 -29.854321) (xy 99.566032 -29.802387)
			(xy 99.602538 -29.754811) (xy 99.644943 -29.712406) (xy 99.692519 -29.6759) (xy 99.744453 -29.645916)
			(xy 99.799857 -29.622967) (xy 99.857782 -29.607446) (xy 99.917238 -29.599618) (xy 99.977206 -29.599618)
			(xy 100.036662 -29.607446) (xy 100.094587 -29.622967) (xy 100.149991 -29.645916) (xy 100.201925 -29.6759)
			(xy 100.249501 -29.712406) (xy 100.291906 -29.754811) (xy 100.328412 -29.802387) (xy 100.358396 -29.854321)
			(xy 100.381345 -29.909725) (xy 100.396866 -29.96765) (xy 100.404694 -30.027106) (xy 100.405184 -30.05709)
			(xy 100.405184 -30.92069) (xy 100.404694 -30.950674) (xy 100.396866 -31.01013) (xy 100.381345 -31.068055)
			(xy 100.358396 -31.123459) (xy 100.328412 -31.175393) (xy 100.291906 -31.222969) (xy 100.249501 -31.265374)
			(xy 100.201925 -31.30188) (xy 100.149991 -31.331864) (xy 100.094587 -31.354813) (xy 100.036662 -31.370334)
			(xy 99.977206 -31.378162) (xy 99.917238 -31.378162) (xy 99.857782 -31.370334) (xy 99.799857 -31.354813)
			(xy 99.744453 -31.331864) (xy 99.692519 -31.30188) (xy 99.644943 -31.265374) (xy 99.602538 -31.222969)
			(xy 99.566032 -31.175393) (xy 99.536048 -31.123459) (xy 99.513099 -31.068055) (xy 99.497578 -31.01013)
			(xy 99.48975 -30.950674) (xy 99.48926 -30.92069) (xy 89.790016 -30.92069) (xy 89.790016 -31.232602)
			(xy 89.815416 -31.261304) (xy 89.83472 -31.26359) (xy 89.862117 -31.26743) (xy 89.915487 -31.281992)
			(xy 89.966195 -31.304111) (xy 90.013176 -31.333321) (xy 90.055445 -31.36901) (xy 90.092117 -31.41043)
			(xy 90.122423 -31.456712) (xy 90.145726 -31.506885) (xy 90.161538 -31.559899) (xy 90.169528 -31.61464)
			(xy 90.169528 -31.669961) (xy 90.161538 -31.724702) (xy 90.145725 -31.777716) (xy 90.122422 -31.827889)
			(xy 90.092117 -31.874171) (xy 90.055445 -31.915591) (xy 90.013175 -31.95128) (xy 89.966194 -31.98049)
			(xy 89.915486 -32.002608) (xy 89.862116 -32.017171) (xy 89.83472 -32.021018) (xy 89.815416 -32.023304)
			(xy 89.790016 -32.052006) (xy 89.790016 -32.714184) (xy 96.847152 -32.714184) (xy 96.847152 -31.850584)
			(xy 96.847642 -31.8206) (xy 96.85547 -31.761144) (xy 96.870991 -31.703219) (xy 96.89394 -31.647815)
			(xy 96.923924 -31.595881) (xy 96.96043 -31.548305) (xy 97.002835 -31.5059) (xy 97.050411 -31.469394)
			(xy 97.102345 -31.43941) (xy 97.157749 -31.416461) (xy 97.215674 -31.40094) (xy 97.27513 -31.393112)
			(xy 97.335098 -31.393112) (xy 97.394554 -31.40094) (xy 97.452479 -31.416461) (xy 97.507883 -31.43941)
			(xy 97.559817 -31.469394) (xy 97.607393 -31.5059) (xy 97.649798 -31.548305) (xy 97.686304 -31.595881)
			(xy 97.716288 -31.647815) (xy 97.739237 -31.703219) (xy 97.754758 -31.761144) (xy 97.762586 -31.8206)
			(xy 97.763076 -31.850584) (xy 97.763076 -32.714184) (xy 97.762586 -32.744168) (xy 97.754758 -32.803624)
			(xy 97.739237 -32.861549) (xy 97.716288 -32.916953) (xy 97.686304 -32.968887) (xy 97.649798 -33.016463)
			(xy 97.607393 -33.058868) (xy 97.559817 -33.095374) (xy 97.507883 -33.125358) (xy 97.452479 -33.148307)
			(xy 97.394554 -33.163828) (xy 97.335098 -33.171656) (xy 97.27513 -33.171656) (xy 97.215674 -33.163828)
			(xy 97.157749 -33.148307) (xy 97.102345 -33.125358) (xy 97.050411 -33.095374) (xy 97.002835 -33.058868)
			(xy 96.96043 -33.016463) (xy 96.923924 -32.968887) (xy 96.89394 -32.916953) (xy 96.870991 -32.861549)
			(xy 96.85547 -32.803624) (xy 96.847642 -32.744168) (xy 96.847152 -32.714184) (xy 89.790016 -32.714184)
			(xy 89.790016 -34.520886) (xy 99.48926 -34.520886) (xy 99.48926 -33.657286) (xy 99.48975 -33.627302)
			(xy 99.497578 -33.567846) (xy 99.513099 -33.509921) (xy 99.536048 -33.454517) (xy 99.566032 -33.402583)
			(xy 99.602538 -33.355007) (xy 99.644943 -33.312602) (xy 99.692519 -33.276096) (xy 99.744453 -33.246112)
			(xy 99.799857 -33.223163) (xy 99.857782 -33.207642) (xy 99.917238 -33.199814) (xy 99.977206 -33.199814)
			(xy 100.036662 -33.207642) (xy 100.094587 -33.223163) (xy 100.149991 -33.246112) (xy 100.201925 -33.276096)
			(xy 100.249501 -33.312602) (xy 100.291906 -33.355007) (xy 100.328412 -33.402583) (xy 100.358396 -33.454517)
			(xy 100.381345 -33.509921) (xy 100.396866 -33.567846) (xy 100.404694 -33.627302) (xy 100.405184 -33.657286)
			(xy 100.405184 -34.520886) (xy 100.404694 -34.55087) (xy 100.396866 -34.610326) (xy 100.381345 -34.668251)
			(xy 100.358396 -34.723655) (xy 100.328412 -34.775589) (xy 100.291906 -34.823165) (xy 100.249501 -34.86557)
			(xy 100.201925 -34.902076) (xy 100.149991 -34.93206) (xy 100.094587 -34.955009) (xy 100.036662 -34.97053)
			(xy 99.977206 -34.978358) (xy 99.917238 -34.978358) (xy 99.857782 -34.97053) (xy 99.799857 -34.955009)
			(xy 99.744453 -34.93206) (xy 99.692519 -34.902076) (xy 99.644943 -34.86557) (xy 99.602538 -34.823165)
			(xy 99.566032 -34.775589) (xy 99.536048 -34.723655) (xy 99.513099 -34.668251) (xy 99.497578 -34.610326)
			(xy 99.48975 -34.55087) (xy 99.48926 -34.520886) (xy 89.790016 -34.520886) (xy 89.790016 -36.60013)
			(xy 89.998303 -36.60013) (xy 90.002307 -36.512245) (xy 90.014287 -36.425088) (xy 90.034142 -36.339381)
			(xy 90.061709 -36.255836) (xy 90.096759 -36.175143) (xy 90.139001 -36.097971) (xy 90.188086 -36.024961)
			(xy 90.243607 -35.956717) (xy 90.305104 -35.893804) (xy 90.372066 -35.836744) (xy 90.44394 -35.78601)
			(xy 90.52013 -35.742022) (xy 90.600004 -35.705144) (xy 90.682901 -35.675683) (xy 90.768133 -35.653881)
			(xy 90.854995 -35.639921) (xy 90.942766 -35.633917) (xy 91.03072 -35.63592) (xy 91.118127 -35.645912)
			(xy 91.204263 -35.663812) (xy 91.288415 -35.68947) (xy 91.369885 -35.722674) (xy 91.447998 -35.763148)
			(xy 91.522106 -35.810559) (xy 91.591597 -35.864512) (xy 91.655893 -35.92456) (xy 91.714462 -35.990207)
			(xy 91.766819 -36.060907) (xy 91.812531 -36.136076) (xy 91.851217 -36.21509) (xy 91.882558 -36.297295)
			(xy 91.906293 -36.382009) (xy 91.922227 -36.46853) (xy 91.930227 -36.556142) (xy 91.930728 -36.60013)
			(xy 91.930227 -36.644118) (xy 91.922227 -36.73173) (xy 91.906293 -36.818251) (xy 91.882558 -36.902965)
			(xy 91.851217 -36.98517) (xy 91.812531 -37.064184) (xy 91.766819 -37.139353) (xy 91.714462 -37.210053)
			(xy 91.655893 -37.2757) (xy 91.591597 -37.335748) (xy 91.522106 -37.389701) (xy 91.447998 -37.437112)
			(xy 91.369885 -37.477586) (xy 91.288415 -37.51079) (xy 91.204263 -37.536448) (xy 91.118127 -37.554348)
			(xy 91.03072 -37.56434) (xy 90.942766 -37.566343) (xy 90.854995 -37.560339) (xy 90.768133 -37.546379)
			(xy 90.682901 -37.524577) (xy 90.600004 -37.495116) (xy 90.52013 -37.458238) (xy 90.44394 -37.41425)
			(xy 90.372066 -37.363516) (xy 90.305104 -37.306456) (xy 90.243607 -37.243543) (xy 90.188086 -37.175299)
			(xy 90.139001 -37.102289) (xy 90.096759 -37.025117) (xy 90.061709 -36.944424) (xy 90.034142 -36.860879)
			(xy 90.014287 -36.775172) (xy 90.002307 -36.688015) (xy 89.998303 -36.60013) (xy 89.790016 -36.60013)
			(xy 89.790016 -40.452802) (xy 89.79044 -40.462872) (xy 89.798157 -40.481474) (xy 89.805002 -40.48887)
			(xy 90.024204 -40.708072) (xy 90.031601 -40.714921) (xy 90.0502 -40.722658) (xy 90.060272 -40.723058)
			(xy 99.08159 -40.723058) (xy 99.09166 -40.723481) (xy 99.110261 -40.731199) (xy 99.117658 -40.738044)
			(xy 100.058728 -41.679114) (xy 100.06558 -41.68651) (xy 100.073321 -41.705109) (xy 100.073714 -41.715182)
			(xy 100.073714 -43.85691) (xy 102.71963 -43.85691) (xy 102.723701 -43.801288) (xy 102.735827 -43.746851)
			(xy 102.75575 -43.69476) (xy 102.783046 -43.646125) (xy 102.817132 -43.601982) (xy 102.857281 -43.563273)
			(xy 102.902639 -43.530822) (xy 102.952239 -43.505321) (xy 103.005023 -43.487314) (xy 103.059866 -43.477184)
			(xy 103.1156 -43.475147) (xy 103.171037 -43.481247) (xy 103.224994 -43.495353) (xy 103.276323 -43.517165)
			(xy 103.323929 -43.546219) (xy 103.366797 -43.581894) (xy 103.404014 -43.623431) (xy 103.434787 -43.669944)
			(xy 103.458459 -43.720441) (xy 103.474527 -43.773848) (xy 103.482647 -43.829024) (xy 103.483156 -43.85691)
			(xy 103.482647 -43.884796) (xy 103.474527 -43.939972) (xy 103.458459 -43.993379) (xy 103.434787 -44.043876)
			(xy 103.404014 -44.090389) (xy 103.366797 -44.131926) (xy 103.323929 -44.167601) (xy 103.276323 -44.196655)
			(xy 103.224994 -44.218467) (xy 103.171037 -44.232573) (xy 103.1156 -44.238673) (xy 103.059866 -44.236636)
			(xy 103.005023 -44.226506) (xy 102.952239 -44.208499) (xy 102.902639 -44.182998) (xy 102.857281 -44.150547)
			(xy 102.817132 -44.111838) (xy 102.783046 -44.067695) (xy 102.75575 -44.01906) (xy 102.735827 -43.966969)
			(xy 102.723701 -43.912532) (xy 102.71963 -43.85691) (xy 100.073714 -43.85691) (xy 100.073714 -45.35424)
			(xy 102.703628 -45.35424) (xy 102.707699 -45.298618) (xy 102.719825 -45.244181) (xy 102.739748 -45.19209)
			(xy 102.767044 -45.143455) (xy 102.80113 -45.099312) (xy 102.841279 -45.060603) (xy 102.886637 -45.028152)
			(xy 102.936237 -45.002651) (xy 102.989021 -44.984644) (xy 103.043864 -44.974514) (xy 103.099598 -44.972477)
			(xy 103.155035 -44.978577) (xy 103.208992 -44.992683) (xy 103.260321 -45.014495) (xy 103.307927 -45.043549)
			(xy 103.350795 -45.079224) (xy 103.388012 -45.120761) (xy 103.418785 -45.167274) (xy 103.442457 -45.217771)
			(xy 103.458525 -45.271178) (xy 103.466645 -45.326354) (xy 103.467154 -45.35424) (xy 103.466645 -45.382126)
			(xy 103.458525 -45.437302) (xy 103.442457 -45.490709) (xy 103.418785 -45.541206) (xy 103.388012 -45.587719)
			(xy 103.350795 -45.629256) (xy 103.307927 -45.664931) (xy 103.260321 -45.693985) (xy 103.208992 -45.715797)
			(xy 103.155035 -45.729903) (xy 103.099598 -45.736003) (xy 103.043864 -45.733966) (xy 102.989021 -45.723836)
			(xy 102.936237 -45.705829) (xy 102.886637 -45.680328) (xy 102.841279 -45.647877) (xy 102.80113 -45.609168)
			(xy 102.767044 -45.565025) (xy 102.739748 -45.51639) (xy 102.719825 -45.464299) (xy 102.707699 -45.409862)
			(xy 102.703628 -45.35424) (xy 100.073714 -45.35424) (xy 100.073714 -46.693836) (xy 102.676198 -46.693836)
			(xy 102.676684 -46.666585) (xy 102.68444 -46.612637) (xy 102.699795 -46.560342) (xy 102.722437 -46.510765)
			(xy 102.751903 -46.464915) (xy 102.787594 -46.423724) (xy 102.828785 -46.388033) (xy 102.874635 -46.358567)
			(xy 102.924212 -46.335925) (xy 102.976507 -46.32057) (xy 103.030455 -46.312814) (xy 103.084957 -46.312814)
			(xy 103.138905 -46.32057) (xy 103.1912 -46.335925) (xy 103.240777 -46.358567) (xy 103.286627 -46.388033)
			(xy 103.327818 -46.423724) (xy 103.363509 -46.464915) (xy 103.392975 -46.510765) (xy 103.415617 -46.560342)
			(xy 103.430972 -46.612637) (xy 103.438728 -46.666585) (xy 103.439214 -46.693836) (xy 103.438739 -46.720263)
			(xy 103.43143 -46.772611) (xy 103.416957 -46.823446) (xy 103.395598 -46.871793) (xy 103.382064 -46.894496)
			(xy 103.375968 -46.904402) (xy 103.373428 -46.927262) (xy 103.407718 -47.023782) (xy 103.42372 -47.040038)
			(xy 103.434896 -47.043848) (xy 103.459415 -47.052889) (xy 103.505867 -47.076838) (xy 103.548617 -47.106899)
			(xy 103.586867 -47.14251) (xy 103.619902 -47.183006) (xy 103.647104 -47.22763) (xy 103.667965 -47.275548)
			(xy 103.682094 -47.325863) (xy 103.689227 -47.377635) (xy 103.689658 -47.403766) (xy 103.689172 -47.431017)
			(xy 103.681416 -47.484965) (xy 103.666061 -47.53726) (xy 103.643419 -47.586837) (xy 103.613953 -47.632687)
			(xy 103.578262 -47.673878) (xy 103.537071 -47.709569) (xy 103.491221 -47.739035) (xy 103.441644 -47.761677)
			(xy 103.389349 -47.777032) (xy 103.335401 -47.784788) (xy 103.280899 -47.784788) (xy 103.226951 -47.777032)
			(xy 103.174656 -47.761677) (xy 103.125079 -47.739035) (xy 103.079229 -47.709569) (xy 103.038038 -47.673878)
			(xy 103.002347 -47.632687) (xy 102.972881 -47.586837) (xy 102.950239 -47.53726) (xy 102.934884 -47.484965)
			(xy 102.927128 -47.431017) (xy 102.926642 -47.403766) (xy 102.92711 -47.377338) (xy 102.93442 -47.32499)
			(xy 102.948895 -47.274155) (xy 102.970256 -47.225809) (xy 102.983792 -47.203106) (xy 102.989888 -47.1932)
			(xy 102.992428 -47.17034) (xy 102.958138 -47.07382) (xy 102.942136 -47.057564) (xy 102.93096 -47.053754)
			(xy 102.906453 -47.044679) (xy 102.860001 -47.020738) (xy 102.817249 -46.990683) (xy 102.778996 -46.955076)
			(xy 102.74596 -46.914584) (xy 102.718756 -46.869963) (xy 102.697894 -46.822049) (xy 102.683763 -46.771736)
			(xy 102.676629 -46.719966) (xy 102.676198 -46.693836) (xy 100.073714 -46.693836) (xy 100.073714 -48.30699)
			(xy 102.553768 -48.30699) (xy 102.557839 -48.251368) (xy 102.569965 -48.196931) (xy 102.589888 -48.14484)
			(xy 102.617184 -48.096205) (xy 102.65127 -48.052062) (xy 102.691419 -48.013353) (xy 102.736777 -47.980902)
			(xy 102.786377 -47.955401) (xy 102.839161 -47.937394) (xy 102.894004 -47.927264) (xy 102.949738 -47.925227)
			(xy 103.005175 -47.931327) (xy 103.059132 -47.945433) (xy 103.110461 -47.967245) (xy 103.158067 -47.996299)
			(xy 103.200935 -48.031974) (xy 103.238152 -48.073511) (xy 103.268925 -48.120024) (xy 103.292597 -48.170521)
			(xy 103.308665 -48.223928) (xy 103.316785 -48.279104) (xy 103.317294 -48.30699) (xy 103.316785 -48.334876)
			(xy 103.308665 -48.390052) (xy 103.292597 -48.443459) (xy 103.268925 -48.493956) (xy 103.238152 -48.540469)
			(xy 103.200935 -48.582006) (xy 103.158067 -48.617681) (xy 103.110461 -48.646735) (xy 103.059132 -48.668547)
			(xy 103.005175 -48.682653) (xy 102.949738 -48.688753) (xy 102.894004 -48.686716) (xy 102.839161 -48.676586)
			(xy 102.786377 -48.658579) (xy 102.736777 -48.633078) (xy 102.691419 -48.600627) (xy 102.65127 -48.561918)
			(xy 102.617184 -48.517775) (xy 102.589888 -48.46914) (xy 102.569965 -48.417049) (xy 102.557839 -48.362612)
			(xy 102.553768 -48.30699) (xy 100.073714 -48.30699) (xy 100.073714 -48.8442) (xy 100.18725 -48.8442)
			(xy 100.191321 -48.788578) (xy 100.203447 -48.734141) (xy 100.22337 -48.68205) (xy 100.250666 -48.633415)
			(xy 100.284752 -48.589272) (xy 100.324901 -48.550563) (xy 100.370259 -48.518112) (xy 100.419859 -48.492611)
			(xy 100.472643 -48.474604) (xy 100.527486 -48.464474) (xy 100.58322 -48.462437) (xy 100.638657 -48.468537)
			(xy 100.692614 -48.482643) (xy 100.743943 -48.504455) (xy 100.791549 -48.533509) (xy 100.834417 -48.569184)
			(xy 100.871634 -48.610721) (xy 100.902407 -48.657234) (xy 100.926079 -48.707731) (xy 100.942147 -48.761138)
			(xy 100.950267 -48.816314) (xy 100.950776 -48.8442) (xy 100.950267 -48.872086) (xy 100.947269 -48.89246)
			(xy 101.213918 -48.89246) (xy 101.217989 -48.836838) (xy 101.230115 -48.782401) (xy 101.250038 -48.73031)
			(xy 101.277334 -48.681675) (xy 101.31142 -48.637532) (xy 101.351569 -48.598823) (xy 101.396927 -48.566372)
			(xy 101.446527 -48.540871) (xy 101.499311 -48.522864) (xy 101.554154 -48.512734) (xy 101.609888 -48.510697)
			(xy 101.665325 -48.516797) (xy 101.719282 -48.530903) (xy 101.770611 -48.552715) (xy 101.818217 -48.581769)
			(xy 101.861085 -48.617444) (xy 101.898302 -48.658981) (xy 101.929075 -48.705494) (xy 101.952747 -48.755991)
			(xy 101.968815 -48.809398) (xy 101.976935 -48.864574) (xy 101.977444 -48.89246) (xy 101.976935 -48.920346)
			(xy 101.968815 -48.975522) (xy 101.952747 -49.028929) (xy 101.929075 -49.079426) (xy 101.898302 -49.125939)
			(xy 101.861085 -49.167476) (xy 101.818217 -49.203151) (xy 101.770611 -49.232205) (xy 101.719282 -49.254017)
			(xy 101.665325 -49.268123) (xy 101.609888 -49.274223) (xy 101.554154 -49.272186) (xy 101.499311 -49.262056)
			(xy 101.446527 -49.244049) (xy 101.396927 -49.218548) (xy 101.351569 -49.186097) (xy 101.31142 -49.147388)
			(xy 101.277334 -49.103245) (xy 101.250038 -49.05461) (xy 101.230115 -49.002519) (xy 101.217989 -48.948082)
			(xy 101.213918 -48.89246) (xy 100.947269 -48.89246) (xy 100.942147 -48.927262) (xy 100.926079 -48.980669)
			(xy 100.902407 -49.031166) (xy 100.871634 -49.077679) (xy 100.834417 -49.119216) (xy 100.791549 -49.154891)
			(xy 100.743943 -49.183945) (xy 100.692614 -49.205757) (xy 100.638657 -49.219863) (xy 100.58322 -49.225963)
			(xy 100.527486 -49.223926) (xy 100.472643 -49.213796) (xy 100.419859 -49.195789) (xy 100.370259 -49.170288)
			(xy 100.324901 -49.137837) (xy 100.284752 -49.099128) (xy 100.250666 -49.054985) (xy 100.22337 -49.00635)
			(xy 100.203447 -48.954259) (xy 100.191321 -48.899822) (xy 100.18725 -48.8442) (xy 100.073714 -48.8442)
			(xy 100.073714 -51.198018) (xy 100.074174 -51.207895) (xy 100.081619 -51.226192) (xy 100.088192 -51.233578)
			(xy 100.088446 -51.233832) (xy 100.232972 -51.378358) (xy 100.240372 -51.385198) (xy 100.258971 -51.392913)
			(xy 100.26904 -51.393344)
		)
		(stroke
			(width 0)
			(type solid)
		)
		(fill yes)
		(layer "In9.Cu")
		(net "GND")
	)
	(gr_poly
		(pts
			(xy 218.832684 -51.393344) (xy 218.841916 -51.392947) (xy 218.85918 -51.386401) (xy 218.872999 -51.374155)
			(xy 218.877642 -51.366166) (xy 218.919298 -51.286664) (xy 218.923207 -51.278382) (xy 218.925485 -51.260225)
			(xy 218.921265 -51.242418) (xy 218.916504 -51.234594) (xy 218.91625 -51.23434) (xy 218.900753 -51.2107)
			(xy 218.876149 -51.159812) (xy 218.859317 -51.105852) (xy 218.850626 -51.05) (xy 218.849956 -51.021742)
			(xy 218.849956 -51.01463) (xy 218.850768 -50.987604) (xy 218.859078 -50.934177) (xy 218.874847 -50.882459)
			(xy 218.897759 -50.833486) (xy 218.927356 -50.788237) (xy 218.963045 -50.74762) (xy 219.00411 -50.712448)
			(xy 219.049729 -50.683426) (xy 219.098989 -50.661135) (xy 219.150903 -50.646021) (xy 219.20443 -50.638388)
			(xy 219.258498 -50.638388) (xy 219.312025 -50.646021) (xy 219.363939 -50.661135) (xy 219.413199 -50.683426)
			(xy 219.458818 -50.712448) (xy 219.499883 -50.74762) (xy 219.535572 -50.788237) (xy 219.565169 -50.833486)
			(xy 219.588081 -50.882459) (xy 219.60385 -50.934177) (xy 219.61216 -50.987604) (xy 219.612972 -51.01463)
			(xy 219.612972 -51.01971) (xy 219.612464 -51.048258) (xy 219.603948 -51.104716) (xy 219.587109 -51.159273)
			(xy 219.562324 -51.210709) (xy 219.546678 -51.234594) (xy 219.53855 -51.246278) (xy 219.537026 -51.274218)
			(xy 219.585286 -51.366166) (xy 219.589933 -51.374152) (xy 219.603754 -51.386393) (xy 219.621013 -51.392949)
			(xy 219.630244 -51.393344) (xy 220.522292 -51.393344) (xy 220.532261 -51.392872) (xy 220.550709 -51.385308)
			(xy 220.558106 -51.378612) (xy 221.076266 -50.860452) (xy 221.080076 -50.852578) (xy 221.089982 -50.833528)
			(xy 221.090236 -50.833274) (xy 221.094046 -50.82667) (xy 221.097348 -50.821082) (xy 221.101412 -50.806858)
			(xy 221.104714 -50.795174) (xy 221.104714 -50.1904) (xy 221.104459 -50.182988) (xy 221.100196 -50.16879)
			(xy 221.096332 -50.16246) (xy 221.081498 -50.139007) (xy 221.058037 -50.088719) (xy 221.042115 -50.03556)
			(xy 221.034069 -49.980654) (xy 221.034068 -49.925162) (xy 221.042112 -49.870257) (xy 221.058031 -49.817097)
			(xy 221.081489 -49.766807) (xy 221.096332 -49.74336) (xy 221.100192 -49.737029) (xy 221.104445 -49.722831)
			(xy 221.104714 -49.71542) (xy 221.104714 -49.1744) (xy 221.104459 -49.166988) (xy 221.100196 -49.15279)
			(xy 221.096332 -49.14646) (xy 221.081498 -49.123007) (xy 221.058037 -49.072719) (xy 221.042115 -49.01956)
			(xy 221.034069 -48.964654) (xy 221.034068 -48.909162) (xy 221.042112 -48.854257) (xy 221.058031 -48.801097)
			(xy 221.081489 -48.750807) (xy 221.096332 -48.72736) (xy 221.100192 -48.721029) (xy 221.104445 -48.706831)
			(xy 221.104714 -48.69942) (xy 221.104714 -47.629572) (xy 221.102174 -47.61865) (xy 221.09938 -47.613062)
			(xy 221.086657 -47.586292) (xy 221.068683 -47.529813) (xy 221.059588 -47.471246) (xy 221.059586 -47.411976)
			(xy 221.068678 -47.353408) (xy 221.086649 -47.296928) (xy 221.09938 -47.270162) (xy 221.102174 -47.264574)
			(xy 221.104714 -47.253652) (xy 221.104714 -46.1264) (xy 221.104459 -46.118988) (xy 221.100196 -46.10479)
			(xy 221.096332 -46.09846) (xy 221.081498 -46.075007) (xy 221.058037 -46.024719) (xy 221.042115 -45.97156)
			(xy 221.034069 -45.916654) (xy 221.034068 -45.861162) (xy 221.042112 -45.806257) (xy 221.058031 -45.753097)
			(xy 221.081489 -45.702807) (xy 221.096332 -45.67936) (xy 221.100192 -45.673029) (xy 221.104445 -45.658831)
			(xy 221.104714 -45.65142) (xy 221.104714 -45.1104) (xy 221.104459 -45.102988) (xy 221.100196 -45.08879)
			(xy 221.096332 -45.08246) (xy 221.081498 -45.059007) (xy 221.058037 -45.008719) (xy 221.042115 -44.95556)
			(xy 221.034069 -44.900654) (xy 221.034068 -44.845162) (xy 221.042112 -44.790257) (xy 221.058031 -44.737097)
			(xy 221.081489 -44.686807) (xy 221.096332 -44.66336) (xy 221.100192 -44.657029) (xy 221.104445 -44.642831)
			(xy 221.104714 -44.63542) (xy 221.104714 -44.0944) (xy 221.104459 -44.086988) (xy 221.100196 -44.07279)
			(xy 221.096332 -44.06646) (xy 221.081498 -44.043007) (xy 221.058037 -43.992719) (xy 221.042115 -43.93956)
			(xy 221.034069 -43.884654) (xy 221.034068 -43.829162) (xy 221.042112 -43.774257) (xy 221.058031 -43.721097)
			(xy 221.081489 -43.670807) (xy 221.096332 -43.64736) (xy 221.100192 -43.641029) (xy 221.104445 -43.626831)
			(xy 221.104714 -43.61942) (xy 221.104714 -43.0784) (xy 221.104459 -43.070988) (xy 221.100196 -43.05679)
			(xy 221.096332 -43.05046) (xy 221.081498 -43.027007) (xy 221.058037 -42.976719) (xy 221.042115 -42.92356)
			(xy 221.034069 -42.868654) (xy 221.034068 -42.813162) (xy 221.042112 -42.758257) (xy 221.058031 -42.705097)
			(xy 221.081489 -42.654807) (xy 221.096332 -42.63136) (xy 221.100192 -42.625029) (xy 221.104445 -42.610831)
			(xy 221.104714 -42.60342) (xy 221.104714 -29.753052) (xy 221.076266 -29.707332) (xy 221.076266 -28.368752)
			(xy 221.076493 -28.361714) (xy 221.080365 -28.348181) (xy 221.083886 -28.342082) (xy 221.09684 -28.322016)
			(xy 221.100497 -28.315758) (xy 221.104488 -28.30183) (xy 221.104714 -28.294584) (xy 221.104714 -27.872436)
			(xy 221.10428 -27.862371) (xy 221.096551 -27.843782) (xy 221.089728 -27.836368) (xy 220.850206 -27.596846)
			(xy 220.84281 -27.589994) (xy 220.824212 -27.58225) (xy 220.814138 -27.58186) (xy 211.49945 -27.58186)
			(xy 211.487124 -27.582455) (xy 211.465294 -27.593904) (xy 211.457794 -27.603704) (xy 211.440634 -27.627665)
			(xy 211.401128 -27.6714) (xy 211.356337 -27.709706) (xy 211.307002 -27.74195) (xy 211.253939 -27.767598)
			(xy 211.198024 -27.786227) (xy 211.140181 -27.797529) (xy 211.081366 -27.801317) (xy 211.022551 -27.797529)
			(xy 210.964708 -27.786227) (xy 210.908793 -27.767598) (xy 210.85573 -27.74195) (xy 210.806395 -27.709706)
			(xy 210.761604 -27.6714) (xy 210.722098 -27.627665) (xy 210.704938 -27.603704) (xy 210.697323 -27.59404)
			(xy 210.675562 -27.582641) (xy 210.663282 -27.58186) (xy 206.527908 -27.58186) (xy 206.517838 -27.582283)
			(xy 206.499238 -27.590002) (xy 206.49184 -27.596846) (xy 206.222854 -27.865832) (xy 206.216504 -27.877262)
			(xy 206.214726 -27.88412) (xy 206.207 -27.91235) (xy 206.184089 -27.966205) (xy 206.153222 -28.015929)
			(xy 206.115126 -28.060359) (xy 206.070692 -28.09845) (xy 206.020963 -28.12931) (xy 205.967106 -28.152215)
			(xy 205.938882 -28.159964) (xy 205.932024 -28.161742) (xy 205.920594 -28.168092) (xy 205.904846 -28.18384)
			(xy 205.898001 -28.191239) (xy 205.890274 -28.209837) (xy 205.88986 -28.219908) (xy 205.88986 -29.114242)
			(xy 212.947504 -29.114242) (xy 212.947504 -28.250642) (xy 212.947994 -28.220674) (xy 212.955817 -28.161252)
			(xy 212.97133 -28.103359) (xy 212.994266 -28.047986) (xy 213.024233 -27.99608) (xy 213.06072 -27.94853)
			(xy 213.1031 -27.90615) (xy 213.15065 -27.869663) (xy 213.202556 -27.839696) (xy 213.257929 -27.81676)
			(xy 213.315822 -27.801247) (xy 213.375244 -27.793424) (xy 213.43518 -27.793424) (xy 213.494602 -27.801247)
			(xy 213.552495 -27.81676) (xy 213.607868 -27.839696) (xy 213.659774 -27.869663) (xy 213.707324 -27.90615)
			(xy 213.749704 -27.94853) (xy 213.786191 -27.99608) (xy 213.816158 -28.047986) (xy 213.839094 -28.103359)
			(xy 213.854607 -28.161252) (xy 213.86243 -28.220674) (xy 213.86292 -28.250642) (xy 213.86292 -28.469082)
			(xy 217.852496 -28.469082) (xy 217.856567 -28.41346) (xy 217.868693 -28.359023) (xy 217.888616 -28.306932)
			(xy 217.915912 -28.258297) (xy 217.949998 -28.214154) (xy 217.990147 -28.175445) (xy 218.035505 -28.142994)
			(xy 218.085105 -28.117493) (xy 218.137889 -28.099486) (xy 218.192732 -28.089356) (xy 218.248466 -28.087319)
			(xy 218.303903 -28.093419) (xy 218.35786 -28.107525) (xy 218.409189 -28.129337) (xy 218.456795 -28.158391)
			(xy 218.499663 -28.194066) (xy 218.53688 -28.235603) (xy 218.567653 -28.282116) (xy 218.591325 -28.332613)
			(xy 218.607393 -28.38602) (xy 218.615513 -28.441196) (xy 218.616022 -28.469082) (xy 218.615513 -28.496968)
			(xy 218.607393 -28.552144) (xy 218.591325 -28.605551) (xy 218.567653 -28.656048) (xy 218.53688 -28.702561)
			(xy 218.499663 -28.744098) (xy 218.456795 -28.779773) (xy 218.409189 -28.808827) (xy 218.35786 -28.830639)
			(xy 218.303903 -28.844745) (xy 218.248466 -28.850845) (xy 218.192732 -28.848808) (xy 218.137889 -28.838678)
			(xy 218.085105 -28.820671) (xy 218.035505 -28.79517) (xy 217.990147 -28.762719) (xy 217.949998 -28.72401)
			(xy 217.915912 -28.679867) (xy 217.888616 -28.631232) (xy 217.868693 -28.579141) (xy 217.856567 -28.524704)
			(xy 217.852496 -28.469082) (xy 213.86292 -28.469082) (xy 213.86292 -29.114242) (xy 213.86243 -29.14421)
			(xy 213.854607 -29.203632) (xy 213.839094 -29.261525) (xy 213.816158 -29.316898) (xy 213.786191 -29.368804)
			(xy 213.749704 -29.416354) (xy 213.707324 -29.458734) (xy 213.659774 -29.495221) (xy 213.607868 -29.525188)
			(xy 213.552495 -29.548124) (xy 213.494602 -29.563637) (xy 213.43518 -29.57146) (xy 213.375244 -29.57146)
			(xy 213.315822 -29.563637) (xy 213.257929 -29.548124) (xy 213.202556 -29.525188) (xy 213.15065 -29.495221)
			(xy 213.1031 -29.458734) (xy 213.06072 -29.416354) (xy 213.024233 -29.368804) (xy 212.994266 -29.316898)
			(xy 212.97133 -29.261525) (xy 212.955817 -29.203632) (xy 212.947994 -29.14421) (xy 212.947504 -29.114242)
			(xy 205.88986 -29.114242) (xy 205.88986 -29.186378) (xy 205.911958 -29.214064) (xy 205.929484 -29.217874)
			(xy 205.955778 -29.224335) (xy 206.00635 -29.243679) (xy 206.053679 -29.269976) (xy 206.096817 -29.302698)
			(xy 206.134897 -29.34119) (xy 206.167153 -29.384677) (xy 206.192939 -29.432287) (xy 206.211737 -29.483064)
			(xy 206.223169 -29.535988) (xy 206.227005 -29.589996) (xy 206.22317 -29.644005) (xy 206.211739 -29.696929)
			(xy 206.192942 -29.747706) (xy 206.167157 -29.795317) (xy 206.134901 -29.838805) (xy 206.096822 -29.877297)
			(xy 206.053685 -29.910021) (xy 206.006356 -29.936318) (xy 205.955785 -29.955662) (xy 205.929484 -29.962094)
			(xy 205.911958 -29.965904) (xy 205.88986 -29.99359) (xy 205.88986 -30.92069) (xy 215.589612 -30.92069)
			(xy 215.589612 -30.05709) (xy 215.590102 -30.027122) (xy 215.597925 -29.9677) (xy 215.613438 -29.909807)
			(xy 215.636374 -29.854434) (xy 215.666341 -29.802528) (xy 215.702828 -29.754978) (xy 215.745208 -29.712598)
			(xy 215.792758 -29.676111) (xy 215.844664 -29.646144) (xy 215.900037 -29.623208) (xy 215.95793 -29.607695)
			(xy 216.017352 -29.599872) (xy 216.077288 -29.599872) (xy 216.13671 -29.607695) (xy 216.194603 -29.623208)
			(xy 216.249976 -29.646144) (xy 216.301882 -29.676111) (xy 216.349432 -29.712598) (xy 216.391812 -29.754978)
			(xy 216.428299 -29.802528) (xy 216.458266 -29.854434) (xy 216.481202 -29.909807) (xy 216.496715 -29.9677)
			(xy 216.504538 -30.027122) (xy 216.505028 -30.05709) (xy 216.505028 -30.92069) (xy 216.504538 -30.950658)
			(xy 216.496715 -31.01008) (xy 216.481202 -31.067973) (xy 216.458266 -31.123346) (xy 216.428299 -31.175252)
			(xy 216.391812 -31.222802) (xy 216.349432 -31.265182) (xy 216.301882 -31.301669) (xy 216.249976 -31.331636)
			(xy 216.194603 -31.354572) (xy 216.13671 -31.370085) (xy 216.077288 -31.377908) (xy 216.017352 -31.377908)
			(xy 215.95793 -31.370085) (xy 215.900037 -31.354572) (xy 215.844664 -31.331636) (xy 215.792758 -31.301669)
			(xy 215.745208 -31.265182) (xy 215.702828 -31.222802) (xy 215.666341 -31.175252) (xy 215.636374 -31.123346)
			(xy 215.613438 -31.067973) (xy 215.597925 -31.01008) (xy 215.590102 -30.950658) (xy 215.589612 -30.92069)
			(xy 205.88986 -30.92069) (xy 205.88986 -31.232602) (xy 205.91526 -31.261304) (xy 205.934564 -31.26359)
			(xy 205.961974 -31.267414) (xy 206.015373 -31.28195) (xy 206.066111 -31.30405) (xy 206.113123 -31.333249)
			(xy 206.155423 -31.368934) (xy 206.192123 -31.410358) (xy 206.222452 -31.456649) (xy 206.245774 -31.506837)
			(xy 206.261599 -31.559868) (xy 206.269596 -31.614629) (xy 206.269596 -31.669972) (xy 206.261599 -31.724733)
			(xy 206.245773 -31.777764) (xy 206.222451 -31.827952) (xy 206.192122 -31.874243) (xy 206.155422 -31.915666)
			(xy 206.113123 -31.951352) (xy 206.06611 -31.980551) (xy 206.015372 -32.00265) (xy 205.961973 -32.017186)
			(xy 205.934564 -32.021018) (xy 205.91526 -32.023304) (xy 205.88986 -32.052006) (xy 205.88986 -32.714184)
			(xy 212.947504 -32.714184) (xy 212.947504 -31.850584) (xy 212.947994 -31.820616) (xy 212.955817 -31.761194)
			(xy 212.97133 -31.703301) (xy 212.994266 -31.647928) (xy 213.024233 -31.596022) (xy 213.06072 -31.548472)
			(xy 213.1031 -31.506092) (xy 213.15065 -31.469605) (xy 213.202556 -31.439638) (xy 213.257929 -31.416702)
			(xy 213.315822 -31.401189) (xy 213.375244 -31.393366) (xy 213.43518 -31.393366) (xy 213.494602 -31.401189)
			(xy 213.552495 -31.416702) (xy 213.607868 -31.439638) (xy 213.659774 -31.469605) (xy 213.707324 -31.506092)
			(xy 213.749704 -31.548472) (xy 213.786191 -31.596022) (xy 213.816158 -31.647928) (xy 213.839094 -31.703301)
			(xy 213.854607 -31.761194) (xy 213.86243 -31.820616) (xy 213.86292 -31.850584) (xy 213.86292 -32.714184)
			(xy 213.86243 -32.744152) (xy 213.854607 -32.803574) (xy 213.839094 -32.861467) (xy 213.816158 -32.91684)
			(xy 213.786191 -32.968746) (xy 213.749704 -33.016296) (xy 213.707324 -33.058676) (xy 213.659774 -33.095163)
			(xy 213.607868 -33.12513) (xy 213.552495 -33.148066) (xy 213.494602 -33.163579) (xy 213.43518 -33.171402)
			(xy 213.375244 -33.171402) (xy 213.315822 -33.163579) (xy 213.257929 -33.148066) (xy 213.202556 -33.12513)
			(xy 213.15065 -33.095163) (xy 213.1031 -33.058676) (xy 213.06072 -33.016296) (xy 213.024233 -32.968746)
			(xy 212.994266 -32.91684) (xy 212.97133 -32.861467) (xy 212.955817 -32.803574) (xy 212.947994 -32.744152)
			(xy 212.947504 -32.714184) (xy 205.88986 -32.714184) (xy 205.88986 -34.520886) (xy 215.589612 -34.520886)
			(xy 215.589612 -33.657286) (xy 215.590102 -33.627318) (xy 215.597925 -33.567896) (xy 215.613438 -33.510003)
			(xy 215.636374 -33.45463) (xy 215.666341 -33.402724) (xy 215.702828 -33.355174) (xy 215.745208 -33.312794)
			(xy 215.792758 -33.276307) (xy 215.844664 -33.24634) (xy 215.900037 -33.223404) (xy 215.95793 -33.207891)
			(xy 216.017352 -33.200068) (xy 216.077288 -33.200068) (xy 216.13671 -33.207891) (xy 216.194603 -33.223404)
			(xy 216.249976 -33.24634) (xy 216.301882 -33.276307) (xy 216.349432 -33.312794) (xy 216.391812 -33.355174)
			(xy 216.428299 -33.402724) (xy 216.458266 -33.45463) (xy 216.481202 -33.510003) (xy 216.496715 -33.567896)
			(xy 216.504538 -33.627318) (xy 216.505028 -33.657286) (xy 216.505028 -34.520886) (xy 216.504538 -34.550854)
			(xy 216.496715 -34.610276) (xy 216.481202 -34.668169) (xy 216.458266 -34.723542) (xy 216.428299 -34.775448)
			(xy 216.391812 -34.822998) (xy 216.349432 -34.865378) (xy 216.301882 -34.901865) (xy 216.249976 -34.931832)
			(xy 216.194603 -34.954768) (xy 216.13671 -34.970281) (xy 216.077288 -34.978104) (xy 216.017352 -34.978104)
			(xy 215.95793 -34.970281) (xy 215.900037 -34.954768) (xy 215.844664 -34.931832) (xy 215.792758 -34.901865)
			(xy 215.745208 -34.865378) (xy 215.702828 -34.822998) (xy 215.666341 -34.775448) (xy 215.636374 -34.723542)
			(xy 215.613438 -34.668169) (xy 215.597925 -34.610276) (xy 215.590102 -34.550854) (xy 215.589612 -34.520886)
			(xy 205.88986 -34.520886) (xy 205.88986 -36.60013) (xy 206.098655 -36.60013) (xy 206.102659 -36.512245)
			(xy 206.114639 -36.425088) (xy 206.134494 -36.339381) (xy 206.162061 -36.255836) (xy 206.197111 -36.175143)
			(xy 206.239353 -36.097971) (xy 206.288438 -36.024961) (xy 206.343959 -35.956717) (xy 206.405456 -35.893804)
			(xy 206.472418 -35.836744) (xy 206.544292 -35.78601) (xy 206.620482 -35.742022) (xy 206.700356 -35.705144)
			(xy 206.783253 -35.675683) (xy 206.868485 -35.653881) (xy 206.955347 -35.639921) (xy 207.043118 -35.633917)
			(xy 207.131072 -35.63592) (xy 207.218479 -35.645912) (xy 207.304615 -35.663812) (xy 207.388767 -35.68947)
			(xy 207.470237 -35.722674) (xy 207.54835 -35.763148) (xy 207.622458 -35.810559) (xy 207.691949 -35.864512)
			(xy 207.756245 -35.92456) (xy 207.814814 -35.990207) (xy 207.867171 -36.060907) (xy 207.912883 -36.136076)
			(xy 207.951569 -36.21509) (xy 207.98291 -36.297295) (xy 208.006645 -36.382009) (xy 208.022579 -36.46853)
			(xy 208.030579 -36.556142) (xy 208.03108 -36.60013) (xy 208.030579 -36.644118) (xy 208.022579 -36.73173)
			(xy 208.006645 -36.818251) (xy 207.98291 -36.902965) (xy 207.951569 -36.98517) (xy 207.912883 -37.064184)
			(xy 207.867171 -37.139353) (xy 207.814814 -37.210053) (xy 207.756245 -37.2757) (xy 207.691949 -37.335748)
			(xy 207.622458 -37.389701) (xy 207.54835 -37.437112) (xy 207.470237 -37.477586) (xy 207.388767 -37.51079)
			(xy 207.304615 -37.536448) (xy 207.218479 -37.554348) (xy 207.131072 -37.56434) (xy 207.043118 -37.566343)
			(xy 206.955347 -37.560339) (xy 206.868485 -37.546379) (xy 206.783253 -37.524577) (xy 206.700356 -37.495116)
			(xy 206.620482 -37.458238) (xy 206.544292 -37.41425) (xy 206.472418 -37.363516) (xy 206.405456 -37.306456)
			(xy 206.343959 -37.243543) (xy 206.288438 -37.175299) (xy 206.239353 -37.102289) (xy 206.197111 -37.025117)
			(xy 206.162061 -36.944424) (xy 206.134494 -36.860879) (xy 206.114639 -36.775172) (xy 206.102659 -36.688015)
			(xy 206.098655 -36.60013) (xy 205.88986 -36.60013) (xy 205.88986 -40.452802) (xy 205.890285 -40.462871)
			(xy 205.898007 -40.481469) (xy 205.904846 -40.48887) (xy 206.124048 -40.708072) (xy 206.131448 -40.714914)
			(xy 206.150046 -40.722635) (xy 206.160116 -40.723058) (xy 215.181434 -40.723058) (xy 215.1915 -40.723489)
			(xy 215.21009 -40.731218) (xy 215.217502 -40.738044) (xy 216.158572 -41.679114) (xy 216.165419 -41.686512)
			(xy 216.173153 -41.70511) (xy 216.173558 -41.715182) (xy 216.173558 -43.85691) (xy 218.819728 -43.85691)
			(xy 218.823799 -43.801288) (xy 218.835925 -43.746851) (xy 218.855848 -43.69476) (xy 218.883144 -43.646125)
			(xy 218.91723 -43.601982) (xy 218.957379 -43.563273) (xy 219.002737 -43.530822) (xy 219.052337 -43.505321)
			(xy 219.105121 -43.487314) (xy 219.159964 -43.477184) (xy 219.215698 -43.475147) (xy 219.271135 -43.481247)
			(xy 219.325092 -43.495353) (xy 219.376421 -43.517165) (xy 219.424027 -43.546219) (xy 219.466895 -43.581894)
			(xy 219.504112 -43.623431) (xy 219.534885 -43.669944) (xy 219.558557 -43.720441) (xy 219.574625 -43.773848)
			(xy 219.582745 -43.829024) (xy 219.583254 -43.85691) (xy 219.582745 -43.884796) (xy 219.574625 -43.939972)
			(xy 219.558557 -43.993379) (xy 219.534885 -44.043876) (xy 219.504112 -44.090389) (xy 219.466895 -44.131926)
			(xy 219.424027 -44.167601) (xy 219.376421 -44.196655) (xy 219.325092 -44.218467) (xy 219.271135 -44.232573)
			(xy 219.215698 -44.238673) (xy 219.159964 -44.236636) (xy 219.105121 -44.226506) (xy 219.052337 -44.208499)
			(xy 219.002737 -44.182998) (xy 218.957379 -44.150547) (xy 218.91723 -44.111838) (xy 218.883144 -44.067695)
			(xy 218.855848 -44.01906) (xy 218.835925 -43.966969) (xy 218.823799 -43.912532) (xy 218.819728 -43.85691)
			(xy 216.173558 -43.85691) (xy 216.173558 -45.35424) (xy 218.803726 -45.35424) (xy 218.807797 -45.298618)
			(xy 218.819923 -45.244181) (xy 218.839846 -45.19209) (xy 218.867142 -45.143455) (xy 218.901228 -45.099312)
			(xy 218.941377 -45.060603) (xy 218.986735 -45.028152) (xy 219.036335 -45.002651) (xy 219.089119 -44.984644)
			(xy 219.143962 -44.974514) (xy 219.199696 -44.972477) (xy 219.255133 -44.978577) (xy 219.30909 -44.992683)
			(xy 219.360419 -45.014495) (xy 219.408025 -45.043549) (xy 219.450893 -45.079224) (xy 219.48811 -45.120761)
			(xy 219.518883 -45.167274) (xy 219.542555 -45.217771) (xy 219.558623 -45.271178) (xy 219.566743 -45.326354)
			(xy 219.567252 -45.35424) (xy 219.566743 -45.382126) (xy 219.558623 -45.437302) (xy 219.542555 -45.490709)
			(xy 219.518883 -45.541206) (xy 219.48811 -45.587719) (xy 219.450893 -45.629256) (xy 219.408025 -45.664931)
			(xy 219.360419 -45.693985) (xy 219.30909 -45.715797) (xy 219.255133 -45.729903) (xy 219.199696 -45.736003)
			(xy 219.143962 -45.733966) (xy 219.089119 -45.723836) (xy 219.036335 -45.705829) (xy 218.986735 -45.680328)
			(xy 218.941377 -45.647877) (xy 218.901228 -45.609168) (xy 218.867142 -45.565025) (xy 218.839846 -45.51639)
			(xy 218.819923 -45.464299) (xy 218.807797 -45.409862) (xy 218.803726 -45.35424) (xy 216.173558 -45.35424)
			(xy 216.173558 -46.693836) (xy 218.776296 -46.693836) (xy 218.776782 -46.666585) (xy 218.784538 -46.612637)
			(xy 218.799893 -46.560342) (xy 218.822535 -46.510765) (xy 218.852001 -46.464915) (xy 218.887692 -46.423724)
			(xy 218.928883 -46.388033) (xy 218.974733 -46.358567) (xy 219.02431 -46.335925) (xy 219.076605 -46.32057)
			(xy 219.130553 -46.312814) (xy 219.185055 -46.312814) (xy 219.239003 -46.32057) (xy 219.291298 -46.335925)
			(xy 219.340875 -46.358567) (xy 219.386725 -46.388033) (xy 219.427916 -46.423724) (xy 219.463607 -46.464915)
			(xy 219.493073 -46.510765) (xy 219.515715 -46.560342) (xy 219.53107 -46.612637) (xy 219.538826 -46.666585)
			(xy 219.539312 -46.693836) (xy 219.538838 -46.720263) (xy 219.531528 -46.772611) (xy 219.517056 -46.823446)
			(xy 219.495696 -46.871793) (xy 219.482162 -46.894496) (xy 219.476066 -46.904402) (xy 219.473526 -46.927262)
			(xy 219.507816 -47.023782) (xy 219.523818 -47.040038) (xy 219.534994 -47.043848) (xy 219.559513 -47.052891)
			(xy 219.605964 -47.076839) (xy 219.648715 -47.106899) (xy 219.686965 -47.142511) (xy 219.72 -47.183007)
			(xy 219.747202 -47.227631) (xy 219.768063 -47.275548) (xy 219.782192 -47.325863) (xy 219.789325 -47.377635)
			(xy 219.789756 -47.403766) (xy 219.78927 -47.431017) (xy 219.781514 -47.484965) (xy 219.766159 -47.53726)
			(xy 219.743517 -47.586837) (xy 219.714051 -47.632687) (xy 219.67836 -47.673878) (xy 219.637169 -47.709569)
			(xy 219.591319 -47.739035) (xy 219.541742 -47.761677) (xy 219.489447 -47.777032) (xy 219.435499 -47.784788)
			(xy 219.380997 -47.784788) (xy 219.327049 -47.777032) (xy 219.274754 -47.761677) (xy 219.225177 -47.739035)
			(xy 219.179327 -47.709569) (xy 219.138136 -47.673878) (xy 219.102445 -47.632687) (xy 219.072979 -47.586837)
			(xy 219.050337 -47.53726) (xy 219.034982 -47.484965) (xy 219.027226 -47.431017) (xy 219.02674 -47.403766)
			(xy 219.027208 -47.377338) (xy 219.034518 -47.324991) (xy 219.048993 -47.274155) (xy 219.070354 -47.225809)
			(xy 219.08389 -47.203106) (xy 219.089986 -47.1932) (xy 219.092526 -47.17034) (xy 219.058236 -47.07382)
			(xy 219.042234 -47.057564) (xy 219.031058 -47.053754) (xy 219.006551 -47.04468) (xy 218.960098 -47.020739)
			(xy 218.917346 -46.990683) (xy 218.879094 -46.955077) (xy 218.846057 -46.914584) (xy 218.818854 -46.869964)
			(xy 218.797991 -46.822049) (xy 218.783861 -46.771736) (xy 218.776727 -46.719966) (xy 218.776296 -46.693836)
			(xy 216.173558 -46.693836) (xy 216.173558 -48.30699) (xy 218.653866 -48.30699) (xy 218.657937 -48.251368)
			(xy 218.670063 -48.196931) (xy 218.689986 -48.14484) (xy 218.717282 -48.096205) (xy 218.751368 -48.052062)
			(xy 218.791517 -48.013353) (xy 218.836875 -47.980902) (xy 218.886475 -47.955401) (xy 218.939259 -47.937394)
			(xy 218.994102 -47.927264) (xy 219.049836 -47.925227) (xy 219.105273 -47.931327) (xy 219.15923 -47.945433)
			(xy 219.210559 -47.967245) (xy 219.258165 -47.996299) (xy 219.301033 -48.031974) (xy 219.33825 -48.073511)
			(xy 219.369023 -48.120024) (xy 219.392695 -48.170521) (xy 219.408763 -48.223928) (xy 219.416883 -48.279104)
			(xy 219.417392 -48.30699) (xy 219.416883 -48.334876) (xy 219.408763 -48.390052) (xy 219.392695 -48.443459)
			(xy 219.369023 -48.493956) (xy 219.33825 -48.540469) (xy 219.301033 -48.582006) (xy 219.258165 -48.617681)
			(xy 219.210559 -48.646735) (xy 219.15923 -48.668547) (xy 219.105273 -48.682653) (xy 219.049836 -48.688753)
			(xy 218.994102 -48.686716) (xy 218.939259 -48.676586) (xy 218.886475 -48.658579) (xy 218.836875 -48.633078)
			(xy 218.791517 -48.600627) (xy 218.751368 -48.561918) (xy 218.717282 -48.517775) (xy 218.689986 -48.46914)
			(xy 218.670063 -48.417049) (xy 218.657937 -48.362612) (xy 218.653866 -48.30699) (xy 216.173558 -48.30699)
			(xy 216.173558 -48.8442) (xy 216.287348 -48.8442) (xy 216.291419 -48.788578) (xy 216.303545 -48.734141)
			(xy 216.323468 -48.68205) (xy 216.350764 -48.633415) (xy 216.38485 -48.589272) (xy 216.424999 -48.550563)
			(xy 216.470357 -48.518112) (xy 216.519957 -48.492611) (xy 216.572741 -48.474604) (xy 216.627584 -48.464474)
			(xy 216.683318 -48.462437) (xy 216.738755 -48.468537) (xy 216.792712 -48.482643) (xy 216.844041 -48.504455)
			(xy 216.891647 -48.533509) (xy 216.934515 -48.569184) (xy 216.971732 -48.610721) (xy 217.002505 -48.657234)
			(xy 217.026177 -48.707731) (xy 217.042245 -48.761138) (xy 217.050365 -48.816314) (xy 217.050874 -48.8442)
			(xy 217.050365 -48.872086) (xy 217.047367 -48.89246) (xy 217.314016 -48.89246) (xy 217.318087 -48.836838)
			(xy 217.330213 -48.782401) (xy 217.350136 -48.73031) (xy 217.377432 -48.681675) (xy 217.411518 -48.637532)
			(xy 217.451667 -48.598823) (xy 217.497025 -48.566372) (xy 217.546625 -48.540871) (xy 217.599409 -48.522864)
			(xy 217.654252 -48.512734) (xy 217.709986 -48.510697) (xy 217.765423 -48.516797) (xy 217.81938 -48.530903)
			(xy 217.870709 -48.552715) (xy 217.918315 -48.581769) (xy 217.961183 -48.617444) (xy 217.9984 -48.658981)
			(xy 218.029173 -48.705494) (xy 218.052845 -48.755991) (xy 218.068913 -48.809398) (xy 218.077033 -48.864574)
			(xy 218.077542 -48.89246) (xy 218.077033 -48.920346) (xy 218.068913 -48.975522) (xy 218.052845 -49.028929)
			(xy 218.029173 -49.079426) (xy 217.9984 -49.125939) (xy 217.961183 -49.167476) (xy 217.918315 -49.203151)
			(xy 217.870709 -49.232205) (xy 217.81938 -49.254017) (xy 217.765423 -49.268123) (xy 217.709986 -49.274223)
			(xy 217.654252 -49.272186) (xy 217.599409 -49.262056) (xy 217.546625 -49.244049) (xy 217.497025 -49.218548)
			(xy 217.451667 -49.186097) (xy 217.411518 -49.147388) (xy 217.377432 -49.103245) (xy 217.350136 -49.05461)
			(xy 217.330213 -49.002519) (xy 217.318087 -48.948082) (xy 217.314016 -48.89246) (xy 217.047367 -48.89246)
			(xy 217.042245 -48.927262) (xy 217.026177 -48.980669) (xy 217.002505 -49.031166) (xy 216.971732 -49.077679)
			(xy 216.934515 -49.119216) (xy 216.891647 -49.154891) (xy 216.844041 -49.183945) (xy 216.792712 -49.205757)
			(xy 216.738755 -49.219863) (xy 216.683318 -49.225963) (xy 216.627584 -49.223926) (xy 216.572741 -49.213796)
			(xy 216.519957 -49.195789) (xy 216.470357 -49.170288) (xy 216.424999 -49.137837) (xy 216.38485 -49.099128)
			(xy 216.350764 -49.054985) (xy 216.323468 -49.00635) (xy 216.303545 -48.954259) (xy 216.291419 -48.899822)
			(xy 216.287348 -48.8442) (xy 216.173558 -48.8442) (xy 216.173558 -51.198018) (xy 216.173986 -51.208085)
			(xy 216.181711 -51.22668) (xy 216.188544 -51.234086) (xy 216.332816 -51.378358) (xy 216.340213 -51.385207)
			(xy 216.358812 -51.392942) (xy 216.368884 -51.393344)
		)
		(stroke
			(width 0)
			(type solid)
		)
		(fill yes)
		(layer "In9.Cu")
		(net "GND")
	)
	(gr_poly
		(pts
			(xy 334.932528 -51.393344) (xy 334.941756 -51.39294) (xy 334.959008 -51.386384) (xy 334.972814 -51.374136)
			(xy 334.977486 -51.366166) (xy 335.019142 -51.286664) (xy 335.023048 -51.278382) (xy 335.025324 -51.260225)
			(xy 335.021107 -51.242418) (xy 335.016348 -51.234594) (xy 335.016094 -51.23434) (xy 335.000599 -51.210699)
			(xy 334.975999 -51.15981) (xy 334.95917 -51.105851) (xy 334.950479 -51.05) (xy 334.9498 -51.021742)
			(xy 334.9498 -51.01463) (xy 334.950612 -50.987604) (xy 334.958922 -50.934177) (xy 334.974691 -50.882459)
			(xy 334.997603 -50.833486) (xy 335.0272 -50.788237) (xy 335.062889 -50.74762) (xy 335.103954 -50.712448)
			(xy 335.149573 -50.683426) (xy 335.198833 -50.661135) (xy 335.250747 -50.646021) (xy 335.304274 -50.638388)
			(xy 335.358342 -50.638388) (xy 335.411869 -50.646021) (xy 335.463783 -50.661135) (xy 335.513043 -50.683426)
			(xy 335.558662 -50.712448) (xy 335.599727 -50.74762) (xy 335.635416 -50.788237) (xy 335.665013 -50.833486)
			(xy 335.687925 -50.882459) (xy 335.703694 -50.934177) (xy 335.712004 -50.987604) (xy 335.712816 -51.01463)
			(xy 335.712816 -51.01971) (xy 335.712308 -51.048258) (xy 335.703793 -51.104717) (xy 335.686956 -51.159274)
			(xy 335.662173 -51.210712) (xy 335.646522 -51.234594) (xy 335.638394 -51.246278) (xy 335.63687 -51.274218)
			(xy 335.68513 -51.366166) (xy 335.689779 -51.374147) (xy 335.703602 -51.386377) (xy 335.72086 -51.392917)
			(xy 335.730088 -51.393344) (xy 336.622136 -51.393344) (xy 336.632102 -51.392864) (xy 336.650538 -51.385289)
			(xy 336.65795 -51.378612) (xy 337.17611 -50.860452) (xy 337.17992 -50.852578) (xy 337.189826 -50.833528)
			(xy 337.19008 -50.833274) (xy 337.19389 -50.82667) (xy 337.197192 -50.821082) (xy 337.201256 -50.806858)
			(xy 337.204558 -50.795174) (xy 337.204558 -50.1904) (xy 337.204303 -50.182988) (xy 337.200044 -50.168788)
			(xy 337.196176 -50.16246) (xy 337.181344 -50.139007) (xy 337.157887 -50.088717) (xy 337.141967 -50.035559)
			(xy 337.133922 -49.980654) (xy 337.133921 -49.925163) (xy 337.141964 -49.870258) (xy 337.157881 -49.817098)
			(xy 337.181335 -49.766808) (xy 337.196176 -49.74336) (xy 337.20004 -49.73703) (xy 337.204297 -49.722831)
			(xy 337.204558 -49.71542) (xy 337.204558 -49.1744) (xy 337.204303 -49.166988) (xy 337.200044 -49.152788)
			(xy 337.196176 -49.14646) (xy 337.181344 -49.123007) (xy 337.157887 -49.072717) (xy 337.141967 -49.019559)
			(xy 337.133922 -48.964654) (xy 337.133921 -48.909163) (xy 337.141964 -48.854258) (xy 337.157881 -48.801098)
			(xy 337.181335 -48.750808) (xy 337.196176 -48.72736) (xy 337.20004 -48.72103) (xy 337.204297 -48.706831)
			(xy 337.204558 -48.69942) (xy 337.204558 -47.629572) (xy 337.202018 -47.61865) (xy 337.199224 -47.613062)
			(xy 337.186499 -47.586292) (xy 337.168524 -47.529814) (xy 337.159427 -47.471246) (xy 337.159426 -47.411976)
			(xy 337.168519 -47.353407) (xy 337.186491 -47.296928) (xy 337.199224 -47.270162) (xy 337.202018 -47.264574)
			(xy 337.204558 -47.253652) (xy 337.204558 -46.1264) (xy 337.204303 -46.118988) (xy 337.200044 -46.104788)
			(xy 337.196176 -46.09846) (xy 337.181344 -46.075007) (xy 337.157887 -46.024717) (xy 337.141967 -45.971559)
			(xy 337.133922 -45.916654) (xy 337.133921 -45.861163) (xy 337.141964 -45.806258) (xy 337.157881 -45.753098)
			(xy 337.181335 -45.702808) (xy 337.196176 -45.67936) (xy 337.20004 -45.67303) (xy 337.204297 -45.658831)
			(xy 337.204558 -45.65142) (xy 337.204558 -45.1104) (xy 337.204303 -45.102988) (xy 337.200044 -45.088788)
			(xy 337.196176 -45.08246) (xy 337.181344 -45.059007) (xy 337.157887 -45.008717) (xy 337.141967 -44.955559)
			(xy 337.133922 -44.900654) (xy 337.133921 -44.845163) (xy 337.141964 -44.790258) (xy 337.157881 -44.737098)
			(xy 337.181335 -44.686808) (xy 337.196176 -44.66336) (xy 337.20004 -44.65703) (xy 337.204297 -44.642831)
			(xy 337.204558 -44.63542) (xy 337.204558 -44.0944) (xy 337.204303 -44.086988) (xy 337.200044 -44.072788)
			(xy 337.196176 -44.06646) (xy 337.181344 -44.043007) (xy 337.157887 -43.992717) (xy 337.141967 -43.939559)
			(xy 337.133922 -43.884654) (xy 337.133921 -43.829163) (xy 337.141964 -43.774258) (xy 337.157881 -43.721098)
			(xy 337.181335 -43.670808) (xy 337.196176 -43.64736) (xy 337.20004 -43.64103) (xy 337.204297 -43.626831)
			(xy 337.204558 -43.61942) (xy 337.204558 -43.0784) (xy 337.204303 -43.070988) (xy 337.200044 -43.056788)
			(xy 337.196176 -43.05046) (xy 337.181344 -43.027007) (xy 337.157887 -42.976717) (xy 337.141967 -42.923559)
			(xy 337.133922 -42.868654) (xy 337.133921 -42.813163) (xy 337.141964 -42.758258) (xy 337.157881 -42.705098)
			(xy 337.181335 -42.654808) (xy 337.196176 -42.63136) (xy 337.20004 -42.62503) (xy 337.204297 -42.610831)
			(xy 337.204558 -42.60342) (xy 337.204558 -29.753052) (xy 337.17611 -29.707332) (xy 337.17611 -28.368752)
			(xy 337.176338 -28.361714) (xy 337.180213 -28.348183) (xy 337.18373 -28.342082) (xy 337.196684 -28.322016)
			(xy 337.200339 -28.315757) (xy 337.204326 -28.301829) (xy 337.204558 -28.294584) (xy 337.204558 -27.872436)
			(xy 337.204122 -27.862372) (xy 337.196386 -27.843788) (xy 337.189572 -27.836368) (xy 336.95005 -27.596846)
			(xy 336.942651 -27.590002) (xy 336.924052 -27.582279) (xy 336.913982 -27.58186) (xy 327.599294 -27.58186)
			(xy 327.586963 -27.582445) (xy 327.565116 -27.593884) (xy 327.557638 -27.603704) (xy 327.540478 -27.627665)
			(xy 327.500972 -27.6714) (xy 327.456181 -27.709706) (xy 327.406846 -27.74195) (xy 327.353783 -27.767598)
			(xy 327.297868 -27.786227) (xy 327.240025 -27.797529) (xy 327.18121 -27.801317) (xy 327.122395 -27.797529)
			(xy 327.064552 -27.786227) (xy 327.008637 -27.767598) (xy 326.955574 -27.74195) (xy 326.906239 -27.709706)
			(xy 326.861448 -27.6714) (xy 326.821942 -27.627665) (xy 326.804782 -27.603704) (xy 326.79717 -27.594033)
			(xy 326.77541 -27.582615) (xy 326.763126 -27.58186) (xy 322.627752 -27.58186) (xy 322.617687 -27.582293)
			(xy 322.599101 -27.590027) (xy 322.591684 -27.596846) (xy 322.322698 -27.865832) (xy 322.316348 -27.877262)
			(xy 322.31457 -27.88412) (xy 322.306845 -27.912351) (xy 322.283935 -27.966208) (xy 322.25307 -28.015937)
			(xy 322.214975 -28.06037) (xy 322.170543 -28.098466) (xy 322.120815 -28.129331) (xy 322.066958 -28.152243)
			(xy 322.038726 -28.159964) (xy 322.031868 -28.161742) (xy 322.020438 -28.168092) (xy 322.00469 -28.18384)
			(xy 321.99784 -28.191236) (xy 321.990106 -28.209835) (xy 321.989704 -28.219908) (xy 321.989704 -29.114242)
			(xy 329.047348 -29.114242) (xy 329.047348 -28.250642) (xy 329.047838 -28.220674) (xy 329.055661 -28.161252)
			(xy 329.071174 -28.103359) (xy 329.09411 -28.047986) (xy 329.124077 -27.99608) (xy 329.160564 -27.94853)
			(xy 329.202944 -27.90615) (xy 329.250494 -27.869663) (xy 329.3024 -27.839696) (xy 329.357773 -27.81676)
			(xy 329.415666 -27.801247) (xy 329.475088 -27.793424) (xy 329.535024 -27.793424) (xy 329.594446 -27.801247)
			(xy 329.652339 -27.81676) (xy 329.707712 -27.839696) (xy 329.759618 -27.869663) (xy 329.807168 -27.90615)
			(xy 329.849548 -27.94853) (xy 329.886035 -27.99608) (xy 329.916002 -28.047986) (xy 329.938938 -28.103359)
			(xy 329.954451 -28.161252) (xy 329.962274 -28.220674) (xy 329.962764 -28.250642) (xy 329.962764 -28.469082)
			(xy 333.95234 -28.469082) (xy 333.956411 -28.41346) (xy 333.968537 -28.359023) (xy 333.98846 -28.306932)
			(xy 334.015756 -28.258297) (xy 334.049842 -28.214154) (xy 334.089991 -28.175445) (xy 334.135349 -28.142994)
			(xy 334.184949 -28.117493) (xy 334.237733 -28.099486) (xy 334.292576 -28.089356) (xy 334.34831 -28.087319)
			(xy 334.403747 -28.093419) (xy 334.457704 -28.107525) (xy 334.509033 -28.129337) (xy 334.556639 -28.158391)
			(xy 334.599507 -28.194066) (xy 334.636724 -28.235603) (xy 334.667497 -28.282116) (xy 334.691169 -28.332613)
			(xy 334.707237 -28.38602) (xy 334.715357 -28.441196) (xy 334.715866 -28.469082) (xy 334.715357 -28.496968)
			(xy 334.707237 -28.552144) (xy 334.691169 -28.605551) (xy 334.667497 -28.656048) (xy 334.636724 -28.702561)
			(xy 334.599507 -28.744098) (xy 334.556639 -28.779773) (xy 334.509033 -28.808827) (xy 334.457704 -28.830639)
			(xy 334.403747 -28.844745) (xy 334.34831 -28.850845) (xy 334.292576 -28.848808) (xy 334.237733 -28.838678)
			(xy 334.184949 -28.820671) (xy 334.135349 -28.79517) (xy 334.089991 -28.762719) (xy 334.049842 -28.72401)
			(xy 334.015756 -28.679867) (xy 333.98846 -28.631232) (xy 333.968537 -28.579141) (xy 333.956411 -28.524704)
			(xy 333.95234 -28.469082) (xy 329.962764 -28.469082) (xy 329.962764 -29.114242) (xy 329.962274 -29.14421)
			(xy 329.954451 -29.203632) (xy 329.938938 -29.261525) (xy 329.916002 -29.316898) (xy 329.886035 -29.368804)
			(xy 329.849548 -29.416354) (xy 329.807168 -29.458734) (xy 329.759618 -29.495221) (xy 329.707712 -29.525188)
			(xy 329.652339 -29.548124) (xy 329.594446 -29.563637) (xy 329.535024 -29.57146) (xy 329.475088 -29.57146)
			(xy 329.415666 -29.563637) (xy 329.357773 -29.548124) (xy 329.3024 -29.525188) (xy 329.250494 -29.495221)
			(xy 329.202944 -29.458734) (xy 329.160564 -29.416354) (xy 329.124077 -29.368804) (xy 329.09411 -29.316898)
			(xy 329.071174 -29.261525) (xy 329.055661 -29.203632) (xy 329.047838 -29.14421) (xy 329.047348 -29.114242)
			(xy 321.989704 -29.114242) (xy 321.989704 -29.186378) (xy 322.011802 -29.214064) (xy 322.029328 -29.217874)
			(xy 322.05562 -29.224338) (xy 322.106187 -29.243685) (xy 322.153511 -29.269985) (xy 322.196644 -29.302709)
			(xy 322.234719 -29.341201) (xy 322.266971 -29.384687) (xy 322.292754 -29.432296) (xy 322.311549 -29.48307)
			(xy 322.322979 -29.535991) (xy 322.326815 -29.589996) (xy 322.32298 -29.644002) (xy 322.311551 -29.696923)
			(xy 322.292756 -29.747698) (xy 322.266975 -29.795307) (xy 322.234723 -29.838794) (xy 322.196649 -29.877287)
			(xy 322.153517 -29.910011) (xy 322.106193 -29.936312) (xy 322.055627 -29.95566) (xy 322.029328 -29.962094)
			(xy 322.011802 -29.965904) (xy 321.989704 -29.99359) (xy 321.989704 -30.92069) (xy 331.689456 -30.92069)
			(xy 331.689456 -30.05709) (xy 331.689946 -30.027122) (xy 331.697769 -29.9677) (xy 331.713282 -29.909807)
			(xy 331.736218 -29.854434) (xy 331.766185 -29.802528) (xy 331.802672 -29.754978) (xy 331.845052 -29.712598)
			(xy 331.892602 -29.676111) (xy 331.944508 -29.646144) (xy 331.999881 -29.623208) (xy 332.057774 -29.607695)
			(xy 332.117196 -29.599872) (xy 332.177132 -29.599872) (xy 332.236554 -29.607695) (xy 332.294447 -29.623208)
			(xy 332.34982 -29.646144) (xy 332.401726 -29.676111) (xy 332.449276 -29.712598) (xy 332.491656 -29.754978)
			(xy 332.528143 -29.802528) (xy 332.55811 -29.854434) (xy 332.581046 -29.909807) (xy 332.596559 -29.9677)
			(xy 332.604382 -30.027122) (xy 332.604872 -30.05709) (xy 332.604872 -30.92069) (xy 332.604382 -30.950658)
			(xy 332.596559 -31.01008) (xy 332.581046 -31.067973) (xy 332.55811 -31.123346) (xy 332.528143 -31.175252)
			(xy 332.491656 -31.222802) (xy 332.449276 -31.265182) (xy 332.401726 -31.301669) (xy 332.34982 -31.331636)
			(xy 332.294447 -31.354572) (xy 332.236554 -31.370085) (xy 332.177132 -31.377908) (xy 332.117196 -31.377908)
			(xy 332.057774 -31.370085) (xy 331.999881 -31.354572) (xy 331.944508 -31.331636) (xy 331.892602 -31.301669)
			(xy 331.845052 -31.265182) (xy 331.802672 -31.222802) (xy 331.766185 -31.175252) (xy 331.736218 -31.123346)
			(xy 331.713282 -31.067973) (xy 331.697769 -31.01008) (xy 331.689946 -30.950658) (xy 331.689456 -30.92069)
			(xy 321.989704 -30.92069) (xy 321.989704 -31.232602) (xy 322.015104 -31.261304) (xy 322.034408 -31.26359)
			(xy 322.061816 -31.267417) (xy 322.11521 -31.281958) (xy 322.165942 -31.30406) (xy 322.212949 -31.333261)
			(xy 322.255244 -31.368947) (xy 322.291939 -31.41037) (xy 322.322264 -31.45666) (xy 322.345583 -31.506845)
			(xy 322.361406 -31.559873) (xy 322.369401 -31.614631) (xy 322.369401 -31.66997) (xy 322.361405 -31.724728)
			(xy 322.345582 -31.777756) (xy 322.322263 -31.827941) (xy 322.291938 -31.874231) (xy 322.255243 -31.915653)
			(xy 322.212949 -31.951339) (xy 322.165942 -31.98054) (xy 322.115209 -32.002643) (xy 322.061815 -32.017184)
			(xy 322.034408 -32.021018) (xy 322.015104 -32.023304) (xy 321.989704 -32.052006) (xy 321.989704 -32.714184)
			(xy 329.047348 -32.714184) (xy 329.047348 -31.850584) (xy 329.047838 -31.820616) (xy 329.055661 -31.761194)
			(xy 329.071174 -31.703301) (xy 329.09411 -31.647928) (xy 329.124077 -31.596022) (xy 329.160564 -31.548472)
			(xy 329.202944 -31.506092) (xy 329.250494 -31.469605) (xy 329.3024 -31.439638) (xy 329.357773 -31.416702)
			(xy 329.415666 -31.401189) (xy 329.475088 -31.393366) (xy 329.535024 -31.393366) (xy 329.594446 -31.401189)
			(xy 329.652339 -31.416702) (xy 329.707712 -31.439638) (xy 329.759618 -31.469605) (xy 329.807168 -31.506092)
			(xy 329.849548 -31.548472) (xy 329.886035 -31.596022) (xy 329.916002 -31.647928) (xy 329.938938 -31.703301)
			(xy 329.954451 -31.761194) (xy 329.962274 -31.820616) (xy 329.962764 -31.850584) (xy 329.962764 -32.714184)
			(xy 329.962274 -32.744152) (xy 329.954451 -32.803574) (xy 329.938938 -32.861467) (xy 329.916002 -32.91684)
			(xy 329.886035 -32.968746) (xy 329.849548 -33.016296) (xy 329.807168 -33.058676) (xy 329.759618 -33.095163)
			(xy 329.707712 -33.12513) (xy 329.652339 -33.148066) (xy 329.594446 -33.163579) (xy 329.535024 -33.171402)
			(xy 329.475088 -33.171402) (xy 329.415666 -33.163579) (xy 329.357773 -33.148066) (xy 329.3024 -33.12513)
			(xy 329.250494 -33.095163) (xy 329.202944 -33.058676) (xy 329.160564 -33.016296) (xy 329.124077 -32.968746)
			(xy 329.09411 -32.91684) (xy 329.071174 -32.861467) (xy 329.055661 -32.803574) (xy 329.047838 -32.744152)
			(xy 329.047348 -32.714184) (xy 321.989704 -32.714184) (xy 321.989704 -34.520886) (xy 331.689456 -34.520886)
			(xy 331.689456 -33.657286) (xy 331.689946 -33.627318) (xy 331.697769 -33.567896) (xy 331.713282 -33.510003)
			(xy 331.736218 -33.45463) (xy 331.766185 -33.402724) (xy 331.802672 -33.355174) (xy 331.845052 -33.312794)
			(xy 331.892602 -33.276307) (xy 331.944508 -33.24634) (xy 331.999881 -33.223404) (xy 332.057774 -33.207891)
			(xy 332.117196 -33.200068) (xy 332.177132 -33.200068) (xy 332.236554 -33.207891) (xy 332.294447 -33.223404)
			(xy 332.34982 -33.24634) (xy 332.401726 -33.276307) (xy 332.449276 -33.312794) (xy 332.491656 -33.355174)
			(xy 332.528143 -33.402724) (xy 332.55811 -33.45463) (xy 332.581046 -33.510003) (xy 332.596559 -33.567896)
			(xy 332.604382 -33.627318) (xy 332.604872 -33.657286) (xy 332.604872 -34.520886) (xy 332.604382 -34.550854)
			(xy 332.596559 -34.610276) (xy 332.581046 -34.668169) (xy 332.55811 -34.723542) (xy 332.528143 -34.775448)
			(xy 332.491656 -34.822998) (xy 332.449276 -34.865378) (xy 332.401726 -34.901865) (xy 332.34982 -34.931832)
			(xy 332.294447 -34.954768) (xy 332.236554 -34.970281) (xy 332.177132 -34.978104) (xy 332.117196 -34.978104)
			(xy 332.057774 -34.970281) (xy 331.999881 -34.954768) (xy 331.944508 -34.931832) (xy 331.892602 -34.901865)
			(xy 331.845052 -34.865378) (xy 331.802672 -34.822998) (xy 331.766185 -34.775448) (xy 331.736218 -34.723542)
			(xy 331.713282 -34.668169) (xy 331.697769 -34.610276) (xy 331.689946 -34.550854) (xy 331.689456 -34.520886)
			(xy 321.989704 -34.520886) (xy 321.989704 -36.60013) (xy 322.198245 -36.60013) (xy 322.202249 -36.512245)
			(xy 322.214229 -36.425088) (xy 322.234084 -36.339381) (xy 322.261651 -36.255836) (xy 322.296701 -36.175143)
			(xy 322.338943 -36.097971) (xy 322.388028 -36.024961) (xy 322.443549 -35.956717) (xy 322.505046 -35.893804)
			(xy 322.572008 -35.836744) (xy 322.643882 -35.78601) (xy 322.720072 -35.742022) (xy 322.799946 -35.705144)
			(xy 322.882843 -35.675683) (xy 322.968075 -35.653881) (xy 323.054937 -35.639921) (xy 323.142708 -35.633917)
			(xy 323.230662 -35.63592) (xy 323.318069 -35.645912) (xy 323.404205 -35.663812) (xy 323.488357 -35.68947)
			(xy 323.569827 -35.722674) (xy 323.64794 -35.763148) (xy 323.722048 -35.810559) (xy 323.791539 -35.864512)
			(xy 323.855835 -35.92456) (xy 323.914404 -35.990207) (xy 323.966761 -36.060907) (xy 324.012473 -36.136076)
			(xy 324.051159 -36.21509) (xy 324.0825 -36.297295) (xy 324.106235 -36.382009) (xy 324.122169 -36.46853)
			(xy 324.130169 -36.556142) (xy 324.13067 -36.60013) (xy 324.130169 -36.644118) (xy 324.122169 -36.73173)
			(xy 324.106235 -36.818251) (xy 324.0825 -36.902965) (xy 324.051159 -36.98517) (xy 324.012473 -37.064184)
			(xy 323.966761 -37.139353) (xy 323.914404 -37.210053) (xy 323.855835 -37.2757) (xy 323.791539 -37.335748)
			(xy 323.722048 -37.389701) (xy 323.64794 -37.437112) (xy 323.569827 -37.477586) (xy 323.488357 -37.51079)
			(xy 323.404205 -37.536448) (xy 323.318069 -37.554348) (xy 323.230662 -37.56434) (xy 323.142708 -37.566343)
			(xy 323.054937 -37.560339) (xy 322.968075 -37.546379) (xy 322.882843 -37.524577) (xy 322.799946 -37.495116)
			(xy 322.720072 -37.458238) (xy 322.643882 -37.41425) (xy 322.572008 -37.363516) (xy 322.505046 -37.306456)
			(xy 322.443549 -37.243543) (xy 322.388028 -37.175299) (xy 322.338943 -37.102289) (xy 322.296701 -37.025117)
			(xy 322.261651 -36.944424) (xy 322.234084 -36.860879) (xy 322.214229 -36.775172) (xy 322.202249 -36.688015)
			(xy 322.198245 -36.60013) (xy 321.989704 -36.60013) (xy 321.989704 -40.452802) (xy 321.990128 -40.462872)
			(xy 321.997843 -40.481475) (xy 322.00469 -40.48887) (xy 322.223892 -40.708072) (xy 322.231289 -40.714923)
			(xy 322.249887 -40.722664) (xy 322.25996 -40.723058) (xy 331.281278 -40.723058) (xy 331.291341 -40.723497)
			(xy 331.309919 -40.731238) (xy 331.317346 -40.738044) (xy 332.258416 -41.679114) (xy 332.265269 -41.686509)
			(xy 332.273012 -41.705108) (xy 332.273402 -41.715182) (xy 332.273402 -41.946576) (xy 332.273656 -41.954196)
			(xy 332.273656 -43.566842) (xy 333.53324 -43.566842) (xy 333.537311 -43.51122) (xy 333.549437 -43.456783)
			(xy 333.56936 -43.404692) (xy 333.596656 -43.356057) (xy 333.630742 -43.311914) (xy 333.670891 -43.273205)
			(xy 333.716249 -43.240754) (xy 333.765849 -43.215253) (xy 333.818633 -43.197246) (xy 333.873476 -43.187116)
			(xy 333.92921 -43.185079) (xy 333.984647 -43.191179) (xy 334.038604 -43.205285) (xy 334.089933 -43.227097)
			(xy 334.137539 -43.256151) (xy 334.180407 -43.291826) (xy 334.217624 -43.333363) (xy 334.248397 -43.379876)
			(xy 334.272069 -43.430373) (xy 334.288137 -43.48378) (xy 334.296257 -43.538956) (xy 334.296766 -43.566842)
			(xy 334.296257 -43.594728) (xy 334.288137 -43.649904) (xy 334.272069 -43.703311) (xy 334.248397 -43.753808)
			(xy 334.217624 -43.800321) (xy 334.180407 -43.841858) (xy 334.16232 -43.85691) (xy 334.919572 -43.85691)
			(xy 334.923643 -43.801288) (xy 334.935769 -43.746851) (xy 334.955692 -43.69476) (xy 334.982988 -43.646125)
			(xy 335.017074 -43.601982) (xy 335.057223 -43.563273) (xy 335.102581 -43.530822) (xy 335.152181 -43.505321)
			(xy 335.204965 -43.487314) (xy 335.259808 -43.477184) (xy 335.315542 -43.475147) (xy 335.370979 -43.481247)
			(xy 335.424936 -43.495353) (xy 335.476265 -43.517165) (xy 335.523871 -43.546219) (xy 335.566739 -43.581894)
			(xy 335.603956 -43.623431) (xy 335.634729 -43.669944) (xy 335.658401 -43.720441) (xy 335.674469 -43.773848)
			(xy 335.682589 -43.829024) (xy 335.683098 -43.85691) (xy 335.682589 -43.884796) (xy 335.674469 -43.939972)
			(xy 335.658401 -43.993379) (xy 335.634729 -44.043876) (xy 335.603956 -44.090389) (xy 335.566739 -44.131926)
			(xy 335.523871 -44.167601) (xy 335.476265 -44.196655) (xy 335.424936 -44.218467) (xy 335.370979 -44.232573)
			(xy 335.315542 -44.238673) (xy 335.259808 -44.236636) (xy 335.204965 -44.226506) (xy 335.152181 -44.208499)
			(xy 335.102581 -44.182998) (xy 335.057223 -44.150547) (xy 335.017074 -44.111838) (xy 334.982988 -44.067695)
			(xy 334.955692 -44.01906) (xy 334.935769 -43.966969) (xy 334.923643 -43.912532) (xy 334.919572 -43.85691)
			(xy 334.16232 -43.85691) (xy 334.137539 -43.877533) (xy 334.089933 -43.906587) (xy 334.038604 -43.928399)
			(xy 333.984647 -43.942505) (xy 333.92921 -43.948605) (xy 333.873476 -43.946568) (xy 333.818633 -43.936438)
			(xy 333.765849 -43.918431) (xy 333.716249 -43.89293) (xy 333.670891 -43.860479) (xy 333.630742 -43.82177)
			(xy 333.596656 -43.777627) (xy 333.56936 -43.728992) (xy 333.549437 -43.676901) (xy 333.537311 -43.622464)
			(xy 333.53324 -43.566842) (xy 332.273656 -43.566842) (xy 332.273656 -45.35424) (xy 334.90357 -45.35424)
			(xy 334.907641 -45.298618) (xy 334.919767 -45.244181) (xy 334.93969 -45.19209) (xy 334.966986 -45.143455)
			(xy 335.001072 -45.099312) (xy 335.041221 -45.060603) (xy 335.086579 -45.028152) (xy 335.136179 -45.002651)
			(xy 335.188963 -44.984644) (xy 335.243806 -44.974514) (xy 335.29954 -44.972477) (xy 335.354977 -44.978577)
			(xy 335.408934 -44.992683) (xy 335.460263 -45.014495) (xy 335.507869 -45.043549) (xy 335.550737 -45.079224)
			(xy 335.587954 -45.120761) (xy 335.618727 -45.167274) (xy 335.642399 -45.217771) (xy 335.658467 -45.271178)
			(xy 335.666587 -45.326354) (xy 335.667096 -45.35424) (xy 335.666587 -45.382126) (xy 335.658467 -45.437302)
			(xy 335.642399 -45.490709) (xy 335.618727 -45.541206) (xy 335.587954 -45.587719) (xy 335.550737 -45.629256)
			(xy 335.507869 -45.664931) (xy 335.460263 -45.693985) (xy 335.408934 -45.715797) (xy 335.354977 -45.729903)
			(xy 335.29954 -45.736003) (xy 335.243806 -45.733966) (xy 335.188963 -45.723836) (xy 335.136179 -45.705829)
			(xy 335.086579 -45.680328) (xy 335.041221 -45.647877) (xy 335.001072 -45.609168) (xy 334.966986 -45.565025)
			(xy 334.93969 -45.51639) (xy 334.919767 -45.464299) (xy 334.907641 -45.409862) (xy 334.90357 -45.35424)
			(xy 332.273656 -45.35424) (xy 332.273656 -46.693836) (xy 334.87614 -46.693836) (xy 334.876626 -46.666585)
			(xy 334.884382 -46.612637) (xy 334.899737 -46.560342) (xy 334.922379 -46.510765) (xy 334.951845 -46.464915)
			(xy 334.987536 -46.423724) (xy 335.028727 -46.388033) (xy 335.074577 -46.358567) (xy 335.124154 -46.335925)
			(xy 335.176449 -46.32057) (xy 335.230397 -46.312814) (xy 335.284899 -46.312814) (xy 335.338847 -46.32057)
			(xy 335.391142 -46.335925) (xy 335.440719 -46.358567) (xy 335.486569 -46.388033) (xy 335.52776 -46.423724)
			(xy 335.563451 -46.464915) (xy 335.592917 -46.510765) (xy 335.615559 -46.560342) (xy 335.630914 -46.612637)
			(xy 335.63867 -46.666585) (xy 335.639156 -46.693836) (xy 335.638689 -46.720264) (xy 335.631379 -46.772612)
			(xy 335.616904 -46.823447) (xy 335.595542 -46.871793) (xy 335.582006 -46.894496) (xy 335.57591 -46.904402)
			(xy 335.57337 -46.927262) (xy 335.60766 -47.023782) (xy 335.623662 -47.040038) (xy 335.634838 -47.043848)
			(xy 335.659345 -47.052922) (xy 335.705798 -47.076864) (xy 335.74855 -47.106919) (xy 335.786802 -47.142525)
			(xy 335.819839 -47.183018) (xy 335.847043 -47.227638) (xy 335.867905 -47.275553) (xy 335.882035 -47.325866)
			(xy 335.889169 -47.377636) (xy 335.8896 -47.403766) (xy 335.889114 -47.431017) (xy 335.881358 -47.484965)
			(xy 335.866003 -47.53726) (xy 335.843361 -47.586837) (xy 335.813895 -47.632687) (xy 335.778204 -47.673878)
			(xy 335.737013 -47.709569) (xy 335.691163 -47.739035) (xy 335.641586 -47.761677) (xy 335.589291 -47.777032)
			(xy 335.535343 -47.784788) (xy 335.480841 -47.784788) (xy 335.426893 -47.777032) (xy 335.374598 -47.761677)
			(xy 335.325021 -47.739035) (xy 335.279171 -47.709569) (xy 335.23798 -47.673878) (xy 335.202289 -47.632687)
			(xy 335.172823 -47.586837) (xy 335.150181 -47.53726) (xy 335.134826 -47.484965) (xy 335.12707 -47.431017)
			(xy 335.126584 -47.403766) (xy 335.12706 -47.377339) (xy 335.134369 -47.324991) (xy 335.148841 -47.274157)
			(xy 335.1702 -47.225809) (xy 335.183734 -47.203106) (xy 335.18983 -47.1932) (xy 335.19237 -47.17034)
			(xy 335.15808 -47.07382) (xy 335.142078 -47.057564) (xy 335.130902 -47.053754) (xy 335.106383 -47.044712)
			(xy 335.059932 -47.020764) (xy 335.017181 -46.990703) (xy 334.978931 -46.955091) (xy 334.945896 -46.914595)
			(xy 334.918694 -46.869971) (xy 334.897834 -46.822054) (xy 334.883705 -46.771739) (xy 334.876571 -46.719967)
			(xy 334.87614 -46.693836) (xy 332.273656 -46.693836) (xy 332.273656 -48.300132) (xy 332.273435 -48.30699)
			(xy 334.75371 -48.30699) (xy 334.757781 -48.251368) (xy 334.769907 -48.196931) (xy 334.78983 -48.14484)
			(xy 334.817126 -48.096205) (xy 334.851212 -48.052062) (xy 334.891361 -48.013353) (xy 334.936719 -47.980902)
			(xy 334.986319 -47.955401) (xy 335.039103 -47.937394) (xy 335.093946 -47.927264) (xy 335.14968 -47.925227)
			(xy 335.205117 -47.931327) (xy 335.259074 -47.945433) (xy 335.310403 -47.967245) (xy 335.358009 -47.996299)
			(xy 335.400877 -48.031974) (xy 335.438094 -48.073511) (xy 335.468867 -48.120024) (xy 335.492539 -48.170521)
			(xy 335.508607 -48.223928) (xy 335.516727 -48.279104) (xy 335.517236 -48.30699) (xy 335.516727 -48.334876)
			(xy 335.508607 -48.390052) (xy 335.492539 -48.443459) (xy 335.468867 -48.493956) (xy 335.438094 -48.540469)
			(xy 335.400877 -48.582006) (xy 335.358009 -48.617681) (xy 335.310403 -48.646735) (xy 335.259074 -48.668547)
			(xy 335.205117 -48.682653) (xy 335.14968 -48.688753) (xy 335.093946 -48.686716) (xy 335.039103 -48.676586)
			(xy 334.986319 -48.658579) (xy 334.936719 -48.633078) (xy 334.891361 -48.600627) (xy 334.851212 -48.561918)
			(xy 334.817126 -48.517775) (xy 334.78983 -48.46914) (xy 334.769907 -48.417049) (xy 334.757781 -48.362612)
			(xy 334.75371 -48.30699) (xy 332.273435 -48.30699) (xy 332.273402 -48.308006) (xy 332.273402 -48.8442)
			(xy 332.387192 -48.8442) (xy 332.391263 -48.788578) (xy 332.403389 -48.734141) (xy 332.423312 -48.68205)
			(xy 332.450608 -48.633415) (xy 332.484694 -48.589272) (xy 332.524843 -48.550563) (xy 332.570201 -48.518112)
			(xy 332.619801 -48.492611) (xy 332.672585 -48.474604) (xy 332.727428 -48.464474) (xy 332.783162 -48.462437)
			(xy 332.838599 -48.468537) (xy 332.892556 -48.482643) (xy 332.943885 -48.504455) (xy 332.991491 -48.533509)
			(xy 333.034359 -48.569184) (xy 333.071576 -48.610721) (xy 333.102349 -48.657234) (xy 333.126021 -48.707731)
			(xy 333.142089 -48.761138) (xy 333.150209 -48.816314) (xy 333.150718 -48.8442) (xy 333.150209 -48.872086)
			(xy 333.147211 -48.89246) (xy 333.41386 -48.89246) (xy 333.417931 -48.836838) (xy 333.430057 -48.782401)
			(xy 333.44998 -48.73031) (xy 333.477276 -48.681675) (xy 333.511362 -48.637532) (xy 333.551511 -48.598823)
			(xy 333.596869 -48.566372) (xy 333.646469 -48.540871) (xy 333.699253 -48.522864) (xy 333.754096 -48.512734)
			(xy 333.80983 -48.510697) (xy 333.865267 -48.516797) (xy 333.919224 -48.530903) (xy 333.970553 -48.552715)
			(xy 334.018159 -48.581769) (xy 334.061027 -48.617444) (xy 334.098244 -48.658981) (xy 334.129017 -48.705494)
			(xy 334.152689 -48.755991) (xy 334.168757 -48.809398) (xy 334.176877 -48.864574) (xy 334.177386 -48.89246)
			(xy 334.176877 -48.920346) (xy 334.168757 -48.975522) (xy 334.152689 -49.028929) (xy 334.129017 -49.079426)
			(xy 334.098244 -49.125939) (xy 334.061027 -49.167476) (xy 334.018159 -49.203151) (xy 333.970553 -49.232205)
			(xy 333.919224 -49.254017) (xy 333.865267 -49.268123) (xy 333.80983 -49.274223) (xy 333.754096 -49.272186)
			(xy 333.699253 -49.262056) (xy 333.646469 -49.244049) (xy 333.596869 -49.218548) (xy 333.551511 -49.186097)
			(xy 333.511362 -49.147388) (xy 333.477276 -49.103245) (xy 333.44998 -49.05461) (xy 333.430057 -49.002519)
			(xy 333.417931 -48.948082) (xy 333.41386 -48.89246) (xy 333.147211 -48.89246) (xy 333.142089 -48.927262)
			(xy 333.126021 -48.980669) (xy 333.102349 -49.031166) (xy 333.071576 -49.077679) (xy 333.034359 -49.119216)
			(xy 332.991491 -49.154891) (xy 332.943885 -49.183945) (xy 332.892556 -49.205757) (xy 332.838599 -49.219863)
			(xy 332.783162 -49.225963) (xy 332.727428 -49.223926) (xy 332.672585 -49.213796) (xy 332.619801 -49.195789)
			(xy 332.570201 -49.170288) (xy 332.524843 -49.137837) (xy 332.484694 -49.099128) (xy 332.450608 -49.054985)
			(xy 332.423312 -49.00635) (xy 332.403389 -48.954259) (xy 332.391263 -48.899822) (xy 332.387192 -48.8442)
			(xy 332.273402 -48.8442) (xy 332.273402 -49.198022) (xy 332.273656 -49.205896) (xy 332.273656 -51.198272)
			(xy 332.274142 -51.208235) (xy 332.281726 -51.226662) (xy 332.288388 -51.234086) (xy 332.43266 -51.378358)
			(xy 332.44006 -51.3852) (xy 332.458658 -51.392919) (xy 332.468728 -51.393344)
		)
		(stroke
			(width 0)
			(type solid)
		)
		(fill yes)
		(layer "In9.Cu")
		(net "GND")
	)
	(gr_poly
		(pts
			(xy 451.032372 -51.393344) (xy 451.041572 -51.392947) (xy 451.058795 -51.386464) (xy 451.072645 -51.374348)
			(xy 451.07733 -51.36642) (xy 451.11924 -51.287172) (xy 451.123237 -51.278809) (xy 451.125538 -51.260433)
			(xy 451.121115 -51.242449) (xy 451.116192 -51.234594) (xy 451.116192 -51.23434) (xy 451.100557 -51.210451)
			(xy 451.075792 -51.15901) (xy 451.058966 -51.104455) (xy 451.050454 -51.048002) (xy 451.049898 -51.019456)
			(xy 451.049898 -51.012598) (xy 451.050914 -50.984383) (xy 451.060236 -50.928701) (xy 451.07766 -50.875)
			(xy 451.102807 -50.824452) (xy 451.135127 -50.778162) (xy 451.173916 -50.737139) (xy 451.218326 -50.70228)
			(xy 451.267387 -50.674345) (xy 451.320029 -50.653944) (xy 451.375103 -50.641522) (xy 451.431406 -50.637351)
			(xy 451.487709 -50.641522) (xy 451.542783 -50.653944) (xy 451.595425 -50.674345) (xy 451.644486 -50.70228)
			(xy 451.688896 -50.737139) (xy 451.727685 -50.778162) (xy 451.760005 -50.824452) (xy 451.785152 -50.875)
			(xy 451.802576 -50.928701) (xy 451.811898 -50.984383) (xy 451.812914 -51.012598) (xy 451.812914 -51.019456)
			(xy 451.81241 -51.048006) (xy 451.803902 -51.104467) (xy 451.787072 -51.15903) (xy 451.762293 -51.210472)
			(xy 451.74662 -51.23434) (xy 451.74662 -51.234594) (xy 451.741737 -51.242457) (xy 451.737382 -51.260433)
			(xy 451.739645 -51.278789) (xy 451.743572 -51.287172) (xy 451.785482 -51.36642) (xy 451.790139 -51.374379)
			(xy 451.803971 -51.386551) (xy 451.821226 -51.393015) (xy 451.83044 -51.393344) (xy 452.722234 -51.393344)
			(xy 452.7322 -51.392865) (xy 452.750636 -51.38529) (xy 452.758048 -51.378612) (xy 453.276208 -50.860452)
			(xy 453.280018 -50.852578) (xy 453.289924 -50.833528) (xy 453.293226 -50.827686) (xy 453.293988 -50.826416)
			(xy 453.29729 -50.820828) (xy 453.302624 -50.802032) (xy 453.304656 -50.788062) (xy 453.304656 -50.1904)
			(xy 453.304401 -50.182988) (xy 453.300142 -50.168788) (xy 453.296274 -50.16246) (xy 453.281442 -50.139007)
			(xy 453.257985 -50.088717) (xy 453.242066 -50.035559) (xy 453.23402 -49.980654) (xy 453.234019 -49.925163)
			(xy 453.242062 -49.870258) (xy 453.257979 -49.817099) (xy 453.281434 -49.766808) (xy 453.296274 -49.74336)
			(xy 453.300138 -49.73703) (xy 453.304395 -49.722831) (xy 453.304656 -49.71542) (xy 453.304656 -49.211484)
			(xy 453.304348 -49.202726) (xy 453.29851 -49.186216) (xy 453.293226 -49.179226) (xy 453.27688 -49.158659)
			(xy 453.249395 -49.113888) (xy 453.228313 -49.065769) (xy 453.214032 -49.015213) (xy 453.206822 -48.963175)
			(xy 453.206821 -48.91064) (xy 453.214028 -48.858602) (xy 453.228307 -48.808045) (xy 453.249388 -48.759926)
			(xy 453.276871 -48.715153) (xy 453.293226 -48.694594) (xy 453.298464 -48.687577) (xy 453.304317 -48.671085)
			(xy 453.304656 -48.662336) (xy 453.304656 -47.634398) (xy 453.303386 -47.622968) (xy 453.300846 -47.611538)
			(xy 453.29729 -47.601632) (xy 453.28518 -47.574074) (xy 453.268841 -47.516142) (xy 453.264778 -47.486316)
			(xy 453.263568 -47.47518) (xy 453.262294 -47.452813) (xy 453.262238 -47.441612) (xy 453.262722 -47.4138)
			(xy 453.27077 -47.358762) (xy 453.286741 -47.305481) (xy 453.298052 -47.280068) (xy 453.298306 -47.27956)
			(xy 453.299576 -47.276766) (xy 453.301608 -47.270924) (xy 453.303016 -47.266745) (xy 453.304545 -47.258061)
			(xy 453.304656 -47.253652) (xy 453.304656 -46.1264) (xy 453.304401 -46.118988) (xy 453.300142 -46.104788)
			(xy 453.296274 -46.09846) (xy 453.281442 -46.075007) (xy 453.257985 -46.024717) (xy 453.242066 -45.971559)
			(xy 453.23402 -45.916654) (xy 453.234019 -45.861163) (xy 453.242062 -45.806258) (xy 453.257979 -45.753099)
			(xy 453.281434 -45.702808) (xy 453.296274 -45.67936) (xy 453.300138 -45.67303) (xy 453.304395 -45.658831)
			(xy 453.304656 -45.65142) (xy 453.304656 -45.1104) (xy 453.304401 -45.102988) (xy 453.300142 -45.088788)
			(xy 453.296274 -45.08246) (xy 453.281442 -45.059007) (xy 453.257985 -45.008717) (xy 453.242066 -44.955559)
			(xy 453.23402 -44.900654) (xy 453.234019 -44.845163) (xy 453.242062 -44.790258) (xy 453.257979 -44.737099)
			(xy 453.281434 -44.686808) (xy 453.296274 -44.66336) (xy 453.300138 -44.65703) (xy 453.304395 -44.642831)
			(xy 453.304656 -44.63542) (xy 453.304656 -44.0944) (xy 453.304401 -44.086988) (xy 453.300142 -44.072788)
			(xy 453.296274 -44.06646) (xy 453.281442 -44.043007) (xy 453.257985 -43.992717) (xy 453.242066 -43.939559)
			(xy 453.23402 -43.884654) (xy 453.234019 -43.829163) (xy 453.242062 -43.774258) (xy 453.257979 -43.721099)
			(xy 453.281434 -43.670808) (xy 453.296274 -43.64736) (xy 453.300138 -43.64103) (xy 453.304395 -43.626831)
			(xy 453.304656 -43.61942) (xy 453.304656 -43.0784) (xy 453.304401 -43.070988) (xy 453.300142 -43.056788)
			(xy 453.296274 -43.05046) (xy 453.281442 -43.027007) (xy 453.257985 -42.976717) (xy 453.242066 -42.923559)
			(xy 453.23402 -42.868654) (xy 453.234019 -42.813163) (xy 453.242062 -42.758258) (xy 453.257979 -42.705099)
			(xy 453.281434 -42.654808) (xy 453.296274 -42.63136) (xy 453.300138 -42.62503) (xy 453.304395 -42.610831)
			(xy 453.304656 -42.60342) (xy 453.304656 -29.76753) (xy 453.304458 -29.760427) (xy 453.300586 -29.746762)
			(xy 453.297036 -29.740606) (xy 453.283828 -29.719778) (xy 453.280307 -29.713612) (xy 453.276454 -29.699951)
			(xy 453.276208 -29.692854) (xy 453.276208 -28.368752) (xy 453.276436 -28.361714) (xy 453.28031 -28.348183)
			(xy 453.283828 -28.342082) (xy 453.296782 -28.322016) (xy 453.300437 -28.315757) (xy 453.304424 -28.301829)
			(xy 453.304656 -28.294584) (xy 453.304656 -27.872436) (xy 453.30422 -27.862372) (xy 453.296484 -27.843789)
			(xy 453.28967 -27.836368) (xy 453.050148 -27.596846) (xy 453.043036 -27.58948) (xy 453.02424 -27.58186)
			(xy 443.699392 -27.58186) (xy 443.687002 -27.582411) (xy 443.665035 -27.593866) (xy 443.657482 -27.603704)
			(xy 443.639075 -27.629341) (xy 443.596345 -27.675789) (xy 443.547641 -27.715928) (xy 443.493887 -27.748999)
			(xy 443.436099 -27.774374) (xy 443.375375 -27.791572) (xy 443.312864 -27.800268) (xy 443.281308 -27.800808)
			(xy 443.249754 -27.80026) (xy 443.187247 -27.791555) (xy 443.126528 -27.774351) (xy 443.068746 -27.748974)
			(xy 443.014996 -27.715903) (xy 442.966295 -27.675766) (xy 442.923565 -27.629322) (xy 442.905134 -27.603704)
			(xy 442.89747 -27.593998) (xy 442.87557 -27.582597) (xy 442.863224 -27.58186) (xy 438.72785 -27.58186)
			(xy 438.717785 -27.582294) (xy 438.6992 -27.590028) (xy 438.691782 -27.596846) (xy 438.422796 -27.865832)
			(xy 438.416446 -27.877262) (xy 438.414668 -27.88412) (xy 438.406943 -27.912351) (xy 438.384032 -27.966208)
			(xy 438.353168 -28.015936) (xy 438.315073 -28.060369) (xy 438.27064 -28.098465) (xy 438.220913 -28.12933)
			(xy 438.167056 -28.152241) (xy 438.138824 -28.159964) (xy 438.131966 -28.161742) (xy 438.120536 -28.168092)
			(xy 438.104788 -28.18384) (xy 438.097422 -28.190952) (xy 438.089802 -28.209748) (xy 438.089802 -29.114242)
			(xy 445.147192 -29.114242) (xy 445.147192 -28.250642) (xy 445.147682 -28.220658) (xy 445.15551 -28.161202)
			(xy 445.171031 -28.103277) (xy 445.19398 -28.047873) (xy 445.223964 -27.995939) (xy 445.26047 -27.948363)
			(xy 445.302875 -27.905958) (xy 445.350451 -27.869452) (xy 445.402385 -27.839468) (xy 445.457789 -27.816519)
			(xy 445.515714 -27.800998) (xy 445.57517 -27.79317) (xy 445.635138 -27.79317) (xy 445.694594 -27.800998)
			(xy 445.752519 -27.816519) (xy 445.807923 -27.839468) (xy 445.859857 -27.869452) (xy 445.907433 -27.905958)
			(xy 445.949838 -27.948363) (xy 445.986344 -27.995939) (xy 446.016328 -28.047873) (xy 446.039277 -28.103277)
			(xy 446.054798 -28.161202) (xy 446.062626 -28.220658) (xy 446.063116 -28.250642) (xy 446.063116 -28.469082)
			(xy 450.052438 -28.469082) (xy 450.056509 -28.41346) (xy 450.068635 -28.359023) (xy 450.088558 -28.306932)
			(xy 450.115854 -28.258297) (xy 450.14994 -28.214154) (xy 450.190089 -28.175445) (xy 450.235447 -28.142994)
			(xy 450.285047 -28.117493) (xy 450.337831 -28.099486) (xy 450.392674 -28.089356) (xy 450.448408 -28.087319)
			(xy 450.503845 -28.093419) (xy 450.557802 -28.107525) (xy 450.609131 -28.129337) (xy 450.656737 -28.158391)
			(xy 450.699605 -28.194066) (xy 450.736822 -28.235603) (xy 450.767595 -28.282116) (xy 450.791267 -28.332613)
			(xy 450.807335 -28.38602) (xy 450.815455 -28.441196) (xy 450.815964 -28.469082) (xy 450.815455 -28.496968)
			(xy 450.807335 -28.552144) (xy 450.791267 -28.605551) (xy 450.767595 -28.656048) (xy 450.736822 -28.702561)
			(xy 450.699605 -28.744098) (xy 450.656737 -28.779773) (xy 450.609131 -28.808827) (xy 450.557802 -28.830639)
			(xy 450.503845 -28.844745) (xy 450.448408 -28.850845) (xy 450.392674 -28.848808) (xy 450.337831 -28.838678)
			(xy 450.285047 -28.820671) (xy 450.235447 -28.79517) (xy 450.190089 -28.762719) (xy 450.14994 -28.72401)
			(xy 450.115854 -28.679867) (xy 450.088558 -28.631232) (xy 450.068635 -28.579141) (xy 450.056509 -28.524704)
			(xy 450.052438 -28.469082) (xy 446.063116 -28.469082) (xy 446.063116 -29.114242) (xy 446.062626 -29.144226)
			(xy 446.054798 -29.203682) (xy 446.039277 -29.261607) (xy 446.016328 -29.317011) (xy 445.986344 -29.368945)
			(xy 445.949838 -29.416521) (xy 445.907433 -29.458926) (xy 445.859857 -29.495432) (xy 445.807923 -29.525416)
			(xy 445.752519 -29.548365) (xy 445.694594 -29.563886) (xy 445.635138 -29.571714) (xy 445.57517 -29.571714)
			(xy 445.515714 -29.563886) (xy 445.457789 -29.548365) (xy 445.402385 -29.525416) (xy 445.350451 -29.495432)
			(xy 445.302875 -29.458926) (xy 445.26047 -29.416521) (xy 445.223964 -29.368945) (xy 445.19398 -29.317011)
			(xy 445.171031 -29.261607) (xy 445.15551 -29.203682) (xy 445.147682 -29.144226) (xy 445.147192 -29.114242)
			(xy 438.089802 -29.114242) (xy 438.089802 -29.186378) (xy 438.1119 -29.214064) (xy 438.129426 -29.217874)
			(xy 438.155718 -29.224338) (xy 438.206285 -29.243685) (xy 438.25361 -29.269984) (xy 438.296743 -29.302708)
			(xy 438.334818 -29.3412) (xy 438.36707 -29.384687) (xy 438.392853 -29.432295) (xy 438.411648 -29.48307)
			(xy 438.423079 -29.535991) (xy 438.426915 -29.589996) (xy 438.42308 -29.644002) (xy 438.41165 -29.696924)
			(xy 438.392856 -29.747698) (xy 438.367074 -29.795307) (xy 438.334822 -29.838795) (xy 438.296748 -29.877287)
			(xy 438.253616 -29.910012) (xy 438.206291 -29.936312) (xy 438.155725 -29.95566) (xy 438.129426 -29.962094)
			(xy 438.1119 -29.965904) (xy 438.089802 -29.99359) (xy 438.089802 -30.92069) (xy 447.7893 -30.92069)
			(xy 447.7893 -30.05709) (xy 447.78979 -30.027106) (xy 447.797618 -29.96765) (xy 447.813139 -29.909725)
			(xy 447.836088 -29.854321) (xy 447.866072 -29.802387) (xy 447.902578 -29.754811) (xy 447.944983 -29.712406)
			(xy 447.992559 -29.6759) (xy 448.044493 -29.645916) (xy 448.099897 -29.622967) (xy 448.157822 -29.607446)
			(xy 448.217278 -29.599618) (xy 448.277246 -29.599618) (xy 448.336702 -29.607446) (xy 448.394627 -29.622967)
			(xy 448.450031 -29.645916) (xy 448.501965 -29.6759) (xy 448.549541 -29.712406) (xy 448.591946 -29.754811)
			(xy 448.628452 -29.802387) (xy 448.658436 -29.854321) (xy 448.681385 -29.909725) (xy 448.696906 -29.96765)
			(xy 448.704734 -30.027106) (xy 448.705224 -30.05709) (xy 448.705224 -30.92069) (xy 448.704734 -30.950674)
			(xy 448.696906 -31.01013) (xy 448.681385 -31.068055) (xy 448.658436 -31.123459) (xy 448.628452 -31.175393)
			(xy 448.591946 -31.222969) (xy 448.549541 -31.265374) (xy 448.501965 -31.30188) (xy 448.450031 -31.331864)
			(xy 448.394627 -31.354813) (xy 448.336702 -31.370334) (xy 448.277246 -31.378162) (xy 448.217278 -31.378162)
			(xy 448.157822 -31.370334) (xy 448.099897 -31.354813) (xy 448.044493 -31.331864) (xy 447.992559 -31.30188)
			(xy 447.944983 -31.265374) (xy 447.902578 -31.222969) (xy 447.866072 -31.175393) (xy 447.836088 -31.123459)
			(xy 447.813139 -31.068055) (xy 447.797618 -31.01013) (xy 447.78979 -30.950674) (xy 447.7893 -30.92069)
			(xy 438.089802 -30.92069) (xy 438.089802 -31.232602) (xy 438.115202 -31.261304) (xy 438.134506 -31.26359)
			(xy 438.161914 -31.267417) (xy 438.215308 -31.281957) (xy 438.266041 -31.30406) (xy 438.313048 -31.333261)
			(xy 438.355343 -31.368947) (xy 438.392038 -31.41037) (xy 438.422363 -31.456659) (xy 438.445682 -31.506845)
			(xy 438.461505 -31.559873) (xy 438.469501 -31.614631) (xy 438.469501 -31.66997) (xy 438.461505 -31.724728)
			(xy 438.445682 -31.777756) (xy 438.422363 -31.827941) (xy 438.392038 -31.874231) (xy 438.355342 -31.915654)
			(xy 438.313047 -31.95134) (xy 438.26604 -31.980541) (xy 438.215307 -32.002643) (xy 438.161913 -32.017184)
			(xy 438.134506 -32.021018) (xy 438.115202 -32.023304) (xy 438.089802 -32.052006) (xy 438.089802 -32.714184)
			(xy 445.147192 -32.714184) (xy 445.147192 -31.850584) (xy 445.147682 -31.8206) (xy 445.15551 -31.761144)
			(xy 445.171031 -31.703219) (xy 445.19398 -31.647815) (xy 445.223964 -31.595881) (xy 445.26047 -31.548305)
			(xy 445.302875 -31.5059) (xy 445.350451 -31.469394) (xy 445.402385 -31.43941) (xy 445.457789 -31.416461)
			(xy 445.515714 -31.40094) (xy 445.57517 -31.393112) (xy 445.635138 -31.393112) (xy 445.694594 -31.40094)
			(xy 445.752519 -31.416461) (xy 445.807923 -31.43941) (xy 445.859857 -31.469394) (xy 445.907433 -31.5059)
			(xy 445.949838 -31.548305) (xy 445.986344 -31.595881) (xy 446.016328 -31.647815) (xy 446.039277 -31.703219)
			(xy 446.054798 -31.761144) (xy 446.062626 -31.8206) (xy 446.063116 -31.850584) (xy 446.063116 -32.714184)
			(xy 446.062626 -32.744168) (xy 446.054798 -32.803624) (xy 446.039277 -32.861549) (xy 446.016328 -32.916953)
			(xy 445.986344 -32.968887) (xy 445.949838 -33.016463) (xy 445.907433 -33.058868) (xy 445.859857 -33.095374)
			(xy 445.807923 -33.125358) (xy 445.752519 -33.148307) (xy 445.694594 -33.163828) (xy 445.635138 -33.171656)
			(xy 445.57517 -33.171656) (xy 445.515714 -33.163828) (xy 445.457789 -33.148307) (xy 445.402385 -33.125358)
			(xy 445.350451 -33.095374) (xy 445.302875 -33.058868) (xy 445.26047 -33.016463) (xy 445.223964 -32.968887)
			(xy 445.19398 -32.916953) (xy 445.171031 -32.861549) (xy 445.15551 -32.803624) (xy 445.147682 -32.744168)
			(xy 445.147192 -32.714184) (xy 438.089802 -32.714184) (xy 438.089802 -34.520886) (xy 447.7893 -34.520886)
			(xy 447.7893 -33.657286) (xy 447.78979 -33.627302) (xy 447.797618 -33.567846) (xy 447.813139 -33.509921)
			(xy 447.836088 -33.454517) (xy 447.866072 -33.402583) (xy 447.902578 -33.355007) (xy 447.944983 -33.312602)
			(xy 447.992559 -33.276096) (xy 448.044493 -33.246112) (xy 448.099897 -33.223163) (xy 448.157822 -33.207642)
			(xy 448.217278 -33.199814) (xy 448.277246 -33.199814) (xy 448.336702 -33.207642) (xy 448.394627 -33.223163)
			(xy 448.450031 -33.246112) (xy 448.501965 -33.276096) (xy 448.549541 -33.312602) (xy 448.591946 -33.355007)
			(xy 448.628452 -33.402583) (xy 448.658436 -33.454517) (xy 448.681385 -33.509921) (xy 448.696906 -33.567846)
			(xy 448.704734 -33.627302) (xy 448.705224 -33.657286) (xy 448.705224 -34.520886) (xy 448.704734 -34.55087)
			(xy 448.696906 -34.610326) (xy 448.681385 -34.668251) (xy 448.658436 -34.723655) (xy 448.628452 -34.775589)
			(xy 448.591946 -34.823165) (xy 448.549541 -34.86557) (xy 448.501965 -34.902076) (xy 448.450031 -34.93206)
			(xy 448.394627 -34.955009) (xy 448.336702 -34.97053) (xy 448.277246 -34.978358) (xy 448.217278 -34.978358)
			(xy 448.157822 -34.97053) (xy 448.099897 -34.955009) (xy 448.044493 -34.93206) (xy 447.992559 -34.902076)
			(xy 447.944983 -34.86557) (xy 447.902578 -34.823165) (xy 447.866072 -34.775589) (xy 447.836088 -34.723655)
			(xy 447.813139 -34.668251) (xy 447.797618 -34.610326) (xy 447.78979 -34.55087) (xy 447.7893 -34.520886)
			(xy 438.089802 -34.520886) (xy 438.089802 -36.60013) (xy 438.298597 -36.60013) (xy 438.302601 -36.512245)
			(xy 438.314581 -36.425088) (xy 438.334436 -36.339381) (xy 438.362003 -36.255836) (xy 438.397053 -36.175143)
			(xy 438.439295 -36.097971) (xy 438.48838 -36.024961) (xy 438.543901 -35.956717) (xy 438.605398 -35.893804)
			(xy 438.67236 -35.836744) (xy 438.744234 -35.78601) (xy 438.820424 -35.742022) (xy 438.900298 -35.705144)
			(xy 438.983195 -35.675683) (xy 439.068427 -35.653881) (xy 439.155289 -35.639921) (xy 439.24306 -35.633917)
			(xy 439.331014 -35.63592) (xy 439.418421 -35.645912) (xy 439.504557 -35.663812) (xy 439.588709 -35.68947)
			(xy 439.670179 -35.722674) (xy 439.748292 -35.763148) (xy 439.8224 -35.810559) (xy 439.891891 -35.864512)
			(xy 439.956187 -35.92456) (xy 440.014756 -35.990207) (xy 440.067113 -36.060907) (xy 440.112825 -36.136076)
			(xy 440.151511 -36.21509) (xy 440.182852 -36.297295) (xy 440.206587 -36.382009) (xy 440.222521 -36.46853)
			(xy 440.230521 -36.556142) (xy 440.231022 -36.60013) (xy 440.230521 -36.644118) (xy 440.222521 -36.73173)
			(xy 440.206587 -36.818251) (xy 440.182852 -36.902965) (xy 440.151511 -36.98517) (xy 440.112825 -37.064184)
			(xy 440.067113 -37.139353) (xy 440.014756 -37.210053) (xy 439.956187 -37.2757) (xy 439.891891 -37.335748)
			(xy 439.8224 -37.389701) (xy 439.748292 -37.437112) (xy 439.670179 -37.477586) (xy 439.588709 -37.51079)
			(xy 439.504557 -37.536448) (xy 439.418421 -37.554348) (xy 439.331014 -37.56434) (xy 439.24306 -37.566343)
			(xy 439.155289 -37.560339) (xy 439.068427 -37.546379) (xy 438.983195 -37.524577) (xy 438.900298 -37.495116)
			(xy 438.820424 -37.458238) (xy 438.744234 -37.41425) (xy 438.67236 -37.363516) (xy 438.605398 -37.306456)
			(xy 438.543901 -37.243543) (xy 438.48838 -37.175299) (xy 438.439295 -37.102289) (xy 438.397053 -37.025117)
			(xy 438.362003 -36.944424) (xy 438.334436 -36.860879) (xy 438.314581 -36.775172) (xy 438.302601 -36.688015)
			(xy 438.298597 -36.60013) (xy 438.089802 -36.60013) (xy 438.089802 -40.452802) (xy 438.090226 -40.462872)
			(xy 438.097941 -40.481476) (xy 438.104788 -40.48887) (xy 438.32399 -40.708072) (xy 438.331387 -40.714923)
			(xy 438.349985 -40.722665) (xy 438.360058 -40.723058) (xy 447.381376 -40.723058) (xy 447.391439 -40.723497)
			(xy 447.410018 -40.731237) (xy 447.417444 -40.738044) (xy 448.358514 -41.679114) (xy 448.365368 -41.686509)
			(xy 448.37311 -41.705108) (xy 448.3735 -41.715182) (xy 448.3735 -43.566842) (xy 449.633338 -43.566842)
			(xy 449.637409 -43.51122) (xy 449.649535 -43.456783) (xy 449.669458 -43.404692) (xy 449.696754 -43.356057)
			(xy 449.73084 -43.311914) (xy 449.770989 -43.273205) (xy 449.816347 -43.240754) (xy 449.865947 -43.215253)
			(xy 449.918731 -43.197246) (xy 449.973574 -43.187116) (xy 450.029308 -43.185079) (xy 450.084745 -43.191179)
			(xy 450.138702 -43.205285) (xy 450.190031 -43.227097) (xy 450.237637 -43.256151) (xy 450.280505 -43.291826)
			(xy 450.317722 -43.333363) (xy 450.348495 -43.379876) (xy 450.372167 -43.430373) (xy 450.388235 -43.48378)
			(xy 450.396355 -43.538956) (xy 450.396864 -43.566842) (xy 450.396355 -43.594728) (xy 450.388235 -43.649904)
			(xy 450.372167 -43.703311) (xy 450.348495 -43.753808) (xy 450.317722 -43.800321) (xy 450.280505 -43.841858)
			(xy 450.262418 -43.85691) (xy 451.01967 -43.85691) (xy 451.023741 -43.801288) (xy 451.035867 -43.746851)
			(xy 451.05579 -43.69476) (xy 451.083086 -43.646125) (xy 451.117172 -43.601982) (xy 451.157321 -43.563273)
			(xy 451.202679 -43.530822) (xy 451.252279 -43.505321) (xy 451.305063 -43.487314) (xy 451.359906 -43.477184)
			(xy 451.41564 -43.475147) (xy 451.471077 -43.481247) (xy 451.525034 -43.495353) (xy 451.576363 -43.517165)
			(xy 451.623969 -43.546219) (xy 451.666837 -43.581894) (xy 451.704054 -43.623431) (xy 451.734827 -43.669944)
			(xy 451.758499 -43.720441) (xy 451.774567 -43.773848) (xy 451.782687 -43.829024) (xy 451.783196 -43.85691)
			(xy 451.782687 -43.884796) (xy 451.774567 -43.939972) (xy 451.758499 -43.993379) (xy 451.734827 -44.043876)
			(xy 451.704054 -44.090389) (xy 451.666837 -44.131926) (xy 451.623969 -44.167601) (xy 451.576363 -44.196655)
			(xy 451.525034 -44.218467) (xy 451.471077 -44.232573) (xy 451.41564 -44.238673) (xy 451.359906 -44.236636)
			(xy 451.305063 -44.226506) (xy 451.252279 -44.208499) (xy 451.202679 -44.182998) (xy 451.157321 -44.150547)
			(xy 451.117172 -44.111838) (xy 451.083086 -44.067695) (xy 451.05579 -44.01906) (xy 451.035867 -43.966969)
			(xy 451.023741 -43.912532) (xy 451.01967 -43.85691) (xy 450.262418 -43.85691) (xy 450.237637 -43.877533)
			(xy 450.190031 -43.906587) (xy 450.138702 -43.928399) (xy 450.084745 -43.942505) (xy 450.029308 -43.948605)
			(xy 449.973574 -43.946568) (xy 449.918731 -43.936438) (xy 449.865947 -43.918431) (xy 449.816347 -43.89293)
			(xy 449.770989 -43.860479) (xy 449.73084 -43.82177) (xy 449.696754 -43.777627) (xy 449.669458 -43.728992)
			(xy 449.649535 -43.676901) (xy 449.637409 -43.622464) (xy 449.633338 -43.566842) (xy 448.3735 -43.566842)
			(xy 448.3735 -45.35424) (xy 451.003668 -45.35424) (xy 451.007739 -45.298618) (xy 451.019865 -45.244181)
			(xy 451.039788 -45.19209) (xy 451.067084 -45.143455) (xy 451.10117 -45.099312) (xy 451.141319 -45.060603)
			(xy 451.186677 -45.028152) (xy 451.236277 -45.002651) (xy 451.289061 -44.984644) (xy 451.343904 -44.974514)
			(xy 451.399638 -44.972477) (xy 451.455075 -44.978577) (xy 451.509032 -44.992683) (xy 451.560361 -45.014495)
			(xy 451.607967 -45.043549) (xy 451.650835 -45.079224) (xy 451.688052 -45.120761) (xy 451.718825 -45.167274)
			(xy 451.742497 -45.217771) (xy 451.758565 -45.271178) (xy 451.766685 -45.326354) (xy 451.767194 -45.35424)
			(xy 451.766685 -45.382126) (xy 451.758565 -45.437302) (xy 451.742497 -45.490709) (xy 451.718825 -45.541206)
			(xy 451.688052 -45.587719) (xy 451.650835 -45.629256) (xy 451.607967 -45.664931) (xy 451.560361 -45.693985)
			(xy 451.509032 -45.715797) (xy 451.455075 -45.729903) (xy 451.399638 -45.736003) (xy 451.343904 -45.733966)
			(xy 451.289061 -45.723836) (xy 451.236277 -45.705829) (xy 451.186677 -45.680328) (xy 451.141319 -45.647877)
			(xy 451.10117 -45.609168) (xy 451.067084 -45.565025) (xy 451.039788 -45.51639) (xy 451.019865 -45.464299)
			(xy 451.007739 -45.409862) (xy 451.003668 -45.35424) (xy 448.3735 -45.35424) (xy 448.3735 -46.693836)
			(xy 450.976238 -46.693836) (xy 450.976724 -46.666585) (xy 450.98448 -46.612637) (xy 450.999835 -46.560342)
			(xy 451.022477 -46.510765) (xy 451.051943 -46.464915) (xy 451.087634 -46.423724) (xy 451.128825 -46.388033)
			(xy 451.174675 -46.358567) (xy 451.224252 -46.335925) (xy 451.276547 -46.32057) (xy 451.330495 -46.312814)
			(xy 451.384997 -46.312814) (xy 451.438945 -46.32057) (xy 451.49124 -46.335925) (xy 451.540817 -46.358567)
			(xy 451.586667 -46.388033) (xy 451.627858 -46.423724) (xy 451.663549 -46.464915) (xy 451.693015 -46.510765)
			(xy 451.715657 -46.560342) (xy 451.731012 -46.612637) (xy 451.738768 -46.666585) (xy 451.739254 -46.693836)
			(xy 451.738788 -46.720264) (xy 451.731477 -46.772612) (xy 451.717002 -46.823447) (xy 451.69564 -46.871793)
			(xy 451.682104 -46.894496) (xy 451.676008 -46.904402) (xy 451.673468 -46.927262) (xy 451.707758 -47.023782)
			(xy 451.72376 -47.040038) (xy 451.734936 -47.043848) (xy 451.759443 -47.052923) (xy 451.805895 -47.076865)
			(xy 451.848648 -47.106919) (xy 451.8869 -47.142526) (xy 451.919937 -47.183018) (xy 451.947141 -47.227638)
			(xy 451.968003 -47.275553) (xy 451.982133 -47.325866) (xy 451.989267 -47.377636) (xy 451.989698 -47.403766)
			(xy 451.989212 -47.431017) (xy 451.981456 -47.484965) (xy 451.966101 -47.53726) (xy 451.943459 -47.586837)
			(xy 451.913993 -47.632687) (xy 451.878302 -47.673878) (xy 451.837111 -47.709569) (xy 451.791261 -47.739035)
			(xy 451.741684 -47.761677) (xy 451.689389 -47.777032) (xy 451.635441 -47.784788) (xy 451.580939 -47.784788)
			(xy 451.526991 -47.777032) (xy 451.474696 -47.761677) (xy 451.425119 -47.739035) (xy 451.379269 -47.709569)
			(xy 451.338078 -47.673878) (xy 451.302387 -47.632687) (xy 451.272921 -47.586837) (xy 451.250279 -47.53726)
			(xy 451.234924 -47.484965) (xy 451.227168 -47.431017) (xy 451.226682 -47.403766) (xy 451.227158 -47.377339)
			(xy 451.234467 -47.324991) (xy 451.248939 -47.274157) (xy 451.270298 -47.225809) (xy 451.283832 -47.203106)
			(xy 451.289928 -47.1932) (xy 451.292468 -47.17034) (xy 451.258178 -47.07382) (xy 451.242176 -47.057564)
			(xy 451.231 -47.053754) (xy 451.206502 -47.044657) (xy 451.160048 -47.02072) (xy 451.117295 -46.990669)
			(xy 451.079041 -46.955066) (xy 451.046003 -46.914576) (xy 451.018798 -46.869958) (xy 450.997935 -46.822045)
			(xy 450.983804 -46.771734) (xy 450.976669 -46.719965) (xy 450.976238 -46.693836) (xy 448.3735 -46.693836)
			(xy 448.3735 -48.30699) (xy 450.853808 -48.30699) (xy 450.857879 -48.251368) (xy 450.870005 -48.196931)
			(xy 450.889928 -48.14484) (xy 450.917224 -48.096205) (xy 450.95131 -48.052062) (xy 450.991459 -48.013353)
			(xy 451.036817 -47.980902) (xy 451.086417 -47.955401) (xy 451.139201 -47.937394) (xy 451.194044 -47.927264)
			(xy 451.249778 -47.925227) (xy 451.305215 -47.931327) (xy 451.359172 -47.945433) (xy 451.410501 -47.967245)
			(xy 451.458107 -47.996299) (xy 451.500975 -48.031974) (xy 451.538192 -48.073511) (xy 451.568965 -48.120024)
			(xy 451.592637 -48.170521) (xy 451.608705 -48.223928) (xy 451.616825 -48.279104) (xy 451.617334 -48.30699)
			(xy 451.616825 -48.334876) (xy 451.608705 -48.390052) (xy 451.592637 -48.443459) (xy 451.568965 -48.493956)
			(xy 451.538192 -48.540469) (xy 451.500975 -48.582006) (xy 451.458107 -48.617681) (xy 451.410501 -48.646735)
			(xy 451.359172 -48.668547) (xy 451.305215 -48.682653) (xy 451.249778 -48.688753) (xy 451.194044 -48.686716)
			(xy 451.139201 -48.676586) (xy 451.086417 -48.658579) (xy 451.036817 -48.633078) (xy 450.991459 -48.600627)
			(xy 450.95131 -48.561918) (xy 450.917224 -48.517775) (xy 450.889928 -48.46914) (xy 450.870005 -48.417049)
			(xy 450.857879 -48.362612) (xy 450.853808 -48.30699) (xy 448.3735 -48.30699) (xy 448.3735 -48.8442)
			(xy 448.48729 -48.8442) (xy 448.491361 -48.788578) (xy 448.503487 -48.734141) (xy 448.52341 -48.68205)
			(xy 448.550706 -48.633415) (xy 448.584792 -48.589272) (xy 448.624941 -48.550563) (xy 448.670299 -48.518112)
			(xy 448.719899 -48.492611) (xy 448.772683 -48.474604) (xy 448.827526 -48.464474) (xy 448.88326 -48.462437)
			(xy 448.938697 -48.468537) (xy 448.992654 -48.482643) (xy 449.043983 -48.504455) (xy 449.091589 -48.533509)
			(xy 449.134457 -48.569184) (xy 449.171674 -48.610721) (xy 449.202447 -48.657234) (xy 449.226119 -48.707731)
			(xy 449.242187 -48.761138) (xy 449.250307 -48.816314) (xy 449.250816 -48.8442) (xy 449.250307 -48.872086)
			(xy 449.247309 -48.89246) (xy 449.513958 -48.89246) (xy 449.518029 -48.836838) (xy 449.530155 -48.782401)
			(xy 449.550078 -48.73031) (xy 449.577374 -48.681675) (xy 449.61146 -48.637532) (xy 449.651609 -48.598823)
			(xy 449.696967 -48.566372) (xy 449.746567 -48.540871) (xy 449.799351 -48.522864) (xy 449.854194 -48.512734)
			(xy 449.909928 -48.510697) (xy 449.965365 -48.516797) (xy 450.019322 -48.530903) (xy 450.070651 -48.552715)
			(xy 450.118257 -48.581769) (xy 450.161125 -48.617444) (xy 450.198342 -48.658981) (xy 450.229115 -48.705494)
			(xy 450.252787 -48.755991) (xy 450.268855 -48.809398) (xy 450.276975 -48.864574) (xy 450.277484 -48.89246)
			(xy 450.276975 -48.920346) (xy 450.268855 -48.975522) (xy 450.252787 -49.028929) (xy 450.229115 -49.079426)
			(xy 450.198342 -49.125939) (xy 450.161125 -49.167476) (xy 450.118257 -49.203151) (xy 450.070651 -49.232205)
			(xy 450.019322 -49.254017) (xy 449.965365 -49.268123) (xy 449.909928 -49.274223) (xy 449.854194 -49.272186)
			(xy 449.799351 -49.262056) (xy 449.746567 -49.244049) (xy 449.696967 -49.218548) (xy 449.651609 -49.186097)
			(xy 449.61146 -49.147388) (xy 449.577374 -49.103245) (xy 449.550078 -49.05461) (xy 449.530155 -49.002519)
			(xy 449.518029 -48.948082) (xy 449.513958 -48.89246) (xy 449.247309 -48.89246) (xy 449.242187 -48.927262)
			(xy 449.226119 -48.980669) (xy 449.202447 -49.031166) (xy 449.171674 -49.077679) (xy 449.134457 -49.119216)
			(xy 449.091589 -49.154891) (xy 449.043983 -49.183945) (xy 448.992654 -49.205757) (xy 448.938697 -49.219863)
			(xy 448.88326 -49.225963) (xy 448.827526 -49.223926) (xy 448.772683 -49.213796) (xy 448.719899 -49.195789)
			(xy 448.670299 -49.170288) (xy 448.624941 -49.137837) (xy 448.584792 -49.099128) (xy 448.550706 -49.054985)
			(xy 448.52341 -49.00635) (xy 448.503487 -48.954259) (xy 448.491361 -48.899822) (xy 448.48729 -48.8442)
			(xy 448.3735 -48.8442) (xy 448.3735 -51.198018) (xy 448.37396 -51.207895) (xy 448.381403 -51.226194)
			(xy 448.387978 -51.233578) (xy 448.388232 -51.233832) (xy 448.532758 -51.378358) (xy 448.540158 -51.3852)
			(xy 448.558756 -51.39292) (xy 448.568826 -51.393344)
		)
		(stroke
			(width 0)
			(type solid)
		)
		(fill yes)
		(layer "In9.Cu")
		(net "GND")
	)
	(gr_poly
		(pts
			(xy 36.111942 -300.93539) (xy 36.122541 -300.934839) (xy 36.141946 -300.926302) (xy 36.149534 -300.91888)
			(xy 36.167383 -300.900161) (xy 36.208214 -300.868417) (xy 36.253813 -300.844014) (xy 36.302874 -300.827649)
			(xy 36.353992 -300.819791) (xy 36.405704 -300.820665) (xy 36.43122 -300.8249) (xy 36.443666 -300.827186)
			(xy 36.467288 -300.81982) (xy 36.544758 -300.74235) (xy 36.552124 -300.718728) (xy 36.549838 -300.706282)
			(xy 36.547353 -300.692317) (xy 36.544681 -300.664077) (xy 36.544504 -300.649894) (xy 36.545026 -300.624639)
			(xy 36.553339 -300.574817) (xy 36.56974 -300.527043) (xy 36.593781 -300.48262) (xy 36.624805 -300.44276)
			(xy 36.661967 -300.40855) (xy 36.704253 -300.380924) (xy 36.750509 -300.360634) (xy 36.799474 -300.348234)
			(xy 36.849812 -300.344063) (xy 36.90015 -300.348234) (xy 36.949115 -300.360634) (xy 36.995371 -300.380924)
			(xy 37.037657 -300.40855) (xy 37.074819 -300.44276) (xy 37.105843 -300.48262) (xy 37.129884 -300.527043)
			(xy 37.146285 -300.574817) (xy 37.154598 -300.624639) (xy 37.15512 -300.649894) (xy 37.154934 -300.664076)
			(xy 37.152261 -300.692316) (xy 37.149786 -300.706282) (xy 37.1475 -300.718728) (xy 37.154866 -300.74235)
			(xy 37.232336 -300.81982) (xy 37.255958 -300.827186) (xy 37.268404 -300.8249) (xy 37.296411 -300.820271)
			(xy 37.353173 -300.820271) (xy 37.38118 -300.8249) (xy 37.393626 -300.827186) (xy 37.417248 -300.81982)
			(xy 37.494718 -300.74235) (xy 37.502084 -300.718728) (xy 37.499798 -300.706282) (xy 37.497313 -300.692317)
			(xy 37.494642 -300.664077) (xy 37.494464 -300.649894) (xy 37.494986 -300.624639) (xy 37.503299 -300.574817)
			(xy 37.5197 -300.527043) (xy 37.543741 -300.48262) (xy 37.574765 -300.44276) (xy 37.611927 -300.40855)
			(xy 37.654213 -300.380924) (xy 37.700469 -300.360634) (xy 37.749434 -300.348234) (xy 37.799772 -300.344063)
			(xy 37.85011 -300.348234) (xy 37.899075 -300.360634) (xy 37.945331 -300.380924) (xy 37.987617 -300.40855)
			(xy 38.024779 -300.44276) (xy 38.055803 -300.48262) (xy 38.079844 -300.527043) (xy 38.096245 -300.574817)
			(xy 38.104558 -300.624639) (xy 38.10508 -300.649894) (xy 38.104988 -300.659062) (xy 38.103844 -300.677362)
			(xy 38.102794 -300.68647) (xy 38.101524 -300.698662) (xy 38.109398 -300.721014) (xy 38.185852 -300.793912)
			(xy 38.208458 -300.801024) (xy 38.220396 -300.798992) (xy 38.233947 -300.796855) (xy 38.261288 -300.794569)
			(xy 38.275006 -300.79442) (xy 38.345364 -300.79442) (xy 38.356053 -300.79385) (xy 38.375598 -300.785183)
			(xy 38.38321 -300.777656) (xy 38.440868 -300.713394) (xy 38.447472 -300.693074) (xy 38.446456 -300.682152)
			(xy 38.444678 -300.649894) (xy 38.4452 -300.624639) (xy 38.453513 -300.574817) (xy 38.469914 -300.527043)
			(xy 38.493955 -300.48262) (xy 38.524979 -300.44276) (xy 38.562141 -300.40855) (xy 38.604427 -300.380924)
			(xy 38.650683 -300.360634) (xy 38.699648 -300.348234) (xy 38.749986 -300.344063) (xy 38.800324 -300.348234)
			(xy 38.849289 -300.360634) (xy 38.895545 -300.380924) (xy 38.937831 -300.40855) (xy 38.974993 -300.44276)
			(xy 39.006017 -300.48262) (xy 39.030058 -300.527043) (xy 39.046459 -300.574817) (xy 39.054772 -300.624639)
			(xy 39.055294 -300.649894) (xy 39.053516 -300.682152) (xy 39.0525 -300.693074) (xy 39.059104 -300.713394)
			(xy 39.116762 -300.777656) (xy 39.124277 -300.785323) (xy 39.143881 -300.794022) (xy 39.154608 -300.79442)
			(xy 39.224966 -300.79442) (xy 39.23862 -300.794582) (xy 39.265833 -300.796871) (xy 39.279322 -300.798992)
			(xy 39.29126 -300.801024) (xy 39.313866 -300.793912) (xy 39.39032 -300.72076) (xy 39.398194 -300.698662)
			(xy 39.396924 -300.68647) (xy 39.395871 -300.677362) (xy 39.394729 -300.659062) (xy 39.394638 -300.649894)
			(xy 39.39516 -300.624639) (xy 39.403473 -300.574817) (xy 39.419874 -300.527043) (xy 39.443915 -300.48262)
			(xy 39.474939 -300.44276) (xy 39.512101 -300.40855) (xy 39.554387 -300.380924) (xy 39.600643 -300.360634)
			(xy 39.649608 -300.348234) (xy 39.699946 -300.344063) (xy 39.750284 -300.348234) (xy 39.799249 -300.360634)
			(xy 39.845505 -300.380924) (xy 39.887791 -300.40855) (xy 39.924953 -300.44276) (xy 39.955977 -300.48262)
			(xy 39.980018 -300.527043) (xy 39.996419 -300.574817) (xy 40.004732 -300.624639) (xy 40.005254 -300.649894)
			(xy 40.005068 -300.664076) (xy 40.002395 -300.692316) (xy 39.99992 -300.706282) (xy 39.997634 -300.718728)
			(xy 40.005 -300.74235) (xy 40.08247 -300.81982) (xy 40.106092 -300.827186) (xy 40.118538 -300.8249)
			(xy 40.146545 -300.820271) (xy 40.203307 -300.820271) (xy 40.231314 -300.8249) (xy 40.24376 -300.827186)
			(xy 40.267382 -300.81982) (xy 40.344852 -300.74235) (xy 40.352218 -300.718728) (xy 40.349932 -300.706282)
			(xy 40.347447 -300.692317) (xy 40.344775 -300.664077) (xy 40.344598 -300.649894) (xy 40.345069 -300.625903)
			(xy 40.352576 -300.578513) (xy 40.367404 -300.53288) (xy 40.389188 -300.490128) (xy 40.417392 -300.451311)
			(xy 40.45132 -300.417384) (xy 40.490139 -300.389182) (xy 40.532891 -300.367399) (xy 40.578524 -300.352573)
			(xy 40.625915 -300.345068) (xy 40.649906 -300.344586) (xy 40.664088 -300.344773) (xy 40.692328 -300.347447)
			(xy 40.706294 -300.34992) (xy 40.71874 -300.352206) (xy 40.742362 -300.34484) (xy 40.819832 -300.26737)
			(xy 40.827198 -300.243748) (xy 40.824912 -300.231302) (xy 40.822426 -300.217337) (xy 40.819753 -300.189097)
			(xy 40.819578 -300.174914) (xy 40.8201 -300.149659) (xy 40.828413 -300.099837) (xy 40.844814 -300.052063)
			(xy 40.868855 -300.00764) (xy 40.899879 -299.96778) (xy 40.937041 -299.93357) (xy 40.979327 -299.905944)
			(xy 41.025583 -299.885654) (xy 41.074548 -299.873254) (xy 41.124886 -299.869083) (xy 41.175224 -299.873254)
			(xy 41.224189 -299.885654) (xy 41.270445 -299.905944) (xy 41.312731 -299.93357) (xy 41.349893 -299.96778)
			(xy 41.380917 -300.00764) (xy 41.404958 -300.052063) (xy 41.421359 -300.099837) (xy 41.429672 -300.149659)
			(xy 41.430194 -300.174914) (xy 41.430007 -300.189096) (xy 41.427332 -300.217335) (xy 41.42486 -300.231302)
			(xy 41.422574 -300.243748) (xy 41.42994 -300.26737) (xy 41.50741 -300.34484) (xy 41.531032 -300.352206)
			(xy 41.543478 -300.34992) (xy 41.557443 -300.347433) (xy 41.585683 -300.344758) (xy 41.599866 -300.344586)
			(xy 41.614049 -300.344771) (xy 41.642288 -300.347441) (xy 41.656254 -300.34992) (xy 41.6687 -300.352206)
			(xy 41.692322 -300.34484) (xy 41.769792 -300.26737) (xy 41.777158 -300.243748) (xy 41.774872 -300.231302)
			(xy 41.772386 -300.217337) (xy 41.769712 -300.189097) (xy 41.769538 -300.174914) (xy 41.77006 -300.149659)
			(xy 41.778373 -300.099837) (xy 41.794774 -300.052063) (xy 41.818815 -300.00764) (xy 41.849839 -299.96778)
			(xy 41.887001 -299.93357) (xy 41.929287 -299.905944) (xy 41.975543 -299.885654) (xy 42.024508 -299.873254)
			(xy 42.074846 -299.869083) (xy 42.125184 -299.873254) (xy 42.174149 -299.885654) (xy 42.220405 -299.905944)
			(xy 42.262691 -299.93357) (xy 42.299853 -299.96778) (xy 42.330877 -300.00764) (xy 42.354918 -300.052063)
			(xy 42.371319 -300.099837) (xy 42.379632 -300.149659) (xy 42.380154 -300.174914) (xy 43.668962 -300.174914)
			(xy 43.672922 -300.12586) (xy 43.684699 -300.078076) (xy 43.70399 -300.0328) (xy 43.730293 -299.991204)
			(xy 43.762928 -299.954367) (xy 43.801049 -299.923242) (xy 43.84367 -299.898635) (xy 43.889686 -299.881183)
			(xy 43.937905 -299.871339) (xy 43.98708 -299.869358) (xy 44.035935 -299.87529) (xy 44.083206 -299.888982)
			(xy 44.127668 -299.91008) (xy 44.168171 -299.938036) (xy 44.203664 -299.972128) (xy 44.233229 -300.011472)
			(xy 44.2561 -300.055049) (xy 44.271684 -300.10173) (xy 44.279579 -300.150307) (xy 44.280074 -300.174914)
			(xy 44.619176 -300.174914) (xy 44.623136 -300.12586) (xy 44.634913 -300.078076) (xy 44.654204 -300.0328)
			(xy 44.680507 -299.991204) (xy 44.713142 -299.954367) (xy 44.751263 -299.923242) (xy 44.793884 -299.898635)
			(xy 44.8399 -299.881183) (xy 44.888119 -299.871339) (xy 44.937294 -299.869358) (xy 44.986149 -299.87529)
			(xy 45.03342 -299.888982) (xy 45.077882 -299.91008) (xy 45.118385 -299.938036) (xy 45.153878 -299.972128)
			(xy 45.183443 -300.011472) (xy 45.206314 -300.055049) (xy 45.221898 -300.10173) (xy 45.229793 -300.150307)
			(xy 45.230288 -300.174914) (xy 45.569136 -300.174914) (xy 45.573096 -300.12586) (xy 45.584873 -300.078076)
			(xy 45.604164 -300.0328) (xy 45.630467 -299.991204) (xy 45.663102 -299.954367) (xy 45.701223 -299.923242)
			(xy 45.743844 -299.898635) (xy 45.78986 -299.881183) (xy 45.838079 -299.871339) (xy 45.887254 -299.869358)
			(xy 45.936109 -299.87529) (xy 45.98338 -299.888982) (xy 46.027842 -299.91008) (xy 46.068345 -299.938036)
			(xy 46.103838 -299.972128) (xy 46.133403 -300.011472) (xy 46.156274 -300.055049) (xy 46.171858 -300.10173)
			(xy 46.179753 -300.150307) (xy 46.180248 -300.174914) (xy 46.179753 -300.199521) (xy 46.171858 -300.248098)
			(xy 46.156274 -300.294779) (xy 46.133403 -300.338356) (xy 46.103838 -300.3777) (xy 46.068345 -300.411792)
			(xy 46.027842 -300.439748) (xy 45.98338 -300.460846) (xy 45.936109 -300.474538) (xy 45.887254 -300.48047)
			(xy 45.838079 -300.478489) (xy 45.78986 -300.468645) (xy 45.743844 -300.451193) (xy 45.701223 -300.426586)
			(xy 45.663102 -300.395461) (xy 45.630467 -300.358624) (xy 45.604164 -300.317028) (xy 45.584873 -300.271752)
			(xy 45.573096 -300.223968) (xy 45.569136 -300.174914) (xy 45.230288 -300.174914) (xy 45.229793 -300.199521)
			(xy 45.221898 -300.248098) (xy 45.206314 -300.294779) (xy 45.183443 -300.338356) (xy 45.153878 -300.3777)
			(xy 45.118385 -300.411792) (xy 45.077882 -300.439748) (xy 45.03342 -300.460846) (xy 44.986149 -300.474538)
			(xy 44.937294 -300.48047) (xy 44.888119 -300.478489) (xy 44.8399 -300.468645) (xy 44.793884 -300.451193)
			(xy 44.751263 -300.426586) (xy 44.713142 -300.395461) (xy 44.680507 -300.358624) (xy 44.654204 -300.317028)
			(xy 44.634913 -300.271752) (xy 44.623136 -300.223968) (xy 44.619176 -300.174914) (xy 44.280074 -300.174914)
			(xy 44.279579 -300.199521) (xy 44.271684 -300.248098) (xy 44.2561 -300.294779) (xy 44.233229 -300.338356)
			(xy 44.203664 -300.3777) (xy 44.168171 -300.411792) (xy 44.127668 -300.439748) (xy 44.083206 -300.460846)
			(xy 44.035935 -300.474538) (xy 43.98708 -300.48047) (xy 43.937905 -300.478489) (xy 43.889686 -300.468645)
			(xy 43.84367 -300.451193) (xy 43.801049 -300.426586) (xy 43.762928 -300.395461) (xy 43.730293 -300.358624)
			(xy 43.70399 -300.317028) (xy 43.684699 -300.271752) (xy 43.672922 -300.223968) (xy 43.668962 -300.174914)
			(xy 42.380154 -300.174914) (xy 42.379967 -300.189096) (xy 42.377293 -300.217335) (xy 42.37482 -300.231302)
			(xy 42.372534 -300.243748) (xy 42.3799 -300.26737) (xy 42.45737 -300.34484) (xy 42.480992 -300.352206)
			(xy 42.493438 -300.34992) (xy 42.507403 -300.347436) (xy 42.535643 -300.344766) (xy 42.549826 -300.344586)
			(xy 42.573816 -300.345059) (xy 42.621205 -300.352568) (xy 42.666836 -300.367397) (xy 42.709585 -300.389182)
			(xy 42.748401 -300.417386) (xy 42.782327 -300.451314) (xy 42.810528 -300.490132) (xy 42.83231 -300.532883)
			(xy 42.847137 -300.578515) (xy 42.854643 -300.625904) (xy 42.855134 -300.649894) (xy 42.854948 -300.664076)
			(xy 42.852275 -300.692316) (xy 42.8498 -300.706282) (xy 42.847514 -300.718728) (xy 42.85488 -300.74235)
			(xy 42.93235 -300.81982) (xy 42.955972 -300.827186) (xy 42.968418 -300.8249) (xy 42.993932 -300.82066)
			(xy 43.045641 -300.81981) (xy 43.096754 -300.827679) (xy 43.145813 -300.844044) (xy 43.191415 -300.868437)
			(xy 43.232258 -300.90016) (xy 43.250104 -300.91888) (xy 43.2576 -300.926431) (xy 43.277064 -300.934977)
			(xy 43.287696 -300.93539) (xy 43.711876 -300.93539) (xy 43.722481 -300.934851) (xy 43.741905 -300.926331)
			(xy 43.749468 -300.91888) (xy 43.766949 -300.900503) (xy 43.806887 -300.869244) (xy 43.851442 -300.845014)
			(xy 43.899388 -300.828482) (xy 43.949408 -300.8201) (xy 44.000124 -300.8201) (xy 44.050144 -300.828482)
			(xy 44.09809 -300.845014) (xy 44.142645 -300.869244) (xy 44.182583 -300.900503) (xy 44.200064 -300.91888)
			(xy 44.207557 -300.926437) (xy 44.227022 -300.934999) (xy 44.237656 -300.93539) (xy 44.66209 -300.93539)
			(xy 44.672693 -300.934849) (xy 44.692113 -300.926325) (xy 44.699682 -300.91888) (xy 44.717163 -300.900503)
			(xy 44.757101 -300.869244) (xy 44.801656 -300.845014) (xy 44.849602 -300.828482) (xy 44.899622 -300.8201)
			(xy 44.950338 -300.8201) (xy 45.000358 -300.828482) (xy 45.048304 -300.845014) (xy 45.092859 -300.869244)
			(xy 45.132797 -300.900503) (xy 45.150278 -300.91888) (xy 45.157772 -300.926435) (xy 45.177237 -300.934991)
			(xy 45.18787 -300.93539) (xy 45.61205 -300.93539) (xy 45.622648 -300.934837) (xy 45.642051 -300.926298)
			(xy 45.649642 -300.91888) (xy 45.667123 -300.900503) (xy 45.707061 -300.869244) (xy 45.751616 -300.845014)
			(xy 45.799562 -300.828482) (xy 45.849582 -300.8201) (xy 45.900298 -300.8201) (xy 45.950318 -300.828482)
			(xy 45.998264 -300.845014) (xy 46.042819 -300.869244) (xy 46.082757 -300.900503) (xy 46.100238 -300.91888)
			(xy 46.107736 -300.926425) (xy 46.1272 -300.934959) (xy 46.13783 -300.93539) (xy 46.56201 -300.93539)
			(xy 46.572611 -300.934845) (xy 46.592026 -300.926316) (xy 46.599602 -300.91888) (xy 46.617085 -300.900504)
			(xy 46.657024 -300.869244) (xy 46.701578 -300.84501) (xy 46.749523 -300.828469) (xy 46.799541 -300.820075)
			(xy 46.8249 -300.819566) (xy 46.848464 -300.820023) (xy 46.895029 -300.827294) (xy 46.91761 -300.834044)
			(xy 46.918118 -300.834044) (xy 46.927049 -300.836442) (xy 46.945496 -300.835389) (xy 46.962371 -300.827861)
			(xy 46.969172 -300.821598) (xy 47.021242 -300.769528) (xy 47.02175 -300.76902) (xy 47.028329 -300.761638)
			(xy 47.03577 -300.743338) (xy 47.036228 -300.73346) (xy 47.036228 -300.566582) (xy 47.035637 -300.554824)
			(xy 47.025178 -300.533765) (xy 47.016162 -300.526196) (xy 46.951646 -300.477174) (xy 46.946856 -300.473744)
			(xy 46.936074 -300.469) (xy 46.93031 -300.467776) (xy 46.91888 -300.465744) (xy 46.907196 -300.468792)
			(xy 46.906688 -300.468792) (xy 46.886653 -300.47408) (xy 46.845617 -300.479818) (xy 46.8249 -300.480222)
			(xy 46.799644 -300.4797) (xy 46.749819 -300.471386) (xy 46.702043 -300.454985) (xy 46.657619 -300.430943)
			(xy 46.617757 -300.399917) (xy 46.583545 -300.362754) (xy 46.555917 -300.320466) (xy 46.535627 -300.274208)
			(xy 46.523226 -300.22524) (xy 46.519055 -300.1749) (xy 46.523226 -300.12456) (xy 46.535627 -300.075592)
			(xy 46.555917 -300.029334) (xy 46.583545 -299.987046) (xy 46.617757 -299.949883) (xy 46.657619 -299.918857)
			(xy 46.702043 -299.894815) (xy 46.749819 -299.878414) (xy 46.799644 -299.8701) (xy 46.8249 -299.869606)
			(xy 46.845616 -299.870025) (xy 46.88665 -299.875765) (xy 46.906688 -299.881036) (xy 46.907196 -299.881036)
			(xy 46.91888 -299.884084) (xy 46.93031 -299.882052) (xy 46.936064 -299.8808) (xy 46.946839 -299.876056)
			(xy 46.951646 -299.872654) (xy 47.016162 -299.823632) (xy 47.025181 -299.815985) (xy 47.035628 -299.794803)
			(xy 47.036228 -299.782992) (xy 47.036228 -299.146468) (xy 47.0358 -299.1364) (xy 47.02808 -299.117801)
			(xy 47.021242 -299.1104) (xy 46.729396 -298.818554) (xy 46.722284 -298.811188) (xy 46.703488 -298.803568)
			(xy 40.999664 -298.803568) (xy 40.97274 -298.823888) (xy 40.968168 -298.840398) (xy 40.957754 -298.871132)
			(xy 40.9546 -298.880322) (xy 40.954726 -298.899735) (xy 40.962076 -298.917703) (xy 40.97559 -298.93164)
			(xy 40.993323 -298.93954) (xy 41.012722 -298.940266) (xy 41.022016 -298.937426) (xy 41.046917 -298.929117)
			(xy 41.09864 -298.920173) (xy 41.124886 -298.919646) (xy 41.149712 -298.92013) (xy 41.198709 -298.928161)
			(xy 41.245762 -298.944013) (xy 41.28963 -298.967269) (xy 41.329158 -298.997316) (xy 41.363303 -299.033363)
			(xy 41.391167 -299.074458) (xy 41.412015 -299.119521) (xy 41.425298 -299.167362) (xy 41.430665 -299.216723)
			(xy 41.430232 -299.2247) (xy 41.769042 -299.2247) (xy 41.773002 -299.175646) (xy 41.784779 -299.127862)
			(xy 41.80407 -299.082586) (xy 41.830373 -299.04099) (xy 41.863008 -299.004153) (xy 41.901129 -298.973028)
			(xy 41.94375 -298.948421) (xy 41.989766 -298.930969) (xy 42.037985 -298.921125) (xy 42.08716 -298.919144)
			(xy 42.136015 -298.925076) (xy 42.183286 -298.938768) (xy 42.227748 -298.959866) (xy 42.268251 -298.987822)
			(xy 42.303744 -299.021914) (xy 42.333309 -299.061258) (xy 42.35618 -299.104835) (xy 42.371764 -299.151516)
			(xy 42.379659 -299.200093) (xy 42.380154 -299.2247) (xy 42.380149 -299.224954) (xy 43.668962 -299.224954)
			(xy 43.672922 -299.1759) (xy 43.684699 -299.128116) (xy 43.70399 -299.08284) (xy 43.730293 -299.041244)
			(xy 43.762928 -299.004407) (xy 43.801049 -298.973282) (xy 43.84367 -298.948675) (xy 43.889686 -298.931223)
			(xy 43.937905 -298.921379) (xy 43.98708 -298.919398) (xy 44.035935 -298.92533) (xy 44.083206 -298.939022)
			(xy 44.127668 -298.96012) (xy 44.168171 -298.988076) (xy 44.203664 -299.022168) (xy 44.233229 -299.061512)
			(xy 44.2561 -299.105089) (xy 44.271684 -299.15177) (xy 44.279579 -299.200347) (xy 44.280074 -299.224954)
			(xy 44.619176 -299.224954) (xy 44.623136 -299.1759) (xy 44.634913 -299.128116) (xy 44.654204 -299.08284)
			(xy 44.680507 -299.041244) (xy 44.713142 -299.004407) (xy 44.751263 -298.973282) (xy 44.793884 -298.948675)
			(xy 44.8399 -298.931223) (xy 44.888119 -298.921379) (xy 44.937294 -298.919398) (xy 44.986149 -298.92533)
			(xy 45.03342 -298.939022) (xy 45.077882 -298.96012) (xy 45.118385 -298.988076) (xy 45.153878 -299.022168)
			(xy 45.183443 -299.061512) (xy 45.206314 -299.105089) (xy 45.221898 -299.15177) (xy 45.229793 -299.200347)
			(xy 45.230288 -299.224954) (xy 45.569136 -299.224954) (xy 45.573096 -299.1759) (xy 45.584873 -299.128116)
			(xy 45.604164 -299.08284) (xy 45.630467 -299.041244) (xy 45.663102 -299.004407) (xy 45.701223 -298.973282)
			(xy 45.743844 -298.948675) (xy 45.78986 -298.931223) (xy 45.838079 -298.921379) (xy 45.887254 -298.919398)
			(xy 45.936109 -298.92533) (xy 45.98338 -298.939022) (xy 46.027842 -298.96012) (xy 46.068345 -298.988076)
			(xy 46.103838 -299.022168) (xy 46.133403 -299.061512) (xy 46.156274 -299.105089) (xy 46.171858 -299.15177)
			(xy 46.179753 -299.200347) (xy 46.180248 -299.224954) (xy 46.179753 -299.249561) (xy 46.171858 -299.298138)
			(xy 46.156274 -299.344819) (xy 46.133403 -299.388396) (xy 46.103838 -299.42774) (xy 46.068345 -299.461832)
			(xy 46.027842 -299.489788) (xy 45.98338 -299.510886) (xy 45.936109 -299.524578) (xy 45.887254 -299.53051)
			(xy 45.838079 -299.528529) (xy 45.78986 -299.518685) (xy 45.743844 -299.501233) (xy 45.701223 -299.476626)
			(xy 45.663102 -299.445501) (xy 45.630467 -299.408664) (xy 45.604164 -299.367068) (xy 45.584873 -299.321792)
			(xy 45.573096 -299.274008) (xy 45.569136 -299.224954) (xy 45.230288 -299.224954) (xy 45.229793 -299.249561)
			(xy 45.221898 -299.298138) (xy 45.206314 -299.344819) (xy 45.183443 -299.388396) (xy 45.153878 -299.42774)
			(xy 45.118385 -299.461832) (xy 45.077882 -299.489788) (xy 45.03342 -299.510886) (xy 44.986149 -299.524578)
			(xy 44.937294 -299.53051) (xy 44.888119 -299.528529) (xy 44.8399 -299.518685) (xy 44.793884 -299.501233)
			(xy 44.751263 -299.476626) (xy 44.713142 -299.445501) (xy 44.680507 -299.408664) (xy 44.654204 -299.367068)
			(xy 44.634913 -299.321792) (xy 44.623136 -299.274008) (xy 44.619176 -299.224954) (xy 44.280074 -299.224954)
			(xy 44.279579 -299.249561) (xy 44.271684 -299.298138) (xy 44.2561 -299.344819) (xy 44.233229 -299.388396)
			(xy 44.203664 -299.42774) (xy 44.168171 -299.461832) (xy 44.127668 -299.489788) (xy 44.083206 -299.510886)
			(xy 44.035935 -299.524578) (xy 43.98708 -299.53051) (xy 43.937905 -299.528529) (xy 43.889686 -299.518685)
			(xy 43.84367 -299.501233) (xy 43.801049 -299.476626) (xy 43.762928 -299.445501) (xy 43.730293 -299.408664)
			(xy 43.70399 -299.367068) (xy 43.684699 -299.321792) (xy 43.672922 -299.274008) (xy 43.668962 -299.224954)
			(xy 42.380149 -299.224954) (xy 42.379659 -299.249307) (xy 42.371764 -299.297884) (xy 42.35618 -299.344565)
			(xy 42.333309 -299.388142) (xy 42.303744 -299.427486) (xy 42.268251 -299.461578) (xy 42.227748 -299.489534)
			(xy 42.183286 -299.510632) (xy 42.136015 -299.524324) (xy 42.08716 -299.530256) (xy 42.037985 -299.528275)
			(xy 41.989766 -299.518431) (xy 41.94375 -299.500979) (xy 41.901129 -299.476372) (xy 41.863008 -299.445247)
			(xy 41.830373 -299.40841) (xy 41.80407 -299.366814) (xy 41.784779 -299.321538) (xy 41.773002 -299.273754)
			(xy 41.769042 -299.2247) (xy 41.430232 -299.2247) (xy 41.427976 -299.266301) (xy 41.417301 -299.314791)
			(xy 41.398922 -299.360916) (xy 41.373322 -299.403459) (xy 41.341177 -299.441299) (xy 41.303333 -299.473441)
			(xy 41.260787 -299.499036) (xy 41.214661 -299.517411) (xy 41.166169 -299.528081) (xy 41.116591 -299.530765)
			(xy 41.067231 -299.525392) (xy 41.019391 -299.512104) (xy 40.97433 -299.491251) (xy 40.933238 -299.463383)
			(xy 40.897195 -299.429234) (xy 40.867152 -299.389703) (xy 40.843901 -299.345833) (xy 40.828054 -299.298778)
			(xy 40.820028 -299.24978) (xy 40.819578 -299.224954) (xy 40.819672 -299.215786) (xy 40.820818 -299.197486)
			(xy 40.821864 -299.188378) (xy 40.823134 -299.176186) (xy 40.81526 -299.154088) (xy 40.738806 -299.080936)
			(xy 40.7162 -299.074078) (xy 40.704262 -299.07611) (xy 40.690769 -299.078177) (xy 40.663556 -299.080338)
			(xy 40.649906 -299.080428) (xy 40.605456 -299.080428) (xy 40.594767 -299.080996) (xy 40.575221 -299.089663)
			(xy 40.56761 -299.097192) (xy 40.509952 -299.1612) (xy 40.503094 -299.18152) (xy 40.504364 -299.192188)
			(xy 40.505888 -299.224954) (xy 40.505408 -299.250966) (xy 40.497276 -299.302351) (xy 40.481206 -299.351832)
			(xy 40.457593 -299.398189) (xy 40.427019 -299.440281) (xy 40.390236 -299.477072) (xy 40.34815 -299.507656)
			(xy 40.301798 -299.531279) (xy 40.252322 -299.54736) (xy 40.200938 -299.555502) (xy 40.174926 -299.555916)
			(xy 40.104568 -299.555916) (xy 40.093912 -299.556382) (xy 40.074456 -299.565075) (xy 40.066976 -299.57268)
			(xy 40.009064 -299.636942) (xy 40.00246 -299.657262) (xy 40.003476 -299.668184) (xy 40.005254 -299.699934)
			(xy 40.004732 -299.725189) (xy 39.996419 -299.775011) (xy 39.980018 -299.822785) (xy 39.955977 -299.867208)
			(xy 39.924953 -299.907068) (xy 39.887791 -299.941278) (xy 39.845505 -299.968904) (xy 39.799249 -299.989194)
			(xy 39.750284 -300.001594) (xy 39.699946 -300.005765) (xy 39.649608 -300.001594) (xy 39.600643 -299.989194)
			(xy 39.554387 -299.968904) (xy 39.512101 -299.941278) (xy 39.474939 -299.907068) (xy 39.443915 -299.867208)
			(xy 39.419874 -299.822785) (xy 39.403473 -299.775011) (xy 39.39516 -299.725189) (xy 39.394638 -299.699934)
			(xy 39.396416 -299.668184) (xy 39.397432 -299.657262) (xy 39.390828 -299.636942) (xy 39.332916 -299.57268)
			(xy 39.325369 -299.565175) (xy 39.30595 -299.55652) (xy 39.295324 -299.555916) (xy 39.224966 -299.555916)
			(xy 39.19896 -299.55543) (xy 39.147589 -299.547288) (xy 39.098124 -299.53121) (xy 39.051783 -299.507591)
			(xy 39.009708 -299.477014) (xy 38.972934 -299.440232) (xy 38.942367 -299.398149) (xy 38.918759 -299.351802)
			(xy 38.902693 -299.302333) (xy 38.894564 -299.25096) (xy 38.894004 -299.224954) (xy 38.894579 -299.197405)
			(xy 38.903751 -299.143075) (xy 38.921785 -299.091012) (xy 38.948184 -299.042649) (xy 38.982221 -298.99932)
			(xy 39.002208 -298.980352) (xy 39.002462 -298.980098) (xy 39.009649 -298.972898) (xy 39.018107 -298.954416)
			(xy 39.018698 -298.9341) (xy 39.015416 -298.924472) (xy 38.98138 -298.83608) (xy 38.979069 -298.830541)
			(xy 38.972269 -298.820655) (xy 38.967918 -298.816522) (xy 38.967664 -298.816522) (xy 38.960473 -298.810651)
			(xy 38.943154 -298.804007) (xy 38.933882 -298.803568) (xy 37.615622 -298.803568) (xy 37.60634 -298.803968)
			(xy 37.589007 -298.810611) (xy 37.58184 -298.816522) (xy 37.581586 -298.816522) (xy 37.57724 -298.82066)
			(xy 37.570446 -298.830546) (xy 37.568124 -298.83608) (xy 37.528246 -298.93895) (xy 37.535612 -298.969684)
			(xy 37.547296 -298.980098) (xy 37.566605 -298.998405) (xy 37.599699 -299.040066) (xy 37.6257 -299.086486)
			(xy 37.643937 -299.136469) (xy 37.653939 -299.188726) (xy 37.655246 -299.215302) (xy 37.6555 -299.221652)
			(xy 37.6555 -299.224954) (xy 37.968948 -299.224954) (xy 37.972908 -299.1759) (xy 37.984685 -299.128116)
			(xy 38.003976 -299.08284) (xy 38.030279 -299.041244) (xy 38.062914 -299.004407) (xy 38.101035 -298.973282)
			(xy 38.143656 -298.948675) (xy 38.189672 -298.931223) (xy 38.237891 -298.921379) (xy 38.287066 -298.919398)
			(xy 38.335921 -298.92533) (xy 38.383192 -298.939022) (xy 38.427654 -298.96012) (xy 38.468157 -298.988076)
			(xy 38.50365 -299.022168) (xy 38.533215 -299.061512) (xy 38.556086 -299.105089) (xy 38.57167 -299.15177)
			(xy 38.579565 -299.200347) (xy 38.58006 -299.224954) (xy 38.579565 -299.249561) (xy 38.57167 -299.298138)
			(xy 38.556086 -299.344819) (xy 38.533215 -299.388396) (xy 38.50365 -299.42774) (xy 38.468157 -299.461832)
			(xy 38.427654 -299.489788) (xy 38.383192 -299.510886) (xy 38.335921 -299.524578) (xy 38.287066 -299.53051)
			(xy 38.237891 -299.528529) (xy 38.189672 -299.518685) (xy 38.143656 -299.501233) (xy 38.101035 -299.476626)
			(xy 38.062914 -299.445501) (xy 38.030279 -299.408664) (xy 38.003976 -299.367068) (xy 37.984685 -299.321792)
			(xy 37.972908 -299.274008) (xy 37.968948 -299.224954) (xy 37.6555 -299.224954) (xy 37.65502 -299.250967)
			(xy 37.646889 -299.302352) (xy 37.630819 -299.351834) (xy 37.607206 -299.398191) (xy 37.576631 -299.440285)
			(xy 37.539849 -299.477077) (xy 37.497763 -299.507662) (xy 37.451411 -299.531286) (xy 37.401934 -299.547369)
			(xy 37.350551 -299.555513) (xy 37.324538 -299.555916) (xy 36.374324 -299.555916) (xy 36.349965 -299.555442)
			(xy 36.301784 -299.548222) (xy 36.25518 -299.534021) (xy 36.21116 -299.513147) (xy 36.170672 -299.486049)
			(xy 36.13459 -299.453312) (xy 36.1188 -299.434758) (xy 36.111434 -299.426122) (xy 36.09213 -299.41647)
			(xy 35.992816 -299.413676) (xy 35.97275 -299.422058) (xy 35.96513 -299.43044) (xy 35.947642 -299.448862)
			(xy 35.907674 -299.480205) (xy 35.863072 -299.504505) (xy 35.815064 -299.52109) (xy 35.764974 -299.529506)
			(xy 35.739578 -299.530008) (xy 35.714324 -299.529485) (xy 35.664505 -299.521168) (xy 35.616734 -299.504765)
			(xy 35.572315 -299.480724) (xy 35.532458 -299.449699) (xy 35.498251 -299.412538) (xy 35.470626 -299.370253)
			(xy 35.450338 -299.323999) (xy 35.43794 -299.275036) (xy 35.433769 -299.2247) (xy 35.43794 -299.174364)
			(xy 35.450338 -299.125401) (xy 35.470626 -299.079147) (xy 35.498251 -299.036862) (xy 35.532458 -298.999701)
			(xy 35.572315 -298.968676) (xy 35.616734 -298.944635) (xy 35.664505 -298.928232) (xy 35.714324 -298.919915)
			(xy 35.739578 -298.919392) (xy 35.765012 -298.919897) (xy 35.815176 -298.928324) (xy 35.863249 -298.944948)
			(xy 35.907903 -298.969309) (xy 35.947902 -299.000735) (xy 35.965384 -299.019214) (xy 35.973004 -299.027342)
			(xy 35.992816 -299.035978) (xy 36.09213 -299.033438) (xy 36.111688 -299.023786) (xy 36.1188 -299.01515)
			(xy 36.126499 -299.005939) (xy 36.143025 -298.988523) (xy 36.15182 -298.980352) (xy 36.163504 -298.969684)
			(xy 36.17087 -298.93895) (xy 36.130992 -298.83608) (xy 36.128682 -298.83054) (xy 36.121883 -298.820653)
			(xy 36.11753 -298.816522) (xy 36.117276 -298.816522) (xy 36.110085 -298.81065) (xy 36.092767 -298.804001)
			(xy 36.083494 -298.803568) (xy 32.156654 -298.803568) (xy 32.152844 -298.803822) (xy 32.142579 -298.805013)
			(xy 32.124217 -298.814448) (xy 32.117284 -298.82211) (xy 32.112966 -298.82846) (xy 32.061404 -298.91482)
			(xy 32.060896 -298.941236) (xy 32.067246 -298.953174) (xy 32.081453 -298.981045) (xy 32.101588 -299.04027)
			(xy 32.111804 -299.101983) (xy 32.112458 -299.13326) (xy 32.112458 -299.139102) (xy 32.111593 -299.166091)
			(xy 32.103195 -299.219431) (xy 32.08736 -299.271054) (xy 32.064404 -299.319928) (xy 32.034785 -299.365077)
			(xy 31.999097 -299.405598) (xy 31.958051 -299.440683) (xy 31.912468 -299.469629) (xy 31.863259 -299.491859)
			(xy 31.811407 -299.506928) (xy 31.757949 -299.514534) (xy 31.73095 -299.515022) (xy 31.704217 -299.51457)
			(xy 31.651274 -299.5071) (xy 31.599893 -299.492313) (xy 31.551078 -299.470499) (xy 31.505786 -299.442085)
			(xy 31.464904 -299.407627) (xy 31.446724 -299.388022) (xy 31.439527 -299.380661) (xy 31.420901 -299.371939)
			(xy 31.400346 -299.371271) (xy 31.39059 -299.37456) (xy 31.301944 -299.408342) (xy 31.292551 -299.412454)
			(xy 31.277839 -299.426711) (xy 31.269896 -299.445595) (xy 31.269432 -299.45584) (xy 31.269432 -299.886116)
			(xy 33.77006 -299.886116) (xy 33.774131 -299.830494) (xy 33.786257 -299.776057) (xy 33.80618 -299.723966)
			(xy 33.833476 -299.675331) (xy 33.867562 -299.631188) (xy 33.907711 -299.592479) (xy 33.953069 -299.560028)
			(xy 34.002669 -299.534527) (xy 34.055453 -299.51652) (xy 34.110296 -299.50639) (xy 34.16603 -299.504353)
			(xy 34.221467 -299.510453) (xy 34.275424 -299.524559) (xy 34.326753 -299.546371) (xy 34.374359 -299.575425)
			(xy 34.417227 -299.6111) (xy 34.454444 -299.652637) (xy 34.485217 -299.69915) (xy 34.508889 -299.749647)
			(xy 34.524957 -299.803054) (xy 34.533077 -299.85823) (xy 34.533586 -299.886116) (xy 34.533077 -299.914002)
			(xy 34.524957 -299.969178) (xy 34.508889 -300.022585) (xy 34.485217 -300.073082) (xy 34.454444 -300.119595)
			(xy 34.417227 -300.161132) (xy 34.374359 -300.196807) (xy 34.326753 -300.225861) (xy 34.275424 -300.247673)
			(xy 34.221467 -300.261779) (xy 34.16603 -300.267879) (xy 34.110296 -300.265842) (xy 34.055453 -300.255712)
			(xy 34.002669 -300.237705) (xy 33.953069 -300.212204) (xy 33.907711 -300.179753) (xy 33.867562 -300.141044)
			(xy 33.833476 -300.096901) (xy 33.80618 -300.048266) (xy 33.786257 -299.996175) (xy 33.774131 -299.941738)
			(xy 33.77006 -299.886116) (xy 31.269432 -299.886116) (xy 31.269432 -300.753272) (xy 31.269902 -300.763144)
			(xy 31.277363 -300.781426) (xy 31.28391 -300.788832) (xy 31.284164 -300.789086) (xy 31.415482 -300.920404)
			(xy 31.41599 -300.920912) (xy 31.423371 -300.927493) (xy 31.441671 -300.934936) (xy 31.45155 -300.93539)
		)
		(stroke
			(width 0)
			(type solid)
		)
		(fill yes)
		(layer "In9.Cu")
		(net "PCEPLL1_VDDA18_PEX0")
	)
	(gr_poly
		(pts
			(xy 276.425914 -416.585908) (xy 276.436365 -416.585339) (xy 276.455497 -416.576906) (xy 276.469697 -416.561559)
			(xy 276.473666 -416.551872) (xy 276.51075 -416.445954) (xy 276.50186 -416.414966) (xy 276.48916 -416.404806)
			(xy 276.467059 -416.386622) (xy 276.428041 -416.344752) (xy 276.395722 -416.297519) (xy 276.370829 -416.245985)
			(xy 276.35392 -416.191308) (xy 276.345378 -416.134718) (xy 276.344888 -416.106102) (xy 276.345374 -416.078851)
			(xy 276.35313 -416.024903) (xy 276.368485 -415.972608) (xy 276.391127 -415.923031) (xy 276.420593 -415.877181)
			(xy 276.456284 -415.83599) (xy 276.497475 -415.800299) (xy 276.543325 -415.770833) (xy 276.592902 -415.748191)
			(xy 276.645197 -415.732836) (xy 276.699145 -415.72508) (xy 276.753647 -415.72508) (xy 276.807595 -415.732836)
			(xy 276.85989 -415.748191) (xy 276.909467 -415.770833) (xy 276.955317 -415.800299) (xy 276.996508 -415.83599)
			(xy 277.032199 -415.877181) (xy 277.061665 -415.923031) (xy 277.084307 -415.972608) (xy 277.099662 -416.024903)
			(xy 277.107418 -416.078851) (xy 277.107904 -416.106102) (xy 277.107392 -416.134716) (xy 277.098841 -416.191302)
			(xy 277.081932 -416.245976) (xy 277.057044 -416.29751) (xy 277.024737 -416.344746) (xy 276.985734 -416.386626)
			(xy 276.963632 -416.404806) (xy 276.950932 -416.414966) (xy 276.942042 -416.445954) (xy 276.979126 -416.551872)
			(xy 276.983051 -416.561584) (xy 276.997256 -416.576948) (xy 277.016417 -416.585356) (xy 277.026878 -416.585908)
			(xy 277.441914 -416.585908) (xy 277.452365 -416.585339) (xy 277.471497 -416.576906) (xy 277.485697 -416.561559)
			(xy 277.489666 -416.551872) (xy 277.52675 -416.445954) (xy 277.51786 -416.414966) (xy 277.50516 -416.404806)
			(xy 277.483059 -416.386622) (xy 277.444041 -416.344752) (xy 277.411722 -416.297519) (xy 277.386829 -416.245985)
			(xy 277.36992 -416.191308) (xy 277.361378 -416.134718) (xy 277.360888 -416.106102) (xy 277.361374 -416.078851)
			(xy 277.36913 -416.024903) (xy 277.384485 -415.972608) (xy 277.407127 -415.923031) (xy 277.436593 -415.877181)
			(xy 277.472284 -415.83599) (xy 277.513475 -415.800299) (xy 277.559325 -415.770833) (xy 277.608902 -415.748191)
			(xy 277.661197 -415.732836) (xy 277.715145 -415.72508) (xy 277.769647 -415.72508) (xy 277.823595 -415.732836)
			(xy 277.87589 -415.748191) (xy 277.925467 -415.770833) (xy 277.971317 -415.800299) (xy 278.012508 -415.83599)
			(xy 278.048199 -415.877181) (xy 278.077665 -415.923031) (xy 278.100307 -415.972608) (xy 278.105197 -415.989262)
			(xy 278.376378 -415.989262) (xy 278.380449 -415.93364) (xy 278.392575 -415.879203) (xy 278.412498 -415.827112)
			(xy 278.439794 -415.778477) (xy 278.47388 -415.734334) (xy 278.514029 -415.695625) (xy 278.559387 -415.663174)
			(xy 278.608987 -415.637673) (xy 278.661771 -415.619666) (xy 278.716614 -415.609536) (xy 278.772348 -415.607499)
			(xy 278.827785 -415.613599) (xy 278.881742 -415.627705) (xy 278.933071 -415.649517) (xy 278.980677 -415.678571)
			(xy 279.023545 -415.714246) (xy 279.060762 -415.755783) (xy 279.091535 -415.802296) (xy 279.115207 -415.852793)
			(xy 279.131275 -415.9062) (xy 279.139395 -415.961376) (xy 279.139904 -415.989262) (xy 279.139593 -416.00628)
			(xy 279.392378 -416.00628) (xy 279.396449 -415.950658) (xy 279.408575 -415.896221) (xy 279.428498 -415.84413)
			(xy 279.455794 -415.795495) (xy 279.48988 -415.751352) (xy 279.530029 -415.712643) (xy 279.575387 -415.680192)
			(xy 279.624987 -415.654691) (xy 279.677771 -415.636684) (xy 279.732614 -415.626554) (xy 279.788348 -415.624517)
			(xy 279.843785 -415.630617) (xy 279.897742 -415.644723) (xy 279.949071 -415.666535) (xy 279.996677 -415.695589)
			(xy 280.039545 -415.731264) (xy 280.076762 -415.772801) (xy 280.107535 -415.819314) (xy 280.131207 -415.869811)
			(xy 280.147275 -415.923218) (xy 280.155395 -415.978394) (xy 280.155904 -416.00628) (xy 280.155395 -416.034166)
			(xy 280.147275 -416.089342) (xy 280.131207 -416.142749) (xy 280.107535 -416.193246) (xy 280.076762 -416.239759)
			(xy 280.039545 -416.281296) (xy 279.996677 -416.316971) (xy 279.949071 -416.346025) (xy 279.897742 -416.367837)
			(xy 279.843785 -416.381943) (xy 279.788348 -416.388043) (xy 279.732614 -416.386006) (xy 279.677771 -416.375876)
			(xy 279.624987 -416.357869) (xy 279.575387 -416.332368) (xy 279.530029 -416.299917) (xy 279.48988 -416.261208)
			(xy 279.455794 -416.217065) (xy 279.428498 -416.16843) (xy 279.408575 -416.116339) (xy 279.396449 -416.061902)
			(xy 279.392378 -416.00628) (xy 279.139593 -416.00628) (xy 279.139395 -416.017148) (xy 279.131275 -416.072324)
			(xy 279.115207 -416.125731) (xy 279.091535 -416.176228) (xy 279.060762 -416.222741) (xy 279.023545 -416.264278)
			(xy 278.980677 -416.299953) (xy 278.933071 -416.329007) (xy 278.881742 -416.350819) (xy 278.827785 -416.364925)
			(xy 278.772348 -416.371025) (xy 278.716614 -416.368988) (xy 278.661771 -416.358858) (xy 278.608987 -416.340851)
			(xy 278.559387 -416.31535) (xy 278.514029 -416.282899) (xy 278.47388 -416.24419) (xy 278.439794 -416.200047)
			(xy 278.412498 -416.151412) (xy 278.392575 -416.099321) (xy 278.380449 -416.044884) (xy 278.376378 -415.989262)
			(xy 278.105197 -415.989262) (xy 278.115662 -416.024903) (xy 278.123418 -416.078851) (xy 278.123904 -416.106102)
			(xy 278.123392 -416.134716) (xy 278.114841 -416.191302) (xy 278.097932 -416.245976) (xy 278.073044 -416.29751)
			(xy 278.040737 -416.344746) (xy 278.001734 -416.386626) (xy 277.979632 -416.404806) (xy 277.966932 -416.414966)
			(xy 277.958042 -416.445954) (xy 277.995126 -416.551872) (xy 277.999051 -416.561584) (xy 278.013256 -416.576948)
			(xy 278.032417 -416.585356) (xy 278.042878 -416.585908) (xy 280.432256 -416.585908) (xy 280.442022 -416.585421)
			(xy 280.460112 -416.57804) (xy 280.474141 -416.564442) (xy 280.478484 -416.555682) (xy 280.522426 -416.456876)
			(xy 280.5176 -416.427412) (xy 280.50744 -416.416236) (xy 280.488979 -416.395076) (xy 280.457829 -416.348356)
			(xy 280.433862 -416.297574) (xy 280.417596 -416.243829) (xy 280.409381 -416.188281) (xy 280.408888 -416.160204)
			(xy 280.409374 -416.132953) (xy 280.41713 -416.079005) (xy 280.432485 -416.02671) (xy 280.455127 -415.977133)
			(xy 280.484593 -415.931283) (xy 280.520284 -415.890092) (xy 280.561475 -415.854401) (xy 280.607325 -415.824935)
			(xy 280.656902 -415.802293) (xy 280.709197 -415.786938) (xy 280.763145 -415.779182) (xy 280.817647 -415.779182)
			(xy 280.871595 -415.786938) (xy 280.92389 -415.802293) (xy 280.973467 -415.824935) (xy 281.019317 -415.854401)
			(xy 281.060508 -415.890092) (xy 281.096199 -415.931283) (xy 281.125665 -415.977133) (xy 281.148307 -416.02671)
			(xy 281.163662 -416.079005) (xy 281.171418 -416.132953) (xy 281.171904 -416.160204) (xy 281.171407 -416.18828)
			(xy 281.163184 -416.243826) (xy 281.146917 -416.29757) (xy 281.122954 -416.348352) (xy 281.091814 -416.395079)
			(xy 281.073352 -416.416236) (xy 281.063192 -416.427412) (xy 281.058366 -416.456876) (xy 281.102308 -416.555682)
			(xy 281.10666 -416.564441) (xy 281.120673 -416.578059) (xy 281.138767 -416.585437) (xy 281.148536 -416.585908)
			(xy 281.502612 -416.585908) (xy 281.512681 -416.585483) (xy 281.531284 -416.577767) (xy 281.53868 -416.570922)
			(xy 282.130754 -415.978848) (xy 282.137597 -415.971449) (xy 282.14532 -415.95285) (xy 282.14574 -415.94278)
			(xy 282.14574 -405.820118) (xy 282.1453 -405.810056) (xy 282.137558 -405.791479) (xy 282.130754 -405.78405)
			(xy 281.526488 -405.179784) (xy 281.519093 -405.17293) (xy 281.500494 -405.165187) (xy 281.49042 -405.164798)
			(xy 275.211794 -405.164798) (xy 275.201724 -405.164374) (xy 275.183122 -405.156657) (xy 275.175726 -405.149812)
			(xy 274.708366 -404.682452) (xy 274.70152 -404.675054) (xy 274.693792 -404.656455) (xy 274.69338 -404.646384)
			(xy 274.69338 -403.295104) (xy 274.693802 -403.285033) (xy 274.701513 -403.266426) (xy 274.708366 -403.259036)
			(xy 274.927314 -403.040088) (xy 274.934709 -403.033234) (xy 274.953308 -403.025491) (xy 274.963382 -403.025102)
			(xy 277.957026 -403.025102) (xy 277.967094 -403.024674) (xy 277.985692 -403.016953) (xy 277.993094 -403.010116)
			(xy 279.360884 -401.642326) (xy 279.368796 -401.633479) (xy 279.376216 -401.610963) (xy 279.375108 -401.599146)
			(xy 279.3619 -401.50669) (xy 279.348438 -401.487386) (xy 279.33777 -401.481544) (xy 279.312445 -401.467037)
			(xy 279.266127 -401.431534) (xy 279.22575 -401.389397) (xy 279.192252 -401.341608) (xy 279.166415 -401.289279)
			(xy 279.14884 -401.233628) (xy 279.139936 -401.175952) (xy 279.139396 -401.146772) (xy 279.139884 -401.119522)
			(xy 279.147643 -401.065578) (xy 279.163001 -401.013287) (xy 279.185644 -400.963713) (xy 279.215111 -400.917866)
			(xy 279.250803 -400.87668) (xy 279.291992 -400.840992) (xy 279.337841 -400.811529) (xy 279.387417 -400.78889)
			(xy 279.439709 -400.773537) (xy 279.493654 -400.765781) (xy 279.520904 -400.765264) (xy 279.550087 -400.765811)
			(xy 279.607774 -400.774686) (xy 279.663436 -400.792243) (xy 279.715775 -400.818073) (xy 279.763569 -400.851573)
			(xy 279.805703 -400.891962) (xy 279.841195 -400.938296) (xy 279.855676 -400.963638) (xy 279.861518 -400.974306)
			(xy 279.880822 -400.987768) (xy 279.973278 -401.000976) (xy 279.985091 -401.002071) (xy 280.007592 -400.994639)
			(xy 280.016458 -400.986752) (xy 281.56789 -399.43532) (xy 281.574689 -399.427971) (xy 281.582394 -399.409508)
			(xy 281.582876 -399.399506) (xy 281.582876 -392.928094) (xy 281.582337 -392.918108) (xy 281.574619 -392.899679)
			(xy 281.56789 -392.89228) (xy 281.28976 -392.61415) (xy 281.282362 -392.607305) (xy 281.263763 -392.599577)
			(xy 281.253692 -392.599164) (xy 280.029666 -392.599164) (xy 280.0196 -392.599595) (xy 280.00101 -392.607325)
			(xy 279.993598 -392.61415) (xy 279.462992 -393.144756) (xy 279.439439 -393.167705) (xy 279.388041 -393.208731)
			(xy 279.332371 -393.243741) (xy 279.273129 -393.272293) (xy 279.211061 -393.294029) (xy 279.146949 -393.308674)
			(xy 279.0816 -393.316043) (xy 279.048718 -393.31646) (xy 279.013304 -393.315947) (xy 278.942991 -393.307412)
			(xy 278.87422 -393.290463) (xy 278.807994 -393.265348) (xy 278.745278 -393.232433) (xy 278.686986 -393.192198)
			(xy 278.63397 -393.14523) (xy 278.587002 -393.092214) (xy 278.546767 -393.033922) (xy 278.513852 -392.971206)
			(xy 278.488737 -392.90498) (xy 278.471788 -392.836209) (xy 278.463253 -392.765896) (xy 278.46274 -392.730482)
			(xy 278.462907 -392.711887) (xy 278.465321 -392.674774) (xy 278.467566 -392.656314) (xy 278.468074 -392.653266)
			(xy 278.468074 -392.649964) (xy 278.467579 -392.639963) (xy 278.459913 -392.621488) (xy 278.44576 -392.607353)
			(xy 278.427276 -392.599708) (xy 278.417274 -392.599164) (xy 278.404066 -392.599164) (xy 278.394 -392.599595)
			(xy 278.37541 -392.607325) (xy 278.367998 -392.61415) (xy 277.807674 -393.174474) (xy 277.784096 -393.197384)
			(xy 277.732682 -393.238357) (xy 277.677004 -393.273318) (xy 277.617763 -393.301827) (xy 277.555703 -393.323525)
			(xy 277.491604 -393.33814) (xy 277.426272 -393.345488) (xy 277.3934 -393.345924) (xy 277.24735 -393.345924)
			(xy 277.211948 -393.345387) (xy 277.14166 -393.33685) (xy 277.072913 -393.319906) (xy 277.006709 -393.294802)
			(xy 276.944012 -393.261903) (xy 276.885735 -393.22169) (xy 276.832728 -393.174749) (xy 276.785764 -393.121762)
			(xy 276.745526 -393.063503) (xy 276.712601 -393.000819) (xy 276.687469 -392.934626) (xy 276.670495 -392.865886)
			(xy 276.661928 -392.795602) (xy 276.661372 -392.7602) (xy 276.661469 -392.747546) (xy 276.662614 -392.722265)
			(xy 276.663658 -392.709654) (xy 276.664674 -392.698732) (xy 276.657816 -392.67892) (xy 276.599904 -392.615674)
			(xy 276.592408 -392.608234) (xy 276.573114 -392.599709) (xy 276.562566 -392.599164) (xy 274.304252 -392.599164)
			(xy 274.294187 -392.599598) (xy 274.275601 -392.607331) (xy 274.268184 -392.61415) (xy 273.649948 -393.232386)
			(xy 273.64311 -393.239787) (xy 273.635399 -393.258386) (xy 273.634962 -393.268454) (xy 273.634962 -394.762482)
			(xy 276.700486 -394.762482) (xy 276.704557 -394.70686) (xy 276.716683 -394.652423) (xy 276.736606 -394.600332)
			(xy 276.763902 -394.551697) (xy 276.797988 -394.507554) (xy 276.838137 -394.468845) (xy 276.883495 -394.436394)
			(xy 276.933095 -394.410893) (xy 276.985879 -394.392886) (xy 277.040722 -394.382756) (xy 277.096456 -394.380719)
			(xy 277.151893 -394.386819) (xy 277.20585 -394.400925) (xy 277.257179 -394.422737) (xy 277.304785 -394.451791)
			(xy 277.347653 -394.487466) (xy 277.38487 -394.529003) (xy 277.415643 -394.575516) (xy 277.439315 -394.626013)
			(xy 277.455383 -394.67942) (xy 277.463503 -394.734596) (xy 277.464012 -394.762482) (xy 279.240486 -394.762482)
			(xy 279.244557 -394.70686) (xy 279.256683 -394.652423) (xy 279.276606 -394.600332) (xy 279.303902 -394.551697)
			(xy 279.337988 -394.507554) (xy 279.378137 -394.468845) (xy 279.423495 -394.436394) (xy 279.473095 -394.410893)
			(xy 279.525879 -394.392886) (xy 279.580722 -394.382756) (xy 279.636456 -394.380719) (xy 279.691893 -394.386819)
			(xy 279.74585 -394.400925) (xy 279.797179 -394.422737) (xy 279.844785 -394.451791) (xy 279.887653 -394.487466)
			(xy 279.92487 -394.529003) (xy 279.955643 -394.575516) (xy 279.979315 -394.626013) (xy 279.995383 -394.67942)
			(xy 280.003503 -394.734596) (xy 280.004012 -394.762482) (xy 280.003503 -394.790368) (xy 279.995383 -394.845544)
			(xy 279.979315 -394.898951) (xy 279.955643 -394.949448) (xy 279.92487 -394.995961) (xy 279.887653 -395.037498)
			(xy 279.844785 -395.073173) (xy 279.797179 -395.102227) (xy 279.74585 -395.124039) (xy 279.691893 -395.138145)
			(xy 279.636456 -395.144245) (xy 279.580722 -395.142208) (xy 279.525879 -395.132078) (xy 279.473095 -395.114071)
			(xy 279.423495 -395.08857) (xy 279.378137 -395.056119) (xy 279.337988 -395.01741) (xy 279.303902 -394.973267)
			(xy 279.276606 -394.924632) (xy 279.256683 -394.872541) (xy 279.244557 -394.818104) (xy 279.240486 -394.762482)
			(xy 277.464012 -394.762482) (xy 277.463503 -394.790368) (xy 277.455383 -394.845544) (xy 277.439315 -394.898951)
			(xy 277.415643 -394.949448) (xy 277.38487 -394.995961) (xy 277.347653 -395.037498) (xy 277.304785 -395.073173)
			(xy 277.257179 -395.102227) (xy 277.20585 -395.124039) (xy 277.151893 -395.138145) (xy 277.096456 -395.144245)
			(xy 277.040722 -395.142208) (xy 276.985879 -395.132078) (xy 276.933095 -395.114071) (xy 276.883495 -395.08857)
			(xy 276.838137 -395.056119) (xy 276.797988 -395.01741) (xy 276.763902 -394.973267) (xy 276.736606 -394.924632)
			(xy 276.716683 -394.872541) (xy 276.704557 -394.818104) (xy 276.700486 -394.762482) (xy 273.634962 -394.762482)
			(xy 273.634962 -395.639544) (xy 273.63453 -395.64961) (xy 273.6268 -395.668199) (xy 273.619976 -395.675612)
			(xy 272.725388 -396.5702) (xy 276.876508 -396.5702) (xy 276.880579 -396.514578) (xy 276.892705 -396.460141)
			(xy 276.912628 -396.40805) (xy 276.939924 -396.359415) (xy 276.97401 -396.315272) (xy 277.014159 -396.276563)
			(xy 277.059517 -396.244112) (xy 277.109117 -396.218611) (xy 277.161901 -396.200604) (xy 277.216744 -396.190474)
			(xy 277.272478 -396.188437) (xy 277.327915 -396.194537) (xy 277.381872 -396.208643) (xy 277.433201 -396.230455)
			(xy 277.480807 -396.259509) (xy 277.523675 -396.295184) (xy 277.560892 -396.336721) (xy 277.591665 -396.383234)
			(xy 277.615337 -396.433731) (xy 277.631405 -396.487138) (xy 277.638134 -396.532862) (xy 278.858216 -396.532862)
			(xy 278.862287 -396.47724) (xy 278.874413 -396.422803) (xy 278.894336 -396.370712) (xy 278.921632 -396.322077)
			(xy 278.955718 -396.277934) (xy 278.995867 -396.239225) (xy 279.041225 -396.206774) (xy 279.090825 -396.181273)
			(xy 279.143609 -396.163266) (xy 279.198452 -396.153136) (xy 279.254186 -396.151099) (xy 279.309623 -396.157199)
			(xy 279.36358 -396.171305) (xy 279.414909 -396.193117) (xy 279.462515 -396.222171) (xy 279.505383 -396.257846)
			(xy 279.5426 -396.299383) (xy 279.573373 -396.345896) (xy 279.597045 -396.396393) (xy 279.613113 -396.4498)
			(xy 279.621233 -396.504976) (xy 279.621742 -396.532862) (xy 279.621233 -396.560748) (xy 279.613113 -396.615924)
			(xy 279.597045 -396.669331) (xy 279.573373 -396.719828) (xy 279.5426 -396.766341) (xy 279.505383 -396.807878)
			(xy 279.462515 -396.843553) (xy 279.414909 -396.872607) (xy 279.36358 -396.894419) (xy 279.309623 -396.908525)
			(xy 279.254186 -396.914625) (xy 279.198452 -396.912588) (xy 279.143609 -396.902458) (xy 279.090825 -396.884451)
			(xy 279.041225 -396.85895) (xy 278.995867 -396.826499) (xy 278.955718 -396.78779) (xy 278.921632 -396.743647)
			(xy 278.894336 -396.695012) (xy 278.874413 -396.642921) (xy 278.862287 -396.588484) (xy 278.858216 -396.532862)
			(xy 277.638134 -396.532862) (xy 277.639525 -396.542314) (xy 277.640034 -396.5702) (xy 277.639525 -396.598086)
			(xy 277.631405 -396.653262) (xy 277.615337 -396.706669) (xy 277.591665 -396.757166) (xy 277.560892 -396.803679)
			(xy 277.523675 -396.845216) (xy 277.480807 -396.880891) (xy 277.433201 -396.909945) (xy 277.381872 -396.931757)
			(xy 277.327915 -396.945863) (xy 277.272478 -396.951963) (xy 277.216744 -396.949926) (xy 277.161901 -396.939796)
			(xy 277.109117 -396.921789) (xy 277.059517 -396.896288) (xy 277.014159 -396.863837) (xy 276.97401 -396.825128)
			(xy 276.939924 -396.780985) (xy 276.912628 -396.73235) (xy 276.892705 -396.680259) (xy 276.880579 -396.625822)
			(xy 276.876508 -396.5702) (xy 272.725388 -396.5702) (xy 271.361916 -397.933672) (xy 279.755598 -397.933672)
			(xy 279.759669 -397.87805) (xy 279.771795 -397.823613) (xy 279.791718 -397.771522) (xy 279.819014 -397.722887)
			(xy 279.8531 -397.678744) (xy 279.893249 -397.640035) (xy 279.938607 -397.607584) (xy 279.988207 -397.582083)
			(xy 280.040991 -397.564076) (xy 280.095834 -397.553946) (xy 280.151568 -397.551909) (xy 280.207005 -397.558009)
			(xy 280.260962 -397.572115) (xy 280.312291 -397.593927) (xy 280.359897 -397.622981) (xy 280.402765 -397.658656)
			(xy 280.439982 -397.700193) (xy 280.470755 -397.746706) (xy 280.494427 -397.797203) (xy 280.510495 -397.85061)
			(xy 280.518615 -397.905786) (xy 280.519124 -397.933672) (xy 280.518615 -397.961558) (xy 280.510495 -398.016734)
			(xy 280.494427 -398.070141) (xy 280.470755 -398.120638) (xy 280.439982 -398.167151) (xy 280.402765 -398.208688)
			(xy 280.359897 -398.244363) (xy 280.312291 -398.273417) (xy 280.260962 -398.295229) (xy 280.207005 -398.309335)
			(xy 280.151568 -398.315435) (xy 280.095834 -398.313398) (xy 280.040991 -398.303268) (xy 279.988207 -398.285261)
			(xy 279.938607 -398.25976) (xy 279.893249 -398.227309) (xy 279.8531 -398.1886) (xy 279.819014 -398.144457)
			(xy 279.791718 -398.095822) (xy 279.771795 -398.043731) (xy 279.759669 -397.989294) (xy 279.755598 -397.933672)
			(xy 271.361916 -397.933672) (xy 270.640556 -398.655032) (xy 270.633158 -398.661879) (xy 270.614559 -398.669608)
			(xy 270.604488 -398.670018) (xy 266.471654 -398.670018) (xy 266.461587 -398.669587) (xy 266.442993 -398.661863)
			(xy 266.435586 -398.655032) (xy 265.197082 -397.416528) (xy 265.193526 -397.413988) (xy 265.109065 -397.35452)
			(xy 264.944341 -397.229841) (xy 264.78464 -397.098788) (xy 264.63021 -396.961563) (xy 264.481289 -396.81838)
			(xy 264.338106 -396.669457) (xy 264.200883 -396.515026) (xy 264.069832 -396.355324) (xy 263.945154 -396.190599)
			(xy 263.88568 -396.106142) (xy 263.88314 -396.102586) (xy 260.15442 -392.373866) (xy 260.14702 -392.367025)
			(xy 260.128421 -392.359309) (xy 260.118352 -392.35888) (xy 254.98552 -392.35888) (xy 254.975456 -392.359317)
			(xy 254.956871 -392.36705) (xy 254.949452 -392.373866) (xy 254.616204 -392.707114) (xy 254.60936 -392.714513)
			(xy 254.60163 -392.733111) (xy 254.601218 -392.743182) (xy 254.601218 -398.402048) (xy 254.600787 -398.412115)
			(xy 254.593062 -398.430708) (xy 254.586232 -398.438116) (xy 253.778766 -399.245582) (xy 253.771367 -399.252425)
			(xy 253.752768 -399.26015) (xy 253.742698 -399.260568) (xy 245.808246 -399.260568) (xy 245.798193 -399.261069)
			(xy 245.779625 -399.268783) (xy 245.772178 -399.275554) (xy 245.217188 -399.830544) (xy 245.210339 -399.83794)
			(xy 245.202606 -399.85654) (xy 245.202202 -399.866612) (xy 245.202202 -400.8755) (xy 245.201779 -400.88557)
			(xy 245.194065 -400.904175) (xy 245.187216 -400.911568) (xy 244.925596 -401.173188) (xy 277.12035 -401.173188)
			(xy 277.120836 -401.145937) (xy 277.128592 -401.091989) (xy 277.143947 -401.039694) (xy 277.166589 -400.990117)
			(xy 277.196055 -400.944267) (xy 277.231746 -400.903076) (xy 277.272937 -400.867385) (xy 277.318787 -400.837919)
			(xy 277.368364 -400.815277) (xy 277.420659 -400.799922) (xy 277.474607 -400.792166) (xy 277.529109 -400.792166)
			(xy 277.583057 -400.799922) (xy 277.635352 -400.815277) (xy 277.684929 -400.837919) (xy 277.730779 -400.867385)
			(xy 277.77197 -400.903076) (xy 277.807661 -400.944267) (xy 277.837127 -400.990117) (xy 277.859769 -401.039694)
			(xy 277.875124 -401.091989) (xy 277.88288 -401.145937) (xy 277.883366 -401.173188) (xy 277.882782 -401.204)
			(xy 277.872891 -401.264824) (xy 277.853365 -401.323272) (xy 277.824709 -401.377827) (xy 277.806658 -401.402804)
			(xy 277.79821 -401.41486) (xy 277.787947 -401.442437) (xy 277.785972 -401.471796) (xy 277.79245 -401.5005)
			(xy 277.806842 -401.526165) (xy 277.827953 -401.546663) (xy 277.854033 -401.56029) (xy 277.86838 -401.563586)
			(xy 277.894092 -401.569098) (xy 277.943829 -401.586165) (xy 277.990751 -401.609903) (xy 278.033966 -401.63986)
			(xy 278.072657 -401.675471) (xy 278.10609 -401.716058) (xy 278.133631 -401.760853) (xy 278.154757 -401.809006)
			(xy 278.169069 -401.859605) (xy 278.176294 -401.91169) (xy 278.176736 -401.937982) (xy 278.17625 -401.965233)
			(xy 278.168494 -402.019181) (xy 278.153139 -402.071476) (xy 278.130497 -402.121053) (xy 278.101031 -402.166903)
			(xy 278.06534 -402.208094) (xy 278.024149 -402.243785) (xy 277.978299 -402.273251) (xy 277.928722 -402.295893)
			(xy 277.876427 -402.311248) (xy 277.822479 -402.319004) (xy 277.767977 -402.319004) (xy 277.714029 -402.311248)
			(xy 277.661734 -402.295893) (xy 277.612157 -402.273251) (xy 277.566307 -402.243785) (xy 277.525116 -402.208094)
			(xy 277.489425 -402.166903) (xy 277.459959 -402.121053) (xy 277.437317 -402.071476) (xy 277.421962 -402.019181)
			(xy 277.414206 -401.965233) (xy 277.41372 -401.937982) (xy 277.414291 -401.90717) (xy 277.424186 -401.846345)
			(xy 277.443716 -401.787898) (xy 277.472376 -401.733343) (xy 277.490428 -401.708366) (xy 277.498921 -401.696339)
			(xy 277.509183 -401.668752) (xy 277.511153 -401.639385) (xy 277.504669 -401.610674) (xy 277.490269 -401.585004)
			(xy 277.469147 -401.564505) (xy 277.443058 -401.550878) (xy 277.428706 -401.547584) (xy 277.402985 -401.542111)
			(xy 277.353246 -401.52504) (xy 277.306323 -401.501298) (xy 277.263107 -401.471336) (xy 277.224416 -401.435721)
			(xy 277.190984 -401.39513) (xy 277.163445 -401.35033) (xy 277.142321 -401.302173) (xy 277.128012 -401.25157)
			(xy 277.12079 -401.199481) (xy 277.12035 -401.173188) (xy 244.925596 -401.173188) (xy 243.90731 -402.191474)
			(xy 243.899913 -402.198325) (xy 243.881315 -402.206067) (xy 243.871242 -402.20646) (xy 239.48898 -402.20646)
			(xy 239.478913 -402.206888) (xy 239.460319 -402.214615) (xy 239.452912 -402.221446) (xy 238.291878 -403.38248)
			(xy 238.285036 -403.389879) (xy 238.277318 -403.408478) (xy 238.276892 -403.418548) (xy 238.276892 -406.147016)
			(xy 275.691598 -406.147016) (xy 275.695669 -406.091394) (xy 275.707795 -406.036957) (xy 275.727718 -405.984866)
			(xy 275.755014 -405.936231) (xy 275.7891 -405.892088) (xy 275.829249 -405.853379) (xy 275.874607 -405.820928)
			(xy 275.924207 -405.795427) (xy 275.976991 -405.77742) (xy 276.031834 -405.76729) (xy 276.087568 -405.765253)
			(xy 276.143005 -405.771353) (xy 276.196962 -405.785459) (xy 276.248291 -405.807271) (xy 276.295897 -405.836325)
			(xy 276.338765 -405.872) (xy 276.375982 -405.913537) (xy 276.406755 -405.96005) (xy 276.430427 -406.010547)
			(xy 276.446495 -406.063954) (xy 276.454615 -406.11913) (xy 276.455124 -406.147016) (xy 276.454615 -406.174902)
			(xy 276.453107 -406.185151) (xy 276.708593 -406.185151) (xy 276.708593 -406.130649) (xy 276.71635 -406.076702)
			(xy 276.731705 -406.024408) (xy 276.754347 -405.974832) (xy 276.783813 -405.928983) (xy 276.819505 -405.887794)
			(xy 276.860695 -405.852104) (xy 276.906546 -405.822639) (xy 276.956123 -405.8) (xy 277.008418 -405.784646)
			(xy 277.062365 -405.776892) (xy 277.089616 -405.77643) (xy 277.118436 -405.776938) (xy 277.175418 -405.785624)
			(xy 277.230446 -405.802782) (xy 277.282267 -405.828021) (xy 277.329703 -405.860766) (xy 277.371675 -405.900274)
			(xy 277.407227 -405.945644) (xy 277.421848 -405.970486) (xy 277.427436 -405.980392) (xy 277.445724 -405.9936)
			(xy 277.544784 -406.011634) (xy 277.566628 -406.006046) (xy 277.575518 -405.99868) (xy 277.596164 -405.982058)
			(xy 277.641186 -405.954089) (xy 277.689649 -405.932626) (xy 277.740618 -405.918084) (xy 277.793111 -405.910743)
			(xy 277.819612 -405.910288) (xy 277.846862 -405.910783) (xy 277.900808 -405.91854) (xy 277.953101 -405.933896)
			(xy 278.002676 -405.956538) (xy 278.048525 -405.986004) (xy 278.089713 -406.021695) (xy 278.125403 -406.062885)
			(xy 278.154868 -406.108734) (xy 278.177508 -406.15831) (xy 278.192862 -406.210603) (xy 278.200618 -406.26455)
			(xy 278.200618 -406.31905) (xy 278.192862 -406.372997) (xy 278.177508 -406.42529) (xy 278.154868 -406.474866)
			(xy 278.125403 -406.520715) (xy 278.089713 -406.561905) (xy 278.048525 -406.597596) (xy 278.002676 -406.627062)
			(xy 277.953101 -406.649704) (xy 277.900808 -406.66506) (xy 277.846862 -406.672817) (xy 277.819612 -406.673304)
			(xy 277.790794 -406.672757) (xy 277.733814 -406.664075) (xy 277.678788 -406.646923) (xy 277.626967 -406.621691)
			(xy 277.579531 -406.588952) (xy 277.537558 -406.549451) (xy 277.502003 -406.504087) (xy 277.48738 -406.479248)
			(xy 277.481792 -406.469342) (xy 277.463504 -406.456134) (xy 277.364444 -406.4381) (xy 277.3426 -406.443688)
			(xy 277.33371 -406.451054) (xy 277.313058 -406.467668) (xy 277.268037 -406.495637) (xy 277.219575 -406.517101)
			(xy 277.168608 -406.531645) (xy 277.116117 -406.538989) (xy 277.089616 -406.539446) (xy 277.062365 -406.538908)
			(xy 277.008418 -406.531154) (xy 276.956123 -406.5158) (xy 276.906546 -406.493161) (xy 276.860695 -406.463696)
			(xy 276.819505 -406.428006) (xy 276.783813 -406.386817) (xy 276.754347 -406.340968) (xy 276.731705 -406.291392)
			(xy 276.71635 -406.239098) (xy 276.708593 -406.185151) (xy 276.453107 -406.185151) (xy 276.446495 -406.230078)
			(xy 276.430427 -406.283485) (xy 276.406755 -406.333982) (xy 276.375982 -406.380495) (xy 276.338765 -406.422032)
			(xy 276.295897 -406.457707) (xy 276.248291 -406.486761) (xy 276.196962 -406.508573) (xy 276.143005 -406.522679)
			(xy 276.087568 -406.528779) (xy 276.031834 -406.526742) (xy 275.976991 -406.516612) (xy 275.924207 -406.498605)
			(xy 275.874607 -406.473104) (xy 275.829249 -406.440653) (xy 275.7891 -406.401944) (xy 275.755014 -406.357801)
			(xy 275.727718 -406.309166) (xy 275.707795 -406.257075) (xy 275.695669 -406.202638) (xy 275.691598 -406.147016)
			(xy 238.276892 -406.147016) (xy 238.276892 -406.551892) (xy 274.490686 -406.551892) (xy 274.494757 -406.49627)
			(xy 274.506883 -406.441833) (xy 274.526806 -406.389742) (xy 274.554102 -406.341107) (xy 274.588188 -406.296964)
			(xy 274.628337 -406.258255) (xy 274.673695 -406.225804) (xy 274.723295 -406.200303) (xy 274.776079 -406.182296)
			(xy 274.830922 -406.172166) (xy 274.886656 -406.170129) (xy 274.942093 -406.176229) (xy 274.99605 -406.190335)
			(xy 275.047379 -406.212147) (xy 275.094985 -406.241201) (xy 275.137853 -406.276876) (xy 275.17507 -406.318413)
			(xy 275.205843 -406.364926) (xy 275.229515 -406.415423) (xy 275.245583 -406.46883) (xy 275.253703 -406.524006)
			(xy 275.254212 -406.551892) (xy 275.253703 -406.579778) (xy 275.245583 -406.634954) (xy 275.229515 -406.688361)
			(xy 275.205843 -406.738858) (xy 275.17507 -406.785371) (xy 275.137853 -406.826908) (xy 275.094985 -406.862583)
			(xy 275.047379 -406.891637) (xy 274.99605 -406.913449) (xy 274.942093 -406.927555) (xy 274.886656 -406.933655)
			(xy 274.830922 -406.931618) (xy 274.776079 -406.921488) (xy 274.723295 -406.903481) (xy 274.673695 -406.87798)
			(xy 274.628337 -406.845529) (xy 274.588188 -406.80682) (xy 274.554102 -406.762677) (xy 274.526806 -406.714042)
			(xy 274.506883 -406.661951) (xy 274.494757 -406.607514) (xy 274.490686 -406.551892) (xy 238.276892 -406.551892)
			(xy 238.276892 -406.943052) (xy 278.739598 -406.943052) (xy 278.743669 -406.88743) (xy 278.755795 -406.832993)
			(xy 278.775718 -406.780902) (xy 278.803014 -406.732267) (xy 278.8371 -406.688124) (xy 278.877249 -406.649415)
			(xy 278.922607 -406.616964) (xy 278.972207 -406.591463) (xy 279.024991 -406.573456) (xy 279.079834 -406.563326)
			(xy 279.135568 -406.561289) (xy 279.191005 -406.567389) (xy 279.244962 -406.581495) (xy 279.296291 -406.603307)
			(xy 279.343897 -406.632361) (xy 279.386765 -406.668036) (xy 279.423982 -406.709573) (xy 279.454755 -406.756086)
			(xy 279.478427 -406.806583) (xy 279.494495 -406.85999) (xy 279.502615 -406.915166) (xy 279.503124 -406.943052)
			(xy 279.502615 -406.970938) (xy 279.494495 -407.026114) (xy 279.478427 -407.079521) (xy 279.454755 -407.130018)
			(xy 279.423982 -407.176531) (xy 279.386765 -407.218068) (xy 279.343897 -407.253743) (xy 279.296291 -407.282797)
			(xy 279.244962 -407.304609) (xy 279.205567 -407.314908) (xy 280.953462 -407.314908) (xy 280.957533 -407.259286)
			(xy 280.969659 -407.204849) (xy 280.989582 -407.152758) (xy 281.016878 -407.104123) (xy 281.050964 -407.05998)
			(xy 281.091113 -407.021271) (xy 281.136471 -406.98882) (xy 281.186071 -406.963319) (xy 281.238855 -406.945312)
			(xy 281.293698 -406.935182) (xy 281.349432 -406.933145) (xy 281.404869 -406.939245) (xy 281.458826 -406.953351)
			(xy 281.510155 -406.975163) (xy 281.557761 -407.004217) (xy 281.600629 -407.039892) (xy 281.637846 -407.081429)
			(xy 281.668619 -407.127942) (xy 281.692291 -407.178439) (xy 281.708359 -407.231846) (xy 281.716479 -407.287022)
			(xy 281.716988 -407.314908) (xy 281.716479 -407.342794) (xy 281.708359 -407.39797) (xy 281.692291 -407.451377)
			(xy 281.668619 -407.501874) (xy 281.637846 -407.548387) (xy 281.600629 -407.589924) (xy 281.557761 -407.625599)
			(xy 281.510155 -407.654653) (xy 281.458826 -407.676465) (xy 281.404869 -407.690571) (xy 281.349432 -407.696671)
			(xy 281.293698 -407.694634) (xy 281.238855 -407.684504) (xy 281.186071 -407.666497) (xy 281.136471 -407.640996)
			(xy 281.091113 -407.608545) (xy 281.050964 -407.569836) (xy 281.016878 -407.525693) (xy 280.989582 -407.477058)
			(xy 280.969659 -407.424967) (xy 280.957533 -407.37053) (xy 280.953462 -407.314908) (xy 279.205567 -407.314908)
			(xy 279.191005 -407.318715) (xy 279.135568 -407.324815) (xy 279.079834 -407.322778) (xy 279.024991 -407.312648)
			(xy 278.972207 -407.294641) (xy 278.922607 -407.26914) (xy 278.877249 -407.236689) (xy 278.8371 -407.19798)
			(xy 278.803014 -407.153837) (xy 278.775718 -407.105202) (xy 278.755795 -407.053111) (xy 278.743669 -406.998674)
			(xy 278.739598 -406.943052) (xy 238.276892 -406.943052) (xy 238.276892 -408.165046) (xy 275.975316 -408.165046)
			(xy 275.979387 -408.109424) (xy 275.991513 -408.054987) (xy 276.011436 -408.002896) (xy 276.038732 -407.954261)
			(xy 276.072818 -407.910118) (xy 276.112967 -407.871409) (xy 276.158325 -407.838958) (xy 276.207925 -407.813457)
			(xy 276.260709 -407.79545) (xy 276.315552 -407.78532) (xy 276.371286 -407.783283) (xy 276.426723 -407.789383)
			(xy 276.48068 -407.803489) (xy 276.532009 -407.825301) (xy 276.579615 -407.854355) (xy 276.622483 -407.89003)
			(xy 276.6597 -407.931567) (xy 276.690473 -407.97808) (xy 276.714145 -408.028577) (xy 276.730213 -408.081984)
			(xy 276.738333 -408.13716) (xy 276.738842 -408.165046) (xy 276.738333 -408.192932) (xy 276.730213 -408.248108)
			(xy 276.714145 -408.301515) (xy 276.690473 -408.352012) (xy 276.6597 -408.398525) (xy 276.622483 -408.440062)
			(xy 276.579615 -408.475737) (xy 276.532009 -408.504791) (xy 276.48068 -408.526603) (xy 276.426723 -408.540709)
			(xy 276.371286 -408.546809) (xy 276.315552 -408.544772) (xy 276.260709 -408.534642) (xy 276.207925 -408.516635)
			(xy 276.158325 -408.491134) (xy 276.112967 -408.458683) (xy 276.072818 -408.419974) (xy 276.038732 -408.375831)
			(xy 276.011436 -408.327196) (xy 275.991513 -408.275105) (xy 275.979387 -408.220668) (xy 275.975316 -408.165046)
			(xy 238.276892 -408.165046) (xy 238.276892 -410.136086) (xy 279.512266 -410.136086) (xy 279.516337 -410.080464)
			(xy 279.528463 -410.026027) (xy 279.548386 -409.973936) (xy 279.575682 -409.925301) (xy 279.609768 -409.881158)
			(xy 279.649917 -409.842449) (xy 279.695275 -409.809998) (xy 279.744875 -409.784497) (xy 279.797659 -409.76649)
			(xy 279.852502 -409.75636) (xy 279.908236 -409.754323) (xy 279.963673 -409.760423) (xy 280.01763 -409.774529)
			(xy 280.068959 -409.796341) (xy 280.116565 -409.825395) (xy 280.159433 -409.86107) (xy 280.19665 -409.902607)
			(xy 280.227423 -409.94912) (xy 280.251095 -409.999617) (xy 280.267163 -410.053024) (xy 280.275283 -410.1082)
			(xy 280.275792 -410.136086) (xy 280.275283 -410.163972) (xy 280.267163 -410.219148) (xy 280.251095 -410.272555)
			(xy 280.227423 -410.323052) (xy 280.19665 -410.369565) (xy 280.159433 -410.411102) (xy 280.116565 -410.446777)
			(xy 280.068959 -410.475831) (xy 280.01763 -410.497643) (xy 279.963673 -410.511749) (xy 279.908236 -410.517849)
			(xy 279.852502 -410.515812) (xy 279.797659 -410.505682) (xy 279.744875 -410.487675) (xy 279.695275 -410.462174)
			(xy 279.649917 -410.429723) (xy 279.609768 -410.391014) (xy 279.575682 -410.346871) (xy 279.548386 -410.298236)
			(xy 279.528463 -410.246145) (xy 279.516337 -410.191708) (xy 279.512266 -410.136086) (xy 238.276892 -410.136086)
			(xy 238.276892 -413.657288) (xy 238.277312 -413.667359) (xy 238.285023 -413.685968) (xy 238.291878 -413.693356)
			(xy 238.371634 -413.773112) (xy 275.328378 -413.773112) (xy 275.332449 -413.71749) (xy 275.344575 -413.663053)
			(xy 275.364498 -413.610962) (xy 275.391794 -413.562327) (xy 275.42588 -413.518184) (xy 275.466029 -413.479475)
			(xy 275.511387 -413.447024) (xy 275.560987 -413.421523) (xy 275.613771 -413.403516) (xy 275.668614 -413.393386)
			(xy 275.724348 -413.391349) (xy 275.779785 -413.397449) (xy 275.833742 -413.411555) (xy 275.885071 -413.433367)
			(xy 275.932677 -413.462421) (xy 275.975545 -413.498096) (xy 276.012762 -413.539633) (xy 276.043535 -413.586146)
			(xy 276.044141 -413.587438) (xy 276.501604 -413.587438) (xy 276.505675 -413.531816) (xy 276.517801 -413.477379)
			(xy 276.537724 -413.425288) (xy 276.56502 -413.376653) (xy 276.599106 -413.33251) (xy 276.639255 -413.293801)
			(xy 276.684613 -413.26135) (xy 276.734213 -413.235849) (xy 276.786997 -413.217842) (xy 276.84184 -413.207712)
			(xy 276.897574 -413.205675) (xy 276.953011 -413.211775) (xy 277.006968 -413.225881) (xy 277.058297 -413.247693)
			(xy 277.105903 -413.276747) (xy 277.148771 -413.312422) (xy 277.185988 -413.353959) (xy 277.216761 -413.400472)
			(xy 277.240433 -413.450969) (xy 277.251535 -413.48787) (xy 278.240996 -413.48787) (xy 278.245067 -413.432248)
			(xy 278.257193 -413.377811) (xy 278.277116 -413.32572) (xy 278.304412 -413.277085) (xy 278.338498 -413.232942)
			(xy 278.378647 -413.194233) (xy 278.424005 -413.161782) (xy 278.473605 -413.136281) (xy 278.526389 -413.118274)
			(xy 278.581232 -413.108144) (xy 278.636966 -413.106107) (xy 278.692403 -413.112207) (xy 278.74636 -413.126313)
			(xy 278.797689 -413.148125) (xy 278.845295 -413.177179) (xy 278.888163 -413.212854) (xy 278.92538 -413.254391)
			(xy 278.956153 -413.300904) (xy 278.979825 -413.351401) (xy 278.995893 -413.404808) (xy 279.004013 -413.459984)
			(xy 279.004522 -413.48787) (xy 279.004013 -413.515756) (xy 278.995893 -413.570932) (xy 278.979825 -413.624339)
			(xy 278.956153 -413.674836) (xy 278.92538 -413.721349) (xy 278.888163 -413.762886) (xy 278.845295 -413.798561)
			(xy 278.797689 -413.827615) (xy 278.74636 -413.849427) (xy 278.692403 -413.863533) (xy 278.636966 -413.869633)
			(xy 278.581232 -413.867596) (xy 278.526389 -413.857466) (xy 278.473605 -413.839459) (xy 278.424005 -413.813958)
			(xy 278.378647 -413.781507) (xy 278.338498 -413.742798) (xy 278.304412 -413.698655) (xy 278.277116 -413.65002)
			(xy 278.257193 -413.597929) (xy 278.245067 -413.543492) (xy 278.240996 -413.48787) (xy 277.251535 -413.48787)
			(xy 277.256501 -413.504376) (xy 277.264621 -413.559552) (xy 277.26513 -413.587438) (xy 277.264621 -413.615324)
			(xy 277.256501 -413.6705) (xy 277.240433 -413.723907) (xy 277.216761 -413.774404) (xy 277.185988 -413.820917)
			(xy 277.148771 -413.862454) (xy 277.127327 -413.8803) (xy 280.408378 -413.8803) (xy 280.412449 -413.824678)
			(xy 280.424575 -413.770241) (xy 280.444498 -413.71815) (xy 280.471794 -413.669515) (xy 280.50588 -413.625372)
			(xy 280.546029 -413.586663) (xy 280.591387 -413.554212) (xy 280.640987 -413.528711) (xy 280.693771 -413.510704)
			(xy 280.748614 -413.500574) (xy 280.804348 -413.498537) (xy 280.859785 -413.504637) (xy 280.913742 -413.518743)
			(xy 280.965071 -413.540555) (xy 281.012677 -413.569609) (xy 281.055545 -413.605284) (xy 281.092762 -413.646821)
			(xy 281.123535 -413.693334) (xy 281.147207 -413.743831) (xy 281.163275 -413.797238) (xy 281.171395 -413.852414)
			(xy 281.171904 -413.8803) (xy 281.171395 -413.908186) (xy 281.163275 -413.963362) (xy 281.147207 -414.016769)
			(xy 281.123535 -414.067266) (xy 281.092762 -414.113779) (xy 281.055545 -414.155316) (xy 281.012677 -414.190991)
			(xy 280.965071 -414.220045) (xy 280.913742 -414.241857) (xy 280.859785 -414.255963) (xy 280.804348 -414.262063)
			(xy 280.748614 -414.260026) (xy 280.693771 -414.249896) (xy 280.640987 -414.231889) (xy 280.591387 -414.206388)
			(xy 280.546029 -414.173937) (xy 280.50588 -414.135228) (xy 280.471794 -414.091085) (xy 280.444498 -414.04245)
			(xy 280.424575 -413.990359) (xy 280.412449 -413.935922) (xy 280.408378 -413.8803) (xy 277.127327 -413.8803)
			(xy 277.105903 -413.898129) (xy 277.058297 -413.927183) (xy 277.006968 -413.948995) (xy 276.953011 -413.963101)
			(xy 276.897574 -413.969201) (xy 276.84184 -413.967164) (xy 276.786997 -413.957034) (xy 276.734213 -413.939027)
			(xy 276.684613 -413.913526) (xy 276.639255 -413.881075) (xy 276.599106 -413.842366) (xy 276.56502 -413.798223)
			(xy 276.537724 -413.749588) (xy 276.517801 -413.697497) (xy 276.505675 -413.64306) (xy 276.501604 -413.587438)
			(xy 276.044141 -413.587438) (xy 276.067207 -413.636643) (xy 276.083275 -413.69005) (xy 276.091395 -413.745226)
			(xy 276.091904 -413.773112) (xy 276.091395 -413.800998) (xy 276.083275 -413.856174) (xy 276.067207 -413.909581)
			(xy 276.043535 -413.960078) (xy 276.012762 -414.006591) (xy 275.975545 -414.048128) (xy 275.932677 -414.083803)
			(xy 275.885071 -414.112857) (xy 275.833742 -414.134669) (xy 275.779785 -414.148775) (xy 275.724348 -414.154875)
			(xy 275.668614 -414.152838) (xy 275.613771 -414.142708) (xy 275.560987 -414.124701) (xy 275.511387 -414.0992)
			(xy 275.466029 -414.066749) (xy 275.42588 -414.02804) (xy 275.391794 -413.983897) (xy 275.364498 -413.935262)
			(xy 275.344575 -413.883171) (xy 275.332449 -413.828734) (xy 275.328378 -413.773112) (xy 238.371634 -413.773112)
			(xy 239.233964 -414.635442) (xy 239.241363 -414.642285) (xy 239.259962 -414.650005) (xy 239.270032 -414.650428)
			(xy 263.550146 -414.650428) (xy 263.560213 -414.649997) (xy 263.578808 -414.642274) (xy 263.586214 -414.635442)
			(xy 272.808954 -414.635442) (xy 272.819019 -414.635876) (xy 272.837605 -414.643609) (xy 272.845022 -414.650428)
			(xy 274.765516 -416.570922) (xy 274.772912 -416.577774) (xy 274.791511 -416.585515) (xy 274.801584 -416.585908)
		)
		(stroke
			(width 0)
			(type solid)
		)
		(fill yes)
		(layer "In9.Cu")
		(net "GND")
	)
	(gr_poly
		(pts
			(xy 140.83284 -51.393344) (xy 140.842076 -51.392954) (xy 140.859353 -51.386418) (xy 140.873184 -51.374175)
			(xy 140.877798 -51.366166) (xy 140.919454 -51.286664) (xy 140.92336 -51.278382) (xy 140.925635 -51.260225)
			(xy 140.92142 -51.242418) (xy 140.91666 -51.234594) (xy 140.916406 -51.23434) (xy 140.90091 -51.2107)
			(xy 140.87631 -51.159811) (xy 140.85948 -51.105851) (xy 140.850789 -51.05) (xy 140.850112 -51.021742)
			(xy 140.850112 -51.01463) (xy 140.850924 -50.987604) (xy 140.859234 -50.934177) (xy 140.875003 -50.882459)
			(xy 140.897915 -50.833486) (xy 140.927512 -50.788237) (xy 140.963201 -50.74762) (xy 141.004266 -50.712448)
			(xy 141.049885 -50.683426) (xy 141.099145 -50.661135) (xy 141.151059 -50.646021) (xy 141.204586 -50.638388)
			(xy 141.258654 -50.638388) (xy 141.312181 -50.646021) (xy 141.364095 -50.661135) (xy 141.413355 -50.683426)
			(xy 141.458974 -50.712448) (xy 141.500039 -50.74762) (xy 141.535728 -50.788237) (xy 141.565325 -50.833486)
			(xy 141.588237 -50.882459) (xy 141.604006 -50.934177) (xy 141.612316 -50.987604) (xy 141.613128 -51.01463)
			(xy 141.613128 -51.01971) (xy 141.61262 -51.048258) (xy 141.604105 -51.104717) (xy 141.587269 -51.159275)
			(xy 141.562486 -51.210713) (xy 141.546834 -51.234594) (xy 141.538706 -51.246278) (xy 141.537182 -51.274218)
			(xy 141.585442 -51.366166) (xy 141.590092 -51.374146) (xy 141.603915 -51.386372) (xy 141.621173 -51.392909)
			(xy 141.6304 -51.393344) (xy 142.522448 -51.393344) (xy 142.532413 -51.392862) (xy 142.550846 -51.385284)
			(xy 142.558262 -51.378612) (xy 143.076422 -50.860452) (xy 143.080232 -50.852578) (xy 143.090138 -50.833528)
			(xy 143.090392 -50.833274) (xy 143.094202 -50.82667) (xy 143.097504 -50.821082) (xy 143.101568 -50.806858)
			(xy 143.10487 -50.795174) (xy 143.10487 -50.1904) (xy 143.104614 -50.182989) (xy 143.100348 -50.168793)
			(xy 143.096488 -50.16246) (xy 143.081655 -50.139007) (xy 143.058197 -50.088717) (xy 143.042278 -50.035559)
			(xy 143.034232 -49.980654) (xy 143.034231 -49.925163) (xy 143.042274 -49.870257) (xy 143.058191 -49.817098)
			(xy 143.081647 -49.766808) (xy 143.096488 -49.74336) (xy 143.100351 -49.73703) (xy 143.104607 -49.722831)
			(xy 143.10487 -49.71542) (xy 143.10487 -49.1744) (xy 143.104614 -49.166989) (xy 143.100348 -49.152793)
			(xy 143.096488 -49.14646) (xy 143.081655 -49.123007) (xy 143.058197 -49.072717) (xy 143.042278 -49.019559)
			(xy 143.034232 -48.964654) (xy 143.034231 -48.909163) (xy 143.042274 -48.854257) (xy 143.058191 -48.801098)
			(xy 143.081647 -48.750808) (xy 143.096488 -48.72736) (xy 143.100351 -48.72103) (xy 143.104607 -48.706831)
			(xy 143.10487 -48.69942) (xy 143.10487 -47.629572) (xy 143.10233 -47.61865) (xy 143.099536 -47.613062)
			(xy 143.086811 -47.586292) (xy 143.068835 -47.529814) (xy 143.059738 -47.471246) (xy 143.059736 -47.411976)
			(xy 143.06883 -47.353407) (xy 143.086803 -47.296928) (xy 143.099536 -47.270162) (xy 143.10233 -47.264574)
			(xy 143.10487 -47.253652) (xy 143.10487 -46.1264) (xy 143.104614 -46.118989) (xy 143.100348 -46.104793)
			(xy 143.096488 -46.09846) (xy 143.081655 -46.075007) (xy 143.058197 -46.024717) (xy 143.042278 -45.971559)
			(xy 143.034232 -45.916654) (xy 143.034231 -45.861163) (xy 143.042274 -45.806257) (xy 143.058191 -45.753098)
			(xy 143.081647 -45.702808) (xy 143.096488 -45.67936) (xy 143.100351 -45.67303) (xy 143.104607 -45.658831)
			(xy 143.10487 -45.65142) (xy 143.10487 -45.1104) (xy 143.104614 -45.102989) (xy 143.100348 -45.088793)
			(xy 143.096488 -45.08246) (xy 143.081655 -45.059007) (xy 143.058197 -45.008717) (xy 143.042278 -44.955559)
			(xy 143.034232 -44.900654) (xy 143.034231 -44.845163) (xy 143.042274 -44.790257) (xy 143.058191 -44.737098)
			(xy 143.081647 -44.686808) (xy 143.096488 -44.66336) (xy 143.100351 -44.65703) (xy 143.104607 -44.642831)
			(xy 143.10487 -44.63542) (xy 143.10487 -44.0944) (xy 143.104614 -44.086989) (xy 143.100348 -44.072793)
			(xy 143.096488 -44.06646) (xy 143.081655 -44.043007) (xy 143.058197 -43.992717) (xy 143.042278 -43.939559)
			(xy 143.034232 -43.884654) (xy 143.034231 -43.829163) (xy 143.042274 -43.774257) (xy 143.058191 -43.721098)
			(xy 143.081647 -43.670808) (xy 143.096488 -43.64736) (xy 143.100351 -43.64103) (xy 143.104607 -43.626831)
			(xy 143.10487 -43.61942) (xy 143.10487 -43.0784) (xy 143.104614 -43.070989) (xy 143.100348 -43.056793)
			(xy 143.096488 -43.05046) (xy 143.081655 -43.027007) (xy 143.058197 -42.976717) (xy 143.042278 -42.923559)
			(xy 143.034232 -42.868654) (xy 143.034231 -42.813163) (xy 143.042274 -42.758257) (xy 143.058191 -42.705098)
			(xy 143.081647 -42.654808) (xy 143.096488 -42.63136) (xy 143.100351 -42.62503) (xy 143.104607 -42.610831)
			(xy 143.10487 -42.60342) (xy 143.10487 -41.423844) (xy 143.104468 -41.413989) (xy 143.097163 -41.395686)
			(xy 143.090646 -41.388284) (xy 143.075406 -41.37279) (xy 143.072315 -41.369738) (xy 143.065292 -41.36463)
			(xy 143.061436 -41.36263) (xy 143.03883 -41.351708) (xy 143.030448 -41.350692) (xy 143.003005 -41.346881)
			(xy 142.949539 -41.332359) (xy 142.898734 -41.310262) (xy 142.851657 -41.281052) (xy 142.809296 -41.245343)
			(xy 142.772543 -41.203886) (xy 142.742168 -41.157552) (xy 142.71881 -41.107313) (xy 142.70296 -41.054226)
			(xy 142.694951 -40.999404) (xy 142.694951 -40.944001) (xy 142.702959 -40.88918) (xy 142.718808 -40.836092)
			(xy 142.742165 -40.785853) (xy 142.772539 -40.739518) (xy 142.809292 -40.698061) (xy 142.851652 -40.662352)
			(xy 142.898729 -40.633141) (xy 142.949534 -40.611042) (xy 143.003 -40.59652) (xy 143.030448 -40.592756)
			(xy 143.03883 -40.59174) (xy 143.061436 -40.580818) (xy 143.065293 -40.57882) (xy 143.072314 -40.573709)
			(xy 143.075406 -40.570658) (xy 143.090646 -40.555164) (xy 143.097164 -40.547759) (xy 143.104484 -40.529461)
			(xy 143.10487 -40.519604) (xy 143.10487 -38.432232) (xy 143.104455 -38.422209) (xy 143.09679 -38.403686)
			(xy 143.082616 -38.389511) (xy 143.064093 -38.381845) (xy 143.05407 -38.381432) (xy 141.384274 -38.381432)
			(xy 141.375139 -38.381819) (xy 141.358035 -38.388241) (xy 141.344274 -38.40026) (xy 141.33957 -38.408102)
			(xy 141.297406 -38.486842) (xy 141.294391 -38.492876) (xy 141.291308 -38.506004) (xy 141.29131 -38.51275)
			(xy 141.291818 -38.527228) (xy 141.299692 -38.539166) (xy 141.314823 -38.562786) (xy 141.338743 -38.613523)
			(xy 141.354985 -38.667213) (xy 141.363197 -38.722702) (xy 141.3637 -38.750748) (xy 141.363211 -38.777997)
			(xy 141.355449 -38.831939) (xy 141.340089 -38.884227) (xy 141.317445 -38.933798) (xy 141.287978 -38.979642)
			(xy 141.252286 -39.020826) (xy 141.211097 -39.056511) (xy 141.165249 -39.085972) (xy 141.115675 -39.108609)
			(xy 141.063384 -39.123961) (xy 141.009441 -39.131715) (xy 140.982192 -39.132256) (xy 140.95389 -39.131741)
			(xy 140.897907 -39.12338) (xy 140.843772 -39.106841) (xy 140.792675 -39.082489) (xy 140.745734 -39.050856)
			(xy 140.70398 -39.012638) (xy 140.668329 -38.968671) (xy 140.653516 -38.94455) (xy 140.646912 -38.933374)
			(xy 140.625322 -38.920166) (xy 140.58011 -38.917626) (xy 140.515848 -38.913816) (xy 140.492988 -38.92423)
			(xy 140.485368 -38.93439) (xy 140.46718 -38.957269) (xy 140.425027 -38.99775) (xy 140.377195 -39.031333)
			(xy 140.324803 -39.057231) (xy 140.269075 -39.07484) (xy 140.211314 -39.083748) (xy 140.182092 -39.08425)
			(xy 140.15484 -39.083764) (xy 140.100891 -39.076006) (xy 140.048595 -39.060651) (xy 139.999016 -39.03801)
			(xy 139.953163 -39.008544) (xy 139.911971 -38.972853) (xy 139.876276 -38.931664) (xy 139.846806 -38.885814)
			(xy 139.824161 -38.836237) (xy 139.808801 -38.783942) (xy 139.801039 -38.729994) (xy 139.800584 -38.702742)
			(xy 139.801143 -38.672656) (xy 139.810588 -38.613231) (xy 139.829265 -38.556033) (xy 139.842494 -38.529006)
			(xy 139.84859 -38.517068) (xy 139.847574 -38.490906) (xy 139.79525 -38.405562) (xy 139.790418 -38.398398)
			(xy 139.776977 -38.387557) (xy 139.760703 -38.381781) (xy 139.75207 -38.381432) (xy 137.385298 -38.381432)
			(xy 137.376443 -38.381858) (xy 137.359813 -38.387964) (xy 137.352786 -38.39337) (xy 137.141204 -38.604952)
			(xy 137.063734 -38.682168) (xy 137.039835 -38.705334) (xy 136.98703 -38.745857) (xy 136.929387 -38.779138)
			(xy 136.867892 -38.804608) (xy 136.803597 -38.821831) (xy 136.737605 -38.830512) (xy 136.704324 -38.831012)
			(xy 135.088884 -38.831012) (xy 135.055606 -38.830467) (xy 134.98962 -38.821781) (xy 134.925332 -38.804558)
			(xy 134.86384 -38.779093) (xy 134.806198 -38.745822) (xy 134.753389 -38.705314) (xy 134.729474 -38.682168)
			(xy 133.881876 -37.83457) (xy 133.858711 -37.81067) (xy 133.818192 -37.757866) (xy 133.784915 -37.700222)
			(xy 133.75945 -37.638726) (xy 133.742234 -37.574432) (xy 133.73356 -37.50844) (xy 133.733032 -37.47516)
			(xy 133.733059 -37.463333) (xy 133.734075 -37.439701) (xy 133.735064 -37.427916) (xy 133.735318 -37.42563)
			(xy 133.735318 -37.42436) (xy 133.738896 -37.393445) (xy 133.752628 -37.332743) (xy 133.773666 -37.274171)
			(xy 133.801695 -37.218604) (xy 133.836296 -37.166873) (xy 133.876951 -37.119751) (xy 133.923053 -37.077943)
			(xy 133.973913 -37.042074) (xy 134.02877 -37.01268) (xy 134.086804 -36.9902) (xy 134.147148 -36.974971)
			(xy 134.208899 -36.96722) (xy 134.240016 -36.966652) (xy 134.241286 -36.966652) (xy 134.273519 -36.967151)
			(xy 134.337466 -36.975307) (xy 134.368794 -36.982908) (xy 134.401387 -36.991944) (xy 134.464019 -37.017475)
			(xy 134.522708 -37.051093) (xy 134.576416 -37.092203) (xy 134.600696 -37.11575) (xy 135.284464 -37.799518)
			(xy 135.291862 -37.806363) (xy 135.310461 -37.814087) (xy 135.320532 -37.814504) (xy 135.949944 -37.814504)
			(xy 135.96069 -37.81402) (xy 135.980288 -37.805197) (xy 135.98779 -37.797486) (xy 136.038336 -37.741352)
			(xy 136.044907 -37.733235) (xy 136.051469 -37.713432) (xy 136.051036 -37.702998) (xy 136.051036 -37.702236)
			(xy 136.05007 -37.692295) (xy 136.049054 -37.672346) (xy 136.049004 -37.662358) (xy 136.049493 -37.635109)
			(xy 136.057255 -37.581167) (xy 136.072613 -37.528878) (xy 136.095257 -37.479307) (xy 136.124725 -37.433462)
			(xy 136.160416 -37.392278) (xy 136.201606 -37.356592) (xy 136.247454 -37.327131) (xy 136.297028 -37.304495)
			(xy 136.349319 -37.289143) (xy 136.403263 -37.281389) (xy 136.430512 -37.28085) (xy 136.459564 -37.281395)
			(xy 136.516997 -37.290204) (xy 136.57243 -37.307618) (xy 136.624584 -37.333232) (xy 136.672252 -37.366457)
			(xy 136.714333 -37.406523) (xy 136.732518 -37.429186) (xy 136.738614 -37.43706) (xy 136.746996 -37.44214)
			(xy 136.751156 -37.444434) (xy 136.760104 -37.447625) (xy 136.764776 -37.44849) (xy 136.833102 -37.459666)
			(xy 136.842675 -37.460793) (xy 136.861471 -37.456597) (xy 136.869678 -37.451538) (xy 136.869932 -37.451284)
			(xy 136.897618 -37.433232) (xy 136.956737 -37.403679) (xy 136.987788 -37.392356) (xy 137.014618 -37.38349)
			(xy 137.069742 -37.371055) (xy 137.125903 -37.364791) (xy 137.154158 -37.364416) (xy 143.05407 -37.364416)
			(xy 143.064096 -37.364002) (xy 143.082626 -37.356338) (xy 143.096812 -37.342165) (xy 143.104493 -37.323642)
			(xy 143.10487 -37.313616) (xy 143.10487 -31.63316) (xy 143.104108 -31.629096) (xy 143.101825 -31.613896)
			(xy 143.099408 -31.583252) (xy 143.099282 -31.567882) (xy 143.099402 -31.552512) (xy 143.10182 -31.521867)
			(xy 143.104108 -31.506668) (xy 143.10487 -31.502604) (xy 143.10487 -30.681168) (xy 143.104748 -30.676355)
			(xy 143.102959 -30.666897) (xy 143.101314 -30.662372) (xy 143.091662 -30.637734) (xy 143.085566 -30.630876)
			(xy 143.067446 -30.609786) (xy 143.036869 -30.563345) (xy 143.013353 -30.512961) (xy 142.997394 -30.459698)
			(xy 142.989331 -30.404683) (xy 142.989333 -30.349081) (xy 142.997402 -30.294067) (xy 143.013365 -30.240806)
			(xy 143.036887 -30.190423) (xy 143.067467 -30.143986) (xy 143.085566 -30.122876) (xy 143.091662 -30.116018)
			(xy 143.101314 -30.09138) (xy 143.103004 -30.086867) (xy 143.104802 -30.077402) (xy 143.10487 -30.072584)
			(xy 143.10487 -29.909008) (xy 143.091154 -29.874972) (xy 143.085312 -29.868368) (xy 143.067267 -29.847301)
			(xy 143.036828 -29.800932) (xy 143.013423 -29.750643) (xy 142.997547 -29.697496) (xy 142.989533 -29.64261)
			(xy 142.989046 -29.614876) (xy 142.989046 -29.614368) (xy 142.989653 -29.583501) (xy 142.99962 -29.522577)
			(xy 143.019274 -29.464054) (xy 143.0481 -29.409463) (xy 143.066262 -29.384498) (xy 143.070932 -29.377758)
			(xy 143.076117 -29.362212) (xy 143.076422 -29.354018) (xy 143.076422 -29.062934) (xy 143.076118 -29.054738)
			(xy 143.070947 -29.039185) (xy 143.066262 -29.032454) (xy 143.05006 -29.01024) (xy 143.023524 -28.962087)
			(xy 143.004168 -28.910625) (xy 142.992394 -28.85692) (xy 142.988444 -28.802081) (xy 142.992399 -28.747242)
			(xy 143.004179 -28.693538) (xy 143.02354 -28.642078) (xy 143.050081 -28.593928) (xy 143.066262 -28.571698)
			(xy 143.070932 -28.564958) (xy 143.076117 -28.549412) (xy 143.076422 -28.541218) (xy 143.076422 -28.38323)
			(xy 143.07664 -28.376189) (xy 143.080497 -28.362647) (xy 143.084042 -28.35656) (xy 143.096996 -28.33624)
			(xy 143.100633 -28.330041) (xy 143.104633 -28.316245) (xy 143.10487 -28.309062) (xy 143.10487 -27.872436)
			(xy 143.104435 -27.862372) (xy 143.0967 -27.843787) (xy 143.089884 -27.836368) (xy 142.850362 -27.596846)
			(xy 142.842964 -27.590001) (xy 142.824365 -27.582273) (xy 142.814294 -27.58186) (xy 133.499606 -27.58186)
			(xy 133.487273 -27.582443) (xy 133.465422 -27.593878) (xy 133.45795 -27.603704) (xy 133.44079 -27.627665)
			(xy 133.401284 -27.6714) (xy 133.356493 -27.709706) (xy 133.307158 -27.74195) (xy 133.254095 -27.767598)
			(xy 133.19818 -27.786227) (xy 133.140337 -27.797529) (xy 133.081522 -27.801317) (xy 133.022707 -27.797529)
			(xy 132.964864 -27.786227) (xy 132.908949 -27.767598) (xy 132.855886 -27.74195) (xy 132.806551 -27.709706)
			(xy 132.76176 -27.6714) (xy 132.722254 -27.627665) (xy 132.705094 -27.603704) (xy 132.697483 -27.594031)
			(xy 132.675723 -27.582608) (xy 132.663438 -27.58186) (xy 128.528064 -27.58186) (xy 128.517998 -27.582291)
			(xy 128.499409 -27.590022) (xy 128.491996 -27.596846) (xy 128.22301 -27.865832) (xy 128.21666 -27.877262)
			(xy 128.214882 -27.88412) (xy 128.207156 -27.912349) (xy 128.184243 -27.966201) (xy 128.153375 -28.015922)
			(xy 128.115277 -28.060347) (xy 128.070842 -28.098434) (xy 128.021112 -28.129289) (xy 127.967254 -28.152188)
			(xy 127.939038 -28.159964) (xy 127.93218 -28.161742) (xy 127.92075 -28.168092) (xy 127.905002 -28.18384)
			(xy 127.898162 -28.191241) (xy 127.890441 -28.209839) (xy 127.890016 -28.219908) (xy 127.890016 -29.114242)
			(xy 134.94766 -29.114242) (xy 134.94766 -28.250642) (xy 134.94815 -28.220674) (xy 134.955973 -28.161252)
			(xy 134.971486 -28.103359) (xy 134.994422 -28.047986) (xy 135.024389 -27.99608) (xy 135.060876 -27.94853)
			(xy 135.103256 -27.90615) (xy 135.150806 -27.869663) (xy 135.202712 -27.839696) (xy 135.258085 -27.81676)
			(xy 135.315978 -27.801247) (xy 135.3754 -27.793424) (xy 135.435336 -27.793424) (xy 135.494758 -27.801247)
			(xy 135.552651 -27.81676) (xy 135.608024 -27.839696) (xy 135.65993 -27.869663) (xy 135.70748 -27.90615)
			(xy 135.74986 -27.94853) (xy 135.786347 -27.99608) (xy 135.816314 -28.047986) (xy 135.83925 -28.103359)
			(xy 135.854763 -28.161252) (xy 135.862586 -28.220674) (xy 135.863076 -28.250642) (xy 135.863076 -28.469082)
			(xy 139.852652 -28.469082) (xy 139.856723 -28.41346) (xy 139.868849 -28.359023) (xy 139.888772 -28.306932)
			(xy 139.916068 -28.258297) (xy 139.950154 -28.214154) (xy 139.990303 -28.175445) (xy 140.035661 -28.142994)
			(xy 140.085261 -28.117493) (xy 140.138045 -28.099486) (xy 140.192888 -28.089356) (xy 140.248622 -28.087319)
			(xy 140.304059 -28.093419) (xy 140.358016 -28.107525) (xy 140.409345 -28.129337) (xy 140.456951 -28.158391)
			(xy 140.499819 -28.194066) (xy 140.537036 -28.235603) (xy 140.567809 -28.282116) (xy 140.591481 -28.332613)
			(xy 140.607549 -28.38602) (xy 140.615669 -28.441196) (xy 140.616178 -28.469082) (xy 140.615669 -28.496968)
			(xy 140.607549 -28.552144) (xy 140.591481 -28.605551) (xy 140.567809 -28.656048) (xy 140.537036 -28.702561)
			(xy 140.499819 -28.744098) (xy 140.456951 -28.779773) (xy 140.409345 -28.808827) (xy 140.358016 -28.830639)
			(xy 140.304059 -28.844745) (xy 140.248622 -28.850845) (xy 140.192888 -28.848808) (xy 140.138045 -28.838678)
			(xy 140.085261 -28.820671) (xy 140.035661 -28.79517) (xy 139.990303 -28.762719) (xy 139.950154 -28.72401)
			(xy 139.916068 -28.679867) (xy 139.888772 -28.631232) (xy 139.868849 -28.579141) (xy 139.856723 -28.524704)
			(xy 139.852652 -28.469082) (xy 135.863076 -28.469082) (xy 135.863076 -29.114242) (xy 135.862586 -29.14421)
			(xy 135.854763 -29.203632) (xy 135.83925 -29.261525) (xy 135.816314 -29.316898) (xy 135.786347 -29.368804)
			(xy 135.74986 -29.416354) (xy 135.70748 -29.458734) (xy 135.65993 -29.495221) (xy 135.608024 -29.525188)
			(xy 135.552651 -29.548124) (xy 135.494758 -29.563637) (xy 135.435336 -29.57146) (xy 135.3754 -29.57146)
			(xy 135.315978 -29.563637) (xy 135.258085 -29.548124) (xy 135.202712 -29.525188) (xy 135.150806 -29.495221)
			(xy 135.103256 -29.458734) (xy 135.060876 -29.416354) (xy 135.024389 -29.368804) (xy 134.994422 -29.316898)
			(xy 134.971486 -29.261525) (xy 134.955973 -29.203632) (xy 134.94815 -29.14421) (xy 134.94766 -29.114242)
			(xy 127.890016 -29.114242) (xy 127.890016 -29.186378) (xy 127.912114 -29.214064) (xy 127.92964 -29.217874)
			(xy 127.955936 -29.224333) (xy 128.006513 -29.243672) (xy 128.053848 -29.269966) (xy 128.09699 -29.302688)
			(xy 128.135074 -29.341179) (xy 128.167335 -29.384667) (xy 128.193125 -29.432279) (xy 128.211925 -29.483058)
			(xy 128.223358 -29.535985) (xy 128.227196 -29.589996) (xy 128.223359 -29.644008) (xy 128.211927 -29.696935)
			(xy 128.193128 -29.747715) (xy 128.167339 -29.795327) (xy 128.135079 -29.838816) (xy 128.096996 -29.877308)
			(xy 128.053854 -29.91003) (xy 128.006519 -29.936325) (xy 127.955943 -29.955665) (xy 127.92964 -29.962094)
			(xy 127.912114 -29.965904) (xy 127.890016 -29.99359) (xy 127.890016 -30.92069) (xy 137.589768 -30.92069)
			(xy 137.589768 -30.05709) (xy 137.590258 -30.027122) (xy 137.598081 -29.9677) (xy 137.613594 -29.909807)
			(xy 137.63653 -29.854434) (xy 137.666497 -29.802528) (xy 137.702984 -29.754978) (xy 137.745364 -29.712598)
			(xy 137.792914 -29.676111) (xy 137.84482 -29.646144) (xy 137.900193 -29.623208) (xy 137.958086 -29.607695)
			(xy 138.017508 -29.599872) (xy 138.077444 -29.599872) (xy 138.136866 -29.607695) (xy 138.194759 -29.623208)
			(xy 138.250132 -29.646144) (xy 138.302038 -29.676111) (xy 138.349588 -29.712598) (xy 138.391968 -29.754978)
			(xy 138.428455 -29.802528) (xy 138.458422 -29.854434) (xy 138.481358 -29.909807) (xy 138.496871 -29.9677)
			(xy 138.504694 -30.027122) (xy 138.505184 -30.05709) (xy 138.505184 -30.92069) (xy 138.504694 -30.950658)
			(xy 138.496871 -31.01008) (xy 138.481358 -31.067973) (xy 138.458422 -31.123346) (xy 138.428455 -31.175252)
			(xy 138.391968 -31.222802) (xy 138.349588 -31.265182) (xy 138.302038 -31.301669) (xy 138.250132 -31.331636)
			(xy 138.194759 -31.354572) (xy 138.136866 -31.370085) (xy 138.077444 -31.377908) (xy 138.017508 -31.377908)
			(xy 137.958086 -31.370085) (xy 137.900193 -31.354572) (xy 137.84482 -31.331636) (xy 137.792914 -31.301669)
			(xy 137.745364 -31.265182) (xy 137.702984 -31.222802) (xy 137.666497 -31.175252) (xy 137.63653 -31.123346)
			(xy 137.613594 -31.067973) (xy 137.598081 -31.01008) (xy 137.590258 -30.950658) (xy 137.589768 -30.92069)
			(xy 127.890016 -30.92069) (xy 127.890016 -32.714184) (xy 134.94766 -32.714184) (xy 134.94766 -31.850584)
			(xy 134.94815 -31.820616) (xy 134.955973 -31.761194) (xy 134.971486 -31.703301) (xy 134.994422 -31.647928)
			(xy 135.024389 -31.596022) (xy 135.060876 -31.548472) (xy 135.103256 -31.506092) (xy 135.150806 -31.469605)
			(xy 135.202712 -31.439638) (xy 135.258085 -31.416702) (xy 135.315978 -31.401189) (xy 135.3754 -31.393366)
			(xy 135.435336 -31.393366) (xy 135.494758 -31.401189) (xy 135.552651 -31.416702) (xy 135.608024 -31.439638)
			(xy 135.65993 -31.469605) (xy 135.70748 -31.506092) (xy 135.74986 -31.548472) (xy 135.786347 -31.596022)
			(xy 135.816314 -31.647928) (xy 135.83925 -31.703301) (xy 135.854763 -31.761194) (xy 135.862586 -31.820616)
			(xy 135.863076 -31.850584) (xy 135.863076 -32.714184) (xy 135.862586 -32.744152) (xy 135.854763 -32.803574)
			(xy 135.83925 -32.861467) (xy 135.816314 -32.91684) (xy 135.786347 -32.968746) (xy 135.74986 -33.016296)
			(xy 135.70748 -33.058676) (xy 135.65993 -33.095163) (xy 135.608024 -33.12513) (xy 135.552651 -33.148066)
			(xy 135.494758 -33.163579) (xy 135.435336 -33.171402) (xy 135.3754 -33.171402) (xy 135.315978 -33.163579)
			(xy 135.258085 -33.148066) (xy 135.202712 -33.12513) (xy 135.150806 -33.095163) (xy 135.103256 -33.058676)
			(xy 135.060876 -33.016296) (xy 135.024389 -32.968746) (xy 134.994422 -32.91684) (xy 134.971486 -32.861467)
			(xy 134.955973 -32.803574) (xy 134.94815 -32.744152) (xy 134.94766 -32.714184) (xy 127.890016 -32.714184)
			(xy 127.890016 -34.520886) (xy 137.589768 -34.520886) (xy 137.589768 -33.657286) (xy 137.590258 -33.627318)
			(xy 137.598081 -33.567896) (xy 137.613594 -33.510003) (xy 137.63653 -33.45463) (xy 137.666497 -33.402724)
			(xy 137.702984 -33.355174) (xy 137.745364 -33.312794) (xy 137.792914 -33.276307) (xy 137.84482 -33.24634)
			(xy 137.900193 -33.223404) (xy 137.958086 -33.207891) (xy 138.017508 -33.200068) (xy 138.077444 -33.200068)
			(xy 138.136866 -33.207891) (xy 138.194759 -33.223404) (xy 138.250132 -33.24634) (xy 138.302038 -33.276307)
			(xy 138.349588 -33.312794) (xy 138.391968 -33.355174) (xy 138.428455 -33.402724) (xy 138.458422 -33.45463)
			(xy 138.481358 -33.510003) (xy 138.496871 -33.567896) (xy 138.504694 -33.627318) (xy 138.505184 -33.657286)
			(xy 138.505184 -34.520886) (xy 138.504694 -34.550854) (xy 138.496871 -34.610276) (xy 138.481358 -34.668169)
			(xy 138.458422 -34.723542) (xy 138.428455 -34.775448) (xy 138.391968 -34.822998) (xy 138.349588 -34.865378)
			(xy 138.302038 -34.901865) (xy 138.250132 -34.931832) (xy 138.194759 -34.954768) (xy 138.136866 -34.970281)
			(xy 138.077444 -34.978104) (xy 138.017508 -34.978104) (xy 137.958086 -34.970281) (xy 137.900193 -34.954768)
			(xy 137.84482 -34.931832) (xy 137.792914 -34.901865) (xy 137.745364 -34.865378) (xy 137.702984 -34.822998)
			(xy 137.666497 -34.775448) (xy 137.63653 -34.723542) (xy 137.613594 -34.668169) (xy 137.598081 -34.610276)
			(xy 137.590258 -34.550854) (xy 137.589768 -34.520886) (xy 127.890016 -34.520886) (xy 127.890016 -36.60013)
			(xy 128.098557 -36.60013) (xy 128.102561 -36.512245) (xy 128.114541 -36.425088) (xy 128.134396 -36.339381)
			(xy 128.161963 -36.255836) (xy 128.197013 -36.175143) (xy 128.239255 -36.097971) (xy 128.28834 -36.024961)
			(xy 128.343861 -35.956717) (xy 128.405358 -35.893804) (xy 128.47232 -35.836744) (xy 128.544194 -35.78601)
			(xy 128.620384 -35.742022) (xy 128.700258 -35.705144) (xy 128.783155 -35.675683) (xy 128.868387 -35.653881)
			(xy 128.955249 -35.639921) (xy 129.04302 -35.633917) (xy 129.130974 -35.63592) (xy 129.218381 -35.645912)
			(xy 129.304517 -35.663812) (xy 129.388669 -35.68947) (xy 129.470139 -35.722674) (xy 129.548252 -35.763148)
			(xy 129.62236 -35.810559) (xy 129.691851 -35.864512) (xy 129.704942 -35.876738) (xy 134.817356 -35.876738)
			(xy 134.821427 -35.821116) (xy 134.833553 -35.766679) (xy 134.853476 -35.714588) (xy 134.880772 -35.665953)
			(xy 134.914858 -35.62181) (xy 134.955007 -35.583101) (xy 135.000365 -35.55065) (xy 135.049965 -35.525149)
			(xy 135.102749 -35.507142) (xy 135.157592 -35.497012) (xy 135.213326 -35.494975) (xy 135.268763 -35.501075)
			(xy 135.32272 -35.515181) (xy 135.374049 -35.536993) (xy 135.421655 -35.566047) (xy 135.464523 -35.601722)
			(xy 135.50174 -35.643259) (xy 135.532513 -35.689772) (xy 135.556185 -35.740269) (xy 135.572253 -35.793676)
			(xy 135.580373 -35.848852) (xy 135.580882 -35.876738) (xy 138.888976 -35.876738) (xy 138.893047 -35.821116)
			(xy 138.905173 -35.766679) (xy 138.925096 -35.714588) (xy 138.952392 -35.665953) (xy 138.986478 -35.62181)
			(xy 139.026627 -35.583101) (xy 139.071985 -35.55065) (xy 139.121585 -35.525149) (xy 139.174369 -35.507142)
			(xy 139.229212 -35.497012) (xy 139.284946 -35.494975) (xy 139.340383 -35.501075) (xy 139.39434 -35.515181)
			(xy 139.445669 -35.536993) (xy 139.493275 -35.566047) (xy 139.536143 -35.601722) (xy 139.57336 -35.643259)
			(xy 139.604133 -35.689772) (xy 139.627805 -35.740269) (xy 139.643873 -35.793676) (xy 139.651993 -35.848852)
			(xy 139.652502 -35.876738) (xy 139.651993 -35.904624) (xy 139.643873 -35.9598) (xy 139.627805 -36.013207)
			(xy 139.604133 -36.063704) (xy 139.57336 -36.110217) (xy 139.536143 -36.151754) (xy 139.493275 -36.187429)
			(xy 139.445669 -36.216483) (xy 139.39434 -36.238295) (xy 139.340383 -36.252401) (xy 139.284946 -36.258501)
			(xy 139.229212 -36.256464) (xy 139.174369 -36.246334) (xy 139.121585 -36.228327) (xy 139.071985 -36.202826)
			(xy 139.026627 -36.170375) (xy 138.986478 -36.131666) (xy 138.952392 -36.087523) (xy 138.925096 -36.038888)
			(xy 138.905173 -35.986797) (xy 138.893047 -35.93236) (xy 138.888976 -35.876738) (xy 135.580882 -35.876738)
			(xy 135.580373 -35.904624) (xy 135.572253 -35.9598) (xy 135.556185 -36.013207) (xy 135.532513 -36.063704)
			(xy 135.50174 -36.110217) (xy 135.464523 -36.151754) (xy 135.421655 -36.187429) (xy 135.374049 -36.216483)
			(xy 135.32272 -36.238295) (xy 135.268763 -36.252401) (xy 135.213326 -36.258501) (xy 135.157592 -36.256464)
			(xy 135.102749 -36.246334) (xy 135.049965 -36.228327) (xy 135.000365 -36.202826) (xy 134.955007 -36.170375)
			(xy 134.914858 -36.131666) (xy 134.880772 -36.087523) (xy 134.853476 -36.038888) (xy 134.833553 -35.986797)
			(xy 134.821427 -35.93236) (xy 134.817356 -35.876738) (xy 129.704942 -35.876738) (xy 129.756147 -35.92456)
			(xy 129.814716 -35.990207) (xy 129.867073 -36.060907) (xy 129.912785 -36.136076) (xy 129.951471 -36.21509)
			(xy 129.982812 -36.297295) (xy 130.006547 -36.382009) (xy 130.022481 -36.46853) (xy 130.026264 -36.50996)
			(xy 136.713974 -36.50996) (xy 136.718045 -36.454338) (xy 136.730171 -36.399901) (xy 136.750094 -36.34781)
			(xy 136.77739 -36.299175) (xy 136.811476 -36.255032) (xy 136.851625 -36.216323) (xy 136.896983 -36.183872)
			(xy 136.946583 -36.158371) (xy 136.999367 -36.140364) (xy 137.05421 -36.130234) (xy 137.109944 -36.128197)
			(xy 137.165381 -36.134297) (xy 137.219338 -36.148403) (xy 137.270667 -36.170215) (xy 137.318273 -36.199269)
			(xy 137.361141 -36.234944) (xy 137.398358 -36.276481) (xy 137.429131 -36.322994) (xy 137.452803 -36.373491)
			(xy 137.468871 -36.426898) (xy 137.472796 -36.453572) (xy 140.028674 -36.453572) (xy 140.032745 -36.39795)
			(xy 140.044871 -36.343513) (xy 140.064794 -36.291422) (xy 140.09209 -36.242787) (xy 140.126176 -36.198644)
			(xy 140.166325 -36.159935) (xy 140.211683 -36.127484) (xy 140.261283 -36.101983) (xy 140.314067 -36.083976)
			(xy 140.36891 -36.073846) (xy 140.424644 -36.071809) (xy 140.480081 -36.077909) (xy 140.534038 -36.092015)
			(xy 140.585367 -36.113827) (xy 140.632973 -36.142881) (xy 140.675841 -36.178556) (xy 140.713058 -36.220093)
			(xy 140.743831 -36.266606) (xy 140.767503 -36.317103) (xy 140.783571 -36.37051) (xy 140.791691 -36.425686)
			(xy 140.7922 -36.453572) (xy 140.791691 -36.481458) (xy 140.783571 -36.536634) (xy 140.767503 -36.590041)
			(xy 140.743831 -36.640538) (xy 140.713058 -36.687051) (xy 140.675841 -36.728588) (xy 140.632973 -36.764263)
			(xy 140.585367 -36.793317) (xy 140.534038 -36.815129) (xy 140.480081 -36.829235) (xy 140.424644 -36.835335)
			(xy 140.36891 -36.833298) (xy 140.314067 -36.823168) (xy 140.261283 -36.805161) (xy 140.211683 -36.77966)
			(xy 140.166325 -36.747209) (xy 140.126176 -36.7085) (xy 140.09209 -36.664357) (xy 140.064794 -36.615722)
			(xy 140.044871 -36.563631) (xy 140.032745 -36.509194) (xy 140.028674 -36.453572) (xy 137.472796 -36.453572)
			(xy 137.476991 -36.482074) (xy 137.4775 -36.50996) (xy 137.476991 -36.537846) (xy 137.468871 -36.593022)
			(xy 137.452803 -36.646429) (xy 137.429131 -36.696926) (xy 137.398358 -36.743439) (xy 137.361141 -36.784976)
			(xy 137.318273 -36.820651) (xy 137.270667 -36.849705) (xy 137.219338 -36.871517) (xy 137.165381 -36.885623)
			(xy 137.109944 -36.891723) (xy 137.05421 -36.889686) (xy 136.999367 -36.879556) (xy 136.946583 -36.861549)
			(xy 136.896983 -36.836048) (xy 136.851625 -36.803597) (xy 136.811476 -36.764888) (xy 136.77739 -36.720745)
			(xy 136.750094 -36.67211) (xy 136.730171 -36.620019) (xy 136.718045 -36.565582) (xy 136.713974 -36.50996)
			(xy 130.026264 -36.50996) (xy 130.030481 -36.556142) (xy 130.030982 -36.60013) (xy 130.030481 -36.644118)
			(xy 130.022481 -36.73173) (xy 130.006547 -36.818251) (xy 129.982812 -36.902965) (xy 129.951471 -36.98517)
			(xy 129.912785 -37.064184) (xy 129.867073 -37.139353) (xy 129.814716 -37.210053) (xy 129.756147 -37.2757)
			(xy 129.691851 -37.335748) (xy 129.62236 -37.389701) (xy 129.548252 -37.437112) (xy 129.470139 -37.477586)
			(xy 129.388669 -37.51079) (xy 129.304517 -37.536448) (xy 129.218381 -37.554348) (xy 129.130974 -37.56434)
			(xy 129.04302 -37.566343) (xy 128.955249 -37.560339) (xy 128.868387 -37.546379) (xy 128.783155 -37.524577)
			(xy 128.700258 -37.495116) (xy 128.620384 -37.458238) (xy 128.544194 -37.41425) (xy 128.47232 -37.363516)
			(xy 128.405358 -37.306456) (xy 128.343861 -37.243543) (xy 128.28834 -37.175299) (xy 128.239255 -37.102289)
			(xy 128.197013 -37.025117) (xy 128.161963 -36.944424) (xy 128.134396 -36.860879) (xy 128.114541 -36.775172)
			(xy 128.102561 -36.688015) (xy 128.098557 -36.60013) (xy 127.890016 -36.60013) (xy 127.890016 -39.97198)
			(xy 141.995904 -39.97198) (xy 141.999975 -39.916358) (xy 142.012101 -39.861921) (xy 142.032024 -39.80983)
			(xy 142.05932 -39.761195) (xy 142.093406 -39.717052) (xy 142.133555 -39.678343) (xy 142.178913 -39.645892)
			(xy 142.228513 -39.620391) (xy 142.281297 -39.602384) (xy 142.33614 -39.592254) (xy 142.391874 -39.590217)
			(xy 142.447311 -39.596317) (xy 142.501268 -39.610423) (xy 142.552597 -39.632235) (xy 142.600203 -39.661289)
			(xy 142.643071 -39.696964) (xy 142.680288 -39.738501) (xy 142.711061 -39.785014) (xy 142.734733 -39.835511)
			(xy 142.750801 -39.888918) (xy 142.758921 -39.944094) (xy 142.75943 -39.97198) (xy 142.758921 -39.999866)
			(xy 142.750801 -40.055042) (xy 142.734733 -40.108449) (xy 142.711061 -40.158946) (xy 142.680288 -40.205459)
			(xy 142.643071 -40.246996) (xy 142.600203 -40.282671) (xy 142.552597 -40.311725) (xy 142.501268 -40.333537)
			(xy 142.447311 -40.347643) (xy 142.391874 -40.353743) (xy 142.33614 -40.351706) (xy 142.281297 -40.341576)
			(xy 142.228513 -40.323569) (xy 142.178913 -40.298068) (xy 142.133555 -40.265617) (xy 142.093406 -40.226908)
			(xy 142.05932 -40.182765) (xy 142.032024 -40.13413) (xy 142.012101 -40.082039) (xy 141.999975 -40.027602)
			(xy 141.995904 -39.97198) (xy 127.890016 -39.97198) (xy 127.890016 -40.452802) (xy 127.89044 -40.462872)
			(xy 127.898157 -40.481474) (xy 127.905002 -40.48887) (xy 128.124204 -40.708072) (xy 128.131601 -40.714921)
			(xy 128.1502 -40.722658) (xy 128.160272 -40.723058) (xy 137.18159 -40.723058) (xy 137.19166 -40.723481)
			(xy 137.210261 -40.731199) (xy 137.217658 -40.738044) (xy 138.158728 -41.679114) (xy 138.16558 -41.68651)
			(xy 138.173321 -41.705109) (xy 138.173714 -41.715182) (xy 138.173714 -43.85691) (xy 140.819884 -43.85691)
			(xy 140.823955 -43.801288) (xy 140.836081 -43.746851) (xy 140.856004 -43.69476) (xy 140.8833 -43.646125)
			(xy 140.917386 -43.601982) (xy 140.957535 -43.563273) (xy 141.002893 -43.530822) (xy 141.052493 -43.505321)
			(xy 141.105277 -43.487314) (xy 141.16012 -43.477184) (xy 141.215854 -43.475147) (xy 141.271291 -43.481247)
			(xy 141.325248 -43.495353) (xy 141.376577 -43.517165) (xy 141.424183 -43.546219) (xy 141.467051 -43.581894)
			(xy 141.504268 -43.623431) (xy 141.535041 -43.669944) (xy 141.558713 -43.720441) (xy 141.574781 -43.773848)
			(xy 141.582901 -43.829024) (xy 141.58341 -43.85691) (xy 141.582901 -43.884796) (xy 141.574781 -43.939972)
			(xy 141.558713 -43.993379) (xy 141.535041 -44.043876) (xy 141.504268 -44.090389) (xy 141.467051 -44.131926)
			(xy 141.424183 -44.167601) (xy 141.376577 -44.196655) (xy 141.325248 -44.218467) (xy 141.271291 -44.232573)
			(xy 141.215854 -44.238673) (xy 141.16012 -44.236636) (xy 141.105277 -44.226506) (xy 141.052493 -44.208499)
			(xy 141.002893 -44.182998) (xy 140.957535 -44.150547) (xy 140.917386 -44.111838) (xy 140.8833 -44.067695)
			(xy 140.856004 -44.01906) (xy 140.836081 -43.966969) (xy 140.823955 -43.912532) (xy 140.819884 -43.85691)
			(xy 138.173714 -43.85691) (xy 138.173714 -45.35424) (xy 140.803882 -45.35424) (xy 140.807953 -45.298618)
			(xy 140.820079 -45.244181) (xy 140.840002 -45.19209) (xy 140.867298 -45.143455) (xy 140.901384 -45.099312)
			(xy 140.941533 -45.060603) (xy 140.986891 -45.028152) (xy 141.036491 -45.002651) (xy 141.089275 -44.984644)
			(xy 141.144118 -44.974514) (xy 141.199852 -44.972477) (xy 141.255289 -44.978577) (xy 141.309246 -44.992683)
			(xy 141.360575 -45.014495) (xy 141.408181 -45.043549) (xy 141.451049 -45.079224) (xy 141.488266 -45.120761)
			(xy 141.519039 -45.167274) (xy 141.542711 -45.217771) (xy 141.558779 -45.271178) (xy 141.566899 -45.326354)
			(xy 141.567408 -45.35424) (xy 141.566899 -45.382126) (xy 141.558779 -45.437302) (xy 141.542711 -45.490709)
			(xy 141.519039 -45.541206) (xy 141.488266 -45.587719) (xy 141.451049 -45.629256) (xy 141.408181 -45.664931)
			(xy 141.360575 -45.693985) (xy 141.309246 -45.715797) (xy 141.255289 -45.729903) (xy 141.199852 -45.736003)
			(xy 141.144118 -45.733966) (xy 141.089275 -45.723836) (xy 141.036491 -45.705829) (xy 140.986891 -45.680328)
			(xy 140.941533 -45.647877) (xy 140.901384 -45.609168) (xy 140.867298 -45.565025) (xy 140.840002 -45.51639)
			(xy 140.820079 -45.464299) (xy 140.807953 -45.409862) (xy 140.803882 -45.35424) (xy 138.173714 -45.35424)
			(xy 138.173714 -46.693836) (xy 140.776452 -46.693836) (xy 140.776938 -46.666585) (xy 140.784694 -46.612637)
			(xy 140.800049 -46.560342) (xy 140.822691 -46.510765) (xy 140.852157 -46.464915) (xy 140.887848 -46.423724)
			(xy 140.929039 -46.388033) (xy 140.974889 -46.358567) (xy 141.024466 -46.335925) (xy 141.076761 -46.32057)
			(xy 141.130709 -46.312814) (xy 141.185211 -46.312814) (xy 141.239159 -46.32057) (xy 141.291454 -46.335925)
			(xy 141.341031 -46.358567) (xy 141.386881 -46.388033) (xy 141.428072 -46.423724) (xy 141.463763 -46.464915)
			(xy 141.493229 -46.510765) (xy 141.515871 -46.560342) (xy 141.531226 -46.612637) (xy 141.538982 -46.666585)
			(xy 141.539468 -46.693836) (xy 141.539 -46.720264) (xy 141.53169 -46.772611) (xy 141.517215 -46.823446)
			(xy 141.495853 -46.871793) (xy 141.482318 -46.894496) (xy 141.476222 -46.904402) (xy 141.473682 -46.927262)
			(xy 141.507972 -47.023782) (xy 141.523974 -47.040038) (xy 141.53515 -47.043848) (xy 141.55966 -47.052915)
			(xy 141.606112 -47.076858) (xy 141.648864 -47.106915) (xy 141.687116 -47.142522) (xy 141.720152 -47.183015)
			(xy 141.747356 -47.227637) (xy 141.768217 -47.275552) (xy 141.782347 -47.325865) (xy 141.789481 -47.377636)
			(xy 141.789912 -47.403766) (xy 141.789426 -47.431017) (xy 141.78167 -47.484965) (xy 141.766315 -47.53726)
			(xy 141.743673 -47.586837) (xy 141.714207 -47.632687) (xy 141.678516 -47.673878) (xy 141.637325 -47.709569)
			(xy 141.591475 -47.739035) (xy 141.541898 -47.761677) (xy 141.489603 -47.777032) (xy 141.435655 -47.784788)
			(xy 141.381153 -47.784788) (xy 141.327205 -47.777032) (xy 141.27491 -47.761677) (xy 141.225333 -47.739035)
			(xy 141.179483 -47.709569) (xy 141.138292 -47.673878) (xy 141.102601 -47.632687) (xy 141.073135 -47.586837)
			(xy 141.050493 -47.53726) (xy 141.035138 -47.484965) (xy 141.027382 -47.431017) (xy 141.026896 -47.403766)
			(xy 141.02737 -47.377338) (xy 141.034679 -47.324991) (xy 141.049152 -47.274156) (xy 141.070511 -47.225809)
			(xy 141.084046 -47.203106) (xy 141.090142 -47.1932) (xy 141.092682 -47.17034) (xy 141.058392 -47.07382)
			(xy 141.04239 -47.057564) (xy 141.031214 -47.053754) (xy 141.006697 -47.044705) (xy 140.960246 -47.020758)
			(xy 140.917495 -46.990699) (xy 140.879245 -46.955088) (xy 140.846209 -46.914593) (xy 140.819007 -46.86997)
			(xy 140.798146 -46.822053) (xy 140.784017 -46.771738) (xy 140.776883 -46.719966) (xy 140.776452 -46.693836)
			(xy 138.173714 -46.693836) (xy 138.173714 -48.30699) (xy 140.654022 -48.30699) (xy 140.658093 -48.251368)
			(xy 140.670219 -48.196931) (xy 140.690142 -48.14484) (xy 140.717438 -48.096205) (xy 140.751524 -48.052062)
			(xy 140.791673 -48.013353) (xy 140.837031 -47.980902) (xy 140.886631 -47.955401) (xy 140.939415 -47.937394)
			(xy 140.994258 -47.927264) (xy 141.049992 -47.925227) (xy 141.105429 -47.931327) (xy 141.159386 -47.945433)
			(xy 141.210715 -47.967245) (xy 141.258321 -47.996299) (xy 141.301189 -48.031974) (xy 141.338406 -48.073511)
			(xy 141.369179 -48.120024) (xy 141.392851 -48.170521) (xy 141.408919 -48.223928) (xy 141.417039 -48.279104)
			(xy 141.417548 -48.30699) (xy 141.417039 -48.334876) (xy 141.408919 -48.390052) (xy 141.392851 -48.443459)
			(xy 141.369179 -48.493956) (xy 141.338406 -48.540469) (xy 141.301189 -48.582006) (xy 141.258321 -48.617681)
			(xy 141.210715 -48.646735) (xy 141.159386 -48.668547) (xy 141.105429 -48.682653) (xy 141.049992 -48.688753)
			(xy 140.994258 -48.686716) (xy 140.939415 -48.676586) (xy 140.886631 -48.658579) (xy 140.837031 -48.633078)
			(xy 140.791673 -48.600627) (xy 140.751524 -48.561918) (xy 140.717438 -48.517775) (xy 140.690142 -48.46914)
			(xy 140.670219 -48.417049) (xy 140.658093 -48.362612) (xy 140.654022 -48.30699) (xy 138.173714 -48.30699)
			(xy 138.173714 -48.89246) (xy 139.314172 -48.89246) (xy 139.318243 -48.836838) (xy 139.330369 -48.782401)
			(xy 139.350292 -48.73031) (xy 139.377588 -48.681675) (xy 139.411674 -48.637532) (xy 139.451823 -48.598823)
			(xy 139.497181 -48.566372) (xy 139.546781 -48.540871) (xy 139.599565 -48.522864) (xy 139.654408 -48.512734)
			(xy 139.710142 -48.510697) (xy 139.765579 -48.516797) (xy 139.819536 -48.530903) (xy 139.870865 -48.552715)
			(xy 139.918471 -48.581769) (xy 139.961339 -48.617444) (xy 139.998556 -48.658981) (xy 140.029329 -48.705494)
			(xy 140.053001 -48.755991) (xy 140.069069 -48.809398) (xy 140.077189 -48.864574) (xy 140.077698 -48.89246)
			(xy 140.077189 -48.920346) (xy 140.069069 -48.975522) (xy 140.053001 -49.028929) (xy 140.029329 -49.079426)
			(xy 139.998556 -49.125939) (xy 139.961339 -49.167476) (xy 139.918471 -49.203151) (xy 139.870865 -49.232205)
			(xy 139.819536 -49.254017) (xy 139.765579 -49.268123) (xy 139.710142 -49.274223) (xy 139.654408 -49.272186)
			(xy 139.599565 -49.262056) (xy 139.546781 -49.244049) (xy 139.497181 -49.218548) (xy 139.451823 -49.186097)
			(xy 139.411674 -49.147388) (xy 139.377588 -49.103245) (xy 139.350292 -49.05461) (xy 139.330369 -49.002519)
			(xy 139.318243 -48.948082) (xy 139.314172 -48.89246) (xy 138.173714 -48.89246) (xy 138.173714 -51.198018)
			(xy 138.174141 -51.208086) (xy 138.181861 -51.226685) (xy 138.1887 -51.234086) (xy 138.332972 -51.378358)
			(xy 138.340372 -51.385198) (xy 138.358971 -51.392913) (xy 138.36904 -51.393344)
		)
		(stroke
			(width 0)
			(type solid)
		)
		(fill yes)
		(layer "In9.Cu")
		(net "GND")
	)
	(gr_poly
		(pts
			(xy 166.832788 -51.393344) (xy 166.84202 -51.392946) (xy 166.859283 -51.3864) (xy 166.8731 -51.374154)
			(xy 166.877746 -51.366166) (xy 166.919402 -51.286664) (xy 166.923311 -51.278382) (xy 166.925589 -51.260225)
			(xy 166.921369 -51.242418) (xy 166.916608 -51.234594) (xy 166.916354 -51.23434) (xy 166.900857 -51.2107)
			(xy 166.876253 -51.159812) (xy 166.859421 -51.105852) (xy 166.85073 -51.05) (xy 166.85006 -51.021742)
			(xy 166.85006 -51.01463) (xy 166.850872 -50.987604) (xy 166.859182 -50.934177) (xy 166.874951 -50.882459)
			(xy 166.897863 -50.833486) (xy 166.92746 -50.788237) (xy 166.963149 -50.74762) (xy 167.004214 -50.712448)
			(xy 167.049833 -50.683426) (xy 167.099093 -50.661135) (xy 167.151007 -50.646021) (xy 167.204534 -50.638388)
			(xy 167.258602 -50.638388) (xy 167.312129 -50.646021) (xy 167.364043 -50.661135) (xy 167.413303 -50.683426)
			(xy 167.458922 -50.712448) (xy 167.499987 -50.74762) (xy 167.535676 -50.788237) (xy 167.565273 -50.833486)
			(xy 167.588185 -50.882459) (xy 167.603954 -50.934177) (xy 167.612264 -50.987604) (xy 167.613076 -51.01463)
			(xy 167.613076 -51.01971) (xy 167.612568 -51.048258) (xy 167.604052 -51.104716) (xy 167.587214 -51.159273)
			(xy 167.562428 -51.210709) (xy 167.546782 -51.234594) (xy 167.538654 -51.246278) (xy 167.53713 -51.274218)
			(xy 167.58539 -51.366166) (xy 167.590037 -51.374152) (xy 167.603858 -51.386392) (xy 167.621117 -51.392946)
			(xy 167.630348 -51.393344) (xy 168.522396 -51.393344) (xy 168.532365 -51.392872) (xy 168.550811 -51.385307)
			(xy 168.55821 -51.378612) (xy 169.07637 -50.860452) (xy 169.08018 -50.852578) (xy 169.090086 -50.833528)
			(xy 169.09034 -50.833274) (xy 169.09415 -50.82667) (xy 169.097452 -50.821082) (xy 169.101516 -50.806858)
			(xy 169.104818 -50.795174) (xy 169.104818 -50.1904) (xy 169.104563 -50.182988) (xy 169.1003 -50.16879)
			(xy 169.096436 -50.16246) (xy 169.081605 -50.139006) (xy 169.05815 -50.088716) (xy 169.042233 -50.035558)
			(xy 169.034189 -49.980654) (xy 169.034187 -49.925163) (xy 169.042229 -49.870259) (xy 169.058145 -49.817099)
			(xy 169.081597 -49.766809) (xy 169.096436 -49.74336) (xy 169.100296 -49.737029) (xy 169.104548 -49.722831)
			(xy 169.104818 -49.71542) (xy 169.104818 -49.1744) (xy 169.104563 -49.166988) (xy 169.1003 -49.15279)
			(xy 169.096436 -49.14646) (xy 169.081605 -49.123006) (xy 169.05815 -49.072716) (xy 169.042233 -49.019558)
			(xy 169.034189 -48.964654) (xy 169.034187 -48.909163) (xy 169.042229 -48.854259) (xy 169.058145 -48.801099)
			(xy 169.081597 -48.750809) (xy 169.096436 -48.72736) (xy 169.100296 -48.721029) (xy 169.104548 -48.706831)
			(xy 169.104818 -48.69942) (xy 169.104818 -47.629572) (xy 169.102278 -47.61865) (xy 169.099484 -47.613062)
			(xy 169.086761 -47.586292) (xy 169.068787 -47.529813) (xy 169.059691 -47.471246) (xy 169.05969 -47.411976)
			(xy 169.068782 -47.353408) (xy 169.086753 -47.296928) (xy 169.099484 -47.270162) (xy 169.102278 -47.264574)
			(xy 169.104818 -47.253652) (xy 169.104818 -46.1264) (xy 169.104563 -46.118988) (xy 169.1003 -46.10479)
			(xy 169.096436 -46.09846) (xy 169.081605 -46.075006) (xy 169.05815 -46.024716) (xy 169.042233 -45.971558)
			(xy 169.034189 -45.916654) (xy 169.034187 -45.861163) (xy 169.042229 -45.806259) (xy 169.058145 -45.753099)
			(xy 169.081597 -45.702809) (xy 169.096436 -45.67936) (xy 169.100296 -45.673029) (xy 169.104548 -45.658831)
			(xy 169.104818 -45.65142) (xy 169.104818 -45.1104) (xy 169.104563 -45.102988) (xy 169.1003 -45.08879)
			(xy 169.096436 -45.08246) (xy 169.081605 -45.059006) (xy 169.05815 -45.008716) (xy 169.042233 -44.955558)
			(xy 169.034189 -44.900654) (xy 169.034187 -44.845163) (xy 169.042229 -44.790259) (xy 169.058145 -44.737099)
			(xy 169.081597 -44.686809) (xy 169.096436 -44.66336) (xy 169.100296 -44.657029) (xy 169.104548 -44.642831)
			(xy 169.104818 -44.63542) (xy 169.104818 -44.0944) (xy 169.104563 -44.086988) (xy 169.1003 -44.07279)
			(xy 169.096436 -44.06646) (xy 169.081605 -44.043006) (xy 169.05815 -43.992716) (xy 169.042233 -43.939558)
			(xy 169.034189 -43.884654) (xy 169.034187 -43.829163) (xy 169.042229 -43.774259) (xy 169.058145 -43.721099)
			(xy 169.081597 -43.670809) (xy 169.096436 -43.64736) (xy 169.100296 -43.641029) (xy 169.104548 -43.626831)
			(xy 169.104818 -43.61942) (xy 169.104818 -43.0784) (xy 169.104563 -43.070988) (xy 169.1003 -43.05679)
			(xy 169.096436 -43.05046) (xy 169.081605 -43.027006) (xy 169.05815 -42.976716) (xy 169.042233 -42.923558)
			(xy 169.034189 -42.868654) (xy 169.034187 -42.813163) (xy 169.042229 -42.758259) (xy 169.058145 -42.705099)
			(xy 169.081597 -42.654809) (xy 169.096436 -42.63136) (xy 169.100296 -42.625029) (xy 169.104548 -42.610831)
			(xy 169.104818 -42.60342) (xy 169.104818 -41.423844) (xy 169.104414 -41.41399) (xy 169.097104 -41.395691)
			(xy 169.090594 -41.388284) (xy 169.075354 -41.37279) (xy 169.072265 -41.369736) (xy 169.065244 -41.364622)
			(xy 169.061384 -41.36263) (xy 169.038778 -41.351708) (xy 169.030396 -41.350692) (xy 169.002951 -41.346884)
			(xy 168.949479 -41.332367) (xy 168.898668 -41.310273) (xy 168.851585 -41.281065) (xy 168.809219 -41.245357)
			(xy 168.77246 -41.2039) (xy 168.742081 -41.157563) (xy 168.71872 -41.107322) (xy 168.702868 -41.054231)
			(xy 168.694857 -40.999406) (xy 168.694857 -40.943999) (xy 168.702866 -40.889174) (xy 168.718718 -40.836083)
			(xy 168.742078 -40.785842) (xy 168.772457 -40.739505) (xy 168.809215 -40.698047) (xy 168.85158 -40.662338)
			(xy 168.898663 -40.63313) (xy 168.949474 -40.611034) (xy 169.002945 -40.596517) (xy 169.030396 -40.592756)
			(xy 169.038778 -40.59174) (xy 169.061384 -40.580818) (xy 169.065243 -40.578823) (xy 169.07227 -40.573717)
			(xy 169.075354 -40.570658) (xy 169.090594 -40.555164) (xy 169.097107 -40.547757) (xy 169.104419 -40.52946)
			(xy 169.104818 -40.519604) (xy 169.104818 -38.432232) (xy 169.104404 -38.422205) (xy 169.096741 -38.403674)
			(xy 169.082568 -38.389488) (xy 169.064044 -38.381806) (xy 169.054018 -38.381432) (xy 167.384222 -38.381432)
			(xy 167.375083 -38.381811) (xy 167.357966 -38.388223) (xy 167.344191 -38.400239) (xy 167.339518 -38.408102)
			(xy 167.297354 -38.486842) (xy 167.294341 -38.492877) (xy 167.291261 -38.506004) (xy 167.291258 -38.51275)
			(xy 167.291766 -38.527228) (xy 167.29964 -38.539166) (xy 167.314773 -38.562785) (xy 167.338696 -38.613522)
			(xy 167.35494 -38.667212) (xy 167.363154 -38.722701) (xy 167.363648 -38.750748) (xy 167.363159 -38.777998)
			(xy 167.355397 -38.831943) (xy 167.340038 -38.884234) (xy 167.317395 -38.933808) (xy 167.287928 -38.979655)
			(xy 167.252237 -39.020843) (xy 167.211049 -39.056533) (xy 167.165201 -39.085999) (xy 167.115626 -39.108641)
			(xy 167.063335 -39.123999) (xy 167.00939 -39.13176) (xy 166.98214 -39.132256) (xy 166.95384 -39.131737)
			(xy 166.897861 -39.123369) (xy 166.843732 -39.106826) (xy 166.79264 -39.082469) (xy 166.745706 -39.050834)
			(xy 166.703958 -39.012614) (xy 166.668313 -38.968648) (xy 166.653464 -38.94455) (xy 166.64686 -38.933374)
			(xy 166.62527 -38.920166) (xy 166.580058 -38.917626) (xy 166.515796 -38.913816) (xy 166.492936 -38.92423)
			(xy 166.485316 -38.93439) (xy 166.467127 -38.957266) (xy 166.424972 -38.997742) (xy 166.377139 -39.031317)
			(xy 166.324747 -39.057209) (xy 166.26902 -39.07481) (xy 166.21126 -39.08371) (xy 166.18204 -39.08425)
			(xy 166.154786 -39.083767) (xy 166.100831 -39.076015) (xy 166.04853 -39.060664) (xy 165.998945 -39.038026)
			(xy 165.953086 -39.008561) (xy 165.911888 -38.97287) (xy 165.876188 -38.93168) (xy 165.846714 -38.885827)
			(xy 165.824065 -38.836247) (xy 165.808702 -38.783949) (xy 165.800939 -38.729996) (xy 165.800532 -38.702742)
			(xy 165.801091 -38.672656) (xy 165.810534 -38.613231) (xy 165.82921 -38.556031) (xy 165.842442 -38.529006)
			(xy 165.848538 -38.517068) (xy 165.847522 -38.490906) (xy 165.795198 -38.405562) (xy 165.790364 -38.398404)
			(xy 165.77692 -38.387576) (xy 165.760648 -38.381817) (xy 165.752018 -38.381432) (xy 163.385246 -38.381432)
			(xy 163.376388 -38.381851) (xy 163.359747 -38.387944) (xy 163.352734 -38.39337) (xy 163.141152 -38.604952)
			(xy 163.063682 -38.682168) (xy 163.039782 -38.705332) (xy 162.986976 -38.745849) (xy 162.929332 -38.779124)
			(xy 162.867837 -38.804588) (xy 162.803543 -38.821805) (xy 162.737552 -38.830479) (xy 162.704272 -38.831012)
			(xy 161.088832 -38.831012) (xy 161.055556 -38.830464) (xy 160.989573 -38.821771) (xy 160.925289 -38.804543)
			(xy 160.863802 -38.779074) (xy 160.806164 -38.7458) (xy 160.753361 -38.705289) (xy 160.729422 -38.682168)
			(xy 159.881824 -37.83457) (xy 159.858661 -37.810669) (xy 159.818146 -37.757863) (xy 159.784872 -37.700219)
			(xy 159.75941 -37.638723) (xy 159.742196 -37.57443) (xy 159.733523 -37.508439) (xy 159.73298 -37.47516)
			(xy 159.733007 -37.463333) (xy 159.734023 -37.439701) (xy 159.735012 -37.427916) (xy 159.735266 -37.42563)
			(xy 159.735266 -37.42436) (xy 159.738844 -37.393446) (xy 159.752577 -37.332747) (xy 159.773616 -37.274177)
			(xy 159.801645 -37.218613) (xy 159.836247 -37.166885) (xy 159.876903 -37.119767) (xy 159.923005 -37.077963)
			(xy 159.973865 -37.042098) (xy 160.028722 -37.012708) (xy 160.086756 -36.990234) (xy 160.147099 -36.97501)
			(xy 160.208849 -36.967264) (xy 160.239964 -36.966652) (xy 160.241234 -36.966652) (xy 160.273467 -36.967148)
			(xy 160.337416 -36.975298) (xy 160.368742 -36.982908) (xy 160.401337 -36.991941) (xy 160.463973 -37.017466)
			(xy 160.522666 -37.05108) (xy 160.576379 -37.092188) (xy 160.600644 -37.11575) (xy 161.284412 -37.799518)
			(xy 161.291807 -37.806371) (xy 161.310406 -37.814114) (xy 161.32048 -37.814504) (xy 161.949892 -37.814504)
			(xy 161.960643 -37.81403) (xy 161.980256 -37.80522) (xy 161.987738 -37.797486) (xy 162.038284 -37.741352)
			(xy 162.04485 -37.733233) (xy 162.051405 -37.713431) (xy 162.050984 -37.702998) (xy 162.050984 -37.702236)
			(xy 162.050018 -37.692295) (xy 162.049002 -37.672346) (xy 162.048952 -37.662358) (xy 162.049441 -37.635108)
			(xy 162.057202 -37.581162) (xy 162.07256 -37.52887) (xy 162.095203 -37.479296) (xy 162.12467 -37.433448)
			(xy 162.160361 -37.392259) (xy 162.201549 -37.356569) (xy 162.247398 -37.327102) (xy 162.296972 -37.304459)
			(xy 162.349264 -37.289101) (xy 162.40321 -37.28134) (xy 162.43046 -37.28085) (xy 162.45951 -37.281399)
			(xy 162.516939 -37.290214) (xy 162.572368 -37.307633) (xy 162.624516 -37.333251) (xy 162.672178 -37.366478)
			(xy 162.714254 -37.406546) (xy 162.732466 -37.429186) (xy 162.738562 -37.43706) (xy 162.746944 -37.44214)
			(xy 162.751103 -37.444438) (xy 162.760049 -37.447638) (xy 162.764724 -37.44849) (xy 162.83305 -37.459666)
			(xy 162.842625 -37.460803) (xy 162.861433 -37.456622) (xy 162.869626 -37.451538) (xy 162.86988 -37.451284)
			(xy 162.897565 -37.43323) (xy 162.956682 -37.403671) (xy 162.987736 -37.392356) (xy 163.014567 -37.383492)
			(xy 163.069691 -37.371062) (xy 163.125852 -37.364804) (xy 163.154106 -37.364416) (xy 169.054018 -37.364416)
			(xy 169.064024 -37.363925) (xy 169.082513 -37.356263) (xy 169.096664 -37.342111) (xy 169.104326 -37.323623)
			(xy 169.104818 -37.313616) (xy 169.104818 -31.63316) (xy 169.104056 -31.629096) (xy 169.101773 -31.613896)
			(xy 169.099356 -31.583252) (xy 169.09923 -31.567882) (xy 169.09935 -31.552512) (xy 169.101768 -31.521867)
			(xy 169.104056 -31.506668) (xy 169.104818 -31.502604) (xy 169.104818 -30.681168) (xy 169.104695 -30.676355)
			(xy 169.102905 -30.666897) (xy 169.101262 -30.662372) (xy 169.09161 -30.637734) (xy 169.085514 -30.630876)
			(xy 169.067392 -30.609786) (xy 169.036811 -30.563347) (xy 169.013292 -30.512963) (xy 168.997331 -30.459699)
			(xy 168.989267 -30.404684) (xy 168.989269 -30.34908) (xy 168.997339 -30.294066) (xy 169.013305 -30.240803)
			(xy 169.036829 -30.190421) (xy 169.067413 -30.143985) (xy 169.085514 -30.122876) (xy 169.09161 -30.116018)
			(xy 169.101262 -30.09138) (xy 169.10295 -30.086867) (xy 169.104747 -30.077402) (xy 169.104818 -30.072584)
			(xy 169.104818 -29.909008) (xy 169.091102 -29.874972) (xy 169.08526 -29.868368) (xy 169.067213 -29.847302)
			(xy 169.03677 -29.800934) (xy 169.013362 -29.750646) (xy 168.997484 -29.697498) (xy 168.989469 -29.642611)
			(xy 168.988994 -29.614876) (xy 168.988994 -29.614368) (xy 168.9896 -29.583501) (xy 168.999567 -29.522576)
			(xy 169.019218 -29.464052) (xy 169.048041 -29.409458) (xy 169.06621 -29.384498) (xy 169.070883 -29.377759)
			(xy 169.076074 -29.362213) (xy 169.07637 -29.354018) (xy 169.07637 -29.062934) (xy 169.076065 -29.054739)
			(xy 169.070889 -29.039188) (xy 169.06621 -29.032454) (xy 169.05001 -29.010239) (xy 169.023477 -28.962085)
			(xy 169.004125 -28.910624) (xy 168.992352 -28.856919) (xy 168.988402 -28.802081) (xy 168.992357 -28.747243)
			(xy 169.004136 -28.69354) (xy 169.023493 -28.64208) (xy 169.050031 -28.593929) (xy 169.06621 -28.571698)
			(xy 169.070883 -28.564959) (xy 169.076074 -28.549413) (xy 169.07637 -28.541218) (xy 169.07637 -28.368752)
			(xy 169.076597 -28.361714) (xy 169.080469 -28.348181) (xy 169.08399 -28.342082) (xy 169.096944 -28.322016)
			(xy 169.100601 -28.315757) (xy 169.104591 -28.30183) (xy 169.104818 -28.294584) (xy 169.104818 -27.872436)
			(xy 169.104384 -27.862371) (xy 169.096655 -27.843781) (xy 169.089832 -27.836368) (xy 168.85031 -27.596846)
			(xy 168.842914 -27.589993) (xy 168.824316 -27.582248) (xy 168.814242 -27.58186) (xy 159.499554 -27.58186)
			(xy 159.487228 -27.582454) (xy 159.465396 -27.593902) (xy 159.457898 -27.603704) (xy 159.440738 -27.627665)
			(xy 159.401232 -27.6714) (xy 159.356441 -27.709706) (xy 159.307106 -27.74195) (xy 159.254043 -27.767598)
			(xy 159.198128 -27.786227) (xy 159.140285 -27.797529) (xy 159.08147 -27.801317) (xy 159.022655 -27.797529)
			(xy 158.964812 -27.786227) (xy 158.908897 -27.767598) (xy 158.855834 -27.74195) (xy 158.806499 -27.709706)
			(xy 158.761708 -27.6714) (xy 158.722202 -27.627665) (xy 158.705042 -27.603704) (xy 158.697427 -27.594039)
			(xy 158.675667 -27.582638) (xy 158.663386 -27.58186) (xy 154.528012 -27.58186) (xy 154.517942 -27.582283)
			(xy 154.49934 -27.590001) (xy 154.491944 -27.596846) (xy 154.222958 -27.865832) (xy 154.216608 -27.877262)
			(xy 154.21483 -27.88412) (xy 154.207104 -27.91235) (xy 154.184193 -27.966205) (xy 154.153327 -28.01593)
			(xy 154.11523 -28.06036) (xy 154.070797 -28.098451) (xy 154.021068 -28.129312) (xy 153.967211 -28.152218)
			(xy 153.938986 -28.159964) (xy 153.932128 -28.161742) (xy 153.920698 -28.168092) (xy 153.90495 -28.18384)
			(xy 153.898105 -28.191238) (xy 153.890377 -28.209837) (xy 153.889964 -28.219908) (xy 153.889964 -29.114242)
			(xy 160.947608 -29.114242) (xy 160.947608 -28.250642) (xy 160.948098 -28.220674) (xy 160.955921 -28.161252)
			(xy 160.971434 -28.103359) (xy 160.99437 -28.047986) (xy 161.024337 -27.99608) (xy 161.060824 -27.94853)
			(xy 161.103204 -27.90615) (xy 161.150754 -27.869663) (xy 161.20266 -27.839696) (xy 161.258033 -27.81676)
			(xy 161.315926 -27.801247) (xy 161.375348 -27.793424) (xy 161.435284 -27.793424) (xy 161.494706 -27.801247)
			(xy 161.552599 -27.81676) (xy 161.607972 -27.839696) (xy 161.659878 -27.869663) (xy 161.707428 -27.90615)
			(xy 161.749808 -27.94853) (xy 161.786295 -27.99608) (xy 161.816262 -28.047986) (xy 161.839198 -28.103359)
			(xy 161.854711 -28.161252) (xy 161.862534 -28.220674) (xy 161.863024 -28.250642) (xy 161.863024 -28.469082)
			(xy 165.8526 -28.469082) (xy 165.856671 -28.41346) (xy 165.868797 -28.359023) (xy 165.88872 -28.306932)
			(xy 165.916016 -28.258297) (xy 165.950102 -28.214154) (xy 165.990251 -28.175445) (xy 166.035609 -28.142994)
			(xy 166.085209 -28.117493) (xy 166.137993 -28.099486) (xy 166.192836 -28.089356) (xy 166.24857 -28.087319)
			(xy 166.304007 -28.093419) (xy 166.357964 -28.107525) (xy 166.409293 -28.129337) (xy 166.456899 -28.158391)
			(xy 166.499767 -28.194066) (xy 166.536984 -28.235603) (xy 166.567757 -28.282116) (xy 166.591429 -28.332613)
			(xy 166.607497 -28.38602) (xy 166.615617 -28.441196) (xy 166.616126 -28.469082) (xy 166.615617 -28.496968)
			(xy 166.607497 -28.552144) (xy 166.591429 -28.605551) (xy 166.567757 -28.656048) (xy 166.536984 -28.702561)
			(xy 166.499767 -28.744098) (xy 166.456899 -28.779773) (xy 166.409293 -28.808827) (xy 166.357964 -28.830639)
			(xy 166.304007 -28.844745) (xy 166.24857 -28.850845) (xy 166.192836 -28.848808) (xy 166.137993 -28.838678)
			(xy 166.085209 -28.820671) (xy 166.035609 -28.79517) (xy 165.990251 -28.762719) (xy 165.950102 -28.72401)
			(xy 165.916016 -28.679867) (xy 165.88872 -28.631232) (xy 165.868797 -28.579141) (xy 165.856671 -28.524704)
			(xy 165.8526 -28.469082) (xy 161.863024 -28.469082) (xy 161.863024 -29.114242) (xy 161.862534 -29.14421)
			(xy 161.854711 -29.203632) (xy 161.839198 -29.261525) (xy 161.816262 -29.316898) (xy 161.786295 -29.368804)
			(xy 161.749808 -29.416354) (xy 161.707428 -29.458734) (xy 161.659878 -29.495221) (xy 161.607972 -29.525188)
			(xy 161.552599 -29.548124) (xy 161.494706 -29.563637) (xy 161.435284 -29.57146) (xy 161.375348 -29.57146)
			(xy 161.315926 -29.563637) (xy 161.258033 -29.548124) (xy 161.20266 -29.525188) (xy 161.150754 -29.495221)
			(xy 161.103204 -29.458734) (xy 161.060824 -29.416354) (xy 161.024337 -29.368804) (xy 160.99437 -29.316898)
			(xy 160.971434 -29.261525) (xy 160.955921 -29.203632) (xy 160.948098 -29.14421) (xy 160.947608 -29.114242)
			(xy 153.889964 -29.114242) (xy 153.889964 -29.186378) (xy 153.912062 -29.214064) (xy 153.929588 -29.217874)
			(xy 153.955882 -29.224336) (xy 154.006453 -29.243679) (xy 154.053782 -29.269976) (xy 154.09692 -29.302699)
			(xy 154.134999 -29.341191) (xy 154.167255 -29.384678) (xy 154.19304 -29.432288) (xy 154.211838 -29.483065)
			(xy 154.22327 -29.535988) (xy 154.227106 -29.589996) (xy 154.223271 -29.644005) (xy 154.21184 -29.696929)
			(xy 154.193043 -29.747706) (xy 154.167259 -29.795316) (xy 154.135003 -29.838804) (xy 154.096925 -29.877296)
			(xy 154.053788 -29.91002) (xy 154.006459 -29.936318) (xy 153.955889 -29.955662) (xy 153.929588 -29.962094)
			(xy 153.912062 -29.965904) (xy 153.889964 -29.99359) (xy 153.889964 -30.92069) (xy 163.589716 -30.92069)
			(xy 163.589716 -30.05709) (xy 163.590206 -30.027122) (xy 163.598029 -29.9677) (xy 163.613542 -29.909807)
			(xy 163.636478 -29.854434) (xy 163.666445 -29.802528) (xy 163.702932 -29.754978) (xy 163.745312 -29.712598)
			(xy 163.792862 -29.676111) (xy 163.844768 -29.646144) (xy 163.900141 -29.623208) (xy 163.958034 -29.607695)
			(xy 164.017456 -29.599872) (xy 164.077392 -29.599872) (xy 164.136814 -29.607695) (xy 164.194707 -29.623208)
			(xy 164.25008 -29.646144) (xy 164.301986 -29.676111) (xy 164.349536 -29.712598) (xy 164.391916 -29.754978)
			(xy 164.428403 -29.802528) (xy 164.45837 -29.854434) (xy 164.481306 -29.909807) (xy 164.496819 -29.9677)
			(xy 164.504642 -30.027122) (xy 164.505132 -30.05709) (xy 164.505132 -30.92069) (xy 164.504642 -30.950658)
			(xy 164.496819 -31.01008) (xy 164.481306 -31.067973) (xy 164.45837 -31.123346) (xy 164.428403 -31.175252)
			(xy 164.391916 -31.222802) (xy 164.349536 -31.265182) (xy 164.301986 -31.301669) (xy 164.25008 -31.331636)
			(xy 164.194707 -31.354572) (xy 164.136814 -31.370085) (xy 164.077392 -31.377908) (xy 164.017456 -31.377908)
			(xy 163.958034 -31.370085) (xy 163.900141 -31.354572) (xy 163.844768 -31.331636) (xy 163.792862 -31.301669)
			(xy 163.745312 -31.265182) (xy 163.702932 -31.222802) (xy 163.666445 -31.175252) (xy 163.636478 -31.123346)
			(xy 163.613542 -31.067973) (xy 163.598029 -31.01008) (xy 163.590206 -30.950658) (xy 163.589716 -30.92069)
			(xy 153.889964 -30.92069) (xy 153.889964 -31.232602) (xy 153.915364 -31.261304) (xy 153.934668 -31.26359)
			(xy 153.962078 -31.267414) (xy 154.015476 -31.281951) (xy 154.066214 -31.304051) (xy 154.113226 -31.33325)
			(xy 154.155525 -31.368936) (xy 154.192224 -31.410359) (xy 154.222553 -31.45665) (xy 154.245875 -31.506838)
			(xy 154.2617 -31.559869) (xy 154.269696 -31.61463) (xy 154.269696 -31.669971) (xy 154.261699 -31.724732)
			(xy 154.245874 -31.777763) (xy 154.222552 -31.827951) (xy 154.192224 -31.874242) (xy 154.155524 -31.915665)
			(xy 154.113225 -31.951351) (xy 154.066213 -31.98055) (xy 154.015475 -32.002649) (xy 153.962077 -32.017186)
			(xy 153.934668 -32.021018) (xy 153.915364 -32.023304) (xy 153.889964 -32.052006) (xy 153.889964 -32.714184)
			(xy 160.947608 -32.714184) (xy 160.947608 -31.850584) (xy 160.948098 -31.820616) (xy 160.955921 -31.761194)
			(xy 160.971434 -31.703301) (xy 160.99437 -31.647928) (xy 161.024337 -31.596022) (xy 161.060824 -31.548472)
			(xy 161.103204 -31.506092) (xy 161.150754 -31.469605) (xy 161.20266 -31.439638) (xy 161.258033 -31.416702)
			(xy 161.315926 -31.401189) (xy 161.375348 -31.393366) (xy 161.435284 -31.393366) (xy 161.494706 -31.401189)
			(xy 161.552599 -31.416702) (xy 161.607972 -31.439638) (xy 161.659878 -31.469605) (xy 161.707428 -31.506092)
			(xy 161.749808 -31.548472) (xy 161.786295 -31.596022) (xy 161.816262 -31.647928) (xy 161.839198 -31.703301)
			(xy 161.854711 -31.761194) (xy 161.862534 -31.820616) (xy 161.863024 -31.850584) (xy 161.863024 -32.714184)
			(xy 161.862534 -32.744152) (xy 161.854711 -32.803574) (xy 161.839198 -32.861467) (xy 161.816262 -32.91684)
			(xy 161.786295 -32.968746) (xy 161.749808 -33.016296) (xy 161.707428 -33.058676) (xy 161.659878 -33.095163)
			(xy 161.607972 -33.12513) (xy 161.552599 -33.148066) (xy 161.494706 -33.163579) (xy 161.435284 -33.171402)
			(xy 161.375348 -33.171402) (xy 161.315926 -33.163579) (xy 161.258033 -33.148066) (xy 161.20266 -33.12513)
			(xy 161.150754 -33.095163) (xy 161.103204 -33.058676) (xy 161.060824 -33.016296) (xy 161.024337 -32.968746)
			(xy 160.99437 -32.91684) (xy 160.971434 -32.861467) (xy 160.955921 -32.803574) (xy 160.948098 -32.744152)
			(xy 160.947608 -32.714184) (xy 153.889964 -32.714184) (xy 153.889964 -34.520886) (xy 163.589716 -34.520886)
			(xy 163.589716 -33.657286) (xy 163.590206 -33.627318) (xy 163.598029 -33.567896) (xy 163.613542 -33.510003)
			(xy 163.636478 -33.45463) (xy 163.666445 -33.402724) (xy 163.702932 -33.355174) (xy 163.745312 -33.312794)
			(xy 163.792862 -33.276307) (xy 163.844768 -33.24634) (xy 163.900141 -33.223404) (xy 163.958034 -33.207891)
			(xy 164.017456 -33.200068) (xy 164.077392 -33.200068) (xy 164.136814 -33.207891) (xy 164.194707 -33.223404)
			(xy 164.25008 -33.24634) (xy 164.301986 -33.276307) (xy 164.349536 -33.312794) (xy 164.391916 -33.355174)
			(xy 164.428403 -33.402724) (xy 164.45837 -33.45463) (xy 164.481306 -33.510003) (xy 164.496819 -33.567896)
			(xy 164.504642 -33.627318) (xy 164.505132 -33.657286) (xy 164.505132 -34.520886) (xy 164.504642 -34.550854)
			(xy 164.496819 -34.610276) (xy 164.481306 -34.668169) (xy 164.45837 -34.723542) (xy 164.428403 -34.775448)
			(xy 164.391916 -34.822998) (xy 164.349536 -34.865378) (xy 164.301986 -34.901865) (xy 164.25008 -34.931832)
			(xy 164.194707 -34.954768) (xy 164.136814 -34.970281) (xy 164.077392 -34.978104) (xy 164.017456 -34.978104)
			(xy 163.958034 -34.970281) (xy 163.900141 -34.954768) (xy 163.844768 -34.931832) (xy 163.792862 -34.901865)
			(xy 163.745312 -34.865378) (xy 163.702932 -34.822998) (xy 163.666445 -34.775448) (xy 163.636478 -34.723542)
			(xy 163.613542 -34.668169) (xy 163.598029 -34.610276) (xy 163.590206 -34.550854) (xy 163.589716 -34.520886)
			(xy 153.889964 -34.520886) (xy 153.889964 -36.60013) (xy 154.098505 -36.60013) (xy 154.102509 -36.512245)
			(xy 154.114489 -36.425088) (xy 154.134344 -36.339381) (xy 154.161911 -36.255836) (xy 154.196961 -36.175143)
			(xy 154.239203 -36.097971) (xy 154.288288 -36.024961) (xy 154.343809 -35.956717) (xy 154.405306 -35.893804)
			(xy 154.472268 -35.836744) (xy 154.544142 -35.78601) (xy 154.620332 -35.742022) (xy 154.700206 -35.705144)
			(xy 154.783103 -35.675683) (xy 154.868335 -35.653881) (xy 154.955197 -35.639921) (xy 155.042968 -35.633917)
			(xy 155.130922 -35.63592) (xy 155.218329 -35.645912) (xy 155.304465 -35.663812) (xy 155.388617 -35.68947)
			(xy 155.470087 -35.722674) (xy 155.5482 -35.763148) (xy 155.622308 -35.810559) (xy 155.691799 -35.864512)
			(xy 155.70489 -35.876738) (xy 160.817304 -35.876738) (xy 160.821375 -35.821116) (xy 160.833501 -35.766679)
			(xy 160.853424 -35.714588) (xy 160.88072 -35.665953) (xy 160.914806 -35.62181) (xy 160.954955 -35.583101)
			(xy 161.000313 -35.55065) (xy 161.049913 -35.525149) (xy 161.102697 -35.507142) (xy 161.15754 -35.497012)
			(xy 161.213274 -35.494975) (xy 161.268711 -35.501075) (xy 161.322668 -35.515181) (xy 161.373997 -35.536993)
			(xy 161.421603 -35.566047) (xy 161.464471 -35.601722) (xy 161.501688 -35.643259) (xy 161.532461 -35.689772)
			(xy 161.556133 -35.740269) (xy 161.572201 -35.793676) (xy 161.580321 -35.848852) (xy 161.58083 -35.876738)
			(xy 164.888924 -35.876738) (xy 164.892995 -35.821116) (xy 164.905121 -35.766679) (xy 164.925044 -35.714588)
			(xy 164.95234 -35.665953) (xy 164.986426 -35.62181) (xy 165.026575 -35.583101) (xy 165.071933 -35.55065)
			(xy 165.121533 -35.525149) (xy 165.174317 -35.507142) (xy 165.22916 -35.497012) (xy 165.284894 -35.494975)
			(xy 165.340331 -35.501075) (xy 165.394288 -35.515181) (xy 165.445617 -35.536993) (xy 165.493223 -35.566047)
			(xy 165.536091 -35.601722) (xy 165.573308 -35.643259) (xy 165.604081 -35.689772) (xy 165.627753 -35.740269)
			(xy 165.643821 -35.793676) (xy 165.651941 -35.848852) (xy 165.65245 -35.876738) (xy 165.651941 -35.904624)
			(xy 165.643821 -35.9598) (xy 165.627753 -36.013207) (xy 165.604081 -36.063704) (xy 165.573308 -36.110217)
			(xy 165.536091 -36.151754) (xy 165.493223 -36.187429) (xy 165.445617 -36.216483) (xy 165.394288 -36.238295)
			(xy 165.340331 -36.252401) (xy 165.284894 -36.258501) (xy 165.22916 -36.256464) (xy 165.174317 -36.246334)
			(xy 165.121533 -36.228327) (xy 165.071933 -36.202826) (xy 165.026575 -36.170375) (xy 164.986426 -36.131666)
			(xy 164.95234 -36.087523) (xy 164.925044 -36.038888) (xy 164.905121 -35.986797) (xy 164.892995 -35.93236)
			(xy 164.888924 -35.876738) (xy 161.58083 -35.876738) (xy 161.580321 -35.904624) (xy 161.572201 -35.9598)
			(xy 161.556133 -36.013207) (xy 161.532461 -36.063704) (xy 161.501688 -36.110217) (xy 161.464471 -36.151754)
			(xy 161.421603 -36.187429) (xy 161.373997 -36.216483) (xy 161.322668 -36.238295) (xy 161.268711 -36.252401)
			(xy 161.213274 -36.258501) (xy 161.15754 -36.256464) (xy 161.102697 -36.246334) (xy 161.049913 -36.228327)
			(xy 161.000313 -36.202826) (xy 160.954955 -36.170375) (xy 160.914806 -36.131666) (xy 160.88072 -36.087523)
			(xy 160.853424 -36.038888) (xy 160.833501 -35.986797) (xy 160.821375 -35.93236) (xy 160.817304 -35.876738)
			(xy 155.70489 -35.876738) (xy 155.756095 -35.92456) (xy 155.814664 -35.990207) (xy 155.867021 -36.060907)
			(xy 155.912733 -36.136076) (xy 155.951419 -36.21509) (xy 155.98276 -36.297295) (xy 156.006495 -36.382009)
			(xy 156.022429 -36.46853) (xy 156.026212 -36.50996) (xy 162.713922 -36.50996) (xy 162.717993 -36.454338)
			(xy 162.730119 -36.399901) (xy 162.750042 -36.34781) (xy 162.777338 -36.299175) (xy 162.811424 -36.255032)
			(xy 162.851573 -36.216323) (xy 162.896931 -36.183872) (xy 162.946531 -36.158371) (xy 162.999315 -36.140364)
			(xy 163.054158 -36.130234) (xy 163.109892 -36.128197) (xy 163.165329 -36.134297) (xy 163.219286 -36.148403)
			(xy 163.270615 -36.170215) (xy 163.318221 -36.199269) (xy 163.361089 -36.234944) (xy 163.398306 -36.276481)
			(xy 163.429079 -36.322994) (xy 163.452751 -36.373491) (xy 163.468819 -36.426898) (xy 163.472744 -36.453572)
			(xy 166.028622 -36.453572) (xy 166.032693 -36.39795) (xy 166.044819 -36.343513) (xy 166.064742 -36.291422)
			(xy 166.092038 -36.242787) (xy 166.126124 -36.198644) (xy 166.166273 -36.159935) (xy 166.211631 -36.127484)
			(xy 166.261231 -36.101983) (xy 166.314015 -36.083976) (xy 166.368858 -36.073846) (xy 166.424592 -36.071809)
			(xy 166.480029 -36.077909) (xy 166.533986 -36.092015) (xy 166.585315 -36.113827) (xy 166.632921 -36.142881)
			(xy 166.675789 -36.178556) (xy 166.713006 -36.220093) (xy 166.743779 -36.266606) (xy 166.767451 -36.317103)
			(xy 166.783519 -36.37051) (xy 166.791639 -36.425686) (xy 166.792148 -36.453572) (xy 166.791639 -36.481458)
			(xy 166.783519 -36.536634) (xy 166.767451 -36.590041) (xy 166.743779 -36.640538) (xy 166.713006 -36.687051)
			(xy 166.675789 -36.728588) (xy 166.632921 -36.764263) (xy 166.585315 -36.793317) (xy 166.533986 -36.815129)
			(xy 166.480029 -36.829235) (xy 166.424592 -36.835335) (xy 166.368858 -36.833298) (xy 166.314015 -36.823168)
			(xy 166.261231 -36.805161) (xy 166.211631 -36.77966) (xy 166.166273 -36.747209) (xy 166.126124 -36.7085)
			(xy 166.092038 -36.664357) (xy 166.064742 -36.615722) (xy 166.044819 -36.563631) (xy 166.032693 -36.509194)
			(xy 166.028622 -36.453572) (xy 163.472744 -36.453572) (xy 163.476939 -36.482074) (xy 163.477448 -36.50996)
			(xy 163.476939 -36.537846) (xy 163.468819 -36.593022) (xy 163.452751 -36.646429) (xy 163.429079 -36.696926)
			(xy 163.398306 -36.743439) (xy 163.361089 -36.784976) (xy 163.318221 -36.820651) (xy 163.270615 -36.849705)
			(xy 163.219286 -36.871517) (xy 163.165329 -36.885623) (xy 163.109892 -36.891723) (xy 163.054158 -36.889686)
			(xy 162.999315 -36.879556) (xy 162.946531 -36.861549) (xy 162.896931 -36.836048) (xy 162.851573 -36.803597)
			(xy 162.811424 -36.764888) (xy 162.777338 -36.720745) (xy 162.750042 -36.67211) (xy 162.730119 -36.620019)
			(xy 162.717993 -36.565582) (xy 162.713922 -36.50996) (xy 156.026212 -36.50996) (xy 156.030429 -36.556142)
			(xy 156.03093 -36.60013) (xy 156.030429 -36.644118) (xy 156.022429 -36.73173) (xy 156.006495 -36.818251)
			(xy 155.98276 -36.902965) (xy 155.951419 -36.98517) (xy 155.912733 -37.064184) (xy 155.867021 -37.139353)
			(xy 155.814664 -37.210053) (xy 155.756095 -37.2757) (xy 155.691799 -37.335748) (xy 155.622308 -37.389701)
			(xy 155.5482 -37.437112) (xy 155.470087 -37.477586) (xy 155.388617 -37.51079) (xy 155.304465 -37.536448)
			(xy 155.218329 -37.554348) (xy 155.130922 -37.56434) (xy 155.042968 -37.566343) (xy 154.955197 -37.560339)
			(xy 154.868335 -37.546379) (xy 154.783103 -37.524577) (xy 154.700206 -37.495116) (xy 154.620332 -37.458238)
			(xy 154.544142 -37.41425) (xy 154.472268 -37.363516) (xy 154.405306 -37.306456) (xy 154.343809 -37.243543)
			(xy 154.288288 -37.175299) (xy 154.239203 -37.102289) (xy 154.196961 -37.025117) (xy 154.161911 -36.944424)
			(xy 154.134344 -36.860879) (xy 154.114489 -36.775172) (xy 154.102509 -36.688015) (xy 154.098505 -36.60013)
			(xy 153.889964 -36.60013) (xy 153.889964 -39.97198) (xy 167.995852 -39.97198) (xy 167.999923 -39.916358)
			(xy 168.012049 -39.861921) (xy 168.031972 -39.80983) (xy 168.059268 -39.761195) (xy 168.093354 -39.717052)
			(xy 168.133503 -39.678343) (xy 168.178861 -39.645892) (xy 168.228461 -39.620391) (xy 168.281245 -39.602384)
			(xy 168.336088 -39.592254) (xy 168.391822 -39.590217) (xy 168.447259 -39.596317) (xy 168.501216 -39.610423)
			(xy 168.552545 -39.632235) (xy 168.600151 -39.661289) (xy 168.643019 -39.696964) (xy 168.680236 -39.738501)
			(xy 168.711009 -39.785014) (xy 168.734681 -39.835511) (xy 168.750749 -39.888918) (xy 168.758869 -39.944094)
			(xy 168.759378 -39.97198) (xy 168.758869 -39.999866) (xy 168.750749 -40.055042) (xy 168.734681 -40.108449)
			(xy 168.711009 -40.158946) (xy 168.680236 -40.205459) (xy 168.643019 -40.246996) (xy 168.600151 -40.282671)
			(xy 168.552545 -40.311725) (xy 168.501216 -40.333537) (xy 168.447259 -40.347643) (xy 168.391822 -40.353743)
			(xy 168.336088 -40.351706) (xy 168.281245 -40.341576) (xy 168.228461 -40.323569) (xy 168.178861 -40.298068)
			(xy 168.133503 -40.265617) (xy 168.093354 -40.226908) (xy 168.059268 -40.182765) (xy 168.031972 -40.13413)
			(xy 168.012049 -40.082039) (xy 167.999923 -40.027602) (xy 167.995852 -39.97198) (xy 153.889964 -39.97198)
			(xy 153.889964 -40.452802) (xy 153.890389 -40.462871) (xy 153.898111 -40.481469) (xy 153.90495 -40.48887)
			(xy 154.124152 -40.708072) (xy 154.131552 -40.714913) (xy 154.15015 -40.722633) (xy 154.16022 -40.723058)
			(xy 163.181538 -40.723058) (xy 163.191604 -40.72349) (xy 163.210193 -40.73122) (xy 163.217606 -40.738044)
			(xy 164.158676 -41.679114) (xy 164.165523 -41.686512) (xy 164.173256 -41.70511) (xy 164.173662 -41.715182)
			(xy 164.173662 -43.85691) (xy 166.819832 -43.85691) (xy 166.823903 -43.801288) (xy 166.836029 -43.746851)
			(xy 166.855952 -43.69476) (xy 166.883248 -43.646125) (xy 166.917334 -43.601982) (xy 166.957483 -43.563273)
			(xy 167.002841 -43.530822) (xy 167.052441 -43.505321) (xy 167.105225 -43.487314) (xy 167.160068 -43.477184)
			(xy 167.215802 -43.475147) (xy 167.271239 -43.481247) (xy 167.325196 -43.495353) (xy 167.376525 -43.517165)
			(xy 167.424131 -43.546219) (xy 167.466999 -43.581894) (xy 167.504216 -43.623431) (xy 167.534989 -43.669944)
			(xy 167.558661 -43.720441) (xy 167.574729 -43.773848) (xy 167.582849 -43.829024) (xy 167.583358 -43.85691)
			(xy 167.582849 -43.884796) (xy 167.574729 -43.939972) (xy 167.558661 -43.993379) (xy 167.534989 -44.043876)
			(xy 167.504216 -44.090389) (xy 167.466999 -44.131926) (xy 167.424131 -44.167601) (xy 167.376525 -44.196655)
			(xy 167.325196 -44.218467) (xy 167.271239 -44.232573) (xy 167.215802 -44.238673) (xy 167.160068 -44.236636)
			(xy 167.105225 -44.226506) (xy 167.052441 -44.208499) (xy 167.002841 -44.182998) (xy 166.957483 -44.150547)
			(xy 166.917334 -44.111838) (xy 166.883248 -44.067695) (xy 166.855952 -44.01906) (xy 166.836029 -43.966969)
			(xy 166.823903 -43.912532) (xy 166.819832 -43.85691) (xy 164.173662 -43.85691) (xy 164.173662 -45.35424)
			(xy 166.80383 -45.35424) (xy 166.807901 -45.298618) (xy 166.820027 -45.244181) (xy 166.83995 -45.19209)
			(xy 166.867246 -45.143455) (xy 166.901332 -45.099312) (xy 166.941481 -45.060603) (xy 166.986839 -45.028152)
			(xy 167.036439 -45.002651) (xy 167.089223 -44.984644) (xy 167.144066 -44.974514) (xy 167.1998 -44.972477)
			(xy 167.255237 -44.978577) (xy 167.309194 -44.992683) (xy 167.360523 -45.014495) (xy 167.408129 -45.043549)
			(xy 167.450997 -45.079224) (xy 167.488214 -45.120761) (xy 167.518987 -45.167274) (xy 167.542659 -45.217771)
			(xy 167.558727 -45.271178) (xy 167.566847 -45.326354) (xy 167.567356 -45.35424) (xy 167.566847 -45.382126)
			(xy 167.558727 -45.437302) (xy 167.542659 -45.490709) (xy 167.518987 -45.541206) (xy 167.488214 -45.587719)
			(xy 167.450997 -45.629256) (xy 167.408129 -45.664931) (xy 167.360523 -45.693985) (xy 167.309194 -45.715797)
			(xy 167.255237 -45.729903) (xy 167.1998 -45.736003) (xy 167.144066 -45.733966) (xy 167.089223 -45.723836)
			(xy 167.036439 -45.705829) (xy 166.986839 -45.680328) (xy 166.941481 -45.647877) (xy 166.901332 -45.609168)
			(xy 166.867246 -45.565025) (xy 166.83995 -45.51639) (xy 166.820027 -45.464299) (xy 166.807901 -45.409862)
			(xy 166.80383 -45.35424) (xy 164.173662 -45.35424) (xy 164.173662 -46.693836) (xy 166.7764 -46.693836)
			(xy 166.776886 -46.666585) (xy 166.784642 -46.612637) (xy 166.799997 -46.560342) (xy 166.822639 -46.510765)
			(xy 166.852105 -46.464915) (xy 166.887796 -46.423724) (xy 166.928987 -46.388033) (xy 166.974837 -46.358567)
			(xy 167.024414 -46.335925) (xy 167.076709 -46.32057) (xy 167.130657 -46.312814) (xy 167.185159 -46.312814)
			(xy 167.239107 -46.32057) (xy 167.291402 -46.335925) (xy 167.340979 -46.358567) (xy 167.386829 -46.388033)
			(xy 167.42802 -46.423724) (xy 167.463711 -46.464915) (xy 167.493177 -46.510765) (xy 167.515819 -46.560342)
			(xy 167.531174 -46.612637) (xy 167.53893 -46.666585) (xy 167.539416 -46.693836) (xy 167.538941 -46.720263)
			(xy 167.531632 -46.772611) (xy 167.517159 -46.823446) (xy 167.4958 -46.871793) (xy 167.482266 -46.894496)
			(xy 167.47617 -46.904402) (xy 167.47363 -46.927262) (xy 167.50792 -47.023782) (xy 167.523922 -47.040038)
			(xy 167.535098 -47.043848) (xy 167.559618 -47.052888) (xy 167.606069 -47.076837) (xy 167.648819 -47.106898)
			(xy 167.68707 -47.14251) (xy 167.720104 -47.183006) (xy 167.747306 -47.22763) (xy 167.768167 -47.275548)
			(xy 167.782296 -47.325863) (xy 167.789429 -47.377635) (xy 167.78986 -47.403766) (xy 167.789374 -47.431017)
			(xy 167.781618 -47.484965) (xy 167.766263 -47.53726) (xy 167.743621 -47.586837) (xy 167.714155 -47.632687)
			(xy 167.678464 -47.673878) (xy 167.637273 -47.709569) (xy 167.591423 -47.739035) (xy 167.541846 -47.761677)
			(xy 167.489551 -47.777032) (xy 167.435603 -47.784788) (xy 167.381101 -47.784788) (xy 167.327153 -47.777032)
			(xy 167.274858 -47.761677) (xy 167.225281 -47.739035) (xy 167.179431 -47.709569) (xy 167.13824 -47.673878)
			(xy 167.102549 -47.632687) (xy 167.073083 -47.586837) (xy 167.050441 -47.53726) (xy 167.035086 -47.484965)
			(xy 167.02733 -47.431017) (xy 167.026844 -47.403766) (xy 167.027312 -47.377338) (xy 167.034622 -47.32499)
			(xy 167.049096 -47.274155) (xy 167.070458 -47.225809) (xy 167.083994 -47.203106) (xy 167.09009 -47.1932)
			(xy 167.09263 -47.17034) (xy 167.05834 -47.07382) (xy 167.042338 -47.057564) (xy 167.031162 -47.053754)
			(xy 167.006656 -47.044678) (xy 166.960203 -47.020737) (xy 166.917451 -46.990682) (xy 166.879199 -46.955076)
			(xy 166.846162 -46.914584) (xy 166.818958 -46.869963) (xy 166.798096 -46.822048) (xy 166.783965 -46.771736)
			(xy 166.776831 -46.719966) (xy 166.7764 -46.693836) (xy 164.173662 -46.693836) (xy 164.173662 -48.30699)
			(xy 166.65397 -48.30699) (xy 166.658041 -48.251368) (xy 166.670167 -48.196931) (xy 166.69009 -48.14484)
			(xy 166.717386 -48.096205) (xy 166.751472 -48.052062) (xy 166.791621 -48.013353) (xy 166.836979 -47.980902)
			(xy 166.886579 -47.955401) (xy 166.939363 -47.937394) (xy 166.994206 -47.927264) (xy 167.04994 -47.925227)
			(xy 167.105377 -47.931327) (xy 167.159334 -47.945433) (xy 167.210663 -47.967245) (xy 167.258269 -47.996299)
			(xy 167.301137 -48.031974) (xy 167.338354 -48.073511) (xy 167.369127 -48.120024) (xy 167.392799 -48.170521)
			(xy 167.408867 -48.223928) (xy 167.416987 -48.279104) (xy 167.417496 -48.30699) (xy 167.416987 -48.334876)
			(xy 167.408867 -48.390052) (xy 167.392799 -48.443459) (xy 167.369127 -48.493956) (xy 167.338354 -48.540469)
			(xy 167.301137 -48.582006) (xy 167.258269 -48.617681) (xy 167.210663 -48.646735) (xy 167.159334 -48.668547)
			(xy 167.105377 -48.682653) (xy 167.04994 -48.688753) (xy 166.994206 -48.686716) (xy 166.939363 -48.676586)
			(xy 166.886579 -48.658579) (xy 166.836979 -48.633078) (xy 166.791621 -48.600627) (xy 166.751472 -48.561918)
			(xy 166.717386 -48.517775) (xy 166.69009 -48.46914) (xy 166.670167 -48.417049) (xy 166.658041 -48.362612)
			(xy 166.65397 -48.30699) (xy 164.173662 -48.30699) (xy 164.173662 -48.89246) (xy 165.31412 -48.89246)
			(xy 165.318191 -48.836838) (xy 165.330317 -48.782401) (xy 165.35024 -48.73031) (xy 165.377536 -48.681675)
			(xy 165.411622 -48.637532) (xy 165.451771 -48.598823) (xy 165.497129 -48.566372) (xy 165.546729 -48.540871)
			(xy 165.599513 -48.522864) (xy 165.654356 -48.512734) (xy 165.71009 -48.510697) (xy 165.765527 -48.516797)
			(xy 165.819484 -48.530903) (xy 165.870813 -48.552715) (xy 165.918419 -48.581769) (xy 165.961287 -48.617444)
			(xy 165.998504 -48.658981) (xy 166.029277 -48.705494) (xy 166.052949 -48.755991) (xy 166.069017 -48.809398)
			(xy 166.077137 -48.864574) (xy 166.077646 -48.89246) (xy 166.077137 -48.920346) (xy 166.069017 -48.975522)
			(xy 166.052949 -49.028929) (xy 166.029277 -49.079426) (xy 165.998504 -49.125939) (xy 165.961287 -49.167476)
			(xy 165.918419 -49.203151) (xy 165.870813 -49.232205) (xy 165.819484 -49.254017) (xy 165.765527 -49.268123)
			(xy 165.71009 -49.274223) (xy 165.654356 -49.272186) (xy 165.599513 -49.262056) (xy 165.546729 -49.244049)
			(xy 165.497129 -49.218548) (xy 165.451771 -49.186097) (xy 165.411622 -49.147388) (xy 165.377536 -49.103245)
			(xy 165.35024 -49.05461) (xy 165.330317 -49.002519) (xy 165.318191 -48.948082) (xy 165.31412 -48.89246)
			(xy 164.173662 -48.89246) (xy 164.173662 -51.198018) (xy 164.17409 -51.208085) (xy 164.181816 -51.226679)
			(xy 164.188648 -51.234086) (xy 164.33292 -51.378358) (xy 164.340318 -51.385206) (xy 164.358916 -51.39294)
			(xy 164.368988 -51.393344)
		)
		(stroke
			(width 0)
			(type solid)
		)
		(fill yes)
		(layer "In9.Cu")
		(net "GND")
	)
	(gr_poly
		(pts
			(xy 373.032782 -51.393344) (xy 373.042014 -51.392947) (xy 373.059279 -51.386402) (xy 373.073098 -51.374156)
			(xy 373.07774 -51.366166) (xy 373.119396 -51.286664) (xy 373.123305 -51.278383) (xy 373.125583 -51.260225)
			(xy 373.121363 -51.242418) (xy 373.116602 -51.234594) (xy 373.116348 -51.23434) (xy 373.100851 -51.2107)
			(xy 373.076247 -51.159812) (xy 373.059416 -51.105852) (xy 373.050724 -51.05) (xy 373.050054 -51.021742)
			(xy 373.050054 -51.01463) (xy 373.050866 -50.987604) (xy 373.059176 -50.934177) (xy 373.074945 -50.882459)
			(xy 373.097857 -50.833486) (xy 373.127454 -50.788237) (xy 373.163143 -50.74762) (xy 373.204208 -50.712448)
			(xy 373.249827 -50.683426) (xy 373.299087 -50.661135) (xy 373.351001 -50.646021) (xy 373.404528 -50.638388)
			(xy 373.458596 -50.638388) (xy 373.512123 -50.646021) (xy 373.564037 -50.661135) (xy 373.613297 -50.683426)
			(xy 373.658916 -50.712448) (xy 373.699981 -50.74762) (xy 373.73567 -50.788237) (xy 373.765267 -50.833486)
			(xy 373.788179 -50.882459) (xy 373.803948 -50.934177) (xy 373.812258 -50.987604) (xy 373.81307 -51.01463)
			(xy 373.81307 -51.01971) (xy 373.812562 -51.048258) (xy 373.804046 -51.104716) (xy 373.787207 -51.159273)
			(xy 373.762421 -51.210709) (xy 373.746776 -51.234594) (xy 373.738648 -51.246278) (xy 373.737124 -51.274218)
			(xy 373.785384 -51.366166) (xy 373.790031 -51.374152) (xy 373.803852 -51.386394) (xy 373.821111 -51.39295)
			(xy 373.830342 -51.393344) (xy 374.72239 -51.393344) (xy 374.732359 -51.392873) (xy 374.750807 -51.385309)
			(xy 374.758204 -51.378612) (xy 375.276364 -50.860452) (xy 375.280174 -50.852578) (xy 375.29008 -50.833528)
			(xy 375.290334 -50.833274) (xy 375.294144 -50.82667) (xy 375.297446 -50.821082) (xy 375.30151 -50.806858)
			(xy 375.304812 -50.795174) (xy 375.304812 -50.1904) (xy 375.304557 -50.182988) (xy 375.300294 -50.168791)
			(xy 375.29643 -50.16246) (xy 375.281596 -50.139007) (xy 375.258135 -50.088718) (xy 375.242214 -50.03556)
			(xy 375.234167 -49.980654) (xy 375.234166 -49.925162) (xy 375.24221 -49.870257) (xy 375.258129 -49.817097)
			(xy 375.281588 -49.766807) (xy 375.29643 -49.74336) (xy 375.300291 -49.737029) (xy 375.304543 -49.722831)
			(xy 375.304812 -49.71542) (xy 375.304812 -49.1744) (xy 375.304557 -49.166988) (xy 375.300294 -49.152791)
			(xy 375.29643 -49.14646) (xy 375.281596 -49.123007) (xy 375.258135 -49.072718) (xy 375.242214 -49.01956)
			(xy 375.234167 -48.964654) (xy 375.234166 -48.909162) (xy 375.24221 -48.854257) (xy 375.258129 -48.801097)
			(xy 375.281588 -48.750807) (xy 375.29643 -48.72736) (xy 375.300291 -48.721029) (xy 375.304543 -48.706831)
			(xy 375.304812 -48.69942) (xy 375.304812 -47.629572) (xy 375.302272 -47.61865) (xy 375.299478 -47.613062)
			(xy 375.286752 -47.586293) (xy 375.268774 -47.529814) (xy 375.259676 -47.471246) (xy 375.259674 -47.411975)
			(xy 375.268769 -47.353407) (xy 375.286744 -47.296927) (xy 375.299478 -47.270162) (xy 375.302272 -47.264574)
			(xy 375.304812 -47.253652) (xy 375.304812 -46.1264) (xy 375.304557 -46.118988) (xy 375.300294 -46.104791)
			(xy 375.29643 -46.09846) (xy 375.281596 -46.075007) (xy 375.258135 -46.024718) (xy 375.242214 -45.97156)
			(xy 375.234167 -45.916654) (xy 375.234166 -45.861162) (xy 375.24221 -45.806257) (xy 375.258129 -45.753097)
			(xy 375.281588 -45.702807) (xy 375.29643 -45.67936) (xy 375.300291 -45.673029) (xy 375.304543 -45.658831)
			(xy 375.304812 -45.65142) (xy 375.304812 -45.1104) (xy 375.304557 -45.102988) (xy 375.300294 -45.088791)
			(xy 375.29643 -45.08246) (xy 375.281596 -45.059007) (xy 375.258135 -45.008718) (xy 375.242214 -44.95556)
			(xy 375.234167 -44.900654) (xy 375.234166 -44.845162) (xy 375.24221 -44.790257) (xy 375.258129 -44.737097)
			(xy 375.281588 -44.686807) (xy 375.29643 -44.66336) (xy 375.300291 -44.657029) (xy 375.304543 -44.642831)
			(xy 375.304812 -44.63542) (xy 375.304812 -44.0944) (xy 375.304557 -44.086988) (xy 375.300294 -44.072791)
			(xy 375.29643 -44.06646) (xy 375.281596 -44.043007) (xy 375.258135 -43.992718) (xy 375.242214 -43.93956)
			(xy 375.234167 -43.884654) (xy 375.234166 -43.829162) (xy 375.24221 -43.774257) (xy 375.258129 -43.721097)
			(xy 375.281588 -43.670807) (xy 375.29643 -43.64736) (xy 375.300291 -43.641029) (xy 375.304543 -43.626831)
			(xy 375.304812 -43.61942) (xy 375.304812 -43.0784) (xy 375.304557 -43.070988) (xy 375.300294 -43.056791)
			(xy 375.29643 -43.05046) (xy 375.281596 -43.027007) (xy 375.258135 -42.976718) (xy 375.242214 -42.92356)
			(xy 375.234167 -42.868654) (xy 375.234166 -42.813162) (xy 375.24221 -42.758257) (xy 375.258129 -42.705097)
			(xy 375.281588 -42.654807) (xy 375.29643 -42.63136) (xy 375.300291 -42.625029) (xy 375.304543 -42.610831)
			(xy 375.304812 -42.60342) (xy 375.304812 -41.423844) (xy 375.304427 -41.414077) (xy 375.297257 -41.395911)
			(xy 375.290842 -41.388538) (xy 375.270014 -41.366948) (xy 375.261632 -41.362884) (xy 375.238264 -41.351454)
			(xy 375.229882 -41.350438) (xy 375.202483 -41.346598) (xy 375.149108 -41.332035) (xy 375.098397 -41.309916)
			(xy 375.051412 -41.280704) (xy 375.009139 -41.245013) (xy 374.972463 -41.203591) (xy 374.942155 -41.157305)
			(xy 374.91885 -41.107128) (xy 374.903036 -41.054111) (xy 374.895045 -40.999366) (xy 374.895044 -40.94404)
			(xy 374.903035 -40.889295) (xy 374.918848 -40.836277) (xy 374.942152 -40.7861) (xy 374.97246 -40.739814)
			(xy 375.009135 -40.698391) (xy 375.051407 -40.662699) (xy 375.098392 -40.633487) (xy 375.149103 -40.611367)
			(xy 375.202477 -40.596803) (xy 375.229882 -40.59301) (xy 375.238264 -40.591994) (xy 375.261886 -40.580564)
			(xy 375.265912 -40.578497) (xy 375.273198 -40.57313) (xy 375.276364 -40.569896) (xy 375.290842 -40.55491)
			(xy 375.297265 -40.547537) (xy 375.304464 -40.529375) (xy 375.304812 -40.519604) (xy 375.304812 -38.432232)
			(xy 375.304398 -38.422206) (xy 375.296734 -38.403676) (xy 375.282561 -38.38949) (xy 375.264038 -38.381811)
			(xy 375.254012 -38.381432) (xy 373.584216 -38.381432) (xy 373.575077 -38.381812) (xy 373.557962 -38.388225)
			(xy 373.544189 -38.400241) (xy 373.539512 -38.408102) (xy 373.497348 -38.486842) (xy 373.494335 -38.492877)
			(xy 373.491256 -38.506004) (xy 373.491252 -38.51275) (xy 373.49176 -38.527228) (xy 373.499634 -38.539166)
			(xy 373.514767 -38.562785) (xy 373.538691 -38.613521) (xy 373.554935 -38.667212) (xy 373.563149 -38.722701)
			(xy 373.563642 -38.750748) (xy 373.563153 -38.777998) (xy 373.555391 -38.831942) (xy 373.540032 -38.884233)
			(xy 373.517389 -38.933807) (xy 373.487922 -38.979653) (xy 373.452231 -39.020841) (xy 373.411042 -39.05653)
			(xy 373.365194 -39.085995) (xy 373.31562 -39.108637) (xy 373.263329 -39.123994) (xy 373.209384 -39.131754)
			(xy 373.182134 -39.132256) (xy 373.153834 -39.131737) (xy 373.097856 -39.123368) (xy 373.043728 -39.106824)
			(xy 372.992636 -39.082467) (xy 372.945703 -39.050832) (xy 372.903956 -39.012612) (xy 372.868311 -38.968645)
			(xy 372.853458 -38.94455) (xy 372.846854 -38.933374) (xy 372.825264 -38.920166) (xy 372.780052 -38.917626)
			(xy 372.71579 -38.913816) (xy 372.69293 -38.92423) (xy 372.68531 -38.93439) (xy 372.667121 -38.957266)
			(xy 372.624966 -38.997741) (xy 372.577133 -39.031316) (xy 372.52474 -39.057206) (xy 372.469013 -39.074807)
			(xy 372.411254 -39.083706) (xy 372.382034 -39.08425) (xy 372.35478 -39.083767) (xy 372.300826 -39.076014)
			(xy 372.248525 -39.060662) (xy 372.198941 -39.038024) (xy 372.153083 -39.008559) (xy 372.111886 -38.972868)
			(xy 372.076186 -38.931678) (xy 372.046713 -38.885826) (xy 372.024064 -38.836246) (xy 372.008702 -38.783948)
			(xy 372.000939 -38.729996) (xy 372.000526 -38.702742) (xy 372.001085 -38.672656) (xy 372.010528 -38.613231)
			(xy 372.029203 -38.556031) (xy 372.042436 -38.529006) (xy 372.048532 -38.517068) (xy 372.047516 -38.490906)
			(xy 371.995192 -38.405562) (xy 371.990358 -38.398405) (xy 371.976914 -38.387578) (xy 371.960642 -38.381821)
			(xy 371.952012 -38.381432) (xy 369.58524 -38.381432) (xy 369.576382 -38.381852) (xy 369.559743 -38.387947)
			(xy 369.552728 -38.39337) (xy 369.341146 -38.604952) (xy 369.263676 -38.682168) (xy 369.239776 -38.705332)
			(xy 369.18697 -38.745848) (xy 369.129326 -38.779123) (xy 369.06783 -38.804586) (xy 369.003537 -38.821801)
			(xy 368.937545 -38.830475) (xy 368.904266 -38.831012) (xy 367.288826 -38.831012) (xy 367.25555 -38.830464)
			(xy 367.189567 -38.82177) (xy 367.125284 -38.804541) (xy 367.063797 -38.779072) (xy 367.00616 -38.745797)
			(xy 366.953357 -38.705286) (xy 366.929416 -38.682168) (xy 366.081818 -37.83457) (xy 366.058281 -37.810282)
			(xy 366.017179 -37.756569) (xy 365.983556 -37.697884) (xy 365.958006 -37.635262) (xy 365.948976 -37.602668)
			(xy 365.941375 -37.57134) (xy 365.933218 -37.507393) (xy 365.93272 -37.47516) (xy 365.933184 -37.44447)
			(xy 365.940578 -37.383538) (xy 365.955253 -37.323938) (xy 365.976996 -37.266539) (xy 366.005491 -37.212174)
			(xy 366.040324 -37.161636) (xy 366.080987 -37.115657) (xy 366.126889 -37.074909) (xy 366.177363 -37.039982)
			(xy 366.231674 -37.011386) (xy 366.289033 -36.989536) (xy 366.348605 -36.97475) (xy 366.409523 -36.967242)
			(xy 366.440212 -36.966652) (xy 366.441228 -36.966652) (xy 366.473461 -36.967147) (xy 366.53741 -36.975297)
			(xy 366.568736 -36.982908) (xy 366.601331 -36.99194) (xy 366.663967 -37.017465) (xy 366.722661 -37.051079)
			(xy 366.776374 -37.092186) (xy 366.800638 -37.11575) (xy 367.484406 -37.799518) (xy 367.491801 -37.806372)
			(xy 367.5104 -37.814118) (xy 367.520474 -37.814504) (xy 368.149886 -37.814504) (xy 368.160638 -37.814031)
			(xy 368.180252 -37.805223) (xy 368.187732 -37.797486) (xy 368.238278 -37.741352) (xy 368.244845 -37.733234)
			(xy 368.251401 -37.713431) (xy 368.250978 -37.702998) (xy 368.250978 -37.702236) (xy 368.250012 -37.692295)
			(xy 368.248996 -37.672346) (xy 368.248946 -37.662358) (xy 368.249435 -37.635108) (xy 368.257196 -37.581162)
			(xy 368.272554 -37.52887) (xy 368.295197 -37.479295) (xy 368.324664 -37.433446) (xy 368.360354 -37.392257)
			(xy 368.401543 -37.356566) (xy 368.447391 -37.327099) (xy 368.496966 -37.304455) (xy 368.549258 -37.289097)
			(xy 368.603204 -37.281335) (xy 368.630454 -37.28085) (xy 368.659505 -37.281398) (xy 368.716934 -37.290213)
			(xy 368.772363 -37.307631) (xy 368.824512 -37.333249) (xy 368.872175 -37.366476) (xy 368.914251 -37.406543)
			(xy 368.93246 -37.429186) (xy 368.938556 -37.43706) (xy 368.946938 -37.44214) (xy 368.951097 -37.444439)
			(xy 368.960043 -37.447639) (xy 368.964718 -37.44849) (xy 369.033044 -37.459666) (xy 369.04262 -37.460804)
			(xy 369.061428 -37.456625) (xy 369.06962 -37.451538) (xy 369.069874 -37.451284) (xy 369.097559 -37.433229)
			(xy 369.156675 -37.40367) (xy 369.18773 -37.392356) (xy 369.214561 -37.383492) (xy 369.269685 -37.371061)
			(xy 369.325846 -37.364802) (xy 369.3541 -37.364416) (xy 375.254012 -37.364416) (xy 375.264019 -37.363926)
			(xy 375.28251 -37.356265) (xy 375.296663 -37.342113) (xy 375.304326 -37.323623) (xy 375.304812 -37.313616)
			(xy 375.304812 -31.63316) (xy 375.30405 -31.629096) (xy 375.301767 -31.613896) (xy 375.29935 -31.583252)
			(xy 375.299224 -31.567882) (xy 375.299344 -31.552512) (xy 375.301762 -31.521867) (xy 375.30405 -31.506668)
			(xy 375.304812 -31.502604) (xy 375.304812 -30.681168) (xy 375.304689 -30.676355) (xy 375.302898 -30.666897)
			(xy 375.301256 -30.662372) (xy 375.291604 -30.637734) (xy 375.285508 -30.630876) (xy 375.267386 -30.609786)
			(xy 375.236806 -30.563347) (xy 375.213287 -30.512963) (xy 375.197326 -30.459699) (xy 375.189262 -30.404684)
			(xy 375.189265 -30.34908) (xy 375.197334 -30.294066) (xy 375.2133 -30.240804) (xy 375.236823 -30.190422)
			(xy 375.267408 -30.143985) (xy 375.285508 -30.122876) (xy 375.291604 -30.116018) (xy 375.301256 -30.09138)
			(xy 375.302944 -30.086867) (xy 375.304741 -30.077402) (xy 375.304812 -30.072584) (xy 375.304812 -29.909008)
			(xy 375.291096 -29.874972) (xy 375.285254 -29.868368) (xy 375.267208 -29.847302) (xy 375.236765 -29.800933)
			(xy 375.213357 -29.750645) (xy 375.197479 -29.697498) (xy 375.189464 -29.642611) (xy 375.188988 -29.614876)
			(xy 375.188988 -29.614368) (xy 375.189594 -29.583501) (xy 375.199561 -29.522575) (xy 375.219212 -29.464051)
			(xy 375.248034 -29.409458) (xy 375.266204 -29.384498) (xy 375.270878 -29.377759) (xy 375.276069 -29.362213)
			(xy 375.276364 -29.354018) (xy 375.276364 -29.062934) (xy 375.276059 -29.054739) (xy 375.270883 -29.039189)
			(xy 375.266204 -29.032454) (xy 375.25 -29.010241) (xy 375.223461 -28.962088) (xy 375.204104 -28.910627)
			(xy 375.192328 -28.856921) (xy 375.188377 -28.802081) (xy 375.192333 -28.747241) (xy 375.204115 -28.693537)
			(xy 375.223477 -28.642077) (xy 375.250021 -28.593927) (xy 375.266204 -28.571698) (xy 375.270878 -28.564959)
			(xy 375.276069 -28.549413) (xy 375.276364 -28.541218) (xy 375.276364 -28.368752) (xy 375.276591 -28.361714)
			(xy 375.280463 -28.348181) (xy 375.283984 -28.342082) (xy 375.296938 -28.322016) (xy 375.300595 -28.315758)
			(xy 375.304586 -28.30183) (xy 375.304812 -28.294584) (xy 375.304812 -27.872436) (xy 375.304378 -27.862371)
			(xy 375.296648 -27.843782) (xy 375.289826 -27.836368) (xy 375.050304 -27.596846) (xy 375.042908 -27.589994)
			(xy 375.024309 -27.582251) (xy 375.014236 -27.58186) (xy 365.699548 -27.58186) (xy 365.687222 -27.582455)
			(xy 365.665392 -27.593905) (xy 365.657892 -27.603704) (xy 365.640732 -27.627665) (xy 365.601226 -27.6714)
			(xy 365.556435 -27.709706) (xy 365.5071 -27.74195) (xy 365.454037 -27.767598) (xy 365.398122 -27.786227)
			(xy 365.340279 -27.797529) (xy 365.281464 -27.801317) (xy 365.222649 -27.797529) (xy 365.164806 -27.786227)
			(xy 365.108891 -27.767598) (xy 365.055828 -27.74195) (xy 365.006493 -27.709706) (xy 364.961702 -27.6714)
			(xy 364.922196 -27.627665) (xy 364.905036 -27.603704) (xy 364.897421 -27.59404) (xy 364.87566 -27.582642)
			(xy 364.86338 -27.58186) (xy 360.728006 -27.58186) (xy 360.717937 -27.582284) (xy 360.699336 -27.590003)
			(xy 360.691938 -27.596846) (xy 360.422952 -27.865832) (xy 360.416602 -27.877262) (xy 360.414824 -27.88412)
			(xy 360.407098 -27.91235) (xy 360.384186 -27.966204) (xy 360.35332 -28.015929) (xy 360.315224 -28.060358)
			(xy 360.27079 -28.098449) (xy 360.221061 -28.129309) (xy 360.167204 -28.152214) (xy 360.13898 -28.159964)
			(xy 360.132122 -28.161742) (xy 360.120692 -28.168092) (xy 360.104944 -28.18384) (xy 360.098099 -28.191239)
			(xy 360.090372 -28.209837) (xy 360.089958 -28.219908) (xy 360.089958 -29.114242) (xy 367.147348 -29.114242)
			(xy 367.147348 -28.250642) (xy 367.147838 -28.220658) (xy 367.155666 -28.161202) (xy 367.171187 -28.103277)
			(xy 367.194136 -28.047873) (xy 367.22412 -27.995939) (xy 367.260626 -27.948363) (xy 367.303031 -27.905958)
			(xy 367.350607 -27.869452) (xy 367.402541 -27.839468) (xy 367.457945 -27.816519) (xy 367.51587 -27.800998)
			(xy 367.575326 -27.79317) (xy 367.635294 -27.79317) (xy 367.69475 -27.800998) (xy 367.752675 -27.816519)
			(xy 367.808079 -27.839468) (xy 367.860013 -27.869452) (xy 367.907589 -27.905958) (xy 367.949994 -27.948363)
			(xy 367.9865 -27.995939) (xy 368.016484 -28.047873) (xy 368.039433 -28.103277) (xy 368.054954 -28.161202)
			(xy 368.062782 -28.220658) (xy 368.063272 -28.250642) (xy 368.063272 -28.469082) (xy 372.052594 -28.469082)
			(xy 372.056665 -28.41346) (xy 372.068791 -28.359023) (xy 372.088714 -28.306932) (xy 372.11601 -28.258297)
			(xy 372.150096 -28.214154) (xy 372.190245 -28.175445) (xy 372.235603 -28.142994) (xy 372.285203 -28.117493)
			(xy 372.337987 -28.099486) (xy 372.39283 -28.089356) (xy 372.448564 -28.087319) (xy 372.504001 -28.093419)
			(xy 372.557958 -28.107525) (xy 372.609287 -28.129337) (xy 372.656893 -28.158391) (xy 372.699761 -28.194066)
			(xy 372.736978 -28.235603) (xy 372.767751 -28.282116) (xy 372.791423 -28.332613) (xy 372.807491 -28.38602)
			(xy 372.815611 -28.441196) (xy 372.81612 -28.469082) (xy 372.815611 -28.496968) (xy 372.807491 -28.552144)
			(xy 372.791423 -28.605551) (xy 372.767751 -28.656048) (xy 372.736978 -28.702561) (xy 372.699761 -28.744098)
			(xy 372.656893 -28.779773) (xy 372.609287 -28.808827) (xy 372.557958 -28.830639) (xy 372.504001 -28.844745)
			(xy 372.448564 -28.850845) (xy 372.39283 -28.848808) (xy 372.337987 -28.838678) (xy 372.285203 -28.820671)
			(xy 372.235603 -28.79517) (xy 372.190245 -28.762719) (xy 372.150096 -28.72401) (xy 372.11601 -28.679867)
			(xy 372.088714 -28.631232) (xy 372.068791 -28.579141) (xy 372.056665 -28.524704) (xy 372.052594 -28.469082)
			(xy 368.063272 -28.469082) (xy 368.063272 -29.114242) (xy 368.062782 -29.144226) (xy 368.054954 -29.203682)
			(xy 368.039433 -29.261607) (xy 368.016484 -29.317011) (xy 367.9865 -29.368945) (xy 367.949994 -29.416521)
			(xy 367.907589 -29.458926) (xy 367.860013 -29.495432) (xy 367.808079 -29.525416) (xy 367.752675 -29.548365)
			(xy 367.69475 -29.563886) (xy 367.635294 -29.571714) (xy 367.575326 -29.571714) (xy 367.51587 -29.563886)
			(xy 367.457945 -29.548365) (xy 367.402541 -29.525416) (xy 367.350607 -29.495432) (xy 367.303031 -29.458926)
			(xy 367.260626 -29.416521) (xy 367.22412 -29.368945) (xy 367.194136 -29.317011) (xy 367.171187 -29.261607)
			(xy 367.155666 -29.203682) (xy 367.147838 -29.144226) (xy 367.147348 -29.114242) (xy 360.089958 -29.114242)
			(xy 360.089958 -29.186378) (xy 360.112056 -29.214064) (xy 360.129582 -29.217874) (xy 360.155876 -29.224335)
			(xy 360.206448 -29.243678) (xy 360.253778 -29.269975) (xy 360.296916 -29.302698) (xy 360.334996 -29.341189)
			(xy 360.367252 -29.384677) (xy 360.393038 -29.432287) (xy 360.411836 -29.483064) (xy 360.423268 -29.535988)
			(xy 360.427105 -29.589996) (xy 360.423269 -29.644005) (xy 360.411838 -29.696929) (xy 360.393041 -29.747707)
			(xy 360.367256 -29.795317) (xy 360.335 -29.838805) (xy 360.296921 -29.877298) (xy 360.253784 -29.910021)
			(xy 360.206454 -29.936319) (xy 360.155883 -29.955663) (xy 360.129582 -29.962094) (xy 360.112056 -29.965904)
			(xy 360.089958 -29.99359) (xy 360.089958 -30.92069) (xy 369.789456 -30.92069) (xy 369.789456 -30.05709)
			(xy 369.789946 -30.027106) (xy 369.797774 -29.96765) (xy 369.813295 -29.909725) (xy 369.836244 -29.854321)
			(xy 369.866228 -29.802387) (xy 369.902734 -29.754811) (xy 369.945139 -29.712406) (xy 369.992715 -29.6759)
			(xy 370.044649 -29.645916) (xy 370.100053 -29.622967) (xy 370.157978 -29.607446) (xy 370.217434 -29.599618)
			(xy 370.277402 -29.599618) (xy 370.336858 -29.607446) (xy 370.394783 -29.622967) (xy 370.450187 -29.645916)
			(xy 370.502121 -29.6759) (xy 370.549697 -29.712406) (xy 370.592102 -29.754811) (xy 370.628608 -29.802387)
			(xy 370.658592 -29.854321) (xy 370.681541 -29.909725) (xy 370.697062 -29.96765) (xy 370.70489 -30.027106)
			(xy 370.70538 -30.05709) (xy 370.70538 -30.92069) (xy 370.70489 -30.950674) (xy 370.697062 -31.01013)
			(xy 370.681541 -31.068055) (xy 370.658592 -31.123459) (xy 370.628608 -31.175393) (xy 370.592102 -31.222969)
			(xy 370.549697 -31.265374) (xy 370.502121 -31.30188) (xy 370.450187 -31.331864) (xy 370.394783 -31.354813)
			(xy 370.336858 -31.370334) (xy 370.277402 -31.378162) (xy 370.217434 -31.378162) (xy 370.157978 -31.370334)
			(xy 370.100053 -31.354813) (xy 370.044649 -31.331864) (xy 369.992715 -31.30188) (xy 369.945139 -31.265374)
			(xy 369.902734 -31.222969) (xy 369.866228 -31.175393) (xy 369.836244 -31.123459) (xy 369.813295 -31.068055)
			(xy 369.797774 -31.01013) (xy 369.789946 -30.950674) (xy 369.789456 -30.92069) (xy 360.089958 -30.92069)
			(xy 360.089958 -32.714184) (xy 367.147348 -32.714184) (xy 367.147348 -31.850584) (xy 367.147838 -31.8206)
			(xy 367.155666 -31.761144) (xy 367.171187 -31.703219) (xy 367.194136 -31.647815) (xy 367.22412 -31.595881)
			(xy 367.260626 -31.548305) (xy 367.303031 -31.5059) (xy 367.350607 -31.469394) (xy 367.402541 -31.43941)
			(xy 367.457945 -31.416461) (xy 367.51587 -31.40094) (xy 367.575326 -31.393112) (xy 367.635294 -31.393112)
			(xy 367.69475 -31.40094) (xy 367.752675 -31.416461) (xy 367.808079 -31.43941) (xy 367.860013 -31.469394)
			(xy 367.907589 -31.5059) (xy 367.949994 -31.548305) (xy 367.9865 -31.595881) (xy 368.016484 -31.647815)
			(xy 368.039433 -31.703219) (xy 368.054954 -31.761144) (xy 368.062782 -31.8206) (xy 368.063272 -31.850584)
			(xy 368.063272 -32.714184) (xy 368.062782 -32.744168) (xy 368.054954 -32.803624) (xy 368.039433 -32.861549)
			(xy 368.016484 -32.916953) (xy 367.9865 -32.968887) (xy 367.949994 -33.016463) (xy 367.907589 -33.058868)
			(xy 367.860013 -33.095374) (xy 367.808079 -33.125358) (xy 367.752675 -33.148307) (xy 367.69475 -33.163828)
			(xy 367.635294 -33.171656) (xy 367.575326 -33.171656) (xy 367.51587 -33.163828) (xy 367.457945 -33.148307)
			(xy 367.402541 -33.125358) (xy 367.350607 -33.095374) (xy 367.303031 -33.058868) (xy 367.260626 -33.016463)
			(xy 367.22412 -32.968887) (xy 367.194136 -32.916953) (xy 367.171187 -32.861549) (xy 367.155666 -32.803624)
			(xy 367.147838 -32.744168) (xy 367.147348 -32.714184) (xy 360.089958 -32.714184) (xy 360.089958 -34.520886)
			(xy 369.789456 -34.520886) (xy 369.789456 -33.657286) (xy 369.789946 -33.627302) (xy 369.797774 -33.567846)
			(xy 369.813295 -33.509921) (xy 369.836244 -33.454517) (xy 369.866228 -33.402583) (xy 369.902734 -33.355007)
			(xy 369.945139 -33.312602) (xy 369.992715 -33.276096) (xy 370.044649 -33.246112) (xy 370.100053 -33.223163)
			(xy 370.157978 -33.207642) (xy 370.217434 -33.199814) (xy 370.277402 -33.199814) (xy 370.336858 -33.207642)
			(xy 370.394783 -33.223163) (xy 370.450187 -33.246112) (xy 370.502121 -33.276096) (xy 370.549697 -33.312602)
			(xy 370.592102 -33.355007) (xy 370.628608 -33.402583) (xy 370.658592 -33.454517) (xy 370.681541 -33.509921)
			(xy 370.697062 -33.567846) (xy 370.70489 -33.627302) (xy 370.70538 -33.657286) (xy 370.70538 -34.520886)
			(xy 370.70489 -34.55087) (xy 370.697062 -34.610326) (xy 370.681541 -34.668251) (xy 370.658592 -34.723655)
			(xy 370.628608 -34.775589) (xy 370.592102 -34.823165) (xy 370.549697 -34.86557) (xy 370.502121 -34.902076)
			(xy 370.450187 -34.93206) (xy 370.394783 -34.955009) (xy 370.336858 -34.97053) (xy 370.277402 -34.978358)
			(xy 370.217434 -34.978358) (xy 370.157978 -34.97053) (xy 370.100053 -34.955009) (xy 370.044649 -34.93206)
			(xy 369.992715 -34.902076) (xy 369.945139 -34.86557) (xy 369.902734 -34.823165) (xy 369.866228 -34.775589)
			(xy 369.836244 -34.723655) (xy 369.813295 -34.668251) (xy 369.797774 -34.610326) (xy 369.789946 -34.55087)
			(xy 369.789456 -34.520886) (xy 360.089958 -34.520886) (xy 360.089958 -36.60013) (xy 360.298499 -36.60013)
			(xy 360.302503 -36.512245) (xy 360.314483 -36.425088) (xy 360.334338 -36.339381) (xy 360.361905 -36.255836)
			(xy 360.396955 -36.175143) (xy 360.439197 -36.097971) (xy 360.488282 -36.024961) (xy 360.543803 -35.956717)
			(xy 360.6053 -35.893804) (xy 360.672262 -35.836744) (xy 360.744136 -35.78601) (xy 360.820326 -35.742022)
			(xy 360.9002 -35.705144) (xy 360.983097 -35.675683) (xy 361.068329 -35.653881) (xy 361.155191 -35.639921)
			(xy 361.242962 -35.633917) (xy 361.330916 -35.63592) (xy 361.418323 -35.645912) (xy 361.504459 -35.663812)
			(xy 361.588611 -35.68947) (xy 361.670081 -35.722674) (xy 361.748194 -35.763148) (xy 361.822302 -35.810559)
			(xy 361.891793 -35.864512) (xy 361.904884 -35.876738) (xy 367.017298 -35.876738) (xy 367.021369 -35.821116)
			(xy 367.033495 -35.766679) (xy 367.053418 -35.714588) (xy 367.080714 -35.665953) (xy 367.1148 -35.62181)
			(xy 367.154949 -35.583101) (xy 367.200307 -35.55065) (xy 367.249907 -35.525149) (xy 367.302691 -35.507142)
			(xy 367.357534 -35.497012) (xy 367.413268 -35.494975) (xy 367.468705 -35.501075) (xy 367.522662 -35.515181)
			(xy 367.573991 -35.536993) (xy 367.621597 -35.566047) (xy 367.664465 -35.601722) (xy 367.701682 -35.643259)
			(xy 367.732455 -35.689772) (xy 367.756127 -35.740269) (xy 367.772195 -35.793676) (xy 367.780315 -35.848852)
			(xy 367.780824 -35.876738) (xy 371.088918 -35.876738) (xy 371.092989 -35.821116) (xy 371.105115 -35.766679)
			(xy 371.125038 -35.714588) (xy 371.152334 -35.665953) (xy 371.18642 -35.62181) (xy 371.226569 -35.583101)
			(xy 371.271927 -35.55065) (xy 371.321527 -35.525149) (xy 371.374311 -35.507142) (xy 371.429154 -35.497012)
			(xy 371.484888 -35.494975) (xy 371.540325 -35.501075) (xy 371.594282 -35.515181) (xy 371.645611 -35.536993)
			(xy 371.693217 -35.566047) (xy 371.736085 -35.601722) (xy 371.773302 -35.643259) (xy 371.804075 -35.689772)
			(xy 371.827747 -35.740269) (xy 371.843815 -35.793676) (xy 371.851935 -35.848852) (xy 371.852444 -35.876738)
			(xy 371.851935 -35.904624) (xy 371.843815 -35.9598) (xy 371.827747 -36.013207) (xy 371.804075 -36.063704)
			(xy 371.773302 -36.110217) (xy 371.736085 -36.151754) (xy 371.693217 -36.187429) (xy 371.645611 -36.216483)
			(xy 371.594282 -36.238295) (xy 371.540325 -36.252401) (xy 371.484888 -36.258501) (xy 371.429154 -36.256464)
			(xy 371.374311 -36.246334) (xy 371.321527 -36.228327) (xy 371.271927 -36.202826) (xy 371.226569 -36.170375)
			(xy 371.18642 -36.131666) (xy 371.152334 -36.087523) (xy 371.125038 -36.038888) (xy 371.105115 -35.986797)
			(xy 371.092989 -35.93236) (xy 371.088918 -35.876738) (xy 367.780824 -35.876738) (xy 367.780315 -35.904624)
			(xy 367.772195 -35.9598) (xy 367.756127 -36.013207) (xy 367.732455 -36.063704) (xy 367.701682 -36.110217)
			(xy 367.664465 -36.151754) (xy 367.621597 -36.187429) (xy 367.573991 -36.216483) (xy 367.522662 -36.238295)
			(xy 367.468705 -36.252401) (xy 367.413268 -36.258501) (xy 367.357534 -36.256464) (xy 367.302691 -36.246334)
			(xy 367.249907 -36.228327) (xy 367.200307 -36.202826) (xy 367.154949 -36.170375) (xy 367.1148 -36.131666)
			(xy 367.080714 -36.087523) (xy 367.053418 -36.038888) (xy 367.033495 -35.986797) (xy 367.021369 -35.93236)
			(xy 367.017298 -35.876738) (xy 361.904884 -35.876738) (xy 361.956089 -35.92456) (xy 362.014658 -35.990207)
			(xy 362.067015 -36.060907) (xy 362.112727 -36.136076) (xy 362.151413 -36.21509) (xy 362.182754 -36.297295)
			(xy 362.206489 -36.382009) (xy 362.222423 -36.46853) (xy 362.226206 -36.50996) (xy 368.913916 -36.50996)
			(xy 368.917987 -36.454338) (xy 368.930113 -36.399901) (xy 368.950036 -36.34781) (xy 368.977332 -36.299175)
			(xy 369.011418 -36.255032) (xy 369.051567 -36.216323) (xy 369.096925 -36.183872) (xy 369.146525 -36.158371)
			(xy 369.199309 -36.140364) (xy 369.254152 -36.130234) (xy 369.309886 -36.128197) (xy 369.365323 -36.134297)
			(xy 369.41928 -36.148403) (xy 369.470609 -36.170215) (xy 369.518215 -36.199269) (xy 369.561083 -36.234944)
			(xy 369.5983 -36.276481) (xy 369.629073 -36.322994) (xy 369.652745 -36.373491) (xy 369.668813 -36.426898)
			(xy 369.672738 -36.453572) (xy 372.228616 -36.453572) (xy 372.232687 -36.39795) (xy 372.244813 -36.343513)
			(xy 372.264736 -36.291422) (xy 372.292032 -36.242787) (xy 372.326118 -36.198644) (xy 372.366267 -36.159935)
			(xy 372.411625 -36.127484) (xy 372.461225 -36.101983) (xy 372.514009 -36.083976) (xy 372.568852 -36.073846)
			(xy 372.624586 -36.071809) (xy 372.680023 -36.077909) (xy 372.73398 -36.092015) (xy 372.785309 -36.113827)
			(xy 372.832915 -36.142881) (xy 372.875783 -36.178556) (xy 372.913 -36.220093) (xy 372.943773 -36.266606)
			(xy 372.967445 -36.317103) (xy 372.983513 -36.37051) (xy 372.991633 -36.425686) (xy 372.992142 -36.453572)
			(xy 372.991633 -36.481458) (xy 372.983513 -36.536634) (xy 372.967445 -36.590041) (xy 372.943773 -36.640538)
			(xy 372.913 -36.687051) (xy 372.875783 -36.728588) (xy 372.832915 -36.764263) (xy 372.785309 -36.793317)
			(xy 372.73398 -36.815129) (xy 372.680023 -36.829235) (xy 372.624586 -36.835335) (xy 372.568852 -36.833298)
			(xy 372.514009 -36.823168) (xy 372.461225 -36.805161) (xy 372.411625 -36.77966) (xy 372.366267 -36.747209)
			(xy 372.326118 -36.7085) (xy 372.292032 -36.664357) (xy 372.264736 -36.615722) (xy 372.244813 -36.563631)
			(xy 372.232687 -36.509194) (xy 372.228616 -36.453572) (xy 369.672738 -36.453572) (xy 369.676933 -36.482074)
			(xy 369.677442 -36.50996) (xy 369.676933 -36.537846) (xy 369.668813 -36.593022) (xy 369.652745 -36.646429)
			(xy 369.629073 -36.696926) (xy 369.5983 -36.743439) (xy 369.561083 -36.784976) (xy 369.518215 -36.820651)
			(xy 369.470609 -36.849705) (xy 369.41928 -36.871517) (xy 369.365323 -36.885623) (xy 369.309886 -36.891723)
			(xy 369.254152 -36.889686) (xy 369.199309 -36.879556) (xy 369.146525 -36.861549) (xy 369.096925 -36.836048)
			(xy 369.051567 -36.803597) (xy 369.011418 -36.764888) (xy 368.977332 -36.720745) (xy 368.950036 -36.67211)
			(xy 368.930113 -36.620019) (xy 368.917987 -36.565582) (xy 368.913916 -36.50996) (xy 362.226206 -36.50996)
			(xy 362.230423 -36.556142) (xy 362.230924 -36.60013) (xy 362.230423 -36.644118) (xy 362.222423 -36.73173)
			(xy 362.206489 -36.818251) (xy 362.182754 -36.902965) (xy 362.151413 -36.98517) (xy 362.112727 -37.064184)
			(xy 362.067015 -37.139353) (xy 362.014658 -37.210053) (xy 361.956089 -37.2757) (xy 361.891793 -37.335748)
			(xy 361.822302 -37.389701) (xy 361.748194 -37.437112) (xy 361.670081 -37.477586) (xy 361.588611 -37.51079)
			(xy 361.504459 -37.536448) (xy 361.418323 -37.554348) (xy 361.330916 -37.56434) (xy 361.242962 -37.566343)
			(xy 361.155191 -37.560339) (xy 361.068329 -37.546379) (xy 360.983097 -37.524577) (xy 360.9002 -37.495116)
			(xy 360.820326 -37.458238) (xy 360.744136 -37.41425) (xy 360.672262 -37.363516) (xy 360.6053 -37.306456)
			(xy 360.543803 -37.243543) (xy 360.488282 -37.175299) (xy 360.439197 -37.102289) (xy 360.396955 -37.025117)
			(xy 360.361905 -36.944424) (xy 360.334338 -36.860879) (xy 360.314483 -36.775172) (xy 360.302503 -36.688015)
			(xy 360.298499 -36.60013) (xy 360.089958 -36.60013) (xy 360.089958 -39.97198) (xy 374.195846 -39.97198)
			(xy 374.199917 -39.916358) (xy 374.212043 -39.861921) (xy 374.231966 -39.80983) (xy 374.259262 -39.761195)
			(xy 374.293348 -39.717052) (xy 374.333497 -39.678343) (xy 374.378855 -39.645892) (xy 374.428455 -39.620391)
			(xy 374.481239 -39.602384) (xy 374.536082 -39.592254) (xy 374.591816 -39.590217) (xy 374.647253 -39.596317)
			(xy 374.70121 -39.610423) (xy 374.752539 -39.632235) (xy 374.800145 -39.661289) (xy 374.843013 -39.696964)
			(xy 374.88023 -39.738501) (xy 374.911003 -39.785014) (xy 374.934675 -39.835511) (xy 374.950743 -39.888918)
			(xy 374.958863 -39.944094) (xy 374.959372 -39.97198) (xy 374.958863 -39.999866) (xy 374.950743 -40.055042)
			(xy 374.934675 -40.108449) (xy 374.911003 -40.158946) (xy 374.88023 -40.205459) (xy 374.843013 -40.246996)
			(xy 374.800145 -40.282671) (xy 374.752539 -40.311725) (xy 374.70121 -40.333537) (xy 374.647253 -40.347643)
			(xy 374.591816 -40.353743) (xy 374.536082 -40.351706) (xy 374.481239 -40.341576) (xy 374.428455 -40.323569)
			(xy 374.378855 -40.298068) (xy 374.333497 -40.265617) (xy 374.293348 -40.226908) (xy 374.259262 -40.182765)
			(xy 374.231966 -40.13413) (xy 374.212043 -40.082039) (xy 374.199917 -40.027602) (xy 374.195846 -39.97198)
			(xy 360.089958 -39.97198) (xy 360.089958 -40.452802) (xy 360.090383 -40.462871) (xy 360.098104 -40.481469)
			(xy 360.104944 -40.48887) (xy 360.324146 -40.708072) (xy 360.331546 -40.714914) (xy 360.350144 -40.722636)
			(xy 360.360214 -40.723058) (xy 369.381532 -40.723058) (xy 369.391598 -40.723489) (xy 369.410189 -40.731218)
			(xy 369.4176 -40.738044) (xy 370.35867 -41.679114) (xy 370.365517 -41.686512) (xy 370.373252 -41.70511)
			(xy 370.373656 -41.715182) (xy 370.373656 -43.566842) (xy 371.633494 -43.566842) (xy 371.637565 -43.51122)
			(xy 371.649691 -43.456783) (xy 371.669614 -43.404692) (xy 371.69691 -43.356057) (xy 371.730996 -43.311914)
			(xy 371.771145 -43.273205) (xy 371.816503 -43.240754) (xy 371.866103 -43.215253) (xy 371.918887 -43.197246)
			(xy 371.97373 -43.187116) (xy 372.029464 -43.185079) (xy 372.084901 -43.191179) (xy 372.138858 -43.205285)
			(xy 372.190187 -43.227097) (xy 372.237793 -43.256151) (xy 372.280661 -43.291826) (xy 372.317878 -43.333363)
			(xy 372.348651 -43.379876) (xy 372.372323 -43.430373) (xy 372.388391 -43.48378) (xy 372.396511 -43.538956)
			(xy 372.39702 -43.566842) (xy 372.396511 -43.594728) (xy 372.388391 -43.649904) (xy 372.372323 -43.703311)
			(xy 372.348651 -43.753808) (xy 372.317878 -43.800321) (xy 372.280661 -43.841858) (xy 372.262574 -43.85691)
			(xy 373.019826 -43.85691) (xy 373.023897 -43.801288) (xy 373.036023 -43.746851) (xy 373.055946 -43.69476)
			(xy 373.083242 -43.646125) (xy 373.117328 -43.601982) (xy 373.157477 -43.563273) (xy 373.202835 -43.530822)
			(xy 373.252435 -43.505321) (xy 373.305219 -43.487314) (xy 373.360062 -43.477184) (xy 373.415796 -43.475147)
			(xy 373.471233 -43.481247) (xy 373.52519 -43.495353) (xy 373.576519 -43.517165) (xy 373.624125 -43.546219)
			(xy 373.666993 -43.581894) (xy 373.70421 -43.623431) (xy 373.734983 -43.669944) (xy 373.758655 -43.720441)
			(xy 373.774723 -43.773848) (xy 373.782843 -43.829024) (xy 373.783352 -43.85691) (xy 373.782843 -43.884796)
			(xy 373.774723 -43.939972) (xy 373.758655 -43.993379) (xy 373.734983 -44.043876) (xy 373.70421 -44.090389)
			(xy 373.666993 -44.131926) (xy 373.624125 -44.167601) (xy 373.576519 -44.196655) (xy 373.52519 -44.218467)
			(xy 373.471233 -44.232573) (xy 373.415796 -44.238673) (xy 373.360062 -44.236636) (xy 373.305219 -44.226506)
			(xy 373.252435 -44.208499) (xy 373.202835 -44.182998) (xy 373.157477 -44.150547) (xy 373.117328 -44.111838)
			(xy 373.083242 -44.067695) (xy 373.055946 -44.01906) (xy 373.036023 -43.966969) (xy 373.023897 -43.912532)
			(xy 373.019826 -43.85691) (xy 372.262574 -43.85691) (xy 372.237793 -43.877533) (xy 372.190187 -43.906587)
			(xy 372.138858 -43.928399) (xy 372.084901 -43.942505) (xy 372.029464 -43.948605) (xy 371.97373 -43.946568)
			(xy 371.918887 -43.936438) (xy 371.866103 -43.918431) (xy 371.816503 -43.89293) (xy 371.771145 -43.860479)
			(xy 371.730996 -43.82177) (xy 371.69691 -43.777627) (xy 371.669614 -43.728992) (xy 371.649691 -43.676901)
			(xy 371.637565 -43.622464) (xy 371.633494 -43.566842) (xy 370.373656 -43.566842) (xy 370.373656 -45.35424)
			(xy 373.003824 -45.35424) (xy 373.007895 -45.298618) (xy 373.020021 -45.244181) (xy 373.039944 -45.19209)
			(xy 373.06724 -45.143455) (xy 373.101326 -45.099312) (xy 373.141475 -45.060603) (xy 373.186833 -45.028152)
			(xy 373.236433 -45.002651) (xy 373.289217 -44.984644) (xy 373.34406 -44.974514) (xy 373.399794 -44.972477)
			(xy 373.455231 -44.978577) (xy 373.509188 -44.992683) (xy 373.560517 -45.014495) (xy 373.608123 -45.043549)
			(xy 373.650991 -45.079224) (xy 373.688208 -45.120761) (xy 373.718981 -45.167274) (xy 373.742653 -45.217771)
			(xy 373.758721 -45.271178) (xy 373.766841 -45.326354) (xy 373.76735 -45.35424) (xy 373.766841 -45.382126)
			(xy 373.758721 -45.437302) (xy 373.742653 -45.490709) (xy 373.718981 -45.541206) (xy 373.688208 -45.587719)
			(xy 373.650991 -45.629256) (xy 373.608123 -45.664931) (xy 373.560517 -45.693985) (xy 373.509188 -45.715797)
			(xy 373.455231 -45.729903) (xy 373.399794 -45.736003) (xy 373.34406 -45.733966) (xy 373.289217 -45.723836)
			(xy 373.236433 -45.705829) (xy 373.186833 -45.680328) (xy 373.141475 -45.647877) (xy 373.101326 -45.609168)
			(xy 373.06724 -45.565025) (xy 373.039944 -45.51639) (xy 373.020021 -45.464299) (xy 373.007895 -45.409862)
			(xy 373.003824 -45.35424) (xy 370.373656 -45.35424) (xy 370.373656 -46.693836) (xy 372.976394 -46.693836)
			(xy 372.97688 -46.666585) (xy 372.984636 -46.612637) (xy 372.999991 -46.560342) (xy 373.022633 -46.510765)
			(xy 373.052099 -46.464915) (xy 373.08779 -46.423724) (xy 373.128981 -46.388033) (xy 373.174831 -46.358567)
			(xy 373.224408 -46.335925) (xy 373.276703 -46.32057) (xy 373.330651 -46.312814) (xy 373.385153 -46.312814)
			(xy 373.439101 -46.32057) (xy 373.491396 -46.335925) (xy 373.540973 -46.358567) (xy 373.586823 -46.388033)
			(xy 373.628014 -46.423724) (xy 373.663705 -46.464915) (xy 373.693171 -46.510765) (xy 373.715813 -46.560342)
			(xy 373.731168 -46.612637) (xy 373.738924 -46.666585) (xy 373.73941 -46.693836) (xy 373.738936 -46.720263)
			(xy 373.731627 -46.772611) (xy 373.717154 -46.823446) (xy 373.695795 -46.871793) (xy 373.68226 -46.894496)
			(xy 373.676164 -46.904402) (xy 373.673624 -46.927262) (xy 373.707914 -47.023782) (xy 373.723916 -47.040038)
			(xy 373.735092 -47.043848) (xy 373.759611 -47.052892) (xy 373.806062 -47.07684) (xy 373.848813 -47.1069)
			(xy 373.887063 -47.142511) (xy 373.920098 -47.183007) (xy 373.9473 -47.227631) (xy 373.968161 -47.275548)
			(xy 373.98229 -47.325863) (xy 373.989423 -47.377635) (xy 373.989854 -47.403766) (xy 373.989368 -47.431017)
			(xy 373.981612 -47.484965) (xy 373.966257 -47.53726) (xy 373.943615 -47.586837) (xy 373.914149 -47.632687)
			(xy 373.878458 -47.673878) (xy 373.837267 -47.709569) (xy 373.791417 -47.739035) (xy 373.74184 -47.761677)
			(xy 373.689545 -47.777032) (xy 373.635597 -47.784788) (xy 373.581095 -47.784788) (xy 373.527147 -47.777032)
			(xy 373.474852 -47.761677) (xy 373.425275 -47.739035) (xy 373.379425 -47.709569) (xy 373.338234 -47.673878)
			(xy 373.302543 -47.632687) (xy 373.273077 -47.586837) (xy 373.250435 -47.53726) (xy 373.23508 -47.484965)
			(xy 373.227324 -47.431017) (xy 373.226838 -47.403766) (xy 373.227306 -47.377338) (xy 373.234616 -47.324991)
			(xy 373.249091 -47.274156) (xy 373.270452 -47.225809) (xy 373.283988 -47.203106) (xy 373.290084 -47.1932)
			(xy 373.292624 -47.17034) (xy 373.258334 -47.07382) (xy 373.242332 -47.057564) (xy 373.231156 -47.053754)
			(xy 373.206648 -47.044682) (xy 373.160196 -47.020739) (xy 373.117444 -46.990684) (xy 373.079192 -46.955077)
			(xy 373.046155 -46.914585) (xy 373.018951 -46.869964) (xy 372.998089 -46.822049) (xy 372.983959 -46.771736)
			(xy 372.976825 -46.719966) (xy 372.976394 -46.693836) (xy 370.373656 -46.693836) (xy 370.373656 -48.30699)
			(xy 372.853964 -48.30699) (xy 372.858035 -48.251368) (xy 372.870161 -48.196931) (xy 372.890084 -48.14484)
			(xy 372.91738 -48.096205) (xy 372.951466 -48.052062) (xy 372.991615 -48.013353) (xy 373.036973 -47.980902)
			(xy 373.086573 -47.955401) (xy 373.139357 -47.937394) (xy 373.1942 -47.927264) (xy 373.249934 -47.925227)
			(xy 373.305371 -47.931327) (xy 373.359328 -47.945433) (xy 373.410657 -47.967245) (xy 373.458263 -47.996299)
			(xy 373.501131 -48.031974) (xy 373.538348 -48.073511) (xy 373.569121 -48.120024) (xy 373.592793 -48.170521)
			(xy 373.608861 -48.223928) (xy 373.616981 -48.279104) (xy 373.61749 -48.30699) (xy 373.616981 -48.334876)
			(xy 373.608861 -48.390052) (xy 373.592793 -48.443459) (xy 373.569121 -48.493956) (xy 373.538348 -48.540469)
			(xy 373.501131 -48.582006) (xy 373.458263 -48.617681) (xy 373.410657 -48.646735) (xy 373.359328 -48.668547)
			(xy 373.305371 -48.682653) (xy 373.249934 -48.688753) (xy 373.1942 -48.686716) (xy 373.139357 -48.676586)
			(xy 373.086573 -48.658579) (xy 373.036973 -48.633078) (xy 372.991615 -48.600627) (xy 372.951466 -48.561918)
			(xy 372.91738 -48.517775) (xy 372.890084 -48.46914) (xy 372.870161 -48.417049) (xy 372.858035 -48.362612)
			(xy 372.853964 -48.30699) (xy 370.373656 -48.30699) (xy 370.373656 -48.89246) (xy 371.514114 -48.89246)
			(xy 371.518185 -48.836838) (xy 371.530311 -48.782401) (xy 371.550234 -48.73031) (xy 371.57753 -48.681675)
			(xy 371.611616 -48.637532) (xy 371.651765 -48.598823) (xy 371.697123 -48.566372) (xy 371.746723 -48.540871)
			(xy 371.799507 -48.522864) (xy 371.85435 -48.512734) (xy 371.910084 -48.510697) (xy 371.965521 -48.516797)
			(xy 372.019478 -48.530903) (xy 372.070807 -48.552715) (xy 372.118413 -48.581769) (xy 372.161281 -48.617444)
			(xy 372.198498 -48.658981) (xy 372.229271 -48.705494) (xy 372.252943 -48.755991) (xy 372.269011 -48.809398)
			(xy 372.277131 -48.864574) (xy 372.27764 -48.89246) (xy 372.277131 -48.920346) (xy 372.269011 -48.975522)
			(xy 372.252943 -49.028929) (xy 372.229271 -49.079426) (xy 372.198498 -49.125939) (xy 372.161281 -49.167476)
			(xy 372.118413 -49.203151) (xy 372.070807 -49.232205) (xy 372.019478 -49.254017) (xy 371.965521 -49.268123)
			(xy 371.910084 -49.274223) (xy 371.85435 -49.272186) (xy 371.799507 -49.262056) (xy 371.746723 -49.244049)
			(xy 371.697123 -49.218548) (xy 371.651765 -49.186097) (xy 371.611616 -49.147388) (xy 371.57753 -49.103245)
			(xy 371.550234 -49.05461) (xy 371.530311 -49.002519) (xy 371.518185 -48.948082) (xy 371.514114 -48.89246)
			(xy 370.373656 -48.89246) (xy 370.373656 -51.192684) (xy 370.37391 -51.197256) (xy 370.374418 -51.203098)
			(xy 370.375602 -51.211921) (xy 370.383126 -51.228041) (xy 370.38915 -51.234594) (xy 370.532914 -51.378358)
			(xy 370.540311 -51.385207) (xy 370.55891 -51.392943) (xy 370.568982 -51.393344)
		)
		(stroke
			(width 0)
			(type solid)
		)
		(fill yes)
		(layer "In9.Cu")
		(net "GND")
	)
	(gr_poly
		(pts
			(xy 50.73269 -51.393344) (xy 50.741921 -51.392946) (xy 50.759184 -51.386399) (xy 50.773001 -51.374153)
			(xy 50.777648 -51.366166) (xy 50.819304 -51.286664) (xy 50.823213 -51.278382) (xy 50.825491 -51.260225)
			(xy 50.821271 -51.242418) (xy 50.81651 -51.234594) (xy 50.816256 -51.23434) (xy 50.800759 -51.2107)
			(xy 50.776155 -51.159812) (xy 50.759323 -51.105852) (xy 50.750631 -51.05) (xy 50.749962 -51.021742)
			(xy 50.749962 -51.01463) (xy 50.750774 -50.987604) (xy 50.759084 -50.934177) (xy 50.774853 -50.882459)
			(xy 50.797765 -50.833486) (xy 50.827362 -50.788237) (xy 50.863051 -50.74762) (xy 50.904116 -50.712448)
			(xy 50.949735 -50.683426) (xy 50.998995 -50.661135) (xy 51.050909 -50.646021) (xy 51.104436 -50.638388)
			(xy 51.158504 -50.638388) (xy 51.212031 -50.646021) (xy 51.263945 -50.661135) (xy 51.313205 -50.683426)
			(xy 51.358824 -50.712448) (xy 51.399889 -50.74762) (xy 51.435578 -50.788237) (xy 51.465175 -50.833486)
			(xy 51.488087 -50.882459) (xy 51.503856 -50.934177) (xy 51.512166 -50.987604) (xy 51.512978 -51.01463)
			(xy 51.512978 -51.01971) (xy 51.51247 -51.048258) (xy 51.503954 -51.104716) (xy 51.487116 -51.159273)
			(xy 51.46233 -51.210709) (xy 51.446684 -51.234594) (xy 51.438556 -51.246278) (xy 51.437032 -51.274218)
			(xy 51.485292 -51.366166) (xy 51.489939 -51.374151) (xy 51.50376 -51.386391) (xy 51.52102 -51.392945)
			(xy 51.53025 -51.393344) (xy 52.422298 -51.393344) (xy 52.432267 -51.392871) (xy 52.450713 -51.385306)
			(xy 52.458112 -51.378612) (xy 52.976272 -50.860452) (xy 52.980082 -50.852578) (xy 52.989988 -50.833528)
			(xy 52.990242 -50.833274) (xy 52.994052 -50.82667) (xy 52.997354 -50.821082) (xy 53.001418 -50.806858)
			(xy 53.00472 -50.795174) (xy 53.00472 -50.1904) (xy 53.004465 -50.182988) (xy 53.000203 -50.16879)
			(xy 52.996338 -50.16246) (xy 52.981507 -50.139006) (xy 52.958052 -50.088716) (xy 52.942135 -50.035558)
			(xy 52.93409 -49.980654) (xy 52.934089 -49.925163) (xy 52.942131 -49.870259) (xy 52.958046 -49.817099)
			(xy 52.981499 -49.766809) (xy 52.996338 -49.74336) (xy 53.000198 -49.737029) (xy 53.00445 -49.722831)
			(xy 53.00472 -49.71542) (xy 53.00472 -49.1744) (xy 53.004465 -49.166988) (xy 53.000203 -49.15279)
			(xy 52.996338 -49.14646) (xy 52.981507 -49.123006) (xy 52.958052 -49.072716) (xy 52.942135 -49.019558)
			(xy 52.93409 -48.964654) (xy 52.934089 -48.909163) (xy 52.942131 -48.854259) (xy 52.958046 -48.801099)
			(xy 52.981499 -48.750809) (xy 52.996338 -48.72736) (xy 53.000198 -48.721029) (xy 53.00445 -48.706831)
			(xy 53.00472 -48.69942) (xy 53.00472 -47.629572) (xy 53.00218 -47.61865) (xy 52.999386 -47.613062)
			(xy 52.986663 -47.586292) (xy 52.968689 -47.529813) (xy 52.959593 -47.471246) (xy 52.959592 -47.411976)
			(xy 52.968684 -47.353408) (xy 52.986654 -47.296928) (xy 52.999386 -47.270162) (xy 53.00218 -47.264574)
			(xy 53.00472 -47.253652) (xy 53.00472 -46.1264) (xy 53.004465 -46.118988) (xy 53.000203 -46.10479)
			(xy 52.996338 -46.09846) (xy 52.981507 -46.075006) (xy 52.958052 -46.024716) (xy 52.942135 -45.971558)
			(xy 52.93409 -45.916654) (xy 52.934089 -45.861163) (xy 52.942131 -45.806259) (xy 52.958046 -45.753099)
			(xy 52.981499 -45.702809) (xy 52.996338 -45.67936) (xy 53.000198 -45.673029) (xy 53.00445 -45.658831)
			(xy 53.00472 -45.65142) (xy 53.00472 -45.1104) (xy 53.004465 -45.102988) (xy 53.000203 -45.08879)
			(xy 52.996338 -45.08246) (xy 52.981507 -45.059006) (xy 52.958052 -45.008716) (xy 52.942135 -44.955558)
			(xy 52.93409 -44.900654) (xy 52.934089 -44.845163) (xy 52.942131 -44.790259) (xy 52.958046 -44.737099)
			(xy 52.981499 -44.686809) (xy 52.996338 -44.66336) (xy 53.000198 -44.657029) (xy 53.00445 -44.642831)
			(xy 53.00472 -44.63542) (xy 53.00472 -44.0944) (xy 53.004465 -44.086988) (xy 53.000203 -44.07279)
			(xy 52.996338 -44.06646) (xy 52.981507 -44.043006) (xy 52.958052 -43.992716) (xy 52.942135 -43.939558)
			(xy 52.93409 -43.884654) (xy 52.934089 -43.829163) (xy 52.942131 -43.774259) (xy 52.958046 -43.721099)
			(xy 52.981499 -43.670809) (xy 52.996338 -43.64736) (xy 53.000198 -43.641029) (xy 53.00445 -43.626831)
			(xy 53.00472 -43.61942) (xy 53.00472 -43.0784) (xy 53.004465 -43.070988) (xy 53.000203 -43.05679)
			(xy 52.996338 -43.05046) (xy 52.981507 -43.027006) (xy 52.958052 -42.976716) (xy 52.942135 -42.923558)
			(xy 52.93409 -42.868654) (xy 52.934089 -42.813163) (xy 52.942131 -42.758259) (xy 52.958046 -42.705099)
			(xy 52.981499 -42.654809) (xy 52.996338 -42.63136) (xy 53.000198 -42.625029) (xy 53.00445 -42.610831)
			(xy 53.00472 -42.60342) (xy 53.00472 -41.423844) (xy 53.004316 -41.41399) (xy 52.997007 -41.395691)
			(xy 52.990496 -41.388284) (xy 52.975256 -41.37279) (xy 52.972167 -41.369736) (xy 52.965146 -41.364621)
			(xy 52.961286 -41.36263) (xy 52.93868 -41.351708) (xy 52.930298 -41.350692) (xy 52.902853 -41.346884)
			(xy 52.849381 -41.332368) (xy 52.79857 -41.310274) (xy 52.751486 -41.281066) (xy 52.70912 -41.245358)
			(xy 52.672361 -41.2039) (xy 52.641982 -41.157564) (xy 52.61862 -41.107322) (xy 52.602768 -41.054231)
			(xy 52.594757 -40.999406) (xy 52.594757 -40.943999) (xy 52.602767 -40.889174) (xy 52.618618 -40.836083)
			(xy 52.641979 -40.785841) (xy 52.672357 -40.739504) (xy 52.709116 -40.698046) (xy 52.751482 -40.662338)
			(xy 52.798565 -40.633129) (xy 52.849376 -40.611034) (xy 52.902847 -40.596517) (xy 52.930298 -40.592756)
			(xy 52.93868 -40.59174) (xy 52.961286 -40.580818) (xy 52.965145 -40.578823) (xy 52.972171 -40.573716)
			(xy 52.975256 -40.570658) (xy 52.990496 -40.555164) (xy 52.997008 -40.547757) (xy 53.00432 -40.52946)
			(xy 53.00472 -40.519604) (xy 53.00472 -38.432232) (xy 53.004306 -38.422205) (xy 52.996643 -38.403674)
			(xy 52.98247 -38.389487) (xy 52.963947 -38.381804) (xy 52.95392 -38.381432) (xy 51.284124 -38.381432)
			(xy 51.274984 -38.38181) (xy 51.257867 -38.388222) (xy 51.244092 -38.400238) (xy 51.23942 -38.408102)
			(xy 51.197256 -38.486842) (xy 51.194243 -38.492877) (xy 51.191163 -38.506004) (xy 51.19116 -38.51275)
			(xy 51.191668 -38.527228) (xy 51.199542 -38.539166) (xy 51.214675 -38.562785) (xy 51.238598 -38.613522)
			(xy 51.254842 -38.667212) (xy 51.263056 -38.722701) (xy 51.26355 -38.750748) (xy 51.263061 -38.777998)
			(xy 51.255299 -38.831943) (xy 51.23994 -38.884234) (xy 51.217297 -38.933808) (xy 51.18783 -38.979656)
			(xy 51.152139 -39.020843) (xy 51.110951 -39.056534) (xy 51.065103 -39.086) (xy 51.015529 -39.108642)
			(xy 50.963237 -39.124) (xy 50.909292 -39.131761) (xy 50.882042 -39.132256) (xy 50.853742 -39.131737)
			(xy 50.797763 -39.12337) (xy 50.743634 -39.106826) (xy 50.692542 -39.08247) (xy 50.645607 -39.050835)
			(xy 50.603859 -39.012615) (xy 50.568214 -38.968649) (xy 50.553366 -38.94455) (xy 50.546762 -38.933374)
			(xy 50.525426 -38.920166) (xy 50.47996 -38.917626) (xy 50.415698 -38.913816) (xy 50.392838 -38.92423)
			(xy 50.385218 -38.93439) (xy 50.367029 -38.957266) (xy 50.324874 -38.997742) (xy 50.277041 -39.031318)
			(xy 50.224649 -39.05721) (xy 50.168922 -39.074811) (xy 50.111163 -39.083712) (xy 50.081942 -39.08425)
			(xy 50.054688 -39.083767) (xy 50.000733 -39.076016) (xy 49.948431 -39.060665) (xy 49.898846 -39.038026)
			(xy 49.852987 -39.008562) (xy 49.811788 -38.972871) (xy 49.776088 -38.93168) (xy 49.746614 -38.885828)
			(xy 49.723965 -38.836248) (xy 49.708602 -38.783949) (xy 49.700839 -38.729996) (xy 49.700434 -38.702742)
			(xy 49.700993 -38.672656) (xy 49.710437 -38.613231) (xy 49.729112 -38.556031) (xy 49.742344 -38.529006)
			(xy 49.74844 -38.517068) (xy 49.747424 -38.490906) (xy 49.6951 -38.405562) (xy 49.690266 -38.398404)
			(xy 49.676823 -38.387576) (xy 49.66055 -38.381815) (xy 49.65192 -38.381432) (xy 47.285148 -38.381432)
			(xy 47.276289 -38.38185) (xy 47.259649 -38.387944) (xy 47.252636 -38.39337) (xy 47.041054 -38.604952)
			(xy 46.963584 -38.682168) (xy 46.939684 -38.705332) (xy 46.886878 -38.745849) (xy 46.829234 -38.779125)
			(xy 46.767739 -38.804589) (xy 46.703445 -38.821806) (xy 46.637454 -38.83048) (xy 46.604174 -38.831012)
			(xy 44.988734 -38.831012) (xy 44.955458 -38.830464) (xy 44.889475 -38.821772) (xy 44.82519 -38.804544)
			(xy 44.763703 -38.779075) (xy 44.706065 -38.745801) (xy 44.653262 -38.70529) (xy 44.629324 -38.682168)
			(xy 43.781726 -37.83457) (xy 43.758189 -37.810282) (xy 43.717086 -37.75657) (xy 43.683463 -37.697885)
			(xy 43.657912 -37.635262) (xy 43.648884 -37.602668) (xy 43.641283 -37.57134) (xy 43.633125 -37.507393)
			(xy 43.632628 -37.47516) (xy 43.633092 -37.44447) (xy 43.640486 -37.383538) (xy 43.655161 -37.323939)
			(xy 43.676905 -37.26654) (xy 43.7054 -37.212176) (xy 43.740232 -37.161638) (xy 43.780895 -37.11566)
			(xy 43.826797 -37.074912) (xy 43.877271 -37.039987) (xy 43.931582 -37.011391) (xy 43.988941 -36.989542)
			(xy 44.048513 -36.974756) (xy 44.109431 -36.96725) (xy 44.14012 -36.966652) (xy 44.141136 -36.966652)
			(xy 44.173369 -36.967148) (xy 44.237318 -36.975298) (xy 44.268644 -36.982908) (xy 44.301239 -36.991941)
			(xy 44.363875 -37.017467) (xy 44.422568 -37.051081) (xy 44.47628 -37.092188) (xy 44.500546 -37.11575)
			(xy 45.184314 -37.799518) (xy 45.191709 -37.806371) (xy 45.210308 -37.814113) (xy 45.220382 -37.814504)
			(xy 45.849794 -37.814504) (xy 45.860545 -37.81403) (xy 45.880157 -37.805219) (xy 45.88764 -37.797486)
			(xy 45.938186 -37.741352) (xy 45.944752 -37.733233) (xy 45.951307 -37.713431) (xy 45.950886 -37.702998)
			(xy 45.950886 -37.702236) (xy 45.94992 -37.692295) (xy 45.948904 -37.672346) (xy 45.948854 -37.662358)
			(xy 45.949343 -37.635108) (xy 45.957104 -37.581163) (xy 45.972462 -37.528871) (xy 45.995105 -37.479296)
			(xy 46.024572 -37.433448) (xy 46.060263 -37.39226) (xy 46.101452 -37.35657) (xy 46.1473 -37.327103)
			(xy 46.196874 -37.304461) (xy 46.249166 -37.289103) (xy 46.303112 -37.281342) (xy 46.330362 -37.28085)
			(xy 46.359412 -37.281399) (xy 46.416841 -37.290215) (xy 46.472269 -37.307633) (xy 46.524417 -37.333252)
			(xy 46.572079 -37.366479) (xy 46.614155 -37.406547) (xy 46.632368 -37.429186) (xy 46.638464 -37.43706)
			(xy 46.646846 -37.44214) (xy 46.651005 -37.444438) (xy 46.659951 -37.447637) (xy 46.664626 -37.44849)
			(xy 46.732952 -37.459666) (xy 46.742527 -37.460803) (xy 46.761334 -37.456621) (xy 46.769528 -37.451538)
			(xy 46.769782 -37.451284) (xy 46.797467 -37.43323) (xy 46.856584 -37.403671) (xy 46.887638 -37.392356)
			(xy 46.914469 -37.383492) (xy 46.969593 -37.371063) (xy 47.025754 -37.364804) (xy 47.054008 -37.364416)
			(xy 52.95392 -37.364416) (xy 52.963906 -37.363875) (xy 52.982334 -37.356158) (xy 52.989734 -37.34943)
			(xy 52.996541 -37.342084) (xy 53.004258 -37.323621) (xy 53.00472 -37.313616) (xy 53.00472 -31.63316)
			(xy 53.003958 -31.629096) (xy 53.001675 -31.613896) (xy 52.999257 -31.583252) (xy 52.999132 -31.567882)
			(xy 52.999252 -31.552512) (xy 53.00167 -31.521867) (xy 53.003958 -31.506668) (xy 53.00472 -31.502604)
			(xy 53.00472 -30.681168) (xy 53.004597 -30.676355) (xy 53.002807 -30.666897) (xy 53.001164 -30.662372)
			(xy 52.991512 -30.637734) (xy 52.985416 -30.630876) (xy 52.967293 -30.609787) (xy 52.936713 -30.563347)
			(xy 52.913193 -30.512963) (xy 52.897233 -30.4597) (xy 52.889168 -30.404684) (xy 52.889171 -30.34908)
			(xy 52.89724 -30.294065) (xy 52.913206 -30.240803) (xy 52.93673 -30.190421) (xy 52.967315 -30.143985)
			(xy 52.985416 -30.122876) (xy 52.991512 -30.116018) (xy 53.001164 -30.09138) (xy 53.002852 -30.086867)
			(xy 53.004649 -30.077402) (xy 53.00472 -30.072584) (xy 53.00472 -29.909008) (xy 52.991004 -29.874972)
			(xy 52.985162 -29.868368) (xy 52.96712 -29.8473) (xy 52.936684 -29.80093) (xy 52.913282 -29.750641)
			(xy 52.897408 -29.697494) (xy 52.889395 -29.64261) (xy 52.888896 -29.614876) (xy 52.888896 -29.614368)
			(xy 52.889502 -29.583501) (xy 52.899469 -29.522576) (xy 52.91912 -29.464052) (xy 52.947943 -29.409458)
			(xy 52.966112 -29.384498) (xy 52.970785 -29.377759) (xy 52.975976 -29.362213) (xy 52.976272 -29.354018)
			(xy 52.976272 -29.062934) (xy 52.975967 -29.054739) (xy 52.970791 -29.039188) (xy 52.966112 -29.032454)
			(xy 52.949912 -29.010239) (xy 52.923379 -28.962085) (xy 52.904026 -28.910624) (xy 52.892253 -28.856919)
			(xy 52.888304 -28.802081) (xy 52.892259 -28.747243) (xy 52.904037 -28.69354) (xy 52.923395 -28.64208)
			(xy 52.949933 -28.593928) (xy 52.966112 -28.571698) (xy 52.970785 -28.564959) (xy 52.975976 -28.549413)
			(xy 52.976272 -28.541218) (xy 52.976272 -28.386024) (xy 52.976423 -28.3803) (xy 52.978991 -28.369143)
			(xy 52.981352 -28.363926) (xy 52.983276 -28.35964) (xy 52.985702 -28.350566) (xy 52.986178 -28.345892)
			(xy 52.98821 -28.31973) (xy 52.98852 -28.312997) (xy 52.986082 -28.299745) (xy 52.983384 -28.293568)
			(xy 52.980844 -28.288742) (xy 52.977034 -28.283916) (xy 52.960798 -28.263692) (xy 52.933359 -28.219682)
			(xy 52.912127 -28.172364) (xy 52.897492 -28.12261) (xy 52.889722 -28.071332) (xy 52.888896 -28.04541)
			(xy 52.888896 -28.039822) (xy 52.889363 -28.013395) (xy 52.896688 -27.961049) (xy 52.911159 -27.910214)
			(xy 52.932501 -27.861859) (xy 52.946046 -27.839162) (xy 52.949837 -27.829518) (xy 52.950192 -27.808818)
			(xy 52.942392 -27.78964) (xy 52.935378 -27.782012) (xy 52.750466 -27.5971) (xy 52.746148 -27.59329)
			(xy 52.745894 -27.593036) (xy 52.738971 -27.58792) (xy 52.722745 -27.582202) (xy 52.714144 -27.58186)
			(xy 43.399456 -27.58186) (xy 43.387129 -27.582454) (xy 43.365297 -27.593901) (xy 43.3578 -27.603704)
			(xy 43.34064 -27.627665) (xy 43.301134 -27.6714) (xy 43.256343 -27.709706) (xy 43.207008 -27.74195)
			(xy 43.153945 -27.767598) (xy 43.09803 -27.786227) (xy 43.040187 -27.797529) (xy 42.981372 -27.801317)
			(xy 42.922557 -27.797529) (xy 42.864714 -27.786227) (xy 42.808799 -27.767598) (xy 42.755736 -27.74195)
			(xy 42.706401 -27.709706) (xy 42.66161 -27.6714) (xy 42.622104 -27.627665) (xy 42.604944 -27.603704)
			(xy 42.597329 -27.594039) (xy 42.575569 -27.582637) (xy 42.563288 -27.58186) (xy 38.422834 -27.58186)
			(xy 38.414122 -27.583157) (xy 38.398282 -27.590831) (xy 38.391846 -27.596846) (xy 38.12286 -27.865832)
			(xy 38.11651 -27.877262) (xy 38.114732 -27.88412) (xy 38.107006 -27.91235) (xy 38.084095 -27.966205)
			(xy 38.053229 -28.01593) (xy 38.015133 -28.06036) (xy 37.970699 -28.098452) (xy 37.92097 -28.129313)
			(xy 37.867113 -28.152219) (xy 37.838888 -28.159964) (xy 37.83203 -28.161742) (xy 37.8206 -28.168092)
			(xy 37.804852 -28.18384) (xy 37.798006 -28.191238) (xy 37.790278 -28.209837) (xy 37.789866 -28.219908)
			(xy 37.789866 -29.114242) (xy 44.847256 -29.114242) (xy 44.847256 -28.250642) (xy 44.847746 -28.220658)
			(xy 44.855574 -28.161202) (xy 44.871095 -28.103277) (xy 44.894044 -28.047873) (xy 44.924028 -27.995939)
			(xy 44.960534 -27.948363) (xy 45.002939 -27.905958) (xy 45.050515 -27.869452) (xy 45.102449 -27.839468)
			(xy 45.157853 -27.816519) (xy 45.215778 -27.800998) (xy 45.275234 -27.79317) (xy 45.335202 -27.79317)
			(xy 45.394658 -27.800998) (xy 45.452583 -27.816519) (xy 45.507987 -27.839468) (xy 45.559921 -27.869452)
			(xy 45.607497 -27.905958) (xy 45.649902 -27.948363) (xy 45.686408 -27.995939) (xy 45.716392 -28.047873)
			(xy 45.739341 -28.103277) (xy 45.754862 -28.161202) (xy 45.76269 -28.220658) (xy 45.76318 -28.250642)
			(xy 45.76318 -28.469082) (xy 49.752502 -28.469082) (xy 49.756573 -28.41346) (xy 49.768699 -28.359023)
			(xy 49.788622 -28.306932) (xy 49.815918 -28.258297) (xy 49.850004 -28.214154) (xy 49.890153 -28.175445)
			(xy 49.935511 -28.142994) (xy 49.985111 -28.117493) (xy 50.037895 -28.099486) (xy 50.092738 -28.089356)
			(xy 50.148472 -28.087319) (xy 50.203909 -28.093419) (xy 50.257866 -28.107525) (xy 50.309195 -28.129337)
			(xy 50.356801 -28.158391) (xy 50.399669 -28.194066) (xy 50.436886 -28.235603) (xy 50.467659 -28.282116)
			(xy 50.491331 -28.332613) (xy 50.507399 -28.38602) (xy 50.515519 -28.441196) (xy 50.516028 -28.469082)
			(xy 50.515519 -28.496968) (xy 50.507399 -28.552144) (xy 50.491331 -28.605551) (xy 50.467659 -28.656048)
			(xy 50.436886 -28.702561) (xy 50.399669 -28.744098) (xy 50.356801 -28.779773) (xy 50.309195 -28.808827)
			(xy 50.257866 -28.830639) (xy 50.203909 -28.844745) (xy 50.148472 -28.850845) (xy 50.092738 -28.848808)
			(xy 50.037895 -28.838678) (xy 49.985111 -28.820671) (xy 49.935511 -28.79517) (xy 49.890153 -28.762719)
			(xy 49.850004 -28.72401) (xy 49.815918 -28.679867) (xy 49.788622 -28.631232) (xy 49.768699 -28.579141)
			(xy 49.756573 -28.524704) (xy 49.752502 -28.469082) (xy 45.76318 -28.469082) (xy 45.76318 -29.114242)
			(xy 45.76269 -29.144226) (xy 45.754862 -29.203682) (xy 45.739341 -29.261607) (xy 45.716392 -29.317011)
			(xy 45.686408 -29.368945) (xy 45.649902 -29.416521) (xy 45.607497 -29.458926) (xy 45.559921 -29.495432)
			(xy 45.507987 -29.525416) (xy 45.452583 -29.548365) (xy 45.394658 -29.563886) (xy 45.335202 -29.571714)
			(xy 45.275234 -29.571714) (xy 45.215778 -29.563886) (xy 45.157853 -29.548365) (xy 45.102449 -29.525416)
			(xy 45.050515 -29.495432) (xy 45.002939 -29.458926) (xy 44.960534 -29.416521) (xy 44.924028 -29.368945)
			(xy 44.894044 -29.317011) (xy 44.871095 -29.261607) (xy 44.855574 -29.203682) (xy 44.847746 -29.144226)
			(xy 44.847256 -29.114242) (xy 37.789866 -29.114242) (xy 37.789866 -29.186378) (xy 37.811964 -29.214064)
			(xy 37.82949 -29.217874) (xy 37.855784 -29.224336) (xy 37.906355 -29.243679) (xy 37.953684 -29.269977)
			(xy 37.996821 -29.3027) (xy 38.0349 -29.341191) (xy 38.067156 -29.384678) (xy 38.092941 -29.432288)
			(xy 38.111738 -29.483065) (xy 38.12317 -29.535988) (xy 38.127007 -29.589996) (xy 38.123171 -29.644005)
			(xy 38.11174 -29.696928) (xy 38.092944 -29.747705) (xy 38.067159 -29.795316) (xy 38.034904 -29.838803)
			(xy 37.996826 -29.877296) (xy 37.95369 -29.910019) (xy 37.906361 -29.936318) (xy 37.855791 -29.955662)
			(xy 37.82949 -29.962094) (xy 37.811964 -29.965904) (xy 37.789866 -29.99359) (xy 37.789866 -30.92069)
			(xy 47.489364 -30.92069) (xy 47.489364 -30.05709) (xy 47.489854 -30.027106) (xy 47.497682 -29.96765)
			(xy 47.513203 -29.909725) (xy 47.536152 -29.854321) (xy 47.566136 -29.802387) (xy 47.602642 -29.754811)
			(xy 47.645047 -29.712406) (xy 47.692623 -29.6759) (xy 47.744557 -29.645916) (xy 47.799961 -29.622967)
			(xy 47.857886 -29.607446) (xy 47.917342 -29.599618) (xy 47.97731 -29.599618) (xy 48.036766 -29.607446)
			(xy 48.094691 -29.622967) (xy 48.150095 -29.645916) (xy 48.202029 -29.6759) (xy 48.249605 -29.712406)
			(xy 48.29201 -29.754811) (xy 48.328516 -29.802387) (xy 48.3585 -29.854321) (xy 48.381449 -29.909725)
			(xy 48.39697 -29.96765) (xy 48.404798 -30.027106) (xy 48.405288 -30.05709) (xy 48.405288 -30.92069)
			(xy 48.404798 -30.950674) (xy 48.39697 -31.01013) (xy 48.381449 -31.068055) (xy 48.3585 -31.123459)
			(xy 48.328516 -31.175393) (xy 48.29201 -31.222969) (xy 48.249605 -31.265374) (xy 48.202029 -31.30188)
			(xy 48.150095 -31.331864) (xy 48.094691 -31.354813) (xy 48.036766 -31.370334) (xy 47.97731 -31.378162)
			(xy 47.917342 -31.378162) (xy 47.857886 -31.370334) (xy 47.799961 -31.354813) (xy 47.744557 -31.331864)
			(xy 47.692623 -31.30188) (xy 47.645047 -31.265374) (xy 47.602642 -31.222969) (xy 47.566136 -31.175393)
			(xy 47.536152 -31.123459) (xy 47.513203 -31.068055) (xy 47.497682 -31.01013) (xy 47.489854 -30.950674)
			(xy 47.489364 -30.92069) (xy 37.789866 -30.92069) (xy 37.789866 -31.232602) (xy 37.815266 -31.261304)
			(xy 37.83457 -31.26359) (xy 37.86198 -31.267414) (xy 37.915378 -31.281951) (xy 37.966115 -31.304051)
			(xy 38.013127 -31.333251) (xy 38.055426 -31.368936) (xy 38.092125 -31.410359) (xy 38.122453 -31.456651)
			(xy 38.145775 -31.506838) (xy 38.1616 -31.559869) (xy 38.169596 -31.61463) (xy 38.169596 -31.669971)
			(xy 38.1616 -31.724732) (xy 38.145775 -31.777763) (xy 38.122453 -31.82795) (xy 38.092124 -31.874241)
			(xy 38.055425 -31.915664) (xy 38.013126 -31.95135) (xy 37.966114 -31.980549) (xy 37.915377 -32.002649)
			(xy 37.861979 -32.017186) (xy 37.83457 -32.021018) (xy 37.815266 -32.023304) (xy 37.789866 -32.052006)
			(xy 37.789866 -32.714184) (xy 44.847256 -32.714184) (xy 44.847256 -31.850584) (xy 44.847746 -31.8206)
			(xy 44.855574 -31.761144) (xy 44.871095 -31.703219) (xy 44.894044 -31.647815) (xy 44.924028 -31.595881)
			(xy 44.960534 -31.548305) (xy 45.002939 -31.5059) (xy 45.050515 -31.469394) (xy 45.102449 -31.43941)
			(xy 45.157853 -31.416461) (xy 45.215778 -31.40094) (xy 45.275234 -31.393112) (xy 45.335202 -31.393112)
			(xy 45.394658 -31.40094) (xy 45.452583 -31.416461) (xy 45.507987 -31.43941) (xy 45.559921 -31.469394)
			(xy 45.607497 -31.5059) (xy 45.649902 -31.548305) (xy 45.686408 -31.595881) (xy 45.716392 -31.647815)
			(xy 45.739341 -31.703219) (xy 45.754862 -31.761144) (xy 45.76269 -31.8206) (xy 45.76318 -31.850584)
			(xy 45.76318 -32.714184) (xy 45.76269 -32.744168) (xy 45.754862 -32.803624) (xy 45.739341 -32.861549)
			(xy 45.716392 -32.916953) (xy 45.686408 -32.968887) (xy 45.649902 -33.016463) (xy 45.607497 -33.058868)
			(xy 45.559921 -33.095374) (xy 45.507987 -33.125358) (xy 45.452583 -33.148307) (xy 45.394658 -33.163828)
			(xy 45.335202 -33.171656) (xy 45.275234 -33.171656) (xy 45.215778 -33.163828) (xy 45.157853 -33.148307)
			(xy 45.102449 -33.125358) (xy 45.050515 -33.095374) (xy 45.002939 -33.058868) (xy 44.960534 -33.016463)
			(xy 44.924028 -32.968887) (xy 44.894044 -32.916953) (xy 44.871095 -32.861549) (xy 44.855574 -32.803624)
			(xy 44.847746 -32.744168) (xy 44.847256 -32.714184) (xy 37.789866 -32.714184) (xy 37.789866 -34.520886)
			(xy 47.489364 -34.520886) (xy 47.489364 -33.657286) (xy 47.489854 -33.627302) (xy 47.497682 -33.567846)
			(xy 47.513203 -33.509921) (xy 47.536152 -33.454517) (xy 47.566136 -33.402583) (xy 47.602642 -33.355007)
			(xy 47.645047 -33.312602) (xy 47.692623 -33.276096) (xy 47.744557 -33.246112) (xy 47.799961 -33.223163)
			(xy 47.857886 -33.207642) (xy 47.917342 -33.199814) (xy 47.97731 -33.199814) (xy 48.036766 -33.207642)
			(xy 48.094691 -33.223163) (xy 48.150095 -33.246112) (xy 48.202029 -33.276096) (xy 48.249605 -33.312602)
			(xy 48.29201 -33.355007) (xy 48.328516 -33.402583) (xy 48.3585 -33.454517) (xy 48.381449 -33.509921)
			(xy 48.39697 -33.567846) (xy 48.404798 -33.627302) (xy 48.405288 -33.657286) (xy 48.405288 -34.520886)
			(xy 48.404798 -34.55087) (xy 48.39697 -34.610326) (xy 48.381449 -34.668251) (xy 48.3585 -34.723655)
			(xy 48.328516 -34.775589) (xy 48.29201 -34.823165) (xy 48.249605 -34.86557) (xy 48.202029 -34.902076)
			(xy 48.150095 -34.93206) (xy 48.094691 -34.955009) (xy 48.036766 -34.97053) (xy 47.97731 -34.978358)
			(xy 47.917342 -34.978358) (xy 47.857886 -34.97053) (xy 47.799961 -34.955009) (xy 47.744557 -34.93206)
			(xy 47.692623 -34.902076) (xy 47.645047 -34.86557) (xy 47.602642 -34.823165) (xy 47.566136 -34.775589)
			(xy 47.536152 -34.723655) (xy 47.513203 -34.668251) (xy 47.497682 -34.610326) (xy 47.489854 -34.55087)
			(xy 47.489364 -34.520886) (xy 37.789866 -34.520886) (xy 37.789866 -36.60013) (xy 37.998407 -36.60013)
			(xy 38.002411 -36.512245) (xy 38.014391 -36.425088) (xy 38.034246 -36.339381) (xy 38.061813 -36.255836)
			(xy 38.096863 -36.175143) (xy 38.139105 -36.097971) (xy 38.18819 -36.024961) (xy 38.243711 -35.956717)
			(xy 38.305208 -35.893804) (xy 38.37217 -35.836744) (xy 38.444044 -35.78601) (xy 38.520234 -35.742022)
			(xy 38.600108 -35.705144) (xy 38.683005 -35.675683) (xy 38.768237 -35.653881) (xy 38.855099 -35.639921)
			(xy 38.94287 -35.633917) (xy 39.030824 -35.63592) (xy 39.118231 -35.645912) (xy 39.204367 -35.663812)
			(xy 39.288519 -35.68947) (xy 39.369989 -35.722674) (xy 39.448102 -35.763148) (xy 39.52221 -35.810559)
			(xy 39.591701 -35.864512) (xy 39.604792 -35.876738) (xy 44.717206 -35.876738) (xy 44.721277 -35.821116)
			(xy 44.733403 -35.766679) (xy 44.753326 -35.714588) (xy 44.780622 -35.665953) (xy 44.814708 -35.62181)
			(xy 44.854857 -35.583101) (xy 44.900215 -35.55065) (xy 44.949815 -35.525149) (xy 45.002599 -35.507142)
			(xy 45.057442 -35.497012) (xy 45.113176 -35.494975) (xy 45.168613 -35.501075) (xy 45.22257 -35.515181)
			(xy 45.273899 -35.536993) (xy 45.321505 -35.566047) (xy 45.364373 -35.601722) (xy 45.40159 -35.643259)
			(xy 45.432363 -35.689772) (xy 45.456035 -35.740269) (xy 45.472103 -35.793676) (xy 45.480223 -35.848852)
			(xy 45.480732 -35.876738) (xy 48.788826 -35.876738) (xy 48.792897 -35.821116) (xy 48.805023 -35.766679)
			(xy 48.824946 -35.714588) (xy 48.852242 -35.665953) (xy 48.886328 -35.62181) (xy 48.926477 -35.583101)
			(xy 48.971835 -35.55065) (xy 49.021435 -35.525149) (xy 49.074219 -35.507142) (xy 49.129062 -35.497012)
			(xy 49.184796 -35.494975) (xy 49.240233 -35.501075) (xy 49.29419 -35.515181) (xy 49.345519 -35.536993)
			(xy 49.393125 -35.566047) (xy 49.435993 -35.601722) (xy 49.47321 -35.643259) (xy 49.503983 -35.689772)
			(xy 49.527655 -35.740269) (xy 49.543723 -35.793676) (xy 49.551843 -35.848852) (xy 49.552352 -35.876738)
			(xy 49.551843 -35.904624) (xy 49.543723 -35.9598) (xy 49.527655 -36.013207) (xy 49.503983 -36.063704)
			(xy 49.47321 -36.110217) (xy 49.435993 -36.151754) (xy 49.393125 -36.187429) (xy 49.345519 -36.216483)
			(xy 49.29419 -36.238295) (xy 49.240233 -36.252401) (xy 49.184796 -36.258501) (xy 49.129062 -36.256464)
			(xy 49.074219 -36.246334) (xy 49.021435 -36.228327) (xy 48.971835 -36.202826) (xy 48.926477 -36.170375)
			(xy 48.886328 -36.131666) (xy 48.852242 -36.087523) (xy 48.824946 -36.038888) (xy 48.805023 -35.986797)
			(xy 48.792897 -35.93236) (xy 48.788826 -35.876738) (xy 45.480732 -35.876738) (xy 45.480223 -35.904624)
			(xy 45.472103 -35.9598) (xy 45.456035 -36.013207) (xy 45.432363 -36.063704) (xy 45.40159 -36.110217)
			(xy 45.364373 -36.151754) (xy 45.321505 -36.187429) (xy 45.273899 -36.216483) (xy 45.22257 -36.238295)
			(xy 45.168613 -36.252401) (xy 45.113176 -36.258501) (xy 45.057442 -36.256464) (xy 45.002599 -36.246334)
			(xy 44.949815 -36.228327) (xy 44.900215 -36.202826) (xy 44.854857 -36.170375) (xy 44.814708 -36.131666)
			(xy 44.780622 -36.087523) (xy 44.753326 -36.038888) (xy 44.733403 -35.986797) (xy 44.721277 -35.93236)
			(xy 44.717206 -35.876738) (xy 39.604792 -35.876738) (xy 39.655997 -35.92456) (xy 39.714566 -35.990207)
			(xy 39.766923 -36.060907) (xy 39.812635 -36.136076) (xy 39.851321 -36.21509) (xy 39.882662 -36.297295)
			(xy 39.906397 -36.382009) (xy 39.922331 -36.46853) (xy 39.926114 -36.50996) (xy 46.613824 -36.50996)
			(xy 46.617895 -36.454338) (xy 46.630021 -36.399901) (xy 46.649944 -36.34781) (xy 46.67724 -36.299175)
			(xy 46.711326 -36.255032) (xy 46.751475 -36.216323) (xy 46.796833 -36.183872) (xy 46.846433 -36.158371)
			(xy 46.899217 -36.140364) (xy 46.95406 -36.130234) (xy 47.009794 -36.128197) (xy 47.065231 -36.134297)
			(xy 47.119188 -36.148403) (xy 47.170517 -36.170215) (xy 47.218123 -36.199269) (xy 47.260991 -36.234944)
			(xy 47.298208 -36.276481) (xy 47.328981 -36.322994) (xy 47.352653 -36.373491) (xy 47.368721 -36.426898)
			(xy 47.372646 -36.453572) (xy 49.928524 -36.453572) (xy 49.932595 -36.39795) (xy 49.944721 -36.343513)
			(xy 49.964644 -36.291422) (xy 49.99194 -36.242787) (xy 50.026026 -36.198644) (xy 50.066175 -36.159935)
			(xy 50.111533 -36.127484) (xy 50.161133 -36.101983) (xy 50.213917 -36.083976) (xy 50.26876 -36.073846)
			(xy 50.324494 -36.071809) (xy 50.379931 -36.077909) (xy 50.433888 -36.092015) (xy 50.485217 -36.113827)
			(xy 50.532823 -36.142881) (xy 50.575691 -36.178556) (xy 50.612908 -36.220093) (xy 50.643681 -36.266606)
			(xy 50.667353 -36.317103) (xy 50.683421 -36.37051) (xy 50.691541 -36.425686) (xy 50.69205 -36.453572)
			(xy 50.691541 -36.481458) (xy 50.683421 -36.536634) (xy 50.667353 -36.590041) (xy 50.643681 -36.640538)
			(xy 50.612908 -36.687051) (xy 50.575691 -36.728588) (xy 50.532823 -36.764263) (xy 50.485217 -36.793317)
			(xy 50.433888 -36.815129) (xy 50.379931 -36.829235) (xy 50.324494 -36.835335) (xy 50.26876 -36.833298)
			(xy 50.213917 -36.823168) (xy 50.161133 -36.805161) (xy 50.111533 -36.77966) (xy 50.066175 -36.747209)
			(xy 50.026026 -36.7085) (xy 49.99194 -36.664357) (xy 49.964644 -36.615722) (xy 49.944721 -36.563631)
			(xy 49.932595 -36.509194) (xy 49.928524 -36.453572) (xy 47.372646 -36.453572) (xy 47.376841 -36.482074)
			(xy 47.37735 -36.50996) (xy 47.376841 -36.537846) (xy 47.368721 -36.593022) (xy 47.352653 -36.646429)
			(xy 47.328981 -36.696926) (xy 47.298208 -36.743439) (xy 47.260991 -36.784976) (xy 47.218123 -36.820651)
			(xy 47.170517 -36.849705) (xy 47.119188 -36.871517) (xy 47.065231 -36.885623) (xy 47.009794 -36.891723)
			(xy 46.95406 -36.889686) (xy 46.899217 -36.879556) (xy 46.846433 -36.861549) (xy 46.796833 -36.836048)
			(xy 46.751475 -36.803597) (xy 46.711326 -36.764888) (xy 46.67724 -36.720745) (xy 46.649944 -36.67211)
			(xy 46.630021 -36.620019) (xy 46.617895 -36.565582) (xy 46.613824 -36.50996) (xy 39.926114 -36.50996)
			(xy 39.930331 -36.556142) (xy 39.930832 -36.60013) (xy 39.930331 -36.644118) (xy 39.922331 -36.73173)
			(xy 39.906397 -36.818251) (xy 39.882662 -36.902965) (xy 39.851321 -36.98517) (xy 39.812635 -37.064184)
			(xy 39.766923 -37.139353) (xy 39.714566 -37.210053) (xy 39.655997 -37.2757) (xy 39.591701 -37.335748)
			(xy 39.52221 -37.389701) (xy 39.448102 -37.437112) (xy 39.369989 -37.477586) (xy 39.288519 -37.51079)
			(xy 39.204367 -37.536448) (xy 39.118231 -37.554348) (xy 39.030824 -37.56434) (xy 38.94287 -37.566343)
			(xy 38.855099 -37.560339) (xy 38.768237 -37.546379) (xy 38.683005 -37.524577) (xy 38.600108 -37.495116)
			(xy 38.520234 -37.458238) (xy 38.444044 -37.41425) (xy 38.37217 -37.363516) (xy 38.305208 -37.306456)
			(xy 38.243711 -37.243543) (xy 38.18819 -37.175299) (xy 38.139105 -37.102289) (xy 38.096863 -37.025117)
			(xy 38.061813 -36.944424) (xy 38.034246 -36.860879) (xy 38.014391 -36.775172) (xy 38.002411 -36.688015)
			(xy 37.998407 -36.60013) (xy 37.789866 -36.60013) (xy 37.789866 -39.97198) (xy 51.895754 -39.97198)
			(xy 51.899825 -39.916358) (xy 51.911951 -39.861921) (xy 51.931874 -39.80983) (xy 51.95917 -39.761195)
			(xy 51.993256 -39.717052) (xy 52.033405 -39.678343) (xy 52.078763 -39.645892) (xy 52.128363 -39.620391)
			(xy 52.181147 -39.602384) (xy 52.23599 -39.592254) (xy 52.291724 -39.590217) (xy 52.347161 -39.596317)
			(xy 52.401118 -39.610423) (xy 52.452447 -39.632235) (xy 52.500053 -39.661289) (xy 52.542921 -39.696964)
			(xy 52.580138 -39.738501) (xy 52.610911 -39.785014) (xy 52.634583 -39.835511) (xy 52.650651 -39.888918)
			(xy 52.658771 -39.944094) (xy 52.65928 -39.97198) (xy 52.658771 -39.999866) (xy 52.650651 -40.055042)
			(xy 52.634583 -40.108449) (xy 52.610911 -40.158946) (xy 52.580138 -40.205459) (xy 52.542921 -40.246996)
			(xy 52.500053 -40.282671) (xy 52.452447 -40.311725) (xy 52.401118 -40.333537) (xy 52.347161 -40.347643)
			(xy 52.291724 -40.353743) (xy 52.23599 -40.351706) (xy 52.181147 -40.341576) (xy 52.128363 -40.323569)
			(xy 52.078763 -40.298068) (xy 52.033405 -40.265617) (xy 51.993256 -40.226908) (xy 51.95917 -40.182765)
			(xy 51.931874 -40.13413) (xy 51.911951 -40.082039) (xy 51.899825 -40.027602) (xy 51.895754 -39.97198)
			(xy 37.789866 -39.97198) (xy 37.789866 -40.452802) (xy 37.790291 -40.462871) (xy 37.798013 -40.481468)
			(xy 37.804852 -40.48887) (xy 38.024054 -40.708072) (xy 38.031454 -40.714913) (xy 38.050053 -40.722632)
			(xy 38.060122 -40.723058) (xy 47.08144 -40.723058) (xy 47.091506 -40.72349) (xy 47.110094 -40.731221)
			(xy 47.117508 -40.738044) (xy 48.058578 -41.679114) (xy 48.065425 -41.686512) (xy 48.073157 -41.70511)
			(xy 48.073564 -41.715182) (xy 48.073564 -43.85691) (xy 50.719734 -43.85691) (xy 50.723805 -43.801288)
			(xy 50.735931 -43.746851) (xy 50.755854 -43.69476) (xy 50.78315 -43.646125) (xy 50.817236 -43.601982)
			(xy 50.857385 -43.563273) (xy 50.902743 -43.530822) (xy 50.952343 -43.505321) (xy 51.005127 -43.487314)
			(xy 51.05997 -43.477184) (xy 51.115704 -43.475147) (xy 51.171141 -43.481247) (xy 51.225098 -43.495353)
			(xy 51.276427 -43.517165) (xy 51.324033 -43.546219) (xy 51.366901 -43.581894) (xy 51.404118 -43.623431)
			(xy 51.434891 -43.669944) (xy 51.458563 -43.720441) (xy 51.474631 -43.773848) (xy 51.482751 -43.829024)
			(xy 51.48326 -43.85691) (xy 51.482751 -43.884796) (xy 51.474631 -43.939972) (xy 51.458563 -43.993379)
			(xy 51.434891 -44.043876) (xy 51.404118 -44.090389) (xy 51.366901 -44.131926) (xy 51.324033 -44.167601)
			(xy 51.276427 -44.196655) (xy 51.225098 -44.218467) (xy 51.171141 -44.232573) (xy 51.115704 -44.238673)
			(xy 51.05997 -44.236636) (xy 51.005127 -44.226506) (xy 50.952343 -44.208499) (xy 50.902743 -44.182998)
			(xy 50.857385 -44.150547) (xy 50.817236 -44.111838) (xy 50.78315 -44.067695) (xy 50.755854 -44.01906)
			(xy 50.735931 -43.966969) (xy 50.723805 -43.912532) (xy 50.719734 -43.85691) (xy 48.073564 -43.85691)
			(xy 48.073564 -45.35424) (xy 50.703732 -45.35424) (xy 50.707803 -45.298618) (xy 50.719929 -45.244181)
			(xy 50.739852 -45.19209) (xy 50.767148 -45.143455) (xy 50.801234 -45.099312) (xy 50.841383 -45.060603)
			(xy 50.886741 -45.028152) (xy 50.936341 -45.002651) (xy 50.989125 -44.984644) (xy 51.043968 -44.974514)
			(xy 51.099702 -44.972477) (xy 51.155139 -44.978577) (xy 51.209096 -44.992683) (xy 51.260425 -45.014495)
			(xy 51.308031 -45.043549) (xy 51.350899 -45.079224) (xy 51.388116 -45.120761) (xy 51.418889 -45.167274)
			(xy 51.442561 -45.217771) (xy 51.458629 -45.271178) (xy 51.466749 -45.326354) (xy 51.467258 -45.35424)
			(xy 51.466749 -45.382126) (xy 51.458629 -45.437302) (xy 51.442561 -45.490709) (xy 51.418889 -45.541206)
			(xy 51.388116 -45.587719) (xy 51.350899 -45.629256) (xy 51.308031 -45.664931) (xy 51.260425 -45.693985)
			(xy 51.209096 -45.715797) (xy 51.155139 -45.729903) (xy 51.099702 -45.736003) (xy 51.043968 -45.733966)
			(xy 50.989125 -45.723836) (xy 50.936341 -45.705829) (xy 50.886741 -45.680328) (xy 50.841383 -45.647877)
			(xy 50.801234 -45.609168) (xy 50.767148 -45.565025) (xy 50.739852 -45.51639) (xy 50.719929 -45.464299)
			(xy 50.707803 -45.409862) (xy 50.703732 -45.35424) (xy 48.073564 -45.35424) (xy 48.073564 -46.693836)
			(xy 50.676302 -46.693836) (xy 50.676788 -46.666585) (xy 50.684544 -46.612637) (xy 50.699899 -46.560342)
			(xy 50.722541 -46.510765) (xy 50.752007 -46.464915) (xy 50.787698 -46.423724) (xy 50.828889 -46.388033)
			(xy 50.874739 -46.358567) (xy 50.924316 -46.335925) (xy 50.976611 -46.32057) (xy 51.030559 -46.312814)
			(xy 51.085061 -46.312814) (xy 51.139009 -46.32057) (xy 51.191304 -46.335925) (xy 51.240881 -46.358567)
			(xy 51.286731 -46.388033) (xy 51.327922 -46.423724) (xy 51.363613 -46.464915) (xy 51.393079 -46.510765)
			(xy 51.415721 -46.560342) (xy 51.431076 -46.612637) (xy 51.438832 -46.666585) (xy 51.439318 -46.693836)
			(xy 51.438843 -46.720263) (xy 51.431534 -46.772611) (xy 51.417061 -46.823446) (xy 51.395702 -46.871793)
			(xy 51.382168 -46.894496) (xy 51.376072 -46.904402) (xy 51.373532 -46.927262) (xy 51.407822 -47.023782)
			(xy 51.423824 -47.040038) (xy 51.435 -47.043848) (xy 51.459499 -47.052944) (xy 51.505952 -47.076881)
			(xy 51.548706 -47.106932) (xy 51.586959 -47.142535) (xy 51.619998 -47.183025) (xy 51.647203 -47.227643)
			(xy 51.668066 -47.275556) (xy 51.682197 -47.325868) (xy 51.689331 -47.377637) (xy 51.689762 -47.403766)
			(xy 51.689276 -47.431017) (xy 51.68152 -47.484965) (xy 51.666165 -47.53726) (xy 51.643523 -47.586837)
			(xy 51.614057 -47.632687) (xy 51.578366 -47.673878) (xy 51.537175 -47.709569) (xy 51.491325 -47.739035)
			(xy 51.441748 -47.761677) (xy 51.389453 -47.777032) (xy 51.335505 -47.784788) (xy 51.281003 -47.784788)
			(xy 51.227055 -47.777032) (xy 51.17476 -47.761677) (xy 51.125183 -47.739035) (xy 51.079333 -47.709569)
			(xy 51.038142 -47.673878) (xy 51.002451 -47.632687) (xy 50.972985 -47.586837) (xy 50.950343 -47.53726)
			(xy 50.934988 -47.484965) (xy 50.927232 -47.431017) (xy 50.926746 -47.403766) (xy 50.927213 -47.377338)
			(xy 50.934523 -47.32499) (xy 50.948998 -47.274155) (xy 50.97036 -47.225809) (xy 50.983896 -47.203106)
			(xy 50.989992 -47.1932) (xy 50.992532 -47.17034) (xy 50.958242 -47.07382) (xy 50.94224 -47.057564)
			(xy 50.931064 -47.053754) (xy 50.906558 -47.044677) (xy 50.860105 -47.020736) (xy 50.817353 -46.990681)
			(xy 50.779101 -46.955075) (xy 50.746064 -46.914583) (xy 50.71886 -46.869963) (xy 50.697998 -46.822048)
			(xy 50.683867 -46.771736) (xy 50.676733 -46.719966) (xy 50.676302 -46.693836) (xy 48.073564 -46.693836)
			(xy 48.073564 -48.30699) (xy 50.553872 -48.30699) (xy 50.557943 -48.251368) (xy 50.570069 -48.196931)
			(xy 50.589992 -48.14484) (xy 50.617288 -48.096205) (xy 50.651374 -48.052062) (xy 50.691523 -48.013353)
			(xy 50.736881 -47.980902) (xy 50.786481 -47.955401) (xy 50.839265 -47.937394) (xy 50.894108 -47.927264)
			(xy 50.949842 -47.925227) (xy 51.005279 -47.931327) (xy 51.059236 -47.945433) (xy 51.110565 -47.967245)
			(xy 51.158171 -47.996299) (xy 51.201039 -48.031974) (xy 51.238256 -48.073511) (xy 51.269029 -48.120024)
			(xy 51.292701 -48.170521) (xy 51.308769 -48.223928) (xy 51.316889 -48.279104) (xy 51.317398 -48.30699)
			(xy 51.316889 -48.334876) (xy 51.308769 -48.390052) (xy 51.292701 -48.443459) (xy 51.269029 -48.493956)
			(xy 51.238256 -48.540469) (xy 51.201039 -48.582006) (xy 51.158171 -48.617681) (xy 51.110565 -48.646735)
			(xy 51.059236 -48.668547) (xy 51.005279 -48.682653) (xy 50.949842 -48.688753) (xy 50.894108 -48.686716)
			(xy 50.839265 -48.676586) (xy 50.786481 -48.658579) (xy 50.736881 -48.633078) (xy 50.691523 -48.600627)
			(xy 50.651374 -48.561918) (xy 50.617288 -48.517775) (xy 50.589992 -48.46914) (xy 50.570069 -48.417049)
			(xy 50.557943 -48.362612) (xy 50.553872 -48.30699) (xy 48.073564 -48.30699) (xy 48.073564 -48.89246)
			(xy 49.214022 -48.89246) (xy 49.218093 -48.836838) (xy 49.230219 -48.782401) (xy 49.250142 -48.73031)
			(xy 49.277438 -48.681675) (xy 49.311524 -48.637532) (xy 49.351673 -48.598823) (xy 49.397031 -48.566372)
			(xy 49.446631 -48.540871) (xy 49.499415 -48.522864) (xy 49.554258 -48.512734) (xy 49.609992 -48.510697)
			(xy 49.665429 -48.516797) (xy 49.719386 -48.530903) (xy 49.770715 -48.552715) (xy 49.818321 -48.581769)
			(xy 49.861189 -48.617444) (xy 49.898406 -48.658981) (xy 49.929179 -48.705494) (xy 49.952851 -48.755991)
			(xy 49.968919 -48.809398) (xy 49.977039 -48.864574) (xy 49.977548 -48.89246) (xy 49.977039 -48.920346)
			(xy 49.968919 -48.975522) (xy 49.952851 -49.028929) (xy 49.929179 -49.079426) (xy 49.898406 -49.125939)
			(xy 49.861189 -49.167476) (xy 49.818321 -49.203151) (xy 49.770715 -49.232205) (xy 49.719386 -49.254017)
			(xy 49.665429 -49.268123) (xy 49.609992 -49.274223) (xy 49.554258 -49.272186) (xy 49.499415 -49.262056)
			(xy 49.446631 -49.244049) (xy 49.397031 -49.218548) (xy 49.351673 -49.186097) (xy 49.311524 -49.147388)
			(xy 49.277438 -49.103245) (xy 49.250142 -49.05461) (xy 49.230219 -49.002519) (xy 49.218093 -48.948082)
			(xy 49.214022 -48.89246) (xy 48.073564 -48.89246) (xy 48.073564 -51.198018) (xy 48.073755 -51.203963)
			(xy 48.076579 -51.215515) (xy 48.079152 -51.220878) (xy 48.081438 -51.225704) (xy 48.086772 -51.232308)
			(xy 48.232822 -51.378358) (xy 48.24022 -51.385206) (xy 48.258818 -51.392939) (xy 48.26889 -51.393344)
		)
		(stroke
			(width 0)
			(type solid)
		)
		(fill yes)
		(layer "In9.Cu")
		(net "GND")
	)
	(gr_poly
		(pts
			(xy 24.73579 -51.393344) (xy 24.748341 -51.391858) (xy 24.769781 -51.378532) (xy 24.776684 -51.367944)
			(xy 24.793956 -51.335178) (xy 24.82088 -51.283616) (xy 24.82314 -51.278054) (xy 24.825321 -51.266251)
			(xy 24.825198 -51.260248) (xy 24.824436 -51.246532) (xy 24.816308 -51.234594) (xy 24.80139 -51.211837)
			(xy 24.77746 -51.162967) (xy 24.760724 -51.111191) (xy 24.751522 -51.057561) (xy 24.750268 -51.030378)
			(xy 24.750268 -51.02987) (xy 24.750014 -51.021742) (xy 24.750014 -51.01463) (xy 24.750826 -50.987604)
			(xy 24.759136 -50.934177) (xy 24.774905 -50.882459) (xy 24.797817 -50.833486) (xy 24.827414 -50.788237)
			(xy 24.863103 -50.74762) (xy 24.904168 -50.712448) (xy 24.949787 -50.683426) (xy 24.999047 -50.661135)
			(xy 25.050961 -50.646021) (xy 25.104488 -50.638388) (xy 25.158556 -50.638388) (xy 25.212083 -50.646021)
			(xy 25.263997 -50.661135) (xy 25.313257 -50.683426) (xy 25.358876 -50.712448) (xy 25.399941 -50.74762)
			(xy 25.43563 -50.788237) (xy 25.465227 -50.833486) (xy 25.488139 -50.882459) (xy 25.503908 -50.934177)
			(xy 25.512218 -50.987604) (xy 25.51303 -51.01463) (xy 25.51303 -51.019964) (xy 25.512479 -51.048478)
			(xy 25.503946 -51.104866) (xy 25.487111 -51.159354) (xy 25.462349 -51.210727) (xy 25.446736 -51.234594)
			(xy 25.445212 -51.236626) (xy 25.442072 -51.242184) (xy 25.438358 -51.254392) (xy 25.437846 -51.260756)
			(xy 25.437084 -51.274218) (xy 25.487122 -51.369214) (xy 25.494122 -51.379272) (xy 25.515087 -51.391885)
			(xy 25.527254 -51.393344) (xy 26.42235 -51.393344) (xy 26.432314 -51.392862) (xy 26.450747 -51.385283)
			(xy 26.458164 -51.378612) (xy 26.976324 -50.860452) (xy 26.980134 -50.852578) (xy 26.994104 -50.82667)
			(xy 26.997406 -50.820828) (xy 27.00147 -50.806858) (xy 27.003248 -50.800508) (xy 27.004772 -50.78857)
			(xy 27.004772 -50.189384) (xy 27.004382 -50.182235) (xy 27.000119 -50.168573) (xy 26.99639 -50.16246)
			(xy 26.981557 -50.139007) (xy 26.958099 -50.088717) (xy 26.942179 -50.035559) (xy 26.934134 -49.980654)
			(xy 26.934133 -49.925163) (xy 26.942176 -49.870257) (xy 26.958093 -49.817098) (xy 26.981549 -49.766808)
			(xy 26.99639 -49.74336) (xy 27.000127 -49.737251) (xy 27.004391 -49.723586) (xy 27.004772 -49.716436)
			(xy 27.004772 -49.173384) (xy 27.004382 -49.166235) (xy 27.000119 -49.152573) (xy 26.99639 -49.14646)
			(xy 26.981557 -49.123007) (xy 26.958099 -49.072717) (xy 26.942179 -49.019559) (xy 26.934134 -48.964654)
			(xy 26.934133 -48.909163) (xy 26.942176 -48.854257) (xy 26.958093 -48.801098) (xy 26.981549 -48.750808)
			(xy 26.99639 -48.72736) (xy 27.000127 -48.721251) (xy 27.004391 -48.707586) (xy 27.004772 -48.700436)
			(xy 27.004772 -47.628048) (xy 27.004518 -47.623222) (xy 27.001978 -47.617888) (xy 26.990369 -47.594428)
			(xy 26.972899 -47.545087) (xy 26.962286 -47.493832) (xy 26.958725 -47.441611) (xy 26.962283 -47.389389)
			(xy 26.972894 -47.338134) (xy 26.990361 -47.288791) (xy 27.001978 -47.265336) (xy 27.004518 -47.260002)
			(xy 27.004772 -47.255684) (xy 27.004772 -46.125384) (xy 27.004382 -46.118235) (xy 27.000119 -46.104573)
			(xy 26.99639 -46.09846) (xy 26.981557 -46.075007) (xy 26.958099 -46.024717) (xy 26.942179 -45.971559)
			(xy 26.934134 -45.916654) (xy 26.934133 -45.861163) (xy 26.942176 -45.806257) (xy 26.958093 -45.753098)
			(xy 26.981549 -45.702808) (xy 26.99639 -45.67936) (xy 27.000127 -45.673251) (xy 27.004391 -45.659586)
			(xy 27.004772 -45.652436) (xy 27.004772 -45.109384) (xy 27.004382 -45.102235) (xy 27.000119 -45.088573)
			(xy 26.99639 -45.08246) (xy 26.981557 -45.059007) (xy 26.958099 -45.008717) (xy 26.942179 -44.955559)
			(xy 26.934134 -44.900654) (xy 26.934133 -44.845163) (xy 26.942176 -44.790257) (xy 26.958093 -44.737098)
			(xy 26.981549 -44.686808) (xy 26.99639 -44.66336) (xy 27.000127 -44.657251) (xy 27.004391 -44.643586)
			(xy 27.004772 -44.636436) (xy 27.004772 -44.093384) (xy 27.004382 -44.086235) (xy 27.000119 -44.072573)
			(xy 26.99639 -44.06646) (xy 26.981557 -44.043007) (xy 26.958099 -43.992717) (xy 26.942179 -43.939559)
			(xy 26.934134 -43.884654) (xy 26.934133 -43.829163) (xy 26.942176 -43.774257) (xy 26.958093 -43.721098)
			(xy 26.981549 -43.670808) (xy 26.99639 -43.64736) (xy 27.000127 -43.641251) (xy 27.004391 -43.627586)
			(xy 27.004772 -43.620436) (xy 27.004772 -43.077384) (xy 27.004382 -43.070235) (xy 27.000119 -43.056573)
			(xy 26.99639 -43.05046) (xy 26.981557 -43.027007) (xy 26.958099 -42.976717) (xy 26.942179 -42.923559)
			(xy 26.934134 -42.868654) (xy 26.934133 -42.813163) (xy 26.942176 -42.758257) (xy 26.958093 -42.705098)
			(xy 26.981549 -42.654808) (xy 26.99639 -42.63136) (xy 27.000127 -42.625251) (xy 27.004391 -42.611586)
			(xy 27.004772 -42.604436) (xy 27.004772 -41.423336) (xy 27.004264 -41.416478) (xy 27.002995 -41.40943)
			(xy 26.997073 -41.396399) (xy 26.99258 -41.390824) (xy 26.974292 -41.37152) (xy 26.965656 -41.364916)
			(xy 26.938478 -41.351454) (xy 26.930096 -41.350438) (xy 26.902686 -41.346612) (xy 26.849287 -41.332071)
			(xy 26.79855 -41.309967) (xy 26.751539 -41.280765) (xy 26.70924 -41.245076) (xy 26.672542 -41.203651)
			(xy 26.642214 -41.157358) (xy 26.618893 -41.107169) (xy 26.603068 -41.054136) (xy 26.595071 -40.999374)
			(xy 26.595071 -40.944031) (xy 26.603067 -40.889269) (xy 26.618891 -40.836237) (xy 26.642211 -40.786047)
			(xy 26.672539 -40.739754) (xy 26.709236 -40.698328) (xy 26.751534 -40.662639) (xy 26.798545 -40.633435)
			(xy 26.849282 -40.611331) (xy 26.90268 -40.596789) (xy 26.930096 -40.59301) (xy 26.938478 -40.591994)
			(xy 26.965656 -40.578532) (xy 26.974292 -40.571928) (xy 26.99258 -40.552624) (xy 26.997047 -40.547031)
			(xy 27.002984 -40.534012) (xy 27.004264 -40.52697) (xy 27.004772 -40.520112) (xy 27.004772 -38.432232)
			(xy 27.004357 -38.422209) (xy 26.996692 -38.403686) (xy 26.982518 -38.38951) (xy 26.963995 -38.381843)
			(xy 26.953972 -38.381432) (xy 25.284176 -38.381432) (xy 25.275388 -38.381805) (xy 25.258851 -38.387762)
			(xy 25.245307 -38.398964) (xy 25.240488 -38.406324) (xy 25.196038 -38.489128) (xy 25.193755 -38.494363)
			(xy 25.191316 -38.505516) (xy 25.191212 -38.511226) (xy 25.191466 -38.520116) (xy 25.19553 -38.53307)
			(xy 25.199594 -38.539166) (xy 25.214725 -38.562786) (xy 25.238645 -38.613523) (xy 25.254886 -38.667213)
			(xy 25.263099 -38.722702) (xy 25.263602 -38.750748) (xy 25.263113 -38.777997) (xy 25.255351 -38.831939)
			(xy 25.239992 -38.884228) (xy 25.217348 -38.933799) (xy 25.18788 -38.979642) (xy 25.152188 -39.020826)
			(xy 25.110999 -39.056512) (xy 25.065151 -39.085973) (xy 25.015577 -39.10861) (xy 24.963286 -39.123962)
			(xy 24.909343 -39.131717) (xy 24.882094 -39.132256) (xy 24.853965 -39.131753) (xy 24.798318 -39.12349)
			(xy 24.744488 -39.107143) (xy 24.693642 -39.083066) (xy 24.646885 -39.051783) (xy 24.605229 -39.013972)
			(xy 24.569578 -38.970452) (xy 24.554688 -38.946582) (xy 24.553164 -38.944296) (xy 24.516334 -38.919912)
			(xy 24.513794 -38.919404) (xy 24.426672 -38.914578) (xy 24.42091 -38.914588) (xy 24.409625 -38.9169)
			(xy 24.40432 -38.91915) (xy 24.398732 -38.92169) (xy 24.389334 -38.929056) (xy 24.38527 -38.93439)
			(xy 24.367082 -38.957269) (xy 24.324929 -38.997751) (xy 24.277097 -39.031333) (xy 24.224705 -39.057232)
			(xy 24.168977 -39.074841) (xy 24.111216 -39.083749) (xy 24.081994 -39.08425) (xy 24.054742 -39.083764)
			(xy 24.000793 -39.076007) (xy 23.948496 -39.060652) (xy 23.898917 -39.038011) (xy 23.853064 -39.008545)
			(xy 23.811871 -38.972854) (xy 23.776177 -38.931664) (xy 23.746707 -38.885815) (xy 23.724061 -38.836238)
			(xy 23.708701 -38.783943) (xy 23.700939 -38.729994) (xy 23.700486 -38.702742) (xy 23.701045 -38.672656)
			(xy 23.71049 -38.613231) (xy 23.729167 -38.556033) (xy 23.742396 -38.529006) (xy 23.74265 -38.528752)
			(xy 23.745385 -38.522911) (xy 23.748097 -38.510308) (xy 23.747984 -38.50386) (xy 23.747476 -38.490906)
			(xy 23.695152 -38.405562) (xy 23.693628 -38.403276) (xy 23.69312 -38.402768) (xy 23.685548 -38.393312)
			(xy 23.664065 -38.382192) (xy 23.651972 -38.381432) (xy 21.285454 -38.381432) (xy 21.275641 -38.381925)
			(xy 21.257473 -38.389363) (xy 21.250148 -38.39591) (xy 20.96389 -38.682422) (xy 20.93995 -38.705572)
			(xy 20.8871 -38.746091) (xy 20.829415 -38.779368) (xy 20.767881 -38.804834) (xy 20.703551 -38.822054)
			(xy 20.637524 -38.830733) (xy 20.604226 -38.831266) (xy 20.587462 -38.831012) (xy 18.988786 -38.831012)
			(xy 18.955508 -38.830467) (xy 18.889522 -38.821781) (xy 18.825233 -38.804558) (xy 18.763742 -38.779094)
			(xy 18.706099 -38.745823) (xy 18.65329 -38.705315) (xy 18.629376 -38.682168) (xy 17.781778 -37.834824)
			(xy 17.759167 -37.811479) (xy 17.719446 -37.760038) (xy 17.686601 -37.703956) (xy 17.661168 -37.644148)
			(xy 17.64356 -37.581587) (xy 17.634065 -37.517292) (xy 17.632934 -37.484812) (xy 17.63268 -37.47516)
			(xy 17.633144 -37.444469) (xy 17.640538 -37.383535) (xy 17.655213 -37.323934) (xy 17.676955 -37.266532)
			(xy 17.70545 -37.212166) (xy 17.740282 -37.161624) (xy 17.780944 -37.115643) (xy 17.826846 -37.074892)
			(xy 17.877319 -37.039962) (xy 17.931631 -37.011362) (xy 17.98899 -36.989507) (xy 18.048562 -36.974717)
			(xy 18.109482 -36.967205) (xy 18.140172 -36.966652) (xy 18.15084 -36.966906) (xy 18.183323 -36.96802)
			(xy 18.247624 -36.977494) (xy 18.310192 -36.995094) (xy 18.370004 -37.02053) (xy 18.426083 -37.053388)
			(xy 18.477512 -37.093131) (xy 18.500852 -37.11575) (xy 18.58645 -37.201602) (xy 19.184874 -37.800026)
			(xy 19.189192 -37.803836) (xy 19.195113 -37.808056) (xy 19.208648 -37.813351) (xy 19.215862 -37.81425)
			(xy 19.220434 -37.814504) (xy 19.8501 -37.814504) (xy 19.859752 -37.813488) (xy 19.871182 -37.809932)
			(xy 19.880072 -37.805614) (xy 19.887692 -37.797486) (xy 19.887946 -37.796978) (xy 19.931888 -37.748718)
			(xy 19.94154 -37.73805) (xy 19.94535 -37.733732) (xy 19.951954 -37.713666) (xy 19.950938 -37.70249)
			(xy 19.949964 -37.692486) (xy 19.948945 -37.672409) (xy 19.948906 -37.662358) (xy 19.949395 -37.635109)
			(xy 19.957157 -37.581167) (xy 19.972515 -37.528878) (xy 19.995159 -37.479307) (xy 20.024627 -37.433463)
			(xy 20.060318 -37.392279) (xy 20.101508 -37.356593) (xy 20.147356 -37.327132) (xy 20.19693 -37.304496)
			(xy 20.249222 -37.289145) (xy 20.303165 -37.281391) (xy 20.330414 -37.28085) (xy 20.359496 -37.281398)
			(xy 20.416985 -37.290225) (xy 20.47247 -37.307674) (xy 20.524664 -37.333339) (xy 20.57236 -37.366627)
			(xy 20.614453 -37.406767) (xy 20.632674 -37.42944) (xy 20.63877 -37.437314) (xy 20.646644 -37.441886)
			(xy 20.650095 -37.44392) (xy 20.657496 -37.446986) (xy 20.661376 -37.447982) (xy 20.70227 -37.454586)
			(xy 20.733004 -37.459666) (xy 20.737308 -37.460245) (xy 20.745991 -37.460118) (xy 20.750276 -37.459412)
			(xy 20.761452 -37.456872) (xy 20.761706 -37.456618) (xy 20.78743 -37.439133) (xy 20.84232 -37.409876)
			(xy 20.900372 -37.387541) (xy 20.960717 -37.37246) (xy 21.022452 -37.36486) (xy 21.053552 -37.364416)
			(xy 26.953972 -37.364416) (xy 26.963962 -37.363884) (xy 26.982403 -37.356179) (xy 26.989786 -37.34943)
			(xy 26.996587 -37.342082) (xy 27.004296 -37.323619) (xy 27.004772 -37.313616) (xy 27.004772 -31.63316)
			(xy 27.00401 -31.629096) (xy 27.001727 -31.613896) (xy 26.99931 -31.583252) (xy 26.999184 -31.567882)
			(xy 26.999304 -31.552512) (xy 27.001722 -31.521867) (xy 27.00401 -31.506668) (xy 27.004772 -31.502604)
			(xy 27.004772 -30.67812) (xy 27.004528 -30.674489) (xy 27.003124 -30.66735) (xy 27.001978 -30.663896)
			(xy 26.991056 -30.636972) (xy 26.985214 -30.630368) (xy 26.967173 -30.609299) (xy 26.936737 -30.562929)
			(xy 26.913331 -30.512643) (xy 26.89745 -30.459498) (xy 26.889426 -30.404615) (xy 26.889428 -30.349149)
			(xy 26.897457 -30.294266) (xy 26.913344 -30.241124) (xy 26.936754 -30.190839) (xy 26.967194 -30.144472)
			(xy 26.985214 -30.123384) (xy 26.991056 -30.11678) (xy 27.001978 -30.089856) (xy 27.003116 -30.0864)
			(xy 27.004519 -30.079261) (xy 27.004772 -30.075632) (xy 27.004772 -29.91612) (xy 27.004528 -29.912489)
			(xy 27.003124 -29.90535) (xy 27.001978 -29.901896) (xy 26.991056 -29.874972) (xy 26.985214 -29.868368)
			(xy 26.967173 -29.847299) (xy 26.936737 -29.800929) (xy 26.913331 -29.750643) (xy 26.89745 -29.697498)
			(xy 26.889426 -29.642615) (xy 26.889428 -29.587149) (xy 26.897457 -29.532266) (xy 26.913344 -29.479124)
			(xy 26.936754 -29.428839) (xy 26.967194 -29.382472) (xy 26.985214 -29.361384) (xy 26.991056 -29.35478)
			(xy 27.001978 -29.327856) (xy 27.003116 -29.3244) (xy 27.004519 -29.317261) (xy 27.004772 -29.313632)
			(xy 27.004772 -29.10332) (xy 27.004528 -29.099689) (xy 27.003124 -29.09255) (xy 27.001978 -29.089096)
			(xy 26.991056 -29.062172) (xy 26.985214 -29.055568) (xy 26.967173 -29.034499) (xy 26.936737 -28.988129)
			(xy 26.913331 -28.937843) (xy 26.89745 -28.884698) (xy 26.889426 -28.829815) (xy 26.889428 -28.774349)
			(xy 26.897457 -28.719466) (xy 26.913344 -28.666324) (xy 26.936754 -28.616039) (xy 26.967194 -28.569672)
			(xy 26.985214 -28.548584) (xy 26.991056 -28.54198) (xy 27.001978 -28.515056) (xy 27.003116 -28.5116)
			(xy 27.004519 -28.504461) (xy 27.004772 -28.500832) (xy 27.004772 -28.34132) (xy 27.004528 -28.337689)
			(xy 27.003124 -28.33055) (xy 27.001978 -28.327096) (xy 26.991056 -28.300172) (xy 26.985214 -28.293568)
			(xy 26.96758 -28.272987) (xy 26.937694 -28.227776) (xy 26.914498 -28.178795) (xy 26.898459 -28.127027)
			(xy 26.889897 -28.073512) (xy 26.888948 -28.046426) (xy 26.888948 -28.039822) (xy 26.889356 -28.014918)
			(xy 26.895844 -27.965536) (xy 26.908699 -27.917416) (xy 26.927702 -27.871377) (xy 26.939748 -27.849576)
			(xy 26.94305 -27.843988) (xy 26.94686 -27.830018) (xy 26.948948 -27.82128) (xy 26.947531 -27.803382)
			(xy 26.94001 -27.787079) (xy 26.933906 -27.780488) (xy 26.71953 -27.566112) (xy 26.715802 -27.562586)
			(xy 26.707232 -27.556947) (xy 26.702512 -27.554936) (xy 26.693876 -27.55138) (xy 17.432274 -27.55138)
			(xy 17.426329 -27.551572) (xy 17.414779 -27.554399) (xy 17.409414 -27.556968) (xy 17.386808 -27.569668)
			(xy 17.376648 -27.577542) (xy 17.37233 -27.581606) (xy 17.369028 -27.58694) (xy 17.352181 -27.612751)
			(xy 17.312638 -27.660032) (xy 17.267112 -27.701582) (xy 17.216425 -27.736653) (xy 17.161493 -27.76461)
			(xy 17.103308 -27.784948) (xy 17.042922 -27.797299) (xy 16.981424 -27.801441) (xy 16.919926 -27.797299)
			(xy 16.85954 -27.784948) (xy 16.801355 -27.76461) (xy 16.746423 -27.736653) (xy 16.695736 -27.701582)
			(xy 16.65021 -27.660032) (xy 16.610667 -27.612751) (xy 16.59382 -27.58694) (xy 16.590518 -27.581606)
			(xy 16.5862 -27.577542) (xy 16.57604 -27.569668) (xy 16.553434 -27.556968) (xy 16.548061 -27.554424)
			(xy 16.536515 -27.551609) (xy 16.530574 -27.55138) (xy 12.53998 -27.55138) (xy 12.529994 -27.55192)
			(xy 12.511565 -27.559637) (xy 12.504166 -27.566366) (xy 12.04595 -28.024582) (xy 12.044172 -28.026868)
			(xy 12.03018 -28.044039) (xy 11.99886 -28.075362) (xy 11.981688 -28.089352) (xy 11.979402 -28.09113)
			(xy 11.804904 -28.265628) (xy 11.798097 -28.272975) (xy 11.790375 -28.291437) (xy 11.789918 -28.301442)
			(xy 11.789918 -29.114242) (xy 18.847308 -29.114242) (xy 18.847308 -28.250642) (xy 18.847798 -28.220658)
			(xy 18.855626 -28.161202) (xy 18.871147 -28.103277) (xy 18.894096 -28.047873) (xy 18.92408 -27.995939)
			(xy 18.960586 -27.948363) (xy 19.002991 -27.905958) (xy 19.050567 -27.869452) (xy 19.102501 -27.839468)
			(xy 19.157905 -27.816519) (xy 19.21583 -27.800998) (xy 19.275286 -27.79317) (xy 19.335254 -27.79317)
			(xy 19.39471 -27.800998) (xy 19.452635 -27.816519) (xy 19.508039 -27.839468) (xy 19.559973 -27.869452)
			(xy 19.607549 -27.905958) (xy 19.649954 -27.948363) (xy 19.68646 -27.995939) (xy 19.716444 -28.047873)
			(xy 19.739393 -28.103277) (xy 19.754914 -28.161202) (xy 19.762742 -28.220658) (xy 19.763232 -28.250642)
			(xy 19.763232 -29.114242) (xy 19.762742 -29.144226) (xy 19.754914 -29.203682) (xy 19.739393 -29.261607)
			(xy 19.716444 -29.317011) (xy 19.68646 -29.368945) (xy 19.649954 -29.416521) (xy 19.607549 -29.458926)
			(xy 19.559973 -29.495432) (xy 19.508039 -29.525416) (xy 19.452635 -29.548365) (xy 19.39471 -29.563886)
			(xy 19.335254 -29.571714) (xy 19.275286 -29.571714) (xy 19.21583 -29.563886) (xy 19.157905 -29.548365)
			(xy 19.102501 -29.525416) (xy 19.050567 -29.495432) (xy 19.002991 -29.458926) (xy 18.960586 -29.416521)
			(xy 18.92408 -29.368945) (xy 18.894096 -29.317011) (xy 18.871147 -29.261607) (xy 18.855626 -29.203682)
			(xy 18.847798 -29.144226) (xy 18.847308 -29.114242) (xy 11.789918 -29.114242) (xy 11.789918 -29.186378)
			(xy 11.812016 -29.21381) (xy 11.829542 -29.217874) (xy 11.855835 -29.224335) (xy 11.906404 -29.243678)
			(xy 11.953731 -29.269974) (xy 11.996866 -29.302695) (xy 12.034944 -29.341185) (xy 12.067198 -29.384671)
			(xy 12.092982 -29.432279) (xy 12.111779 -29.483053) (xy 12.12321 -29.535975) (xy 12.127045 -29.589981)
			(xy 12.123209 -29.643987) (xy 12.111778 -29.696908) (xy 12.092982 -29.747683) (xy 12.067197 -29.795291)
			(xy 12.034942 -29.838776) (xy 11.996865 -29.877266) (xy 11.95373 -29.909987) (xy 11.906402 -29.936283)
			(xy 11.855833 -29.955625) (xy 11.829542 -29.962094) (xy 11.812016 -29.966158) (xy 11.789918 -29.99359)
			(xy 11.789918 -30.92069) (xy 21.489416 -30.92069) (xy 21.489416 -30.05709) (xy 21.489906 -30.027106)
			(xy 21.497734 -29.96765) (xy 21.513255 -29.909725) (xy 21.536204 -29.854321) (xy 21.566188 -29.802387)
			(xy 21.602694 -29.754811) (xy 21.645099 -29.712406) (xy 21.692675 -29.6759) (xy 21.744609 -29.645916)
			(xy 21.800013 -29.622967) (xy 21.857938 -29.607446) (xy 21.917394 -29.599618) (xy 21.977362 -29.599618)
			(xy 22.036818 -29.607446) (xy 22.094743 -29.622967) (xy 22.150147 -29.645916) (xy 22.202081 -29.6759)
			(xy 22.249657 -29.712406) (xy 22.292062 -29.754811) (xy 22.328568 -29.802387) (xy 22.358552 -29.854321)
			(xy 22.381501 -29.909725) (xy 22.397022 -29.96765) (xy 22.40485 -30.027106) (xy 22.40534 -30.05709)
			(xy 22.40534 -30.92069) (xy 22.40485 -30.950674) (xy 22.397022 -31.01013) (xy 22.381501 -31.068055)
			(xy 22.358552 -31.123459) (xy 22.328568 -31.175393) (xy 22.292062 -31.222969) (xy 22.249657 -31.265374)
			(xy 22.202081 -31.30188) (xy 22.150147 -31.331864) (xy 22.094743 -31.354813) (xy 22.036818 -31.370334)
			(xy 21.977362 -31.378162) (xy 21.917394 -31.378162) (xy 21.857938 -31.370334) (xy 21.800013 -31.354813)
			(xy 21.744609 -31.331864) (xy 21.692675 -31.30188) (xy 21.645099 -31.265374) (xy 21.602694 -31.222969)
			(xy 21.566188 -31.175393) (xy 21.536204 -31.123459) (xy 21.513255 -31.068055) (xy 21.497734 -31.01013)
			(xy 21.489906 -30.950674) (xy 21.489416 -30.92069) (xy 11.789918 -30.92069) (xy 11.789918 -32.714184)
			(xy 18.847308 -32.714184) (xy 18.847308 -31.850584) (xy 18.847798 -31.8206) (xy 18.855626 -31.761144)
			(xy 18.871147 -31.703219) (xy 18.894096 -31.647815) (xy 18.92408 -31.595881) (xy 18.960586 -31.548305)
			(xy 19.002991 -31.5059) (xy 19.050567 -31.469394) (xy 19.102501 -31.43941) (xy 19.157905 -31.416461)
			(xy 19.21583 -31.40094) (xy 19.275286 -31.393112) (xy 19.335254 -31.393112) (xy 19.39471 -31.40094)
			(xy 19.452635 -31.416461) (xy 19.508039 -31.43941) (xy 19.559973 -31.469394) (xy 19.607549 -31.5059)
			(xy 19.649954 -31.548305) (xy 19.68646 -31.595881) (xy 19.716444 -31.647815) (xy 19.739393 -31.703219)
			(xy 19.754914 -31.761144) (xy 19.762742 -31.8206) (xy 19.763232 -31.850584) (xy 19.763232 -32.714184)
			(xy 19.762742 -32.744168) (xy 19.754914 -32.803624) (xy 19.739393 -32.861549) (xy 19.716444 -32.916953)
			(xy 19.68646 -32.968887) (xy 19.649954 -33.016463) (xy 19.607549 -33.058868) (xy 19.559973 -33.095374)
			(xy 19.508039 -33.125358) (xy 19.452635 -33.148307) (xy 19.39471 -33.163828) (xy 19.335254 -33.171656)
			(xy 19.275286 -33.171656) (xy 19.21583 -33.163828) (xy 19.157905 -33.148307) (xy 19.102501 -33.125358)
			(xy 19.050567 -33.095374) (xy 19.002991 -33.058868) (xy 18.960586 -33.016463) (xy 18.92408 -32.968887)
			(xy 18.894096 -32.916953) (xy 18.871147 -32.861549) (xy 18.855626 -32.803624) (xy 18.847798 -32.744168)
			(xy 18.847308 -32.714184) (xy 11.789918 -32.714184) (xy 11.789918 -34.520886) (xy 21.489416 -34.520886)
			(xy 21.489416 -33.657286) (xy 21.489906 -33.627302) (xy 21.497734 -33.567846) (xy 21.513255 -33.509921)
			(xy 21.536204 -33.454517) (xy 21.566188 -33.402583) (xy 21.602694 -33.355007) (xy 21.645099 -33.312602)
			(xy 21.692675 -33.276096) (xy 21.744609 -33.246112) (xy 21.800013 -33.223163) (xy 21.857938 -33.207642)
			(xy 21.917394 -33.199814) (xy 21.977362 -33.199814) (xy 22.036818 -33.207642) (xy 22.094743 -33.223163)
			(xy 22.150147 -33.246112) (xy 22.202081 -33.276096) (xy 22.249657 -33.312602) (xy 22.292062 -33.355007)
			(xy 22.328568 -33.402583) (xy 22.358552 -33.454517) (xy 22.381501 -33.509921) (xy 22.397022 -33.567846)
			(xy 22.40485 -33.627302) (xy 22.40534 -33.657286) (xy 22.40534 -34.520886) (xy 22.40485 -34.55087)
			(xy 22.397022 -34.610326) (xy 22.381501 -34.668251) (xy 22.358552 -34.723655) (xy 22.328568 -34.775589)
			(xy 22.292062 -34.823165) (xy 22.249657 -34.86557) (xy 22.202081 -34.902076) (xy 22.150147 -34.93206)
			(xy 22.094743 -34.955009) (xy 22.036818 -34.97053) (xy 21.977362 -34.978358) (xy 21.917394 -34.978358)
			(xy 21.857938 -34.97053) (xy 21.800013 -34.955009) (xy 21.744609 -34.93206) (xy 21.692675 -34.902076)
			(xy 21.645099 -34.86557) (xy 21.602694 -34.823165) (xy 21.566188 -34.775589) (xy 21.536204 -34.723655)
			(xy 21.513255 -34.668251) (xy 21.497734 -34.610326) (xy 21.489906 -34.55087) (xy 21.489416 -34.520886)
			(xy 11.789918 -34.520886) (xy 11.789918 -36.60013) (xy 11.998205 -36.60013) (xy 12.00221 -36.512222)
			(xy 12.014193 -36.425042) (xy 12.034053 -36.339313) (xy 12.061628 -36.255745) (xy 12.096687 -36.175031)
			(xy 12.13894 -36.097839) (xy 12.188038 -36.02481) (xy 12.243574 -35.956548) (xy 12.305086 -35.893618)
			(xy 12.372067 -35.836544) (xy 12.44396 -35.785796) (xy 12.520169 -35.741796) (xy 12.600064 -35.704909)
			(xy 12.682983 -35.67544) (xy 12.768238 -35.653633) (xy 12.855122 -35.639669) (xy 12.942916 -35.633663)
			(xy 13.030893 -35.635667) (xy 13.118323 -35.645662) (xy 13.204482 -35.663566) (xy 13.288656 -35.68923)
			(xy 13.370147 -35.722443) (xy 13.448281 -35.762929) (xy 13.522409 -35.810351) (xy 13.591917 -35.864318)
			(xy 13.605216 -35.876738) (xy 18.717258 -35.876738) (xy 18.721329 -35.821116) (xy 18.733455 -35.766679)
			(xy 18.753378 -35.714588) (xy 18.780674 -35.665953) (xy 18.81476 -35.62181) (xy 18.854909 -35.583101)
			(xy 18.900267 -35.55065) (xy 18.949867 -35.525149) (xy 19.002651 -35.507142) (xy 19.057494 -35.497012)
			(xy 19.113228 -35.494975) (xy 19.168665 -35.501075) (xy 19.222622 -35.515181) (xy 19.273951 -35.536993)
			(xy 19.321557 -35.566047) (xy 19.364425 -35.601722) (xy 19.401642 -35.643259) (xy 19.432415 -35.689772)
			(xy 19.456087 -35.740269) (xy 19.472155 -35.793676) (xy 19.480275 -35.848852) (xy 19.480784 -35.876738)
			(xy 22.789388 -35.876738) (xy 22.789874 -35.849487) (xy 22.79763 -35.795539) (xy 22.812985 -35.743244)
			(xy 22.835627 -35.693667) (xy 22.865093 -35.647817) (xy 22.900784 -35.606626) (xy 22.941975 -35.570935)
			(xy 22.987825 -35.541469) (xy 23.037402 -35.518827) (xy 23.089697 -35.503472) (xy 23.143645 -35.495716)
			(xy 23.198147 -35.495716) (xy 23.252095 -35.503472) (xy 23.30439 -35.518827) (xy 23.353967 -35.541469)
			(xy 23.399817 -35.570935) (xy 23.441008 -35.606626) (xy 23.476699 -35.647817) (xy 23.506165 -35.693667)
			(xy 23.528807 -35.743244) (xy 23.544162 -35.795539) (xy 23.551918 -35.849487) (xy 23.552404 -35.876738)
			(xy 23.551879 -35.905485) (xy 23.543214 -35.962323) (xy 23.526116 -36.017217) (xy 23.500973 -36.068923)
			(xy 23.485094 -36.092892) (xy 23.477483 -36.104722) (xy 23.468486 -36.131366) (xy 23.467098 -36.159453)
			(xy 23.473425 -36.186853) (xy 23.486986 -36.211489) (xy 23.506754 -36.23149) (xy 23.531228 -36.24534)
			(xy 23.544784 -36.249102) (xy 23.57205 -36.256313) (xy 23.624227 -36.277717) (xy 23.672687 -36.306568)
			(xy 23.716372 -36.342237) (xy 23.754332 -36.383948) (xy 23.785739 -36.43079) (xy 23.796546 -36.453572)
			(xy 23.928576 -36.453572) (xy 23.932647 -36.39795) (xy 23.944773 -36.343513) (xy 23.964696 -36.291422)
			(xy 23.991992 -36.242787) (xy 24.026078 -36.198644) (xy 24.066227 -36.159935) (xy 24.111585 -36.127484)
			(xy 24.161185 -36.101983) (xy 24.213969 -36.083976) (xy 24.268812 -36.073846) (xy 24.324546 -36.071809)
			(xy 24.379983 -36.077909) (xy 24.43394 -36.092015) (xy 24.485269 -36.113827) (xy 24.532875 -36.142881)
			(xy 24.575743 -36.178556) (xy 24.61296 -36.220093) (xy 24.643733 -36.266606) (xy 24.667405 -36.317103)
			(xy 24.683473 -36.37051) (xy 24.691593 -36.425686) (xy 24.692102 -36.453572) (xy 24.691593 -36.481458)
			(xy 24.683473 -36.536634) (xy 24.667405 -36.590041) (xy 24.643733 -36.640538) (xy 24.61296 -36.687051)
			(xy 24.575743 -36.728588) (xy 24.532875 -36.764263) (xy 24.485269 -36.793317) (xy 24.43394 -36.815129)
			(xy 24.379983 -36.829235) (xy 24.324546 -36.835335) (xy 24.268812 -36.833298) (xy 24.213969 -36.823168)
			(xy 24.161185 -36.805161) (xy 24.111585 -36.77966) (xy 24.066227 -36.747209) (xy 24.026078 -36.7085)
			(xy 23.991992 -36.664357) (xy 23.964696 -36.615722) (xy 23.944773 -36.563631) (xy 23.932647 -36.509194)
			(xy 23.928576 -36.453572) (xy 23.796546 -36.453572) (xy 23.80991 -36.481746) (xy 23.826318 -36.535704)
			(xy 23.834606 -36.591489) (xy 23.835106 -36.619688) (xy 23.83462 -36.646939) (xy 23.826864 -36.700887)
			(xy 23.811509 -36.753182) (xy 23.788867 -36.802759) (xy 23.759401 -36.848609) (xy 23.72371 -36.8898)
			(xy 23.682519 -36.925491) (xy 23.636669 -36.954957) (xy 23.587092 -36.977599) (xy 23.534797 -36.992954)
			(xy 23.480849 -37.00071) (xy 23.426347 -37.00071) (xy 23.372399 -36.992954) (xy 23.320104 -36.977599)
			(xy 23.270527 -36.954957) (xy 23.224677 -36.925491) (xy 23.183486 -36.8898) (xy 23.147795 -36.848609)
			(xy 23.118329 -36.802759) (xy 23.095687 -36.753182) (xy 23.080332 -36.700887) (xy 23.072576 -36.646939)
			(xy 23.07209 -36.619688) (xy 23.072629 -36.590941) (xy 23.08129 -36.534104) (xy 23.098384 -36.47921)
			(xy 23.123523 -36.427504) (xy 23.1394 -36.403534) (xy 23.146982 -36.391686) (xy 23.155984 -36.365049)
			(xy 23.157376 -36.336966) (xy 23.151054 -36.309568) (xy 23.137497 -36.284935) (xy 23.117734 -36.264935)
			(xy 23.093264 -36.251086) (xy 23.07971 -36.247324) (xy 23.05245 -36.240094) (xy 23.000274 -36.21869)
			(xy 22.951816 -36.189841) (xy 22.908131 -36.154174) (xy 22.870172 -36.112467) (xy 22.838764 -36.065626)
			(xy 22.814591 -36.014674) (xy 22.798181 -35.960719) (xy 22.78989 -35.904936) (xy 22.789388 -35.876738)
			(xy 19.480784 -35.876738) (xy 19.480275 -35.904624) (xy 19.472155 -35.9598) (xy 19.456087 -36.013207)
			(xy 19.432415 -36.063704) (xy 19.401642 -36.110217) (xy 19.364425 -36.151754) (xy 19.321557 -36.187429)
			(xy 19.273951 -36.216483) (xy 19.222622 -36.238295) (xy 19.168665 -36.252401) (xy 19.113228 -36.258501)
			(xy 19.057494 -36.256464) (xy 19.002651 -36.246334) (xy 18.949867 -36.228327) (xy 18.900267 -36.202826)
			(xy 18.854909 -36.170375) (xy 18.81476 -36.131666) (xy 18.780674 -36.087523) (xy 18.753378 -36.038888)
			(xy 18.733455 -35.986797) (xy 18.721329 -35.93236) (xy 18.717258 -35.876738) (xy 13.605216 -35.876738)
			(xy 13.656231 -35.924383) (xy 13.714815 -35.990047) (xy 13.767186 -36.060766) (xy 13.812909 -36.135954)
			(xy 13.851606 -36.214989) (xy 13.882955 -36.297215) (xy 13.906697 -36.381951) (xy 13.922635 -36.468495)
			(xy 13.926421 -36.50996) (xy 20.613876 -36.50996) (xy 20.617947 -36.454338) (xy 20.630073 -36.399901)
			(xy 20.649996 -36.34781) (xy 20.677292 -36.299175) (xy 20.711378 -36.255032) (xy 20.751527 -36.216323)
			(xy 20.796885 -36.183872) (xy 20.846485 -36.158371) (xy 20.899269 -36.140364) (xy 20.954112 -36.130234)
			(xy 21.009846 -36.128197) (xy 21.065283 -36.134297) (xy 21.11924 -36.148403) (xy 21.170569 -36.170215)
			(xy 21.218175 -36.199269) (xy 21.261043 -36.234944) (xy 21.29826 -36.276481) (xy 21.329033 -36.322994)
			(xy 21.352705 -36.373491) (xy 21.368773 -36.426898) (xy 21.376893 -36.482074) (xy 21.377402 -36.50996)
			(xy 21.376893 -36.537846) (xy 21.368773 -36.593022) (xy 21.352705 -36.646429) (xy 21.329033 -36.696926)
			(xy 21.29826 -36.743439) (xy 21.261043 -36.784976) (xy 21.218175 -36.820651) (xy 21.170569 -36.849705)
			(xy 21.11924 -36.871517) (xy 21.065283 -36.885623) (xy 21.009846 -36.891723) (xy 20.954112 -36.889686)
			(xy 20.899269 -36.879556) (xy 20.846485 -36.861549) (xy 20.796885 -36.836048) (xy 20.751527 -36.803597)
			(xy 20.711378 -36.764888) (xy 20.677292 -36.720745) (xy 20.649996 -36.67211) (xy 20.630073 -36.620019)
			(xy 20.617947 -36.565582) (xy 20.613876 -36.50996) (xy 13.926421 -36.50996) (xy 13.930637 -36.55613)
			(xy 13.931138 -36.60013) (xy 13.930637 -36.64413) (xy 13.922635 -36.731765) (xy 13.906697 -36.818309)
			(xy 13.882955 -36.903045) (xy 13.851606 -36.985271) (xy 13.812909 -37.064306) (xy 13.767186 -37.139494)
			(xy 13.714815 -37.210213) (xy 13.656231 -37.275877) (xy 13.591917 -37.335942) (xy 13.522409 -37.389909)
			(xy 13.448281 -37.437331) (xy 13.370147 -37.477817) (xy 13.288656 -37.51103) (xy 13.204482 -37.536694)
			(xy 13.118323 -37.554598) (xy 13.030893 -37.564593) (xy 12.942916 -37.566597) (xy 12.855122 -37.560591)
			(xy 12.768238 -37.546627) (xy 12.682983 -37.52482) (xy 12.600064 -37.495351) (xy 12.520169 -37.458464)
			(xy 12.44396 -37.414464) (xy 12.372067 -37.363716) (xy 12.305086 -37.306642) (xy 12.243574 -37.243712)
			(xy 12.188038 -37.17545) (xy 12.13894 -37.102421) (xy 12.096687 -37.025229) (xy 12.061628 -36.944515)
			(xy 12.034053 -36.860947) (xy 12.014193 -36.775218) (xy 12.00221 -36.688038) (xy 11.998205 -36.60013)
			(xy 11.789918 -36.60013) (xy 11.789918 -39.97198) (xy 25.895806 -39.97198) (xy 25.899877 -39.916358)
			(xy 25.912003 -39.861921) (xy 25.931926 -39.80983) (xy 25.959222 -39.761195) (xy 25.993308 -39.717052)
			(xy 26.033457 -39.678343) (xy 26.078815 -39.645892) (xy 26.128415 -39.620391) (xy 26.181199 -39.602384)
			(xy 26.236042 -39.592254) (xy 26.291776 -39.590217) (xy 26.347213 -39.596317) (xy 26.40117 -39.610423)
			(xy 26.452499 -39.632235) (xy 26.500105 -39.661289) (xy 26.542973 -39.696964) (xy 26.58019 -39.738501)
			(xy 26.610963 -39.785014) (xy 26.634635 -39.835511) (xy 26.650703 -39.888918) (xy 26.658823 -39.944094)
			(xy 26.659332 -39.97198) (xy 26.658823 -39.999866) (xy 26.650703 -40.055042) (xy 26.634635 -40.108449)
			(xy 26.610963 -40.158946) (xy 26.58019 -40.205459) (xy 26.542973 -40.246996) (xy 26.500105 -40.282671)
			(xy 26.452499 -40.311725) (xy 26.40117 -40.333537) (xy 26.347213 -40.347643) (xy 26.291776 -40.353743)
			(xy 26.236042 -40.351706) (xy 26.181199 -40.341576) (xy 26.128415 -40.323569) (xy 26.078815 -40.298068)
			(xy 26.033457 -40.265617) (xy 25.993308 -40.226908) (xy 25.959222 -40.182765) (xy 25.931926 -40.13413)
			(xy 25.912003 -40.082039) (xy 25.899877 -40.027602) (xy 25.895806 -39.97198) (xy 11.789918 -39.97198)
			(xy 11.789918 -40.452802) (xy 11.79068 -40.46093) (xy 11.79068 -40.461438) (xy 11.792281 -40.468956)
			(xy 11.799257 -40.482645) (xy 11.804396 -40.488362) (xy 12.024614 -40.70858) (xy 12.030296 -40.713767)
			(xy 12.044003 -40.720736) (xy 12.051538 -40.722296) (xy 12.052046 -40.722296) (xy 12.060174 -40.723058)
			(xy 21.081492 -40.723058) (xy 21.091562 -40.723481) (xy 21.110163 -40.7312) (xy 21.11756 -40.738044)
			(xy 22.05863 -41.679114) (xy 22.065482 -41.68651) (xy 22.073222 -41.705109) (xy 22.073616 -41.715182)
			(xy 22.073616 -43.85691) (xy 24.719786 -43.85691) (xy 24.723857 -43.801288) (xy 24.735983 -43.746851)
			(xy 24.755906 -43.69476) (xy 24.783202 -43.646125) (xy 24.817288 -43.601982) (xy 24.857437 -43.563273)
			(xy 24.902795 -43.530822) (xy 24.952395 -43.505321) (xy 25.005179 -43.487314) (xy 25.060022 -43.477184)
			(xy 25.115756 -43.475147) (xy 25.171193 -43.481247) (xy 25.22515 -43.495353) (xy 25.276479 -43.517165)
			(xy 25.324085 -43.546219) (xy 25.366953 -43.581894) (xy 25.40417 -43.623431) (xy 25.434943 -43.669944)
			(xy 25.458615 -43.720441) (xy 25.474683 -43.773848) (xy 25.482803 -43.829024) (xy 25.483312 -43.85691)
			(xy 25.482803 -43.884796) (xy 25.474683 -43.939972) (xy 25.458615 -43.993379) (xy 25.434943 -44.043876)
			(xy 25.40417 -44.090389) (xy 25.366953 -44.131926) (xy 25.324085 -44.167601) (xy 25.276479 -44.196655)
			(xy 25.22515 -44.218467) (xy 25.171193 -44.232573) (xy 25.115756 -44.238673) (xy 25.060022 -44.236636)
			(xy 25.005179 -44.226506) (xy 24.952395 -44.208499) (xy 24.902795 -44.182998) (xy 24.857437 -44.150547)
			(xy 24.817288 -44.111838) (xy 24.783202 -44.067695) (xy 24.755906 -44.01906) (xy 24.735983 -43.966969)
			(xy 24.723857 -43.912532) (xy 24.719786 -43.85691) (xy 22.073616 -43.85691) (xy 22.073616 -45.35424)
			(xy 24.703784 -45.35424) (xy 24.707855 -45.298618) (xy 24.719981 -45.244181) (xy 24.739904 -45.19209)
			(xy 24.7672 -45.143455) (xy 24.801286 -45.099312) (xy 24.841435 -45.060603) (xy 24.886793 -45.028152)
			(xy 24.936393 -45.002651) (xy 24.989177 -44.984644) (xy 25.04402 -44.974514) (xy 25.099754 -44.972477)
			(xy 25.155191 -44.978577) (xy 25.209148 -44.992683) (xy 25.260477 -45.014495) (xy 25.308083 -45.043549)
			(xy 25.350951 -45.079224) (xy 25.388168 -45.120761) (xy 25.418941 -45.167274) (xy 25.442613 -45.217771)
			(xy 25.458681 -45.271178) (xy 25.466801 -45.326354) (xy 25.46731 -45.35424) (xy 25.466801 -45.382126)
			(xy 25.458681 -45.437302) (xy 25.442613 -45.490709) (xy 25.418941 -45.541206) (xy 25.388168 -45.587719)
			(xy 25.350951 -45.629256) (xy 25.308083 -45.664931) (xy 25.260477 -45.693985) (xy 25.209148 -45.715797)
			(xy 25.155191 -45.729903) (xy 25.099754 -45.736003) (xy 25.04402 -45.733966) (xy 24.989177 -45.723836)
			(xy 24.936393 -45.705829) (xy 24.886793 -45.680328) (xy 24.841435 -45.647877) (xy 24.801286 -45.609168)
			(xy 24.7672 -45.565025) (xy 24.739904 -45.51639) (xy 24.719981 -45.464299) (xy 24.707855 -45.409862)
			(xy 24.703784 -45.35424) (xy 22.073616 -45.35424) (xy 22.073616 -46.693836) (xy 24.676354 -46.693836)
			(xy 24.67684 -46.666585) (xy 24.684596 -46.612637) (xy 24.699951 -46.560342) (xy 24.722593 -46.510765)
			(xy 24.752059 -46.464915) (xy 24.78775 -46.423724) (xy 24.828941 -46.388033) (xy 24.874791 -46.358567)
			(xy 24.924368 -46.335925) (xy 24.976663 -46.32057) (xy 25.030611 -46.312814) (xy 25.085113 -46.312814)
			(xy 25.139061 -46.32057) (xy 25.191356 -46.335925) (xy 25.240933 -46.358567) (xy 25.286783 -46.388033)
			(xy 25.327974 -46.423724) (xy 25.363665 -46.464915) (xy 25.393131 -46.510765) (xy 25.415773 -46.560342)
			(xy 25.431128 -46.612637) (xy 25.438884 -46.666585) (xy 25.43937 -46.693836) (xy 25.438901 -46.720264)
			(xy 25.431591 -46.772611) (xy 25.417117 -46.823446) (xy 25.395755 -46.871793) (xy 25.38222 -46.894496)
			(xy 25.381966 -46.89475) (xy 25.37663 -46.904768) (xy 25.374372 -46.927318) (xy 25.377648 -46.938184)
			(xy 25.40381 -47.01286) (xy 25.408168 -47.023389) (xy 25.424274 -47.039472) (xy 25.434798 -47.043848)
			(xy 25.435052 -47.043848) (xy 25.459562 -47.052914) (xy 25.506014 -47.076857) (xy 25.548766 -47.106914)
			(xy 25.587018 -47.142522) (xy 25.620054 -47.183015) (xy 25.647258 -47.227636) (xy 25.668119 -47.275552)
			(xy 25.682249 -47.325865) (xy 25.689383 -47.377636) (xy 25.689814 -47.403766) (xy 25.689328 -47.431017)
			(xy 25.681572 -47.484965) (xy 25.666217 -47.53726) (xy 25.643575 -47.586837) (xy 25.614109 -47.632687)
			(xy 25.578418 -47.673878) (xy 25.537227 -47.709569) (xy 25.491377 -47.739035) (xy 25.4418 -47.761677)
			(xy 25.389505 -47.777032) (xy 25.335557 -47.784788) (xy 25.281055 -47.784788) (xy 25.227107 -47.777032)
			(xy 25.174812 -47.761677) (xy 25.125235 -47.739035) (xy 25.079385 -47.709569) (xy 25.038194 -47.673878)
			(xy 25.002503 -47.632687) (xy 24.973037 -47.586837) (xy 24.950395 -47.53726) (xy 24.93504 -47.484965)
			(xy 24.927284 -47.431017) (xy 24.926798 -47.403766) (xy 24.927272 -47.377338) (xy 24.934581 -47.324991)
			(xy 24.949054 -47.274156) (xy 24.970413 -47.225809) (xy 24.983948 -47.203106) (xy 24.984202 -47.202852)
			(xy 24.989537 -47.192833) (xy 24.991798 -47.170283) (xy 24.98852 -47.159418) (xy 24.962358 -47.084742)
			(xy 24.958014 -47.074206) (xy 24.941898 -47.058126) (xy 24.93137 -47.053754) (xy 24.931116 -47.053754)
			(xy 24.9066 -47.044704) (xy 24.860148 -47.020757) (xy 24.817398 -46.990698) (xy 24.779147 -46.955088)
			(xy 24.746112 -46.914592) (xy 24.718909 -46.869969) (xy 24.698048 -46.822053) (xy 24.683919 -46.771738)
			(xy 24.676785 -46.719966) (xy 24.676354 -46.693836) (xy 22.073616 -46.693836) (xy 22.073616 -48.30699)
			(xy 24.553924 -48.30699) (xy 24.557995 -48.251368) (xy 24.570121 -48.196931) (xy 24.590044 -48.14484)
			(xy 24.61734 -48.096205) (xy 24.651426 -48.052062) (xy 24.691575 -48.013353) (xy 24.736933 -47.980902)
			(xy 24.786533 -47.955401) (xy 24.839317 -47.937394) (xy 24.89416 -47.927264) (xy 24.949894 -47.925227)
			(xy 25.005331 -47.931327) (xy 25.059288 -47.945433) (xy 25.110617 -47.967245) (xy 25.158223 -47.996299)
			(xy 25.201091 -48.031974) (xy 25.238308 -48.073511) (xy 25.269081 -48.120024) (xy 25.292753 -48.170521)
			(xy 25.308821 -48.223928) (xy 25.316941 -48.279104) (xy 25.31745 -48.30699) (xy 25.316941 -48.334876)
			(xy 25.308821 -48.390052) (xy 25.292753 -48.443459) (xy 25.269081 -48.493956) (xy 25.238308 -48.540469)
			(xy 25.201091 -48.582006) (xy 25.158223 -48.617681) (xy 25.110617 -48.646735) (xy 25.059288 -48.668547)
			(xy 25.005331 -48.682653) (xy 24.949894 -48.688753) (xy 24.89416 -48.686716) (xy 24.839317 -48.676586)
			(xy 24.786533 -48.658579) (xy 24.736933 -48.633078) (xy 24.691575 -48.600627) (xy 24.651426 -48.561918)
			(xy 24.61734 -48.517775) (xy 24.590044 -48.46914) (xy 24.570121 -48.417049) (xy 24.557995 -48.362612)
			(xy 24.553924 -48.30699) (xy 22.073616 -48.30699) (xy 22.073616 -48.89246) (xy 23.214074 -48.89246)
			(xy 23.218145 -48.836838) (xy 23.230271 -48.782401) (xy 23.250194 -48.73031) (xy 23.27749 -48.681675)
			(xy 23.311576 -48.637532) (xy 23.351725 -48.598823) (xy 23.397083 -48.566372) (xy 23.446683 -48.540871)
			(xy 23.499467 -48.522864) (xy 23.55431 -48.512734) (xy 23.610044 -48.510697) (xy 23.665481 -48.516797)
			(xy 23.719438 -48.530903) (xy 23.770767 -48.552715) (xy 23.818373 -48.581769) (xy 23.861241 -48.617444)
			(xy 23.898458 -48.658981) (xy 23.929231 -48.705494) (xy 23.952903 -48.755991) (xy 23.968971 -48.809398)
			(xy 23.977091 -48.864574) (xy 23.9776 -48.89246) (xy 23.977091 -48.920346) (xy 23.968971 -48.975522)
			(xy 23.952903 -49.028929) (xy 23.929231 -49.079426) (xy 23.898458 -49.125939) (xy 23.861241 -49.167476)
			(xy 23.818373 -49.203151) (xy 23.770767 -49.232205) (xy 23.719438 -49.254017) (xy 23.665481 -49.268123)
			(xy 23.610044 -49.274223) (xy 23.55431 -49.272186) (xy 23.499467 -49.262056) (xy 23.446683 -49.244049)
			(xy 23.397083 -49.218548) (xy 23.351725 -49.186097) (xy 23.311576 -49.147388) (xy 23.27749 -49.103245)
			(xy 23.250194 -49.05461) (xy 23.230271 -49.002519) (xy 23.218145 -48.948082) (xy 23.214074 -48.89246)
			(xy 22.073616 -48.89246) (xy 22.073616 -51.19751) (xy 22.07387 -51.203098) (xy 22.074908 -51.210581)
			(xy 22.080727 -51.224515) (xy 22.0853 -51.23053) (xy 22.086824 -51.232308) (xy 22.233382 -51.378866)
			(xy 22.238816 -51.383838) (xy 22.251859 -51.390666) (xy 22.259036 -51.392328) (xy 22.259544 -51.392328)
			(xy 22.268942 -51.393344)
		)
		(stroke
			(width 0)
			(type solid)
		)
		(fill yes)
		(layer "In9.Cu")
		(net "GND")
	)
	(gr_poly
		(pts
			(xy 76.732638 -51.393344) (xy 76.741874 -51.392955) (xy 76.759151 -51.386419) (xy 76.772983 -51.374176)
			(xy 76.777596 -51.366166) (xy 76.819252 -51.286664) (xy 76.823158 -51.278382) (xy 76.825434 -51.260225)
			(xy 76.821218 -51.242418) (xy 76.816458 -51.234594) (xy 76.816204 -51.23434) (xy 76.800709 -51.2107)
			(xy 76.776108 -51.159811) (xy 76.759278 -51.105851) (xy 76.750588 -51.05) (xy 76.74991 -51.021742)
			(xy 76.74991 -51.01463) (xy 76.750722 -50.987604) (xy 76.759032 -50.934177) (xy 76.774801 -50.882459)
			(xy 76.797713 -50.833486) (xy 76.82731 -50.788237) (xy 76.862999 -50.74762) (xy 76.904064 -50.712448)
			(xy 76.949683 -50.683426) (xy 76.998943 -50.661135) (xy 77.050857 -50.646021) (xy 77.104384 -50.638388)
			(xy 77.158452 -50.638388) (xy 77.211979 -50.646021) (xy 77.263893 -50.661135) (xy 77.313153 -50.683426)
			(xy 77.358772 -50.712448) (xy 77.399837 -50.74762) (xy 77.435526 -50.788237) (xy 77.465123 -50.833486)
			(xy 77.488035 -50.882459) (xy 77.503804 -50.934177) (xy 77.512114 -50.987604) (xy 77.512926 -51.01463)
			(xy 77.512926 -51.01971) (xy 77.512418 -51.048258) (xy 77.503903 -51.104717) (xy 77.487067 -51.159275)
			(xy 77.462284 -51.210713) (xy 77.446632 -51.234594) (xy 77.438504 -51.246278) (xy 77.43698 -51.274218)
			(xy 77.48524 -51.366166) (xy 77.48989 -51.374146) (xy 77.503713 -51.386373) (xy 77.520971 -51.39291)
			(xy 77.530198 -51.393344) (xy 78.422246 -51.393344) (xy 78.432211 -51.392863) (xy 78.450644 -51.385285)
			(xy 78.45806 -51.378612) (xy 78.97622 -50.860452) (xy 78.98003 -50.852578) (xy 78.989936 -50.833528)
			(xy 78.99019 -50.833274) (xy 78.994 -50.82667) (xy 78.997302 -50.821082) (xy 79.001366 -50.806858)
			(xy 79.004668 -50.795174) (xy 79.004668 -50.1904) (xy 79.004412 -50.182989) (xy 79.000146 -50.168793)
			(xy 78.996286 -50.16246) (xy 78.981453 -50.139007) (xy 78.957996 -50.088717) (xy 78.942076 -50.035559)
			(xy 78.93403 -49.980654) (xy 78.934029 -49.925163) (xy 78.942072 -49.870258) (xy 78.95799 -49.817098)
			(xy 78.981445 -49.766808) (xy 78.996286 -49.74336) (xy 79.000149 -49.73703) (xy 79.004405 -49.722831)
			(xy 79.004668 -49.71542) (xy 79.004668 -49.1744) (xy 79.004412 -49.166989) (xy 79.000146 -49.152793)
			(xy 78.996286 -49.14646) (xy 78.981453 -49.123007) (xy 78.957996 -49.072717) (xy 78.942076 -49.019559)
			(xy 78.93403 -48.964654) (xy 78.934029 -48.909163) (xy 78.942072 -48.854258) (xy 78.95799 -48.801098)
			(xy 78.981445 -48.750808) (xy 78.996286 -48.72736) (xy 79.000149 -48.72103) (xy 79.004405 -48.706831)
			(xy 79.004668 -48.69942) (xy 79.004668 -47.629572) (xy 79.002128 -47.61865) (xy 78.999334 -47.613062)
			(xy 78.986609 -47.586292) (xy 78.968633 -47.529814) (xy 78.959536 -47.471246) (xy 78.959535 -47.411976)
			(xy 78.968628 -47.353407) (xy 78.986601 -47.296928) (xy 78.999334 -47.270162) (xy 79.002128 -47.264574)
			(xy 79.004668 -47.253652) (xy 79.004668 -46.1264) (xy 79.004412 -46.118989) (xy 79.000146 -46.104793)
			(xy 78.996286 -46.09846) (xy 78.981453 -46.075007) (xy 78.957996 -46.024717) (xy 78.942076 -45.971559)
			(xy 78.93403 -45.916654) (xy 78.934029 -45.861163) (xy 78.942072 -45.806258) (xy 78.95799 -45.753098)
			(xy 78.981445 -45.702808) (xy 78.996286 -45.67936) (xy 79.000149 -45.67303) (xy 79.004405 -45.658831)
			(xy 79.004668 -45.65142) (xy 79.004668 -45.1104) (xy 79.004412 -45.102989) (xy 79.000146 -45.088793)
			(xy 78.996286 -45.08246) (xy 78.981453 -45.059007) (xy 78.957996 -45.008717) (xy 78.942076 -44.955559)
			(xy 78.93403 -44.900654) (xy 78.934029 -44.845163) (xy 78.942072 -44.790258) (xy 78.95799 -44.737098)
			(xy 78.981445 -44.686808) (xy 78.996286 -44.66336) (xy 79.000149 -44.65703) (xy 79.004405 -44.642831)
			(xy 79.004668 -44.63542) (xy 79.004668 -44.0944) (xy 79.004412 -44.086989) (xy 79.000146 -44.072793)
			(xy 78.996286 -44.06646) (xy 78.981453 -44.043007) (xy 78.957996 -43.992717) (xy 78.942076 -43.939559)
			(xy 78.93403 -43.884654) (xy 78.934029 -43.829163) (xy 78.942072 -43.774258) (xy 78.95799 -43.721098)
			(xy 78.981445 -43.670808) (xy 78.996286 -43.64736) (xy 79.000149 -43.64103) (xy 79.004405 -43.626831)
			(xy 79.004668 -43.61942) (xy 79.004668 -43.0784) (xy 79.004412 -43.070989) (xy 79.000146 -43.056793)
			(xy 78.996286 -43.05046) (xy 78.981453 -43.027007) (xy 78.957996 -42.976717) (xy 78.942076 -42.923559)
			(xy 78.93403 -42.868654) (xy 78.934029 -42.813163) (xy 78.942072 -42.758258) (xy 78.95799 -42.705098)
			(xy 78.981445 -42.654808) (xy 78.996286 -42.63136) (xy 79.000149 -42.62503) (xy 79.004405 -42.610831)
			(xy 79.004668 -42.60342) (xy 79.004668 -41.423844) (xy 79.004282 -41.414078) (xy 78.997107 -41.395915)
			(xy 78.990698 -41.388538) (xy 78.96987 -41.366948) (xy 78.961488 -41.362884) (xy 78.93812 -41.351454)
			(xy 78.929738 -41.350438) (xy 78.902341 -41.346596) (xy 78.848971 -41.332028) (xy 78.798265 -41.309905)
			(xy 78.751286 -41.280692) (xy 78.709018 -41.245) (xy 78.672347 -41.203578) (xy 78.642043 -41.157295)
			(xy 78.618741 -41.10712) (xy 78.602929 -41.054106) (xy 78.594939 -40.999364) (xy 78.594939 -40.944042)
			(xy 78.602928 -40.8893) (xy 78.618739 -40.836286) (xy 78.64204 -40.786111) (xy 78.672344 -40.739826)
			(xy 78.709014 -40.698404) (xy 78.751281 -40.662711) (xy 78.79826 -40.633497) (xy 78.848966 -40.611374)
			(xy 78.902335 -40.596805) (xy 78.929738 -40.59301) (xy 78.93812 -40.591994) (xy 78.961742 -40.580564)
			(xy 78.96577 -40.5785) (xy 78.973061 -40.573137) (xy 78.97622 -40.569896) (xy 78.990698 -40.55491)
			(xy 78.997116 -40.547535) (xy 79.004306 -40.529373) (xy 79.004668 -40.519604) (xy 79.004668 -38.432232)
			(xy 79.004253 -38.422209) (xy 78.996588 -38.403687) (xy 78.982413 -38.389512) (xy 78.963891 -38.381847)
			(xy 78.953868 -38.381432) (xy 77.284072 -38.381432) (xy 77.274937 -38.381819) (xy 77.257834 -38.388242)
			(xy 77.244074 -38.400261) (xy 77.239368 -38.408102) (xy 77.197204 -38.486842) (xy 77.194189 -38.492876)
			(xy 77.191106 -38.506004) (xy 77.191108 -38.51275) (xy 77.191616 -38.527228) (xy 77.19949 -38.539166)
			(xy 77.214621 -38.562786) (xy 77.238542 -38.613523) (xy 77.254783 -38.667213) (xy 77.262996 -38.722702)
			(xy 77.263498 -38.750748) (xy 77.263008 -38.777997) (xy 77.255246 -38.831939) (xy 77.239887 -38.884227)
			(xy 77.217243 -38.933797) (xy 77.187775 -38.979641) (xy 77.152084 -39.020825) (xy 77.110895 -39.05651)
			(xy 77.065047 -39.085971) (xy 77.015473 -39.108607) (xy 76.963182 -39.123959) (xy 76.909239 -39.131713)
			(xy 76.88199 -39.132256) (xy 76.853688 -39.131741) (xy 76.797705 -39.123379) (xy 76.743571 -39.106841)
			(xy 76.692473 -39.082488) (xy 76.645533 -39.050855) (xy 76.603779 -39.012637) (xy 76.568128 -38.96867)
			(xy 76.553314 -38.94455) (xy 76.54671 -38.933374) (xy 76.525374 -38.920166) (xy 76.479908 -38.917626)
			(xy 76.415646 -38.913816) (xy 76.392786 -38.92423) (xy 76.385166 -38.93439) (xy 76.366978 -38.957269)
			(xy 76.324825 -38.99775) (xy 76.276993 -39.031332) (xy 76.2246 -39.05723) (xy 76.168873 -39.074839)
			(xy 76.111112 -39.083746) (xy 76.08189 -39.08425) (xy 76.054638 -39.083764) (xy 76.000689 -39.076006)
			(xy 75.948393 -39.060651) (xy 75.898815 -39.038009) (xy 75.852962 -39.008544) (xy 75.81177 -38.972853)
			(xy 75.776076 -38.931663) (xy 75.746606 -38.885813) (xy 75.723961 -38.836237) (xy 75.708601 -38.783942)
			(xy 75.700839 -38.729994) (xy 75.700382 -38.702742) (xy 75.700941 -38.672656) (xy 75.710386 -38.613231)
			(xy 75.729063 -38.556033) (xy 75.742292 -38.529006) (xy 75.748388 -38.517068) (xy 75.747372 -38.490906)
			(xy 75.695048 -38.405562) (xy 75.690216 -38.398399) (xy 75.676775 -38.387558) (xy 75.660501 -38.381783)
			(xy 75.651868 -38.381432) (xy 73.285096 -38.381432) (xy 73.276241 -38.381859) (xy 73.259611 -38.387965)
			(xy 73.252584 -38.39337) (xy 73.041002 -38.604952) (xy 72.963532 -38.682168) (xy 72.939633 -38.705334)
			(xy 72.886828 -38.745857) (xy 72.829185 -38.779138) (xy 72.76769 -38.804608) (xy 72.703395 -38.82183)
			(xy 72.637403 -38.830511) (xy 72.604122 -38.831012) (xy 70.988682 -38.831012) (xy 70.955404 -38.830467)
			(xy 70.889418 -38.82178) (xy 70.82513 -38.804557) (xy 70.763639 -38.779092) (xy 70.705996 -38.745821)
			(xy 70.653188 -38.705313) (xy 70.629272 -38.682168) (xy 69.781674 -37.83457) (xy 69.758139 -37.81028)
			(xy 69.71704 -37.756567) (xy 69.68342 -37.697881) (xy 69.657872 -37.635259) (xy 69.648832 -37.602668)
			(xy 69.64123 -37.57134) (xy 69.633072 -37.507393) (xy 69.632576 -37.47516) (xy 69.63304 -37.444469)
			(xy 69.640434 -37.383535) (xy 69.655109 -37.323933) (xy 69.676851 -37.266532) (xy 69.705346 -37.212165)
			(xy 69.740178 -37.161623) (xy 69.78084 -37.115642) (xy 69.826742 -37.07489) (xy 69.877215 -37.03996)
			(xy 69.931526 -37.011359) (xy 69.988885 -36.989505) (xy 70.048458 -36.974713) (xy 70.109378 -36.967201)
			(xy 70.140068 -36.966652) (xy 70.141084 -36.966652) (xy 70.173317 -36.967151) (xy 70.237264 -36.975307)
			(xy 70.268592 -36.982908) (xy 70.301185 -36.991943) (xy 70.363817 -37.017474) (xy 70.422507 -37.051092)
			(xy 70.476215 -37.092203) (xy 70.500494 -37.11575) (xy 71.184262 -37.799518) (xy 71.19166 -37.806363)
			(xy 71.210259 -37.814088) (xy 71.22033 -37.814504) (xy 71.849742 -37.814504) (xy 71.860489 -37.814021)
			(xy 71.880087 -37.805198) (xy 71.887588 -37.797486) (xy 71.938134 -37.741352) (xy 71.944705 -37.733235)
			(xy 71.951267 -37.713432) (xy 71.950834 -37.702998) (xy 71.950834 -37.702236) (xy 71.949868 -37.692295)
			(xy 71.948852 -37.672346) (xy 71.948802 -37.662358) (xy 71.949291 -37.635109) (xy 71.957053 -37.581166)
			(xy 71.972411 -37.528877) (xy 71.995055 -37.479306) (xy 72.024523 -37.433462) (xy 72.060214 -37.392277)
			(xy 72.101403 -37.356591) (xy 72.147252 -37.32713) (xy 72.196826 -37.304493) (xy 72.249117 -37.289141)
			(xy 72.303061 -37.281387) (xy 72.33031 -37.28085) (xy 72.359362 -37.281395) (xy 72.416795 -37.290204)
			(xy 72.472229 -37.307617) (xy 72.524382 -37.333232) (xy 72.572051 -37.366456) (xy 72.614132 -37.406522)
			(xy 72.632316 -37.429186) (xy 72.638412 -37.43706) (xy 72.646794 -37.44214) (xy 72.650954 -37.444434)
			(xy 72.659902 -37.447625) (xy 72.664574 -37.44849) (xy 72.7329 -37.459666) (xy 72.742473 -37.460794)
			(xy 72.761269 -37.456598) (xy 72.769476 -37.451538) (xy 72.76973 -37.451284) (xy 72.797416 -37.433232)
			(xy 72.856535 -37.403679) (xy 72.887586 -37.392356) (xy 72.914416 -37.383489) (xy 72.96954 -37.371054)
			(xy 73.025701 -37.36479) (xy 73.053956 -37.364416) (xy 78.953868 -37.364416) (xy 78.963895 -37.364002)
			(xy 78.982425 -37.356338) (xy 78.996611 -37.342166) (xy 79.004293 -37.323642) (xy 79.004668 -37.313616)
			(xy 79.004668 -31.63316) (xy 79.003906 -31.629096) (xy 79.001623 -31.613896) (xy 78.999206 -31.583252)
			(xy 78.99908 -31.567882) (xy 78.9992 -31.552512) (xy 79.001618 -31.521867) (xy 79.003906 -31.506668)
			(xy 79.004668 -31.502604) (xy 79.004668 -30.671008) (xy 78.990952 -30.636972) (xy 78.98511 -30.630368)
			(xy 78.967069 -30.609299) (xy 78.936633 -30.562929) (xy 78.913228 -30.512642) (xy 78.897347 -30.459498)
			(xy 78.889323 -30.404615) (xy 78.889325 -30.349149) (xy 78.897354 -30.294267) (xy 78.913241 -30.241124)
			(xy 78.936651 -30.19084) (xy 78.967091 -30.144472) (xy 78.98511 -30.123384) (xy 78.990952 -30.11678)
			(xy 79.004668 -30.082744) (xy 79.004668 -29.909008) (xy 78.990952 -29.874972) (xy 78.98511 -29.868368)
			(xy 78.967066 -29.847301) (xy 78.936626 -29.800932) (xy 78.913222 -29.750643) (xy 78.897345 -29.697496)
			(xy 78.889331 -29.64261) (xy 78.888844 -29.614876) (xy 78.888844 -29.614368) (xy 78.889451 -29.583501)
			(xy 78.899418 -29.522577) (xy 78.919072 -29.464054) (xy 78.947897 -29.409463) (xy 78.96606 -29.384498)
			(xy 78.97073 -29.377758) (xy 78.975915 -29.362212) (xy 78.97622 -29.354018) (xy 78.97622 -29.062934)
			(xy 78.975916 -29.054738) (xy 78.970744 -29.039185) (xy 78.96606 -29.032454) (xy 78.949858 -29.01024)
			(xy 78.923322 -28.962087) (xy 78.903967 -28.910625) (xy 78.892192 -28.85692) (xy 78.888242 -28.802081)
			(xy 78.892198 -28.747242) (xy 78.903978 -28.693538) (xy 78.923338 -28.642078) (xy 78.949879 -28.593928)
			(xy 78.96606 -28.571698) (xy 78.97073 -28.564958) (xy 78.975915 -28.549412) (xy 78.97622 -28.541218)
			(xy 78.97622 -28.38323) (xy 78.976438 -28.376189) (xy 78.980295 -28.362647) (xy 78.98384 -28.35656)
			(xy 78.996794 -28.33624) (xy 79.000431 -28.330041) (xy 79.004431 -28.316245) (xy 79.004668 -28.309062)
			(xy 79.004668 -27.872436) (xy 79.004233 -27.862372) (xy 78.996498 -27.843787) (xy 78.989682 -27.836368)
			(xy 78.75016 -27.596846) (xy 78.742761 -27.590001) (xy 78.724163 -27.582274) (xy 78.714092 -27.58186)
			(xy 69.399404 -27.58186) (xy 69.387072 -27.582443) (xy 69.365221 -27.593879) (xy 69.357748 -27.603704)
			(xy 69.340588 -27.627665) (xy 69.301082 -27.6714) (xy 69.256291 -27.709706) (xy 69.206956 -27.74195)
			(xy 69.153893 -27.767598) (xy 69.097978 -27.786227) (xy 69.040135 -27.797529) (xy 68.98132 -27.801317)
			(xy 68.922505 -27.797529) (xy 68.864662 -27.786227) (xy 68.808747 -27.767598) (xy 68.755684 -27.74195)
			(xy 68.706349 -27.709706) (xy 68.661558 -27.6714) (xy 68.622052 -27.627665) (xy 68.604892 -27.603704)
			(xy 68.597281 -27.594031) (xy 68.575521 -27.582609) (xy 68.563236 -27.58186) (xy 64.427862 -27.58186)
			(xy 64.417796 -27.582292) (xy 64.399207 -27.590022) (xy 64.391794 -27.596846) (xy 64.122808 -27.865832)
			(xy 64.116458 -27.877262) (xy 64.11468 -27.88412) (xy 64.106954 -27.912349) (xy 64.08404 -27.9662)
			(xy 64.053173 -28.015922) (xy 64.015074 -28.060347) (xy 63.970639 -28.098433) (xy 63.92091 -28.129288)
			(xy 63.867052 -28.152186) (xy 63.838836 -28.159964) (xy 63.831978 -28.161742) (xy 63.820548 -28.168092)
			(xy 63.8048 -28.18384) (xy 63.79796 -28.191241) (xy 63.79024 -28.209839) (xy 63.789814 -28.219908)
			(xy 63.789814 -29.114242) (xy 70.847204 -29.114242) (xy 70.847204 -28.250642) (xy 70.847694 -28.220658)
			(xy 70.855522 -28.161202) (xy 70.871043 -28.103277) (xy 70.893992 -28.047873) (xy 70.923976 -27.995939)
			(xy 70.960482 -27.948363) (xy 71.002887 -27.905958) (xy 71.050463 -27.869452) (xy 71.102397 -27.839468)
			(xy 71.157801 -27.816519) (xy 71.215726 -27.800998) (xy 71.275182 -27.79317) (xy 71.33515 -27.79317)
			(xy 71.394606 -27.800998) (xy 71.452531 -27.816519) (xy 71.507935 -27.839468) (xy 71.559869 -27.869452)
			(xy 71.607445 -27.905958) (xy 71.64985 -27.948363) (xy 71.686356 -27.995939) (xy 71.71634 -28.047873)
			(xy 71.739289 -28.103277) (xy 71.75481 -28.161202) (xy 71.762638 -28.220658) (xy 71.763128 -28.250642)
			(xy 71.763128 -28.469082) (xy 75.75245 -28.469082) (xy 75.756521 -28.41346) (xy 75.768647 -28.359023)
			(xy 75.78857 -28.306932) (xy 75.815866 -28.258297) (xy 75.849952 -28.214154) (xy 75.890101 -28.175445)
			(xy 75.935459 -28.142994) (xy 75.985059 -28.117493) (xy 76.037843 -28.099486) (xy 76.092686 -28.089356)
			(xy 76.14842 -28.087319) (xy 76.203857 -28.093419) (xy 76.257814 -28.107525) (xy 76.309143 -28.129337)
			(xy 76.356749 -28.158391) (xy 76.399617 -28.194066) (xy 76.436834 -28.235603) (xy 76.467607 -28.282116)
			(xy 76.491279 -28.332613) (xy 76.507347 -28.38602) (xy 76.515467 -28.441196) (xy 76.515976 -28.469082)
			(xy 76.515467 -28.496968) (xy 76.507347 -28.552144) (xy 76.491279 -28.605551) (xy 76.467607 -28.656048)
			(xy 76.436834 -28.702561) (xy 76.399617 -28.744098) (xy 76.356749 -28.779773) (xy 76.309143 -28.808827)
			(xy 76.257814 -28.830639) (xy 76.203857 -28.844745) (xy 76.14842 -28.850845) (xy 76.092686 -28.848808)
			(xy 76.037843 -28.838678) (xy 75.985059 -28.820671) (xy 75.935459 -28.79517) (xy 75.890101 -28.762719)
			(xy 75.849952 -28.72401) (xy 75.815866 -28.679867) (xy 75.78857 -28.631232) (xy 75.768647 -28.579141)
			(xy 75.756521 -28.524704) (xy 75.75245 -28.469082) (xy 71.763128 -28.469082) (xy 71.763128 -29.114242)
			(xy 71.762638 -29.144226) (xy 71.75481 -29.203682) (xy 71.739289 -29.261607) (xy 71.71634 -29.317011)
			(xy 71.686356 -29.368945) (xy 71.64985 -29.416521) (xy 71.607445 -29.458926) (xy 71.559869 -29.495432)
			(xy 71.507935 -29.525416) (xy 71.452531 -29.548365) (xy 71.394606 -29.563886) (xy 71.33515 -29.571714)
			(xy 71.275182 -29.571714) (xy 71.215726 -29.563886) (xy 71.157801 -29.548365) (xy 71.102397 -29.525416)
			(xy 71.050463 -29.495432) (xy 71.002887 -29.458926) (xy 70.960482 -29.416521) (xy 70.923976 -29.368945)
			(xy 70.893992 -29.317011) (xy 70.871043 -29.261607) (xy 70.855522 -29.203682) (xy 70.847694 -29.144226)
			(xy 70.847204 -29.114242) (xy 63.789814 -29.114242) (xy 63.789814 -29.186378) (xy 63.811912 -29.214064)
			(xy 63.829438 -29.217874) (xy 63.855734 -29.224333) (xy 63.906311 -29.243672) (xy 63.953646 -29.269966)
			(xy 63.996789 -29.302687) (xy 64.034873 -29.341178) (xy 64.067134 -29.384667) (xy 64.092924 -29.432278)
			(xy 64.111724 -29.483058) (xy 64.123158 -29.535985) (xy 64.126995 -29.589996) (xy 64.123159 -29.644008)
			(xy 64.111726 -29.696935) (xy 64.092927 -29.747715) (xy 64.067138 -29.795327) (xy 64.034878 -29.838816)
			(xy 63.996794 -29.877308) (xy 63.953652 -29.91003) (xy 63.906318 -29.936325) (xy 63.855741 -29.955665)
			(xy 63.829438 -29.962094) (xy 63.811912 -29.965904) (xy 63.789814 -29.99359) (xy 63.789814 -30.92069)
			(xy 73.489312 -30.92069) (xy 73.489312 -30.05709) (xy 73.489802 -30.027106) (xy 73.49763 -29.96765)
			(xy 73.513151 -29.909725) (xy 73.5361 -29.854321) (xy 73.566084 -29.802387) (xy 73.60259 -29.754811)
			(xy 73.644995 -29.712406) (xy 73.692571 -29.6759) (xy 73.744505 -29.645916) (xy 73.799909 -29.622967)
			(xy 73.857834 -29.607446) (xy 73.91729 -29.599618) (xy 73.977258 -29.599618) (xy 74.036714 -29.607446)
			(xy 74.094639 -29.622967) (xy 74.150043 -29.645916) (xy 74.201977 -29.6759) (xy 74.249553 -29.712406)
			(xy 74.291958 -29.754811) (xy 74.328464 -29.802387) (xy 74.358448 -29.854321) (xy 74.381397 -29.909725)
			(xy 74.396918 -29.96765) (xy 74.404746 -30.027106) (xy 74.405236 -30.05709) (xy 74.405236 -30.92069)
			(xy 74.404746 -30.950674) (xy 74.396918 -31.01013) (xy 74.381397 -31.068055) (xy 74.358448 -31.123459)
			(xy 74.328464 -31.175393) (xy 74.291958 -31.222969) (xy 74.249553 -31.265374) (xy 74.201977 -31.30188)
			(xy 74.150043 -31.331864) (xy 74.094639 -31.354813) (xy 74.036714 -31.370334) (xy 73.977258 -31.378162)
			(xy 73.91729 -31.378162) (xy 73.857834 -31.370334) (xy 73.799909 -31.354813) (xy 73.744505 -31.331864)
			(xy 73.692571 -31.30188) (xy 73.644995 -31.265374) (xy 73.60259 -31.222969) (xy 73.566084 -31.175393)
			(xy 73.5361 -31.123459) (xy 73.513151 -31.068055) (xy 73.49763 -31.01013) (xy 73.489802 -30.950674)
			(xy 73.489312 -30.92069) (xy 63.789814 -30.92069) (xy 63.789814 -31.232602) (xy 63.815214 -31.261304)
			(xy 63.834518 -31.26359) (xy 63.861925 -31.267417) (xy 63.915318 -31.281959) (xy 63.96605 -31.304063)
			(xy 64.013055 -31.333264) (xy 64.055349 -31.36895) (xy 64.092043 -31.410373) (xy 64.122367 -31.456662)
			(xy 64.145685 -31.506847) (xy 64.161507 -31.559875) (xy 64.169502 -31.614632) (xy 64.169502 -31.669969)
			(xy 64.161507 -31.724726) (xy 64.145684 -31.777754) (xy 64.122366 -31.827939) (xy 64.092042 -31.874228)
			(xy 64.055348 -31.91565) (xy 64.013055 -31.951337) (xy 63.966049 -31.980538) (xy 63.915317 -32.002641)
			(xy 63.861924 -32.017183) (xy 63.834518 -32.021018) (xy 63.815214 -32.023304) (xy 63.789814 -32.052006)
			(xy 63.789814 -32.714184) (xy 70.847204 -32.714184) (xy 70.847204 -31.850584) (xy 70.847694 -31.8206)
			(xy 70.855522 -31.761144) (xy 70.871043 -31.703219) (xy 70.893992 -31.647815) (xy 70.923976 -31.595881)
			(xy 70.960482 -31.548305) (xy 71.002887 -31.5059) (xy 71.050463 -31.469394) (xy 71.102397 -31.43941)
			(xy 71.157801 -31.416461) (xy 71.215726 -31.40094) (xy 71.275182 -31.393112) (xy 71.33515 -31.393112)
			(xy 71.394606 -31.40094) (xy 71.452531 -31.416461) (xy 71.507935 -31.43941) (xy 71.559869 -31.469394)
			(xy 71.607445 -31.5059) (xy 71.64985 -31.548305) (xy 71.686356 -31.595881) (xy 71.71634 -31.647815)
			(xy 71.739289 -31.703219) (xy 71.75481 -31.761144) (xy 71.762638 -31.8206) (xy 71.763128 -31.850584)
			(xy 71.763128 -32.714184) (xy 71.762638 -32.744168) (xy 71.75481 -32.803624) (xy 71.739289 -32.861549)
			(xy 71.71634 -32.916953) (xy 71.686356 -32.968887) (xy 71.64985 -33.016463) (xy 71.607445 -33.058868)
			(xy 71.559869 -33.095374) (xy 71.507935 -33.125358) (xy 71.452531 -33.148307) (xy 71.394606 -33.163828)
			(xy 71.33515 -33.171656) (xy 71.275182 -33.171656) (xy 71.215726 -33.163828) (xy 71.157801 -33.148307)
			(xy 71.102397 -33.125358) (xy 71.050463 -33.095374) (xy 71.002887 -33.058868) (xy 70.960482 -33.016463)
			(xy 70.923976 -32.968887) (xy 70.893992 -32.916953) (xy 70.871043 -32.861549) (xy 70.855522 -32.803624)
			(xy 70.847694 -32.744168) (xy 70.847204 -32.714184) (xy 63.789814 -32.714184) (xy 63.789814 -34.520886)
			(xy 73.489312 -34.520886) (xy 73.489312 -33.657286) (xy 73.489802 -33.627302) (xy 73.49763 -33.567846)
			(xy 73.513151 -33.509921) (xy 73.5361 -33.454517) (xy 73.566084 -33.402583) (xy 73.60259 -33.355007)
			(xy 73.644995 -33.312602) (xy 73.692571 -33.276096) (xy 73.744505 -33.246112) (xy 73.799909 -33.223163)
			(xy 73.857834 -33.207642) (xy 73.91729 -33.199814) (xy 73.977258 -33.199814) (xy 74.036714 -33.207642)
			(xy 74.094639 -33.223163) (xy 74.150043 -33.246112) (xy 74.201977 -33.276096) (xy 74.249553 -33.312602)
			(xy 74.291958 -33.355007) (xy 74.328464 -33.402583) (xy 74.358448 -33.454517) (xy 74.381397 -33.509921)
			(xy 74.396918 -33.567846) (xy 74.404746 -33.627302) (xy 74.405236 -33.657286) (xy 74.405236 -34.520886)
			(xy 74.404746 -34.55087) (xy 74.396918 -34.610326) (xy 74.381397 -34.668251) (xy 74.358448 -34.723655)
			(xy 74.328464 -34.775589) (xy 74.291958 -34.823165) (xy 74.249553 -34.86557) (xy 74.201977 -34.902076)
			(xy 74.150043 -34.93206) (xy 74.094639 -34.955009) (xy 74.036714 -34.97053) (xy 73.977258 -34.978358)
			(xy 73.91729 -34.978358) (xy 73.857834 -34.97053) (xy 73.799909 -34.955009) (xy 73.744505 -34.93206)
			(xy 73.692571 -34.902076) (xy 73.644995 -34.86557) (xy 73.60259 -34.823165) (xy 73.566084 -34.775589)
			(xy 73.5361 -34.723655) (xy 73.513151 -34.668251) (xy 73.49763 -34.610326) (xy 73.489802 -34.55087)
			(xy 73.489312 -34.520886) (xy 63.789814 -34.520886) (xy 63.789814 -36.60013) (xy 63.998355 -36.60013)
			(xy 64.002359 -36.512245) (xy 64.014339 -36.425088) (xy 64.034194 -36.339381) (xy 64.061761 -36.255836)
			(xy 64.096811 -36.175143) (xy 64.139053 -36.097971) (xy 64.188138 -36.024961) (xy 64.243659 -35.956717)
			(xy 64.305156 -35.893804) (xy 64.372118 -35.836744) (xy 64.443992 -35.78601) (xy 64.520182 -35.742022)
			(xy 64.600056 -35.705144) (xy 64.682953 -35.675683) (xy 64.768185 -35.653881) (xy 64.855047 -35.639921)
			(xy 64.942818 -35.633917) (xy 65.030772 -35.63592) (xy 65.118179 -35.645912) (xy 65.204315 -35.663812)
			(xy 65.288467 -35.68947) (xy 65.369937 -35.722674) (xy 65.44805 -35.763148) (xy 65.522158 -35.810559)
			(xy 65.591649 -35.864512) (xy 65.60474 -35.876738) (xy 70.717154 -35.876738) (xy 70.721225 -35.821116)
			(xy 70.733351 -35.766679) (xy 70.753274 -35.714588) (xy 70.78057 -35.665953) (xy 70.814656 -35.62181)
			(xy 70.854805 -35.583101) (xy 70.900163 -35.55065) (xy 70.949763 -35.525149) (xy 71.002547 -35.507142)
			(xy 71.05739 -35.497012) (xy 71.113124 -35.494975) (xy 71.168561 -35.501075) (xy 71.222518 -35.515181)
			(xy 71.273847 -35.536993) (xy 71.321453 -35.566047) (xy 71.364321 -35.601722) (xy 71.401538 -35.643259)
			(xy 71.432311 -35.689772) (xy 71.455983 -35.740269) (xy 71.472051 -35.793676) (xy 71.480171 -35.848852)
			(xy 71.48068 -35.876738) (xy 74.788774 -35.876738) (xy 74.792845 -35.821116) (xy 74.804971 -35.766679)
			(xy 74.824894 -35.714588) (xy 74.85219 -35.665953) (xy 74.886276 -35.62181) (xy 74.926425 -35.583101)
			(xy 74.971783 -35.55065) (xy 75.021383 -35.525149) (xy 75.074167 -35.507142) (xy 75.12901 -35.497012)
			(xy 75.184744 -35.494975) (xy 75.240181 -35.501075) (xy 75.294138 -35.515181) (xy 75.345467 -35.536993)
			(xy 75.393073 -35.566047) (xy 75.435941 -35.601722) (xy 75.473158 -35.643259) (xy 75.503931 -35.689772)
			(xy 75.527603 -35.740269) (xy 75.543671 -35.793676) (xy 75.551791 -35.848852) (xy 75.5523 -35.876738)
			(xy 75.551791 -35.904624) (xy 75.543671 -35.9598) (xy 75.527603 -36.013207) (xy 75.503931 -36.063704)
			(xy 75.473158 -36.110217) (xy 75.435941 -36.151754) (xy 75.393073 -36.187429) (xy 75.345467 -36.216483)
			(xy 75.294138 -36.238295) (xy 75.240181 -36.252401) (xy 75.184744 -36.258501) (xy 75.12901 -36.256464)
			(xy 75.074167 -36.246334) (xy 75.021383 -36.228327) (xy 74.971783 -36.202826) (xy 74.926425 -36.170375)
			(xy 74.886276 -36.131666) (xy 74.85219 -36.087523) (xy 74.824894 -36.038888) (xy 74.804971 -35.986797)
			(xy 74.792845 -35.93236) (xy 74.788774 -35.876738) (xy 71.48068 -35.876738) (xy 71.480171 -35.904624)
			(xy 71.472051 -35.9598) (xy 71.455983 -36.013207) (xy 71.432311 -36.063704) (xy 71.401538 -36.110217)
			(xy 71.364321 -36.151754) (xy 71.321453 -36.187429) (xy 71.273847 -36.216483) (xy 71.222518 -36.238295)
			(xy 71.168561 -36.252401) (xy 71.113124 -36.258501) (xy 71.05739 -36.256464) (xy 71.002547 -36.246334)
			(xy 70.949763 -36.228327) (xy 70.900163 -36.202826) (xy 70.854805 -36.170375) (xy 70.814656 -36.131666)
			(xy 70.78057 -36.087523) (xy 70.753274 -36.038888) (xy 70.733351 -35.986797) (xy 70.721225 -35.93236)
			(xy 70.717154 -35.876738) (xy 65.60474 -35.876738) (xy 65.655945 -35.92456) (xy 65.714514 -35.990207)
			(xy 65.766871 -36.060907) (xy 65.812583 -36.136076) (xy 65.851269 -36.21509) (xy 65.88261 -36.297295)
			(xy 65.906345 -36.382009) (xy 65.922279 -36.46853) (xy 65.926062 -36.50996) (xy 72.613772 -36.50996)
			(xy 72.617843 -36.454338) (xy 72.629969 -36.399901) (xy 72.649892 -36.34781) (xy 72.677188 -36.299175)
			(xy 72.711274 -36.255032) (xy 72.751423 -36.216323) (xy 72.796781 -36.183872) (xy 72.846381 -36.158371)
			(xy 72.899165 -36.140364) (xy 72.954008 -36.130234) (xy 73.009742 -36.128197) (xy 73.065179 -36.134297)
			(xy 73.119136 -36.148403) (xy 73.170465 -36.170215) (xy 73.218071 -36.199269) (xy 73.260939 -36.234944)
			(xy 73.298156 -36.276481) (xy 73.328929 -36.322994) (xy 73.352601 -36.373491) (xy 73.368669 -36.426898)
			(xy 73.372594 -36.453572) (xy 75.928472 -36.453572) (xy 75.932543 -36.39795) (xy 75.944669 -36.343513)
			(xy 75.964592 -36.291422) (xy 75.991888 -36.242787) (xy 76.025974 -36.198644) (xy 76.066123 -36.159935)
			(xy 76.111481 -36.127484) (xy 76.161081 -36.101983) (xy 76.213865 -36.083976) (xy 76.268708 -36.073846)
			(xy 76.324442 -36.071809) (xy 76.379879 -36.077909) (xy 76.433836 -36.092015) (xy 76.485165 -36.113827)
			(xy 76.532771 -36.142881) (xy 76.575639 -36.178556) (xy 76.612856 -36.220093) (xy 76.643629 -36.266606)
			(xy 76.667301 -36.317103) (xy 76.683369 -36.37051) (xy 76.691489 -36.425686) (xy 76.691998 -36.453572)
			(xy 76.691489 -36.481458) (xy 76.683369 -36.536634) (xy 76.667301 -36.590041) (xy 76.643629 -36.640538)
			(xy 76.612856 -36.687051) (xy 76.575639 -36.728588) (xy 76.532771 -36.764263) (xy 76.485165 -36.793317)
			(xy 76.433836 -36.815129) (xy 76.379879 -36.829235) (xy 76.324442 -36.835335) (xy 76.268708 -36.833298)
			(xy 76.213865 -36.823168) (xy 76.161081 -36.805161) (xy 76.111481 -36.77966) (xy 76.066123 -36.747209)
			(xy 76.025974 -36.7085) (xy 75.991888 -36.664357) (xy 75.964592 -36.615722) (xy 75.944669 -36.563631)
			(xy 75.932543 -36.509194) (xy 75.928472 -36.453572) (xy 73.372594 -36.453572) (xy 73.376789 -36.482074)
			(xy 73.377298 -36.50996) (xy 73.376789 -36.537846) (xy 73.368669 -36.593022) (xy 73.352601 -36.646429)
			(xy 73.328929 -36.696926) (xy 73.298156 -36.743439) (xy 73.260939 -36.784976) (xy 73.218071 -36.820651)
			(xy 73.170465 -36.849705) (xy 73.119136 -36.871517) (xy 73.065179 -36.885623) (xy 73.009742 -36.891723)
			(xy 72.954008 -36.889686) (xy 72.899165 -36.879556) (xy 72.846381 -36.861549) (xy 72.796781 -36.836048)
			(xy 72.751423 -36.803597) (xy 72.711274 -36.764888) (xy 72.677188 -36.720745) (xy 72.649892 -36.67211)
			(xy 72.629969 -36.620019) (xy 72.617843 -36.565582) (xy 72.613772 -36.50996) (xy 65.926062 -36.50996)
			(xy 65.930279 -36.556142) (xy 65.93078 -36.60013) (xy 65.930279 -36.644118) (xy 65.922279 -36.73173)
			(xy 65.906345 -36.818251) (xy 65.88261 -36.902965) (xy 65.851269 -36.98517) (xy 65.812583 -37.064184)
			(xy 65.766871 -37.139353) (xy 65.714514 -37.210053) (xy 65.655945 -37.2757) (xy 65.591649 -37.335748)
			(xy 65.522158 -37.389701) (xy 65.44805 -37.437112) (xy 65.369937 -37.477586) (xy 65.288467 -37.51079)
			(xy 65.204315 -37.536448) (xy 65.118179 -37.554348) (xy 65.030772 -37.56434) (xy 64.942818 -37.566343)
			(xy 64.855047 -37.560339) (xy 64.768185 -37.546379) (xy 64.682953 -37.524577) (xy 64.600056 -37.495116)
			(xy 64.520182 -37.458238) (xy 64.443992 -37.41425) (xy 64.372118 -37.363516) (xy 64.305156 -37.306456)
			(xy 64.243659 -37.243543) (xy 64.188138 -37.175299) (xy 64.139053 -37.102289) (xy 64.096811 -37.025117)
			(xy 64.061761 -36.944424) (xy 64.034194 -36.860879) (xy 64.014339 -36.775172) (xy 64.002359 -36.688015)
			(xy 63.998355 -36.60013) (xy 63.789814 -36.60013) (xy 63.789814 -39.97198) (xy 77.895702 -39.97198)
			(xy 77.899773 -39.916358) (xy 77.911899 -39.861921) (xy 77.931822 -39.80983) (xy 77.959118 -39.761195)
			(xy 77.993204 -39.717052) (xy 78.033353 -39.678343) (xy 78.078711 -39.645892) (xy 78.128311 -39.620391)
			(xy 78.181095 -39.602384) (xy 78.235938 -39.592254) (xy 78.291672 -39.590217) (xy 78.347109 -39.596317)
			(xy 78.401066 -39.610423) (xy 78.452395 -39.632235) (xy 78.500001 -39.661289) (xy 78.542869 -39.696964)
			(xy 78.580086 -39.738501) (xy 78.610859 -39.785014) (xy 78.634531 -39.835511) (xy 78.650599 -39.888918)
			(xy 78.658719 -39.944094) (xy 78.659228 -39.97198) (xy 78.658719 -39.999866) (xy 78.650599 -40.055042)
			(xy 78.634531 -40.108449) (xy 78.610859 -40.158946) (xy 78.580086 -40.205459) (xy 78.542869 -40.246996)
			(xy 78.500001 -40.282671) (xy 78.452395 -40.311725) (xy 78.401066 -40.333537) (xy 78.347109 -40.347643)
			(xy 78.291672 -40.353743) (xy 78.235938 -40.351706) (xy 78.181095 -40.341576) (xy 78.128311 -40.323569)
			(xy 78.078711 -40.298068) (xy 78.033353 -40.265617) (xy 77.993204 -40.226908) (xy 77.959118 -40.182765)
			(xy 77.931822 -40.13413) (xy 77.911899 -40.082039) (xy 77.899773 -40.027602) (xy 77.895702 -39.97198)
			(xy 63.789814 -39.97198) (xy 63.789814 -40.452802) (xy 63.790238 -40.462872) (xy 63.797954 -40.481474)
			(xy 63.8048 -40.48887) (xy 64.024002 -40.708072) (xy 64.031399 -40.714921) (xy 64.049998 -40.722659)
			(xy 64.06007 -40.723058) (xy 73.081388 -40.723058) (xy 73.091458 -40.72348) (xy 73.11006 -40.731198)
			(xy 73.117456 -40.738044) (xy 74.058526 -41.679114) (xy 74.065378 -41.68651) (xy 74.073119 -41.705109)
			(xy 74.073512 -41.715182) (xy 74.073512 -43.85691) (xy 76.719682 -43.85691) (xy 76.723753 -43.801288)
			(xy 76.735879 -43.746851) (xy 76.755802 -43.69476) (xy 76.783098 -43.646125) (xy 76.817184 -43.601982)
			(xy 76.857333 -43.563273) (xy 76.902691 -43.530822) (xy 76.952291 -43.505321) (xy 77.005075 -43.487314)
			(xy 77.059918 -43.477184) (xy 77.115652 -43.475147) (xy 77.171089 -43.481247) (xy 77.225046 -43.495353)
			(xy 77.276375 -43.517165) (xy 77.323981 -43.546219) (xy 77.366849 -43.581894) (xy 77.404066 -43.623431)
			(xy 77.434839 -43.669944) (xy 77.458511 -43.720441) (xy 77.474579 -43.773848) (xy 77.482699 -43.829024)
			(xy 77.483208 -43.85691) (xy 77.482699 -43.884796) (xy 77.474579 -43.939972) (xy 77.458511 -43.993379)
			(xy 77.434839 -44.043876) (xy 77.404066 -44.090389) (xy 77.366849 -44.131926) (xy 77.323981 -44.167601)
			(xy 77.276375 -44.196655) (xy 77.225046 -44.218467) (xy 77.171089 -44.232573) (xy 77.115652 -44.238673)
			(xy 77.059918 -44.236636) (xy 77.005075 -44.226506) (xy 76.952291 -44.208499) (xy 76.902691 -44.182998)
			(xy 76.857333 -44.150547) (xy 76.817184 -44.111838) (xy 76.783098 -44.067695) (xy 76.755802 -44.01906)
			(xy 76.735879 -43.966969) (xy 76.723753 -43.912532) (xy 76.719682 -43.85691) (xy 74.073512 -43.85691)
			(xy 74.073512 -45.35424) (xy 76.70368 -45.35424) (xy 76.707751 -45.298618) (xy 76.719877 -45.244181)
			(xy 76.7398 -45.19209) (xy 76.767096 -45.143455) (xy 76.801182 -45.099312) (xy 76.841331 -45.060603)
			(xy 76.886689 -45.028152) (xy 76.936289 -45.002651) (xy 76.989073 -44.984644) (xy 77.043916 -44.974514)
			(xy 77.09965 -44.972477) (xy 77.155087 -44.978577) (xy 77.209044 -44.992683) (xy 77.260373 -45.014495)
			(xy 77.307979 -45.043549) (xy 77.350847 -45.079224) (xy 77.388064 -45.120761) (xy 77.418837 -45.167274)
			(xy 77.442509 -45.217771) (xy 77.458577 -45.271178) (xy 77.466697 -45.326354) (xy 77.467206 -45.35424)
			(xy 77.466697 -45.382126) (xy 77.458577 -45.437302) (xy 77.442509 -45.490709) (xy 77.418837 -45.541206)
			(xy 77.388064 -45.587719) (xy 77.350847 -45.629256) (xy 77.307979 -45.664931) (xy 77.260373 -45.693985)
			(xy 77.209044 -45.715797) (xy 77.155087 -45.729903) (xy 77.09965 -45.736003) (xy 77.043916 -45.733966)
			(xy 76.989073 -45.723836) (xy 76.936289 -45.705829) (xy 76.886689 -45.680328) (xy 76.841331 -45.647877)
			(xy 76.801182 -45.609168) (xy 76.767096 -45.565025) (xy 76.7398 -45.51639) (xy 76.719877 -45.464299)
			(xy 76.707751 -45.409862) (xy 76.70368 -45.35424) (xy 74.073512 -45.35424) (xy 74.073512 -46.693836)
			(xy 76.67625 -46.693836) (xy 76.676736 -46.666585) (xy 76.684492 -46.612637) (xy 76.699847 -46.560342)
			(xy 76.722489 -46.510765) (xy 76.751955 -46.464915) (xy 76.787646 -46.423724) (xy 76.828837 -46.388033)
			(xy 76.874687 -46.358567) (xy 76.924264 -46.335925) (xy 76.976559 -46.32057) (xy 77.030507 -46.312814)
			(xy 77.085009 -46.312814) (xy 77.138957 -46.32057) (xy 77.191252 -46.335925) (xy 77.240829 -46.358567)
			(xy 77.286679 -46.388033) (xy 77.32787 -46.423724) (xy 77.363561 -46.464915) (xy 77.393027 -46.510765)
			(xy 77.415669 -46.560342) (xy 77.431024 -46.612637) (xy 77.43878 -46.666585) (xy 77.439266 -46.693836)
			(xy 77.438798 -46.720264) (xy 77.431488 -46.772611) (xy 77.417013 -46.823446) (xy 77.395652 -46.871793)
			(xy 77.382116 -46.894496) (xy 77.37602 -46.904402) (xy 77.37348 -46.927262) (xy 77.40777 -47.023782)
			(xy 77.423772 -47.040038) (xy 77.434948 -47.043848) (xy 77.459457 -47.052916) (xy 77.50591 -47.076859)
			(xy 77.548661 -47.106915) (xy 77.586913 -47.142523) (xy 77.61995 -47.183016) (xy 77.647153 -47.227637)
			(xy 77.668015 -47.275552) (xy 77.682145 -47.325866) (xy 77.689279 -47.377636) (xy 77.68971 -47.403766)
			(xy 77.689224 -47.431017) (xy 77.681468 -47.484965) (xy 77.666113 -47.53726) (xy 77.643471 -47.586837)
			(xy 77.614005 -47.632687) (xy 77.578314 -47.673878) (xy 77.537123 -47.709569) (xy 77.491273 -47.739035)
			(xy 77.441696 -47.761677) (xy 77.389401 -47.777032) (xy 77.335453 -47.784788) (xy 77.280951 -47.784788)
			(xy 77.227003 -47.777032) (xy 77.174708 -47.761677) (xy 77.125131 -47.739035) (xy 77.079281 -47.709569)
			(xy 77.03809 -47.673878) (xy 77.002399 -47.632687) (xy 76.972933 -47.586837) (xy 76.950291 -47.53726)
			(xy 76.934936 -47.484965) (xy 76.92718 -47.431017) (xy 76.926694 -47.403766) (xy 76.927168 -47.377339)
			(xy 76.934477 -47.324991) (xy 76.94895 -47.274156) (xy 76.970309 -47.225809) (xy 76.983844 -47.203106)
			(xy 76.98994 -47.1932) (xy 76.99248 -47.17034) (xy 76.95819 -47.07382) (xy 76.942188 -47.057564)
			(xy 76.931012 -47.053754) (xy 76.906495 -47.044706) (xy 76.860044 -47.020759) (xy 76.817293 -46.990699)
			(xy 76.779042 -46.955089) (xy 76.746007 -46.914593) (xy 76.718805 -46.86997) (xy 76.697944 -46.822053)
			(xy 76.683815 -46.771738) (xy 76.676681 -46.719966) (xy 76.67625 -46.693836) (xy 74.073512 -46.693836)
			(xy 74.073512 -48.919754) (xy 75.214938 -48.919754) (xy 75.214938 -48.865246) (xy 75.222695 -48.811294)
			(xy 75.238051 -48.758995) (xy 75.260694 -48.709413) (xy 75.290162 -48.663559) (xy 75.325856 -48.622364)
			(xy 75.367049 -48.586669) (xy 75.412903 -48.557199) (xy 75.462484 -48.534555) (xy 75.514782 -48.519197)
			(xy 75.568734 -48.511439) (xy 75.595988 -48.510952) (xy 75.622735 -48.511351) (xy 75.675703 -48.518842)
			(xy 75.727107 -48.533652) (xy 75.775942 -48.55549) (xy 75.821251 -48.58393) (xy 75.862148 -48.618414)
			(xy 75.897832 -48.658268) (xy 75.927606 -48.702711) (xy 75.93965 -48.726598) (xy 75.945238 -48.738536)
			(xy 75.96632 -48.753522) (xy 76.077826 -48.766476) (xy 76.101702 -48.75657) (xy 76.110084 -48.74641)
			(xy 76.128305 -48.724697) (xy 76.170056 -48.686361) (xy 76.21702 -48.654627) (xy 76.268163 -48.630191)
			(xy 76.32236 -48.613594) (xy 76.378416 -48.605199) (xy 76.406756 -48.604678) (xy 76.424966 -48.604869)
			(xy 76.461224 -48.608301) (xy 76.479146 -48.611536) (xy 76.493116 -48.61433) (xy 76.52004 -48.60417)
			(xy 76.593192 -48.51019) (xy 76.596494 -48.481742) (xy 76.590398 -48.468788) (xy 76.579001 -48.443355)
			(xy 76.562925 -48.389993) (xy 76.554809 -48.334856) (xy 76.55433 -48.30699) (xy 76.554789 -48.27974)
			(xy 76.562546 -48.225796) (xy 76.577901 -48.173504) (xy 76.600542 -48.12393) (xy 76.630007 -48.078082)
			(xy 76.665697 -48.036894) (xy 76.706885 -48.001205) (xy 76.752733 -47.97174) (xy 76.802308 -47.9491)
			(xy 76.8546 -47.933745) (xy 76.908544 -47.925989) (xy 76.963044 -47.925988) (xy 77.016989 -47.933743)
			(xy 77.069281 -47.949096) (xy 77.118856 -47.971734) (xy 77.164705 -48.001198) (xy 77.205894 -48.036886)
			(xy 77.241585 -48.078073) (xy 77.271052 -48.123919) (xy 77.293694 -48.173493) (xy 77.309051 -48.225784)
			(xy 77.31681 -48.279728) (xy 77.316813 -48.334228) (xy 77.309061 -48.388173) (xy 77.29371 -48.440466)
			(xy 77.271073 -48.490042) (xy 77.241612 -48.535892) (xy 77.205925 -48.577083) (xy 77.16474 -48.612776)
			(xy 77.118895 -48.642244) (xy 77.069322 -48.664889) (xy 77.017032 -48.680248) (xy 76.963088 -48.688009)
			(xy 76.935838 -48.688498) (xy 76.917628 -48.688308) (xy 76.88137 -48.684875) (xy 76.863448 -48.68164)
			(xy 76.849478 -48.678846) (xy 76.822554 -48.689006) (xy 76.749402 -48.782986) (xy 76.7461 -48.811434)
			(xy 76.752196 -48.824388) (xy 76.763585 -48.849824) (xy 76.779663 -48.903185) (xy 76.787783 -48.958321)
			(xy 76.788264 -48.986186) (xy 76.787832 -49.013441) (xy 76.780075 -49.067395) (xy 76.764719 -49.119696)
			(xy 76.742075 -49.169279) (xy 76.712604 -49.215134) (xy 76.676907 -49.256328) (xy 76.63571 -49.292022)
			(xy 76.589853 -49.321489) (xy 76.540268 -49.344129) (xy 76.487965 -49.359482) (xy 76.434011 -49.367234)
			(xy 76.406756 -49.367694) (xy 76.380011 -49.367232) (xy 76.327047 -49.359748) (xy 76.275646 -49.344946)
			(xy 76.226813 -49.323116) (xy 76.181504 -49.294686) (xy 76.140606 -49.26021) (xy 76.104919 -49.220365)
			(xy 76.075141 -49.17593) (xy 76.063094 -49.152048) (xy 76.057506 -49.14011) (xy 76.036424 -49.125124)
			(xy 75.924918 -49.11217) (xy 75.901042 -49.122076) (xy 75.89266 -49.132236) (xy 75.874426 -49.153937)
			(xy 75.832677 -49.192272) (xy 75.785715 -49.224007) (xy 75.734574 -49.248443) (xy 75.680381 -49.265044)
			(xy 75.624327 -49.273444) (xy 75.595988 -49.273968) (xy 75.568734 -49.273561) (xy 75.514782 -49.265803)
			(xy 75.462484 -49.250445) (xy 75.412903 -49.227801) (xy 75.367049 -49.198331) (xy 75.325856 -49.162636)
			(xy 75.290162 -49.121441) (xy 75.260694 -49.075587) (xy 75.238051 -49.026005) (xy 75.222695 -48.973706)
			(xy 75.214938 -48.919754) (xy 74.073512 -48.919754) (xy 74.073512 -51.191922) (xy 74.073512 -51.19497)
			(xy 74.07402 -51.20132) (xy 74.07493 -51.210557) (xy 74.082485 -51.227494) (xy 74.088752 -51.23434)
			(xy 74.23277 -51.378358) (xy 74.24017 -51.385198) (xy 74.258769 -51.392914) (xy 74.268838 -51.393344)
		)
		(stroke
			(width 0)
			(type solid)
		)
		(fill yes)
		(layer "In9.Cu")
		(net "GND")
	)
	(gr_poly
		(pts
			(xy 399.03273 -51.393344) (xy 399.041958 -51.392939) (xy 399.059209 -51.386384) (xy 399.073015 -51.374135)
			(xy 399.077688 -51.366166) (xy 399.119344 -51.286664) (xy 399.12325 -51.278382) (xy 399.125526 -51.260225)
			(xy 399.121309 -51.242418) (xy 399.11655 -51.234594) (xy 399.116296 -51.23434) (xy 399.100801 -51.210699)
			(xy 399.076201 -51.15981) (xy 399.059371 -51.105851) (xy 399.050681 -51.05) (xy 399.050002 -51.021742)
			(xy 399.050002 -51.01463) (xy 399.050814 -50.987604) (xy 399.059124 -50.934177) (xy 399.074893 -50.882459)
			(xy 399.097805 -50.833486) (xy 399.127402 -50.788237) (xy 399.163091 -50.74762) (xy 399.204156 -50.712448)
			(xy 399.249775 -50.683426) (xy 399.299035 -50.661135) (xy 399.350949 -50.646021) (xy 399.404476 -50.638388)
			(xy 399.458544 -50.638388) (xy 399.512071 -50.646021) (xy 399.563985 -50.661135) (xy 399.613245 -50.683426)
			(xy 399.658864 -50.712448) (xy 399.699929 -50.74762) (xy 399.735618 -50.788237) (xy 399.765215 -50.833486)
			(xy 399.788127 -50.882459) (xy 399.803896 -50.934177) (xy 399.812206 -50.987604) (xy 399.813018 -51.01463)
			(xy 399.813018 -51.01971) (xy 399.81251 -51.048258) (xy 399.803995 -51.104717) (xy 399.787158 -51.159275)
			(xy 399.762375 -51.210712) (xy 399.746724 -51.234594) (xy 399.738596 -51.246278) (xy 399.737072 -51.274218)
			(xy 399.785332 -51.366166) (xy 399.789981 -51.374147) (xy 399.803804 -51.386376) (xy 399.821062 -51.392916)
			(xy 399.83029 -51.393344) (xy 400.722338 -51.393344) (xy 400.732303 -51.392864) (xy 400.750739 -51.385288)
			(xy 400.758152 -51.378612) (xy 401.276312 -50.860452) (xy 401.280122 -50.852578) (xy 401.290028 -50.833528)
			(xy 401.290282 -50.833274) (xy 401.294092 -50.82667) (xy 401.297394 -50.821082) (xy 401.301458 -50.806858)
			(xy 401.30476 -50.795174) (xy 401.30476 -50.1904) (xy 401.304505 -50.182988) (xy 401.300246 -50.168788)
			(xy 401.296378 -50.16246) (xy 401.281546 -50.139007) (xy 401.258088 -50.088717) (xy 401.242169 -50.035559)
			(xy 401.234124 -49.980654) (xy 401.234123 -49.925163) (xy 401.242165 -49.870258) (xy 401.258082 -49.817098)
			(xy 401.281537 -49.766808) (xy 401.296378 -49.74336) (xy 401.300242 -49.73703) (xy 401.304498 -49.722831)
			(xy 401.30476 -49.71542) (xy 401.30476 -49.1744) (xy 401.304505 -49.166988) (xy 401.300246 -49.152788)
			(xy 401.296378 -49.14646) (xy 401.281546 -49.123007) (xy 401.258088 -49.072717) (xy 401.242169 -49.019559)
			(xy 401.234124 -48.964654) (xy 401.234123 -48.909163) (xy 401.242165 -48.854258) (xy 401.258082 -48.801098)
			(xy 401.281537 -48.750808) (xy 401.296378 -48.72736) (xy 401.300242 -48.72103) (xy 401.304498 -48.706831)
			(xy 401.30476 -48.69942) (xy 401.30476 -47.629572) (xy 401.30222 -47.61865) (xy 401.299426 -47.613062)
			(xy 401.286701 -47.586292) (xy 401.268726 -47.529814) (xy 401.259629 -47.471246) (xy 401.259627 -47.411976)
			(xy 401.268721 -47.353407) (xy 401.286693 -47.296928) (xy 401.299426 -47.270162) (xy 401.30222 -47.264574)
			(xy 401.30476 -47.253652) (xy 401.30476 -46.1264) (xy 401.304505 -46.118988) (xy 401.300246 -46.104788)
			(xy 401.296378 -46.09846) (xy 401.281546 -46.075007) (xy 401.258088 -46.024717) (xy 401.242169 -45.971559)
			(xy 401.234124 -45.916654) (xy 401.234123 -45.861163) (xy 401.242165 -45.806258) (xy 401.258082 -45.753098)
			(xy 401.281537 -45.702808) (xy 401.296378 -45.67936) (xy 401.300242 -45.67303) (xy 401.304498 -45.658831)
			(xy 401.30476 -45.65142) (xy 401.30476 -45.1104) (xy 401.304505 -45.102988) (xy 401.300246 -45.088788)
			(xy 401.296378 -45.08246) (xy 401.281546 -45.059007) (xy 401.258088 -45.008717) (xy 401.242169 -44.955559)
			(xy 401.234124 -44.900654) (xy 401.234123 -44.845163) (xy 401.242165 -44.790258) (xy 401.258082 -44.737098)
			(xy 401.281537 -44.686808) (xy 401.296378 -44.66336) (xy 401.300242 -44.65703) (xy 401.304498 -44.642831)
			(xy 401.30476 -44.63542) (xy 401.30476 -44.0944) (xy 401.304505 -44.086988) (xy 401.300246 -44.072788)
			(xy 401.296378 -44.06646) (xy 401.281546 -44.043007) (xy 401.258088 -43.992717) (xy 401.242169 -43.939559)
			(xy 401.234124 -43.884654) (xy 401.234123 -43.829163) (xy 401.242165 -43.774258) (xy 401.258082 -43.721098)
			(xy 401.281537 -43.670808) (xy 401.296378 -43.64736) (xy 401.300242 -43.64103) (xy 401.304498 -43.626831)
			(xy 401.30476 -43.61942) (xy 401.30476 -43.0784) (xy 401.304505 -43.070988) (xy 401.300246 -43.056788)
			(xy 401.296378 -43.05046) (xy 401.281546 -43.027007) (xy 401.258088 -42.976717) (xy 401.242169 -42.923559)
			(xy 401.234124 -42.868654) (xy 401.234123 -42.813163) (xy 401.242165 -42.758258) (xy 401.258082 -42.705098)
			(xy 401.281537 -42.654808) (xy 401.296378 -42.63136) (xy 401.300242 -42.62503) (xy 401.304498 -42.610831)
			(xy 401.30476 -42.60342) (xy 401.30476 -41.423844) (xy 401.304374 -41.414078) (xy 401.297198 -41.395916)
			(xy 401.29079 -41.388538) (xy 401.269962 -41.366948) (xy 401.26158 -41.362884) (xy 401.238212 -41.351454)
			(xy 401.22983 -41.350438) (xy 401.202433 -41.346595) (xy 401.149065 -41.332027) (xy 401.09836 -41.309904)
			(xy 401.051381 -41.28069) (xy 401.009114 -41.244998) (xy 400.972444 -41.203576) (xy 400.942141 -41.157293)
			(xy 400.918839 -41.107118) (xy 400.903028 -41.054105) (xy 400.895038 -40.999363) (xy 400.895038 -40.944042)
			(xy 400.903027 -40.889301) (xy 400.918837 -40.836287) (xy 400.942138 -40.786112) (xy 400.972441 -40.739829)
			(xy 401.00911 -40.698406) (xy 401.051376 -40.662714) (xy 401.098355 -40.633499) (xy 401.149059 -40.611375)
			(xy 401.202428 -40.596806) (xy 401.22983 -40.59301) (xy 401.238212 -40.591994) (xy 401.261834 -40.580564)
			(xy 401.265858 -40.578494) (xy 401.273138 -40.573122) (xy 401.276312 -40.569896) (xy 401.29079 -40.55491)
			(xy 401.297208 -40.547535) (xy 401.3044 -40.529374) (xy 401.30476 -40.519604) (xy 401.30476 -38.432232)
			(xy 401.304345 -38.422209) (xy 401.29668 -38.403688) (xy 401.282505 -38.389516) (xy 401.263983 -38.381853)
			(xy 401.25396 -38.381432) (xy 399.584164 -38.381432) (xy 399.57503 -38.38182) (xy 399.557929 -38.388245)
			(xy 399.544171 -38.400264) (xy 399.53946 -38.408102) (xy 399.497296 -38.486842) (xy 399.494281 -38.492876)
			(xy 399.491199 -38.506004) (xy 399.4912 -38.51275) (xy 399.491708 -38.527228) (xy 399.499582 -38.539166)
			(xy 399.514713 -38.562786) (xy 399.538634 -38.613523) (xy 399.554876 -38.667213) (xy 399.563089 -38.722702)
			(xy 399.56359 -38.750748) (xy 399.5631 -38.777997) (xy 399.555338 -38.831938) (xy 399.539979 -38.884226)
			(xy 399.517335 -38.933796) (xy 399.487867 -38.979639) (xy 399.452175 -39.020822) (xy 399.410986 -39.056507)
			(xy 399.365138 -39.085966) (xy 399.315564 -39.108602) (xy 399.263273 -39.123952) (xy 399.209331 -39.131705)
			(xy 399.182082 -39.132256) (xy 399.15378 -39.13174) (xy 399.097798 -39.123378) (xy 399.043665 -39.106838)
			(xy 398.992568 -39.082485) (xy 398.945629 -39.050852) (xy 398.903876 -39.012633) (xy 398.868226 -38.968667)
			(xy 398.853406 -38.94455) (xy 398.846802 -38.933374) (xy 398.825212 -38.920166) (xy 398.78 -38.917626)
			(xy 398.715738 -38.913816) (xy 398.692878 -38.92423) (xy 398.685258 -38.93439) (xy 398.66707 -38.957268)
			(xy 398.624916 -38.997749) (xy 398.577084 -39.03133) (xy 398.524692 -39.057227) (xy 398.468964 -39.074834)
			(xy 398.411204 -39.083741) (xy 398.381982 -39.08425) (xy 398.354731 -39.083763) (xy 398.300782 -39.076005)
			(xy 398.248487 -39.060648) (xy 398.19891 -39.038007) (xy 398.153059 -39.008541) (xy 398.111867 -38.97285)
			(xy 398.076174 -38.931661) (xy 398.046705 -38.885811) (xy 398.02406 -38.836235) (xy 398.0087 -38.783941)
			(xy 398.000939 -38.729993) (xy 398.000474 -38.702742) (xy 398.001033 -38.672656) (xy 398.010478 -38.613231)
			(xy 398.029154 -38.556032) (xy 398.042384 -38.529006) (xy 398.04848 -38.517068) (xy 398.047464 -38.490906)
			(xy 397.99514 -38.405562) (xy 397.990308 -38.3984) (xy 397.976866 -38.387561) (xy 397.960592 -38.381788)
			(xy 397.95196 -38.381432) (xy 395.585188 -38.381432) (xy 395.576333 -38.38186) (xy 395.559705 -38.387968)
			(xy 395.552676 -38.39337) (xy 395.341094 -38.604952) (xy 395.263624 -38.682168) (xy 395.239724 -38.705334)
			(xy 395.18692 -38.745856) (xy 395.129276 -38.779136) (xy 395.067781 -38.804605) (xy 395.003487 -38.821826)
			(xy 394.937494 -38.830506) (xy 394.904214 -38.831012) (xy 393.288774 -38.831012) (xy 393.255497 -38.830467)
			(xy 393.189511 -38.821779) (xy 393.125223 -38.804555) (xy 393.063733 -38.779089) (xy 393.006091 -38.745818)
			(xy 392.953284 -38.70531) (xy 392.929364 -38.682168) (xy 392.081766 -37.83457) (xy 392.058231 -37.81028)
			(xy 392.017133 -37.756566) (xy 391.983513 -37.697881) (xy 391.957966 -37.635258) (xy 391.948924 -37.602668)
			(xy 391.941322 -37.57134) (xy 391.933164 -37.507393) (xy 391.932668 -37.47516) (xy 391.933132 -37.444469)
			(xy 391.940526 -37.383534) (xy 391.955201 -37.323932) (xy 391.976943 -37.26653) (xy 392.005438 -37.212163)
			(xy 392.040269 -37.161621) (xy 392.080931 -37.115639) (xy 392.126833 -37.074887) (xy 392.177307 -37.039956)
			(xy 392.231618 -37.011354) (xy 392.288977 -36.989499) (xy 392.34855 -36.974707) (xy 392.40947 -36.967193)
			(xy 392.44016 -36.966652) (xy 392.441176 -36.966652) (xy 392.473409 -36.96715) (xy 392.537356 -36.975306)
			(xy 392.568684 -36.982908) (xy 392.601278 -36.991943) (xy 392.66391 -37.017473) (xy 392.7226 -37.05109)
			(xy 392.776309 -37.0922) (xy 392.800586 -37.11575) (xy 393.484354 -37.799518) (xy 393.491751 -37.806365)
			(xy 393.510351 -37.814093) (xy 393.520422 -37.814504) (xy 394.149834 -37.814504) (xy 394.160581 -37.814022)
			(xy 394.180182 -37.805201) (xy 394.18768 -37.797486) (xy 394.238226 -37.741352) (xy 394.244798 -37.733236)
			(xy 394.251361 -37.713432) (xy 394.250926 -37.702998) (xy 394.250926 -37.702236) (xy 394.24996 -37.692295)
			(xy 394.248944 -37.672346) (xy 394.248894 -37.662358) (xy 394.249383 -37.635109) (xy 394.257144 -37.581166)
			(xy 394.272503 -37.528876) (xy 394.295146 -37.479304) (xy 394.324614 -37.433459) (xy 394.360305 -37.392274)
			(xy 394.401495 -37.356587) (xy 394.447343 -37.327125) (xy 394.496917 -37.304487) (xy 394.549209 -37.289135)
			(xy 394.603153 -37.28138) (xy 394.630402 -37.28085) (xy 394.659454 -37.281394) (xy 394.716888 -37.290202)
			(xy 394.772323 -37.307615) (xy 394.824477 -37.333229) (xy 394.872146 -37.366452) (xy 394.914229 -37.406518)
			(xy 394.932408 -37.429186) (xy 394.938504 -37.43706) (xy 394.946886 -37.44214) (xy 394.951046 -37.444435)
			(xy 394.959994 -37.447627) (xy 394.964666 -37.44849) (xy 395.032992 -37.459666) (xy 395.042565 -37.460795)
			(xy 395.061364 -37.456602) (xy 395.069568 -37.451538) (xy 395.069822 -37.451284) (xy 395.097508 -37.433232)
			(xy 395.156626 -37.403678) (xy 395.187678 -37.392356) (xy 395.214509 -37.383494) (xy 395.269634 -37.371069)
			(xy 395.325794 -37.364815) (xy 395.354048 -37.364416) (xy 401.25396 -37.364416) (xy 401.263988 -37.364003)
			(xy 401.282521 -37.356341) (xy 401.29671 -37.342168) (xy 401.304392 -37.323643) (xy 401.30476 -37.313616)
			(xy 401.30476 -31.63316) (xy 401.303998 -31.629096) (xy 401.301715 -31.613896) (xy 401.299298 -31.583252)
			(xy 401.299172 -31.567882) (xy 401.299292 -31.552512) (xy 401.30171 -31.521867) (xy 401.303998 -31.506668)
			(xy 401.30476 -31.502604) (xy 401.30476 -30.681168) (xy 401.304637 -30.676355) (xy 401.302848 -30.666897)
			(xy 401.301204 -30.662372) (xy 401.291552 -30.637734) (xy 401.285456 -30.630876) (xy 401.267332 -30.609787)
			(xy 401.236748 -30.563349) (xy 401.213226 -30.512965) (xy 401.197263 -30.459701) (xy 401.189198 -30.404684)
			(xy 401.189201 -30.34908) (xy 401.197271 -30.294064) (xy 401.213239 -30.240802) (xy 401.236766 -30.190419)
			(xy 401.267354 -30.143984) (xy 401.285456 -30.122876) (xy 401.291552 -30.116018) (xy 401.301204 -30.09138)
			(xy 401.302894 -30.086867) (xy 401.304693 -30.077402) (xy 401.30476 -30.072584) (xy 401.30476 -29.909008)
			(xy 401.291044 -29.874972) (xy 401.285202 -29.868368) (xy 401.267158 -29.847301) (xy 401.236719 -29.800931)
			(xy 401.213315 -29.750643) (xy 401.197439 -29.697496) (xy 401.189425 -29.64261) (xy 401.188936 -29.614876)
			(xy 401.188936 -29.614368) (xy 401.189543 -29.583501) (xy 401.19951 -29.522576) (xy 401.219163 -29.464054)
			(xy 401.247988 -29.409462) (xy 401.266152 -29.384498) (xy 401.270822 -29.377758) (xy 401.276009 -29.362212)
			(xy 401.276312 -29.354018) (xy 401.276312 -29.062934) (xy 401.276008 -29.054738) (xy 401.270836 -29.039185)
			(xy 401.266152 -29.032454) (xy 401.24995 -29.01024) (xy 401.223415 -28.962086) (xy 401.20406 -28.910625)
			(xy 401.192286 -28.85692) (xy 401.188336 -28.802081) (xy 401.192291 -28.747242) (xy 401.204071 -28.693538)
			(xy 401.223431 -28.642079) (xy 401.249971 -28.593928) (xy 401.266152 -28.571698) (xy 401.270822 -28.564958)
			(xy 401.276009 -28.549412) (xy 401.276312 -28.541218) (xy 401.276312 -28.368752) (xy 401.27654 -28.361714)
			(xy 401.280415 -28.348183) (xy 401.283932 -28.342082) (xy 401.296886 -28.322016) (xy 401.300541 -28.315757)
			(xy 401.304527 -28.301829) (xy 401.30476 -28.294584) (xy 401.30476 -27.872436) (xy 401.304324 -27.862372)
			(xy 401.296589 -27.843788) (xy 401.289774 -27.836368) (xy 401.050252 -27.596846) (xy 401.042853 -27.590002)
			(xy 401.024254 -27.582278) (xy 401.014184 -27.58186) (xy 391.699496 -27.58186) (xy 391.687165 -27.582445)
			(xy 391.665317 -27.593883) (xy 391.65784 -27.603704) (xy 391.64068 -27.627665) (xy 391.601174 -27.6714)
			(xy 391.556383 -27.709706) (xy 391.507048 -27.74195) (xy 391.453985 -27.767598) (xy 391.39807 -27.786227)
			(xy 391.340227 -27.797529) (xy 391.281412 -27.801317) (xy 391.222597 -27.797529) (xy 391.164754 -27.786227)
			(xy 391.108839 -27.767598) (xy 391.055776 -27.74195) (xy 391.006441 -27.709706) (xy 390.96165 -27.6714)
			(xy 390.922144 -27.627665) (xy 390.904984 -27.603704) (xy 390.897372 -27.594032) (xy 390.875612 -27.582614)
			(xy 390.863328 -27.58186) (xy 386.727954 -27.58186) (xy 386.717889 -27.582293) (xy 386.699302 -27.590026)
			(xy 386.691886 -27.596846) (xy 386.4229 -27.865832) (xy 386.41655 -27.877262) (xy 386.414772 -27.88412)
			(xy 386.407046 -27.912348) (xy 386.384132 -27.9662) (xy 386.353264 -28.015921) (xy 386.315166 -28.060345)
			(xy 386.27073 -28.09843) (xy 386.221 -28.129284) (xy 386.167142 -28.152181) (xy 386.138928 -28.159964)
			(xy 386.13207 -28.161742) (xy 386.12064 -28.168092) (xy 386.104892 -28.18384) (xy 386.098053 -28.191241)
			(xy 386.090334 -28.209839) (xy 386.089906 -28.219908) (xy 386.089906 -29.114242) (xy 393.147296 -29.114242)
			(xy 393.147296 -28.250642) (xy 393.147786 -28.220658) (xy 393.155614 -28.161202) (xy 393.171135 -28.103277)
			(xy 393.194084 -28.047873) (xy 393.224068 -27.995939) (xy 393.260574 -27.948363) (xy 393.302979 -27.905958)
			(xy 393.350555 -27.869452) (xy 393.402489 -27.839468) (xy 393.457893 -27.816519) (xy 393.515818 -27.800998)
			(xy 393.575274 -27.79317) (xy 393.635242 -27.79317) (xy 393.694698 -27.800998) (xy 393.752623 -27.816519)
			(xy 393.808027 -27.839468) (xy 393.859961 -27.869452) (xy 393.907537 -27.905958) (xy 393.949942 -27.948363)
			(xy 393.986448 -27.995939) (xy 394.016432 -28.047873) (xy 394.039381 -28.103277) (xy 394.054902 -28.161202)
			(xy 394.06273 -28.220658) (xy 394.06322 -28.250642) (xy 394.06322 -28.469082) (xy 398.052542 -28.469082)
			(xy 398.056613 -28.41346) (xy 398.068739 -28.359023) (xy 398.088662 -28.306932) (xy 398.115958 -28.258297)
			(xy 398.150044 -28.214154) (xy 398.190193 -28.175445) (xy 398.235551 -28.142994) (xy 398.285151 -28.117493)
			(xy 398.337935 -28.099486) (xy 398.392778 -28.089356) (xy 398.448512 -28.087319) (xy 398.503949 -28.093419)
			(xy 398.557906 -28.107525) (xy 398.609235 -28.129337) (xy 398.656841 -28.158391) (xy 398.699709 -28.194066)
			(xy 398.736926 -28.235603) (xy 398.767699 -28.282116) (xy 398.791371 -28.332613) (xy 398.807439 -28.38602)
			(xy 398.815559 -28.441196) (xy 398.816068 -28.469082) (xy 398.815559 -28.496968) (xy 398.807439 -28.552144)
			(xy 398.791371 -28.605551) (xy 398.767699 -28.656048) (xy 398.736926 -28.702561) (xy 398.699709 -28.744098)
			(xy 398.656841 -28.779773) (xy 398.609235 -28.808827) (xy 398.557906 -28.830639) (xy 398.503949 -28.844745)
			(xy 398.448512 -28.850845) (xy 398.392778 -28.848808) (xy 398.337935 -28.838678) (xy 398.285151 -28.820671)
			(xy 398.235551 -28.79517) (xy 398.190193 -28.762719) (xy 398.150044 -28.72401) (xy 398.115958 -28.679867)
			(xy 398.088662 -28.631232) (xy 398.068739 -28.579141) (xy 398.056613 -28.524704) (xy 398.052542 -28.469082)
			(xy 394.06322 -28.469082) (xy 394.06322 -29.114242) (xy 394.06273 -29.144226) (xy 394.054902 -29.203682)
			(xy 394.039381 -29.261607) (xy 394.016432 -29.317011) (xy 393.986448 -29.368945) (xy 393.949942 -29.416521)
			(xy 393.907537 -29.458926) (xy 393.859961 -29.495432) (xy 393.808027 -29.525416) (xy 393.752623 -29.548365)
			(xy 393.694698 -29.563886) (xy 393.635242 -29.571714) (xy 393.575274 -29.571714) (xy 393.515818 -29.563886)
			(xy 393.457893 -29.548365) (xy 393.402489 -29.525416) (xy 393.350555 -29.495432) (xy 393.302979 -29.458926)
			(xy 393.260574 -29.416521) (xy 393.224068 -29.368945) (xy 393.194084 -29.317011) (xy 393.171135 -29.261607)
			(xy 393.155614 -29.203682) (xy 393.147786 -29.144226) (xy 393.147296 -29.114242) (xy 386.089906 -29.114242)
			(xy 386.089906 -29.186378) (xy 386.112004 -29.214064) (xy 386.12953 -29.217874) (xy 386.155822 -29.224338)
			(xy 386.206388 -29.243685) (xy 386.253713 -29.269985) (xy 386.296845 -29.302709) (xy 386.33492 -29.341201)
			(xy 386.367172 -29.384688) (xy 386.392954 -29.432296) (xy 386.411749 -29.48307) (xy 386.423179 -29.535991)
			(xy 386.427016 -29.589996) (xy 386.42318 -29.644002) (xy 386.411751 -29.696923) (xy 386.392957 -29.747698)
			(xy 386.367176 -29.795306) (xy 386.334924 -29.838794) (xy 386.296851 -29.877286) (xy 386.253719 -29.910011)
			(xy 386.206395 -29.936312) (xy 386.155829 -29.95566) (xy 386.12953 -29.962094) (xy 386.112004 -29.965904)
			(xy 386.089906 -29.99359) (xy 386.089906 -30.92069) (xy 395.789404 -30.92069) (xy 395.789404 -30.05709)
			(xy 395.789894 -30.027106) (xy 395.797722 -29.96765) (xy 395.813243 -29.909725) (xy 395.836192 -29.854321)
			(xy 395.866176 -29.802387) (xy 395.902682 -29.754811) (xy 395.945087 -29.712406) (xy 395.992663 -29.6759)
			(xy 396.044597 -29.645916) (xy 396.100001 -29.622967) (xy 396.157926 -29.607446) (xy 396.217382 -29.599618)
			(xy 396.27735 -29.599618) (xy 396.336806 -29.607446) (xy 396.394731 -29.622967) (xy 396.450135 -29.645916)
			(xy 396.502069 -29.6759) (xy 396.549645 -29.712406) (xy 396.59205 -29.754811) (xy 396.628556 -29.802387)
			(xy 396.65854 -29.854321) (xy 396.681489 -29.909725) (xy 396.69701 -29.96765) (xy 396.704838 -30.027106)
			(xy 396.705328 -30.05709) (xy 396.705328 -30.92069) (xy 396.704838 -30.950674) (xy 396.69701 -31.01013)
			(xy 396.681489 -31.068055) (xy 396.65854 -31.123459) (xy 396.628556 -31.175393) (xy 396.59205 -31.222969)
			(xy 396.549645 -31.265374) (xy 396.502069 -31.30188) (xy 396.450135 -31.331864) (xy 396.394731 -31.354813)
			(xy 396.336806 -31.370334) (xy 396.27735 -31.378162) (xy 396.217382 -31.378162) (xy 396.157926 -31.370334)
			(xy 396.100001 -31.354813) (xy 396.044597 -31.331864) (xy 395.992663 -31.30188) (xy 395.945087 -31.265374)
			(xy 395.902682 -31.222969) (xy 395.866176 -31.175393) (xy 395.836192 -31.123459) (xy 395.813243 -31.068055)
			(xy 395.797722 -31.01013) (xy 395.789894 -30.950674) (xy 395.789404 -30.92069) (xy 386.089906 -30.92069)
			(xy 386.089906 -31.232602) (xy 386.115306 -31.261304) (xy 386.13461 -31.26359) (xy 386.162018 -31.267417)
			(xy 386.215411 -31.281958) (xy 386.266144 -31.304061) (xy 386.313151 -31.333262) (xy 386.355445 -31.368948)
			(xy 386.39214 -31.410371) (xy 386.422464 -31.45666) (xy 386.445783 -31.506846) (xy 386.461606 -31.559874)
			(xy 386.469601 -31.614631) (xy 386.469601 -31.66997) (xy 386.461606 -31.724727) (xy 386.445783 -31.777755)
			(xy 386.422464 -31.827941) (xy 386.392139 -31.87423) (xy 386.355444 -31.915653) (xy 386.31315 -31.951339)
			(xy 386.266143 -31.98054) (xy 386.21541 -32.002642) (xy 386.162017 -32.017183) (xy 386.13461 -32.021018)
			(xy 386.115306 -32.023304) (xy 386.089906 -32.052006) (xy 386.089906 -32.714184) (xy 393.147296 -32.714184)
			(xy 393.147296 -31.850584) (xy 393.147786 -31.8206) (xy 393.155614 -31.761144) (xy 393.171135 -31.703219)
			(xy 393.194084 -31.647815) (xy 393.224068 -31.595881) (xy 393.260574 -31.548305) (xy 393.302979 -31.5059)
			(xy 393.350555 -31.469394) (xy 393.402489 -31.43941) (xy 393.457893 -31.416461) (xy 393.515818 -31.40094)
			(xy 393.575274 -31.393112) (xy 393.635242 -31.393112) (xy 393.694698 -31.40094) (xy 393.752623 -31.416461)
			(xy 393.808027 -31.43941) (xy 393.859961 -31.469394) (xy 393.907537 -31.5059) (xy 393.949942 -31.548305)
			(xy 393.986448 -31.595881) (xy 394.016432 -31.647815) (xy 394.039381 -31.703219) (xy 394.054902 -31.761144)
			(xy 394.06273 -31.8206) (xy 394.06322 -31.850584) (xy 394.06322 -32.714184) (xy 394.06273 -32.744168)
			(xy 394.054902 -32.803624) (xy 394.039381 -32.861549) (xy 394.016432 -32.916953) (xy 393.986448 -32.968887)
			(xy 393.949942 -33.016463) (xy 393.907537 -33.058868) (xy 393.859961 -33.095374) (xy 393.808027 -33.125358)
			(xy 393.752623 -33.148307) (xy 393.694698 -33.163828) (xy 393.635242 -33.171656) (xy 393.575274 -33.171656)
			(xy 393.515818 -33.163828) (xy 393.457893 -33.148307) (xy 393.402489 -33.125358) (xy 393.350555 -33.095374)
			(xy 393.302979 -33.058868) (xy 393.260574 -33.016463) (xy 393.224068 -32.968887) (xy 393.194084 -32.916953)
			(xy 393.171135 -32.861549) (xy 393.155614 -32.803624) (xy 393.147786 -32.744168) (xy 393.147296 -32.714184)
			(xy 386.089906 -32.714184) (xy 386.089906 -34.520886) (xy 395.789404 -34.520886) (xy 395.789404 -33.657286)
			(xy 395.789894 -33.627302) (xy 395.797722 -33.567846) (xy 395.813243 -33.509921) (xy 395.836192 -33.454517)
			(xy 395.866176 -33.402583) (xy 395.902682 -33.355007) (xy 395.945087 -33.312602) (xy 395.992663 -33.276096)
			(xy 396.044597 -33.246112) (xy 396.100001 -33.223163) (xy 396.157926 -33.207642) (xy 396.217382 -33.199814)
			(xy 396.27735 -33.199814) (xy 396.336806 -33.207642) (xy 396.394731 -33.223163) (xy 396.450135 -33.246112)
			(xy 396.502069 -33.276096) (xy 396.549645 -33.312602) (xy 396.59205 -33.355007) (xy 396.628556 -33.402583)
			(xy 396.65854 -33.454517) (xy 396.681489 -33.509921) (xy 396.69701 -33.567846) (xy 396.704838 -33.627302)
			(xy 396.705328 -33.657286) (xy 396.705328 -34.520886) (xy 396.704838 -34.55087) (xy 396.69701 -34.610326)
			(xy 396.681489 -34.668251) (xy 396.65854 -34.723655) (xy 396.628556 -34.775589) (xy 396.59205 -34.823165)
			(xy 396.549645 -34.86557) (xy 396.502069 -34.902076) (xy 396.450135 -34.93206) (xy 396.394731 -34.955009)
			(xy 396.336806 -34.97053) (xy 396.27735 -34.978358) (xy 396.217382 -34.978358) (xy 396.157926 -34.97053)
			(xy 396.100001 -34.955009) (xy 396.044597 -34.93206) (xy 395.992663 -34.902076) (xy 395.945087 -34.86557)
			(xy 395.902682 -34.823165) (xy 395.866176 -34.775589) (xy 395.836192 -34.723655) (xy 395.813243 -34.668251)
			(xy 395.797722 -34.610326) (xy 395.789894 -34.55087) (xy 395.789404 -34.520886) (xy 386.089906 -34.520886)
			(xy 386.089906 -36.60013) (xy 386.298447 -36.60013) (xy 386.302451 -36.512245) (xy 386.314431 -36.425088)
			(xy 386.334286 -36.339381) (xy 386.361853 -36.255836) (xy 386.396903 -36.175143) (xy 386.439145 -36.097971)
			(xy 386.48823 -36.024961) (xy 386.543751 -35.956717) (xy 386.605248 -35.893804) (xy 386.67221 -35.836744)
			(xy 386.744084 -35.78601) (xy 386.820274 -35.742022) (xy 386.900148 -35.705144) (xy 386.983045 -35.675683)
			(xy 387.068277 -35.653881) (xy 387.155139 -35.639921) (xy 387.24291 -35.633917) (xy 387.330864 -35.63592)
			(xy 387.418271 -35.645912) (xy 387.504407 -35.663812) (xy 387.588559 -35.68947) (xy 387.670029 -35.722674)
			(xy 387.748142 -35.763148) (xy 387.82225 -35.810559) (xy 387.891741 -35.864512) (xy 387.904832 -35.876738)
			(xy 393.017246 -35.876738) (xy 393.021317 -35.821116) (xy 393.033443 -35.766679) (xy 393.053366 -35.714588)
			(xy 393.080662 -35.665953) (xy 393.114748 -35.62181) (xy 393.154897 -35.583101) (xy 393.200255 -35.55065)
			(xy 393.249855 -35.525149) (xy 393.302639 -35.507142) (xy 393.357482 -35.497012) (xy 393.413216 -35.494975)
			(xy 393.468653 -35.501075) (xy 393.52261 -35.515181) (xy 393.573939 -35.536993) (xy 393.621545 -35.566047)
			(xy 393.664413 -35.601722) (xy 393.70163 -35.643259) (xy 393.732403 -35.689772) (xy 393.756075 -35.740269)
			(xy 393.772143 -35.793676) (xy 393.780263 -35.848852) (xy 393.780772 -35.876738) (xy 397.088866 -35.876738)
			(xy 397.092937 -35.821116) (xy 397.105063 -35.766679) (xy 397.124986 -35.714588) (xy 397.152282 -35.665953)
			(xy 397.186368 -35.62181) (xy 397.226517 -35.583101) (xy 397.271875 -35.55065) (xy 397.321475 -35.525149)
			(xy 397.374259 -35.507142) (xy 397.429102 -35.497012) (xy 397.484836 -35.494975) (xy 397.540273 -35.501075)
			(xy 397.59423 -35.515181) (xy 397.645559 -35.536993) (xy 397.693165 -35.566047) (xy 397.736033 -35.601722)
			(xy 397.77325 -35.643259) (xy 397.804023 -35.689772) (xy 397.827695 -35.740269) (xy 397.843763 -35.793676)
			(xy 397.851883 -35.848852) (xy 397.852392 -35.876738) (xy 397.851883 -35.904624) (xy 397.843763 -35.9598)
			(xy 397.827695 -36.013207) (xy 397.804023 -36.063704) (xy 397.77325 -36.110217) (xy 397.736033 -36.151754)
			(xy 397.693165 -36.187429) (xy 397.645559 -36.216483) (xy 397.59423 -36.238295) (xy 397.540273 -36.252401)
			(xy 397.484836 -36.258501) (xy 397.429102 -36.256464) (xy 397.374259 -36.246334) (xy 397.321475 -36.228327)
			(xy 397.271875 -36.202826) (xy 397.226517 -36.170375) (xy 397.186368 -36.131666) (xy 397.152282 -36.087523)
			(xy 397.124986 -36.038888) (xy 397.105063 -35.986797) (xy 397.092937 -35.93236) (xy 397.088866 -35.876738)
			(xy 393.780772 -35.876738) (xy 393.780263 -35.904624) (xy 393.772143 -35.9598) (xy 393.756075 -36.013207)
			(xy 393.732403 -36.063704) (xy 393.70163 -36.110217) (xy 393.664413 -36.151754) (xy 393.621545 -36.187429)
			(xy 393.573939 -36.216483) (xy 393.52261 -36.238295) (xy 393.468653 -36.252401) (xy 393.413216 -36.258501)
			(xy 393.357482 -36.256464) (xy 393.302639 -36.246334) (xy 393.249855 -36.228327) (xy 393.200255 -36.202826)
			(xy 393.154897 -36.170375) (xy 393.114748 -36.131666) (xy 393.080662 -36.087523) (xy 393.053366 -36.038888)
			(xy 393.033443 -35.986797) (xy 393.021317 -35.93236) (xy 393.017246 -35.876738) (xy 387.904832 -35.876738)
			(xy 387.956037 -35.92456) (xy 388.014606 -35.990207) (xy 388.066963 -36.060907) (xy 388.112675 -36.136076)
			(xy 388.151361 -36.21509) (xy 388.182702 -36.297295) (xy 388.206437 -36.382009) (xy 388.222371 -36.46853)
			(xy 388.226154 -36.50996) (xy 394.913864 -36.50996) (xy 394.917935 -36.454338) (xy 394.930061 -36.399901)
			(xy 394.949984 -36.34781) (xy 394.97728 -36.299175) (xy 395.011366 -36.255032) (xy 395.051515 -36.216323)
			(xy 395.096873 -36.183872) (xy 395.146473 -36.158371) (xy 395.199257 -36.140364) (xy 395.2541 -36.130234)
			(xy 395.309834 -36.128197) (xy 395.365271 -36.134297) (xy 395.419228 -36.148403) (xy 395.470557 -36.170215)
			(xy 395.518163 -36.199269) (xy 395.561031 -36.234944) (xy 395.598248 -36.276481) (xy 395.629021 -36.322994)
			(xy 395.652693 -36.373491) (xy 395.668761 -36.426898) (xy 395.672686 -36.453572) (xy 398.228564 -36.453572)
			(xy 398.232635 -36.39795) (xy 398.244761 -36.343513) (xy 398.264684 -36.291422) (xy 398.29198 -36.242787)
			(xy 398.326066 -36.198644) (xy 398.366215 -36.159935) (xy 398.411573 -36.127484) (xy 398.461173 -36.101983)
			(xy 398.513957 -36.083976) (xy 398.5688 -36.073846) (xy 398.624534 -36.071809) (xy 398.679971 -36.077909)
			(xy 398.733928 -36.092015) (xy 398.785257 -36.113827) (xy 398.832863 -36.142881) (xy 398.875731 -36.178556)
			(xy 398.912948 -36.220093) (xy 398.943721 -36.266606) (xy 398.967393 -36.317103) (xy 398.983461 -36.37051)
			(xy 398.991581 -36.425686) (xy 398.99209 -36.453572) (xy 398.991581 -36.481458) (xy 398.983461 -36.536634)
			(xy 398.967393 -36.590041) (xy 398.943721 -36.640538) (xy 398.912948 -36.687051) (xy 398.875731 -36.728588)
			(xy 398.832863 -36.764263) (xy 398.785257 -36.793317) (xy 398.733928 -36.815129) (xy 398.679971 -36.829235)
			(xy 398.624534 -36.835335) (xy 398.5688 -36.833298) (xy 398.513957 -36.823168) (xy 398.461173 -36.805161)
			(xy 398.411573 -36.77966) (xy 398.366215 -36.747209) (xy 398.326066 -36.7085) (xy 398.29198 -36.664357)
			(xy 398.264684 -36.615722) (xy 398.244761 -36.563631) (xy 398.232635 -36.509194) (xy 398.228564 -36.453572)
			(xy 395.672686 -36.453572) (xy 395.676881 -36.482074) (xy 395.67739 -36.50996) (xy 395.676881 -36.537846)
			(xy 395.668761 -36.593022) (xy 395.652693 -36.646429) (xy 395.629021 -36.696926) (xy 395.598248 -36.743439)
			(xy 395.561031 -36.784976) (xy 395.518163 -36.820651) (xy 395.470557 -36.849705) (xy 395.419228 -36.871517)
			(xy 395.365271 -36.885623) (xy 395.309834 -36.891723) (xy 395.2541 -36.889686) (xy 395.199257 -36.879556)
			(xy 395.146473 -36.861549) (xy 395.096873 -36.836048) (xy 395.051515 -36.803597) (xy 395.011366 -36.764888)
			(xy 394.97728 -36.720745) (xy 394.949984 -36.67211) (xy 394.930061 -36.620019) (xy 394.917935 -36.565582)
			(xy 394.913864 -36.50996) (xy 388.226154 -36.50996) (xy 388.230371 -36.556142) (xy 388.230872 -36.60013)
			(xy 388.230371 -36.644118) (xy 388.222371 -36.73173) (xy 388.206437 -36.818251) (xy 388.182702 -36.902965)
			(xy 388.151361 -36.98517) (xy 388.112675 -37.064184) (xy 388.066963 -37.139353) (xy 388.014606 -37.210053)
			(xy 387.956037 -37.2757) (xy 387.891741 -37.335748) (xy 387.82225 -37.389701) (xy 387.748142 -37.437112)
			(xy 387.670029 -37.477586) (xy 387.588559 -37.51079) (xy 387.504407 -37.536448) (xy 387.418271 -37.554348)
			(xy 387.330864 -37.56434) (xy 387.24291 -37.566343) (xy 387.155139 -37.560339) (xy 387.068277 -37.546379)
			(xy 386.983045 -37.524577) (xy 386.900148 -37.495116) (xy 386.820274 -37.458238) (xy 386.744084 -37.41425)
			(xy 386.67221 -37.363516) (xy 386.605248 -37.306456) (xy 386.543751 -37.243543) (xy 386.48823 -37.175299)
			(xy 386.439145 -37.102289) (xy 386.396903 -37.025117) (xy 386.361853 -36.944424) (xy 386.334286 -36.860879)
			(xy 386.314431 -36.775172) (xy 386.302451 -36.688015) (xy 386.298447 -36.60013) (xy 386.089906 -36.60013)
			(xy 386.089906 -39.97198) (xy 400.195794 -39.97198) (xy 400.199865 -39.916358) (xy 400.211991 -39.861921)
			(xy 400.231914 -39.80983) (xy 400.25921 -39.761195) (xy 400.293296 -39.717052) (xy 400.333445 -39.678343)
			(xy 400.378803 -39.645892) (xy 400.428403 -39.620391) (xy 400.481187 -39.602384) (xy 400.53603 -39.592254)
			(xy 400.591764 -39.590217) (xy 400.647201 -39.596317) (xy 400.701158 -39.610423) (xy 400.752487 -39.632235)
			(xy 400.800093 -39.661289) (xy 400.842961 -39.696964) (xy 400.880178 -39.738501) (xy 400.910951 -39.785014)
			(xy 400.934623 -39.835511) (xy 400.950691 -39.888918) (xy 400.958811 -39.944094) (xy 400.95932 -39.97198)
			(xy 400.958811 -39.999866) (xy 400.950691 -40.055042) (xy 400.934623 -40.108449) (xy 400.910951 -40.158946)
			(xy 400.880178 -40.205459) (xy 400.842961 -40.246996) (xy 400.800093 -40.282671) (xy 400.752487 -40.311725)
			(xy 400.701158 -40.333537) (xy 400.647201 -40.347643) (xy 400.591764 -40.353743) (xy 400.53603 -40.351706)
			(xy 400.481187 -40.341576) (xy 400.428403 -40.323569) (xy 400.378803 -40.298068) (xy 400.333445 -40.265617)
			(xy 400.293296 -40.226908) (xy 400.25921 -40.182765) (xy 400.231914 -40.13413) (xy 400.211991 -40.082039)
			(xy 400.199865 -40.027602) (xy 400.195794 -39.97198) (xy 386.089906 -39.97198) (xy 386.089906 -40.452802)
			(xy 386.09033 -40.462872) (xy 386.098045 -40.481475) (xy 386.104892 -40.48887) (xy 386.324094 -40.708072)
			(xy 386.331491 -40.714922) (xy 386.350089 -40.722663) (xy 386.360162 -40.723058) (xy 395.38148 -40.723058)
			(xy 395.391542 -40.723497) (xy 395.41012 -40.731239) (xy 395.417548 -40.738044) (xy 396.358618 -41.679114)
			(xy 396.365471 -41.686509) (xy 396.373213 -41.705108) (xy 396.373604 -41.715182) (xy 396.373604 -43.566842)
			(xy 397.633442 -43.566842) (xy 397.637513 -43.51122) (xy 397.649639 -43.456783) (xy 397.669562 -43.404692)
			(xy 397.696858 -43.356057) (xy 397.730944 -43.311914) (xy 397.771093 -43.273205) (xy 397.816451 -43.240754)
			(xy 397.866051 -43.215253) (xy 397.918835 -43.197246) (xy 397.973678 -43.187116) (xy 398.029412 -43.185079)
			(xy 398.084849 -43.191179) (xy 398.138806 -43.205285) (xy 398.190135 -43.227097) (xy 398.237741 -43.256151)
			(xy 398.280609 -43.291826) (xy 398.317826 -43.333363) (xy 398.348599 -43.379876) (xy 398.372271 -43.430373)
			(xy 398.388339 -43.48378) (xy 398.396459 -43.538956) (xy 398.396968 -43.566842) (xy 398.396459 -43.594728)
			(xy 398.388339 -43.649904) (xy 398.372271 -43.703311) (xy 398.348599 -43.753808) (xy 398.317826 -43.800321)
			(xy 398.280609 -43.841858) (xy 398.262522 -43.85691) (xy 399.019774 -43.85691) (xy 399.023845 -43.801288)
			(xy 399.035971 -43.746851) (xy 399.055894 -43.69476) (xy 399.08319 -43.646125) (xy 399.117276 -43.601982)
			(xy 399.157425 -43.563273) (xy 399.202783 -43.530822) (xy 399.252383 -43.505321) (xy 399.305167 -43.487314)
			(xy 399.36001 -43.477184) (xy 399.415744 -43.475147) (xy 399.471181 -43.481247) (xy 399.525138 -43.495353)
			(xy 399.576467 -43.517165) (xy 399.624073 -43.546219) (xy 399.666941 -43.581894) (xy 399.704158 -43.623431)
			(xy 399.734931 -43.669944) (xy 399.758603 -43.720441) (xy 399.774671 -43.773848) (xy 399.782791 -43.829024)
			(xy 399.7833 -43.85691) (xy 399.782791 -43.884796) (xy 399.774671 -43.939972) (xy 399.758603 -43.993379)
			(xy 399.734931 -44.043876) (xy 399.704158 -44.090389) (xy 399.666941 -44.131926) (xy 399.624073 -44.167601)
			(xy 399.576467 -44.196655) (xy 399.525138 -44.218467) (xy 399.471181 -44.232573) (xy 399.415744 -44.238673)
			(xy 399.36001 -44.236636) (xy 399.305167 -44.226506) (xy 399.252383 -44.208499) (xy 399.202783 -44.182998)
			(xy 399.157425 -44.150547) (xy 399.117276 -44.111838) (xy 399.08319 -44.067695) (xy 399.055894 -44.01906)
			(xy 399.035971 -43.966969) (xy 399.023845 -43.912532) (xy 399.019774 -43.85691) (xy 398.262522 -43.85691)
			(xy 398.237741 -43.877533) (xy 398.190135 -43.906587) (xy 398.138806 -43.928399) (xy 398.084849 -43.942505)
			(xy 398.029412 -43.948605) (xy 397.973678 -43.946568) (xy 397.918835 -43.936438) (xy 397.866051 -43.918431)
			(xy 397.816451 -43.89293) (xy 397.771093 -43.860479) (xy 397.730944 -43.82177) (xy 397.696858 -43.777627)
			(xy 397.669562 -43.728992) (xy 397.649639 -43.676901) (xy 397.637513 -43.622464) (xy 397.633442 -43.566842)
			(xy 396.373604 -43.566842) (xy 396.373604 -45.35424) (xy 399.003772 -45.35424) (xy 399.007843 -45.298618)
			(xy 399.019969 -45.244181) (xy 399.039892 -45.19209) (xy 399.067188 -45.143455) (xy 399.101274 -45.099312)
			(xy 399.141423 -45.060603) (xy 399.186781 -45.028152) (xy 399.236381 -45.002651) (xy 399.289165 -44.984644)
			(xy 399.344008 -44.974514) (xy 399.399742 -44.972477) (xy 399.455179 -44.978577) (xy 399.509136 -44.992683)
			(xy 399.560465 -45.014495) (xy 399.608071 -45.043549) (xy 399.650939 -45.079224) (xy 399.688156 -45.120761)
			(xy 399.718929 -45.167274) (xy 399.742601 -45.217771) (xy 399.758669 -45.271178) (xy 399.766789 -45.326354)
			(xy 399.767298 -45.35424) (xy 399.766789 -45.382126) (xy 399.758669 -45.437302) (xy 399.742601 -45.490709)
			(xy 399.718929 -45.541206) (xy 399.688156 -45.587719) (xy 399.650939 -45.629256) (xy 399.608071 -45.664931)
			(xy 399.560465 -45.693985) (xy 399.509136 -45.715797) (xy 399.455179 -45.729903) (xy 399.399742 -45.736003)
			(xy 399.344008 -45.733966) (xy 399.289165 -45.723836) (xy 399.236381 -45.705829) (xy 399.186781 -45.680328)
			(xy 399.141423 -45.647877) (xy 399.101274 -45.609168) (xy 399.067188 -45.565025) (xy 399.039892 -45.51639)
			(xy 399.019969 -45.464299) (xy 399.007843 -45.409862) (xy 399.003772 -45.35424) (xy 396.373604 -45.35424)
			(xy 396.373604 -46.693836) (xy 398.976342 -46.693836) (xy 398.976828 -46.666585) (xy 398.984584 -46.612637)
			(xy 398.999939 -46.560342) (xy 399.022581 -46.510765) (xy 399.052047 -46.464915) (xy 399.087738 -46.423724)
			(xy 399.128929 -46.388033) (xy 399.174779 -46.358567) (xy 399.224356 -46.335925) (xy 399.276651 -46.32057)
			(xy 399.330599 -46.312814) (xy 399.385101 -46.312814) (xy 399.439049 -46.32057) (xy 399.491344 -46.335925)
			(xy 399.540921 -46.358567) (xy 399.586771 -46.388033) (xy 399.627962 -46.423724) (xy 399.663653 -46.464915)
			(xy 399.693119 -46.510765) (xy 399.715761 -46.560342) (xy 399.731116 -46.612637) (xy 399.738872 -46.666585)
			(xy 399.739358 -46.693836) (xy 399.738891 -46.720264) (xy 399.731581 -46.772612) (xy 399.717106 -46.823447)
			(xy 399.695744 -46.871793) (xy 399.682208 -46.894496) (xy 399.676112 -46.904402) (xy 399.673572 -46.927262)
			(xy 399.707862 -47.023782) (xy 399.723864 -47.040038) (xy 399.73504 -47.043848) (xy 399.759547 -47.052921)
			(xy 399.806 -47.076863) (xy 399.848752 -47.106918) (xy 399.887004 -47.142525) (xy 399.920041 -47.183017)
			(xy 399.947245 -47.227638) (xy 399.968107 -47.275553) (xy 399.982237 -47.325866) (xy 399.989371 -47.377636)
			(xy 399.989802 -47.403766) (xy 399.989316 -47.431017) (xy 399.98156 -47.484965) (xy 399.966205 -47.53726)
			(xy 399.943563 -47.586837) (xy 399.914097 -47.632687) (xy 399.878406 -47.673878) (xy 399.837215 -47.709569)
			(xy 399.791365 -47.739035) (xy 399.741788 -47.761677) (xy 399.689493 -47.777032) (xy 399.635545 -47.784788)
			(xy 399.581043 -47.784788) (xy 399.527095 -47.777032) (xy 399.4748 -47.761677) (xy 399.425223 -47.739035)
			(xy 399.379373 -47.709569) (xy 399.338182 -47.673878) (xy 399.302491 -47.632687) (xy 399.273025 -47.586837)
			(xy 399.250383 -47.53726) (xy 399.235028 -47.484965) (xy 399.227272 -47.431017) (xy 399.226786 -47.403766)
			(xy 399.227262 -47.377339) (xy 399.23457 -47.324991) (xy 399.249043 -47.274156) (xy 399.270402 -47.225809)
			(xy 399.283936 -47.203106) (xy 399.290032 -47.1932) (xy 399.292572 -47.17034) (xy 399.258282 -47.07382)
			(xy 399.24228 -47.057564) (xy 399.231104 -47.053754) (xy 399.206585 -47.044711) (xy 399.160134 -47.020763)
			(xy 399.117384 -46.990702) (xy 399.079133 -46.955091) (xy 399.046099 -46.914595) (xy 399.018897 -46.869971)
			(xy 398.998036 -46.822054) (xy 398.983907 -46.771739) (xy 398.976773 -46.719967) (xy 398.976342 -46.693836)
			(xy 396.373604 -46.693836) (xy 396.373604 -48.30699) (xy 398.853912 -48.30699) (xy 398.857983 -48.251368)
			(xy 398.870109 -48.196931) (xy 398.890032 -48.14484) (xy 398.917328 -48.096205) (xy 398.951414 -48.052062)
			(xy 398.991563 -48.013353) (xy 399.036921 -47.980902) (xy 399.086521 -47.955401) (xy 399.139305 -47.937394)
			(xy 399.194148 -47.927264) (xy 399.249882 -47.925227) (xy 399.305319 -47.931327) (xy 399.359276 -47.945433)
			(xy 399.410605 -47.967245) (xy 399.458211 -47.996299) (xy 399.501079 -48.031974) (xy 399.538296 -48.073511)
			(xy 399.569069 -48.120024) (xy 399.592741 -48.170521) (xy 399.608809 -48.223928) (xy 399.616929 -48.279104)
			(xy 399.617438 -48.30699) (xy 399.616929 -48.334876) (xy 399.608809 -48.390052) (xy 399.592741 -48.443459)
			(xy 399.569069 -48.493956) (xy 399.538296 -48.540469) (xy 399.501079 -48.582006) (xy 399.458211 -48.617681)
			(xy 399.410605 -48.646735) (xy 399.359276 -48.668547) (xy 399.305319 -48.682653) (xy 399.249882 -48.688753)
			(xy 399.194148 -48.686716) (xy 399.139305 -48.676586) (xy 399.086521 -48.658579) (xy 399.036921 -48.633078)
			(xy 398.991563 -48.600627) (xy 398.951414 -48.561918) (xy 398.917328 -48.517775) (xy 398.890032 -48.46914)
			(xy 398.870109 -48.417049) (xy 398.857983 -48.362612) (xy 398.853912 -48.30699) (xy 396.373604 -48.30699)
			(xy 396.373604 -48.89246) (xy 397.514062 -48.89246) (xy 397.518133 -48.836838) (xy 397.530259 -48.782401)
			(xy 397.550182 -48.73031) (xy 397.577478 -48.681675) (xy 397.611564 -48.637532) (xy 397.651713 -48.598823)
			(xy 397.697071 -48.566372) (xy 397.746671 -48.540871) (xy 397.799455 -48.522864) (xy 397.854298 -48.512734)
			(xy 397.910032 -48.510697) (xy 397.965469 -48.516797) (xy 398.019426 -48.530903) (xy 398.070755 -48.552715)
			(xy 398.118361 -48.581769) (xy 398.161229 -48.617444) (xy 398.198446 -48.658981) (xy 398.229219 -48.705494)
			(xy 398.252891 -48.755991) (xy 398.268959 -48.809398) (xy 398.277079 -48.864574) (xy 398.277588 -48.89246)
			(xy 398.277079 -48.920346) (xy 398.268959 -48.975522) (xy 398.252891 -49.028929) (xy 398.229219 -49.079426)
			(xy 398.198446 -49.125939) (xy 398.161229 -49.167476) (xy 398.118361 -49.203151) (xy 398.070755 -49.232205)
			(xy 398.019426 -49.254017) (xy 397.965469 -49.268123) (xy 397.910032 -49.274223) (xy 397.854298 -49.272186)
			(xy 397.799455 -49.262056) (xy 397.746671 -49.244049) (xy 397.697071 -49.218548) (xy 397.651713 -49.186097)
			(xy 397.611564 -49.147388) (xy 397.577478 -49.103245) (xy 397.550182 -49.05461) (xy 397.530259 -49.002519)
			(xy 397.518133 -48.948082) (xy 397.514062 -48.89246) (xy 396.373604 -48.89246) (xy 396.373604 -51.198018)
			(xy 396.374031 -51.208087) (xy 396.38175 -51.226686) (xy 396.38859 -51.234086) (xy 396.532862 -51.378358)
			(xy 396.540262 -51.385199) (xy 396.558861 -51.392918) (xy 396.56893 -51.393344)
		)
		(stroke
			(width 0)
			(type solid)
		)
		(fill yes)
		(layer "In9.Cu")
		(net "GND")
	)
	(gr_poly
		(pts
			(xy 282.932632 -51.393344) (xy 282.941859 -51.392939) (xy 282.959111 -51.386383) (xy 282.972915 -51.374134)
			(xy 282.97759 -51.366166) (xy 283.019246 -51.286664) (xy 283.023152 -51.278382) (xy 283.025428 -51.260225)
			(xy 283.021211 -51.242418) (xy 283.016452 -51.234594) (xy 283.016198 -51.23434) (xy 283.000703 -51.210699)
			(xy 282.976102 -51.159811) (xy 282.959273 -51.105851) (xy 282.950583 -51.05) (xy 282.949904 -51.021742)
			(xy 282.949904 -51.01463) (xy 282.950716 -50.987604) (xy 282.959026 -50.934177) (xy 282.974795 -50.882459)
			(xy 282.997707 -50.833486) (xy 283.027304 -50.788237) (xy 283.062993 -50.74762) (xy 283.104058 -50.712448)
			(xy 283.149677 -50.683426) (xy 283.198937 -50.661135) (xy 283.250851 -50.646021) (xy 283.304378 -50.638388)
			(xy 283.358446 -50.638388) (xy 283.411973 -50.646021) (xy 283.463887 -50.661135) (xy 283.513147 -50.683426)
			(xy 283.558766 -50.712448) (xy 283.599831 -50.74762) (xy 283.63552 -50.788237) (xy 283.665117 -50.833486)
			(xy 283.688029 -50.882459) (xy 283.703798 -50.934177) (xy 283.712108 -50.987604) (xy 283.71292 -51.01463)
			(xy 283.71292 -51.01971) (xy 283.712412 -51.048258) (xy 283.703897 -51.104717) (xy 283.68706 -51.159275)
			(xy 283.662277 -51.210712) (xy 283.646626 -51.234594) (xy 283.638498 -51.246278) (xy 283.636974 -51.274218)
			(xy 283.685234 -51.366166) (xy 283.689884 -51.374147) (xy 283.703706 -51.386375) (xy 283.720964 -51.392915)
			(xy 283.730192 -51.393344) (xy 284.62224 -51.393344) (xy 284.632205 -51.392864) (xy 284.65064 -51.385288)
			(xy 284.658054 -51.378612) (xy 285.176214 -50.860452) (xy 285.180024 -50.852578) (xy 285.18993 -50.833528)
			(xy 285.190184 -50.833274) (xy 285.193994 -50.82667) (xy 285.197296 -50.821082) (xy 285.20136 -50.806858)
			(xy 285.204662 -50.795174) (xy 285.204662 -50.1904) (xy 285.204407 -50.182988) (xy 285.200148 -50.168788)
			(xy 285.19628 -50.16246) (xy 285.181448 -50.139007) (xy 285.15799 -50.088717) (xy 285.142071 -50.035559)
			(xy 285.134025 -49.980654) (xy 285.134024 -49.925163) (xy 285.142067 -49.870258) (xy 285.157984 -49.817098)
			(xy 285.181439 -49.766808) (xy 285.19628 -49.74336) (xy 285.200144 -49.73703) (xy 285.2044 -49.722831)
			(xy 285.204662 -49.71542) (xy 285.204662 -49.1744) (xy 285.204407 -49.166988) (xy 285.200148 -49.152788)
			(xy 285.19628 -49.14646) (xy 285.181448 -49.123007) (xy 285.15799 -49.072717) (xy 285.142071 -49.019559)
			(xy 285.134025 -48.964654) (xy 285.134024 -48.909163) (xy 285.142067 -48.854258) (xy 285.157984 -48.801098)
			(xy 285.181439 -48.750808) (xy 285.19628 -48.72736) (xy 285.200144 -48.72103) (xy 285.2044 -48.706831)
			(xy 285.204662 -48.69942) (xy 285.204662 -47.629572) (xy 285.202122 -47.61865) (xy 285.199328 -47.613062)
			(xy 285.186603 -47.586292) (xy 285.168627 -47.529814) (xy 285.159531 -47.471246) (xy 285.159529 -47.411976)
			(xy 285.168622 -47.353407) (xy 285.186595 -47.296928) (xy 285.199328 -47.270162) (xy 285.202122 -47.264574)
			(xy 285.204662 -47.253652) (xy 285.204662 -46.1264) (xy 285.204407 -46.118988) (xy 285.200148 -46.104788)
			(xy 285.19628 -46.09846) (xy 285.181448 -46.075007) (xy 285.15799 -46.024717) (xy 285.142071 -45.971559)
			(xy 285.134025 -45.916654) (xy 285.134024 -45.861163) (xy 285.142067 -45.806258) (xy 285.157984 -45.753098)
			(xy 285.181439 -45.702808) (xy 285.19628 -45.67936) (xy 285.200144 -45.67303) (xy 285.2044 -45.658831)
			(xy 285.204662 -45.65142) (xy 285.204662 -45.1104) (xy 285.204407 -45.102988) (xy 285.200148 -45.088788)
			(xy 285.19628 -45.08246) (xy 285.181448 -45.059007) (xy 285.15799 -45.008717) (xy 285.142071 -44.955559)
			(xy 285.134025 -44.900654) (xy 285.134024 -44.845163) (xy 285.142067 -44.790258) (xy 285.157984 -44.737098)
			(xy 285.181439 -44.686808) (xy 285.19628 -44.66336) (xy 285.200144 -44.65703) (xy 285.2044 -44.642831)
			(xy 285.204662 -44.63542) (xy 285.204662 -44.0944) (xy 285.204407 -44.086988) (xy 285.200148 -44.072788)
			(xy 285.19628 -44.06646) (xy 285.181448 -44.043007) (xy 285.15799 -43.992717) (xy 285.142071 -43.939559)
			(xy 285.134025 -43.884654) (xy 285.134024 -43.829163) (xy 285.142067 -43.774258) (xy 285.157984 -43.721098)
			(xy 285.181439 -43.670808) (xy 285.19628 -43.64736) (xy 285.200144 -43.64103) (xy 285.2044 -43.626831)
			(xy 285.204662 -43.61942) (xy 285.204662 -43.0784) (xy 285.204407 -43.070988) (xy 285.200148 -43.056788)
			(xy 285.19628 -43.05046) (xy 285.181448 -43.027007) (xy 285.15799 -42.976717) (xy 285.142071 -42.923559)
			(xy 285.134025 -42.868654) (xy 285.134024 -42.813163) (xy 285.142067 -42.758258) (xy 285.157984 -42.705098)
			(xy 285.181439 -42.654808) (xy 285.19628 -42.63136) (xy 285.200144 -42.62503) (xy 285.2044 -42.610831)
			(xy 285.204662 -42.60342) (xy 285.204662 -41.423844) (xy 285.204276 -41.414078) (xy 285.197101 -41.395916)
			(xy 285.190692 -41.388538) (xy 285.169864 -41.366948) (xy 285.161482 -41.362884) (xy 285.138114 -41.351454)
			(xy 285.129732 -41.350438) (xy 285.102335 -41.346595) (xy 285.048966 -41.332027) (xy 284.998261 -41.309904)
			(xy 284.951282 -41.28069) (xy 284.909015 -41.244998) (xy 284.872345 -41.203576) (xy 284.842042 -41.157293)
			(xy 284.81874 -41.107119) (xy 284.802928 -41.054105) (xy 284.794939 -40.999364) (xy 284.794938 -40.944042)
			(xy 284.802927 -40.889301) (xy 284.818738 -40.836287) (xy 284.842039 -40.786112) (xy 284.872342 -40.739828)
			(xy 284.909011 -40.698406) (xy 284.951278 -40.662713) (xy 284.998256 -40.633499) (xy 285.048961 -40.611375)
			(xy 285.102329 -40.596806) (xy 285.129732 -40.59301) (xy 285.138114 -40.591994) (xy 285.161736 -40.580564)
			(xy 285.165765 -40.5785) (xy 285.173056 -40.573138) (xy 285.176214 -40.569896) (xy 285.190692 -40.55491)
			(xy 285.19711 -40.547535) (xy 285.204301 -40.529374) (xy 285.204662 -40.519604) (xy 285.204662 -38.432232)
			(xy 285.204247 -38.422209) (xy 285.196582 -38.403688) (xy 285.182407 -38.389515) (xy 285.163885 -38.381852)
			(xy 285.153862 -38.381432) (xy 283.484066 -38.381432) (xy 283.474932 -38.38182) (xy 283.45783 -38.388244)
			(xy 283.444072 -38.400264) (xy 283.439362 -38.408102) (xy 283.397198 -38.486842) (xy 283.394183 -38.492876)
			(xy 283.391101 -38.506004) (xy 283.391102 -38.51275) (xy 283.39161 -38.527228) (xy 283.399484 -38.539166)
			(xy 283.414615 -38.562786) (xy 283.438536 -38.613523) (xy 283.454778 -38.667213) (xy 283.462991 -38.722702)
			(xy 283.463492 -38.750748) (xy 283.463002 -38.777997) (xy 283.45524 -38.831938) (xy 283.439881 -38.884226)
			(xy 283.417237 -38.933796) (xy 283.387769 -38.979639) (xy 283.352077 -39.020823) (xy 283.310888 -39.056507)
			(xy 283.26504 -39.085968) (xy 283.215466 -39.108603) (xy 283.163176 -39.123954) (xy 283.109233 -39.131707)
			(xy 283.081984 -39.132256) (xy 283.053682 -39.13174) (xy 282.9977 -39.123378) (xy 282.943566 -39.106839)
			(xy 282.892469 -39.082486) (xy 282.84553 -39.050853) (xy 282.803777 -39.012634) (xy 282.768127 -38.968668)
			(xy 282.753308 -38.94455) (xy 282.746704 -38.933374) (xy 282.725114 -38.920166) (xy 282.679902 -38.917626)
			(xy 282.61564 -38.913816) (xy 282.59278 -38.92423) (xy 282.58516 -38.93439) (xy 282.566972 -38.957268)
			(xy 282.524818 -38.997749) (xy 282.476986 -39.03133) (xy 282.424594 -39.057227) (xy 282.368866 -39.074835)
			(xy 282.311106 -39.083742) (xy 282.281884 -39.08425) (xy 282.254632 -39.083763) (xy 282.200684 -39.076005)
			(xy 282.148389 -39.060649) (xy 282.098811 -39.038007) (xy 282.05296 -39.008541) (xy 282.011768 -38.972851)
			(xy 281.976074 -38.931661) (xy 281.946605 -38.885812) (xy 281.92396 -38.836235) (xy 281.908601 -38.783941)
			(xy 281.900839 -38.729994) (xy 281.900376 -38.702742) (xy 281.900935 -38.672656) (xy 281.91038 -38.613231)
			(xy 281.929057 -38.556032) (xy 281.942286 -38.529006) (xy 281.948382 -38.517068) (xy 281.947366 -38.490906)
			(xy 281.895042 -38.405562) (xy 281.89021 -38.398399) (xy 281.876768 -38.38756) (xy 281.860495 -38.381787)
			(xy 281.851862 -38.381432) (xy 279.48509 -38.381432) (xy 279.476235 -38.38186) (xy 279.459607 -38.387967)
			(xy 279.452578 -38.39337) (xy 279.240996 -38.604952) (xy 279.163526 -38.682168) (xy 279.139626 -38.705334)
			(xy 279.086822 -38.745856) (xy 279.029178 -38.779136) (xy 278.967683 -38.804605) (xy 278.903389 -38.821827)
			(xy 278.837396 -38.830507) (xy 278.804116 -38.831012) (xy 277.188676 -38.831012) (xy 277.155398 -38.830467)
			(xy 277.089413 -38.821779) (xy 277.025125 -38.804555) (xy 276.963635 -38.77909) (xy 276.905993 -38.745819)
			(xy 276.853185 -38.705311) (xy 276.829266 -38.682168) (xy 275.981668 -37.83457) (xy 275.958503 -37.81067)
			(xy 275.917985 -37.757865) (xy 275.884708 -37.700221) (xy 275.859244 -37.638726) (xy 275.842028 -37.574432)
			(xy 275.833355 -37.50844) (xy 275.832824 -37.47516) (xy 275.832851 -37.463333) (xy 275.833867 -37.439701)
			(xy 275.834856 -37.427916) (xy 275.83511 -37.42563) (xy 275.83511 -37.42436) (xy 275.838688 -37.393445)
			(xy 275.85242 -37.332742) (xy 275.873458 -37.27417) (xy 275.901487 -37.218602) (xy 275.936088 -37.166871)
			(xy 275.976743 -37.119748) (xy 276.022845 -37.07794) (xy 276.073704 -37.04207) (xy 276.128561 -37.012675)
			(xy 276.186596 -36.990194) (xy 276.24694 -36.974964) (xy 276.308691 -36.967212) (xy 276.339808 -36.966652)
			(xy 276.341078 -36.966652) (xy 276.373311 -36.96715) (xy 276.437258 -36.975306) (xy 276.468586 -36.982908)
			(xy 276.50118 -36.991943) (xy 276.563812 -37.017473) (xy 276.622502 -37.051091) (xy 276.67621 -37.092201)
			(xy 276.700488 -37.11575) (xy 277.384256 -37.799518) (xy 277.391654 -37.806364) (xy 277.410253 -37.814091)
			(xy 277.420324 -37.814504) (xy 278.049736 -37.814504) (xy 278.060483 -37.814022) (xy 278.080083 -37.805201)
			(xy 278.087582 -37.797486) (xy 278.138128 -37.741352) (xy 278.1447 -37.733236) (xy 278.151262 -37.713432)
			(xy 278.150828 -37.702998) (xy 278.150828 -37.702236) (xy 278.149862 -37.692295) (xy 278.148846 -37.672346)
			(xy 278.148796 -37.662358) (xy 278.149285 -37.635109) (xy 278.157046 -37.581166) (xy 278.172405 -37.528876)
			(xy 278.195048 -37.479305) (xy 278.224516 -37.43346) (xy 278.260208 -37.392275) (xy 278.301397 -37.356588)
			(xy 278.347245 -37.327126) (xy 278.39682 -37.304489) (xy 278.449111 -37.289136) (xy 278.503055 -37.281381)
			(xy 278.530304 -37.28085) (xy 278.559356 -37.281395) (xy 278.61679 -37.290203) (xy 278.672224 -37.307615)
			(xy 278.724378 -37.333229) (xy 278.772048 -37.366453) (xy 278.81413 -37.406519) (xy 278.83231 -37.429186)
			(xy 278.838406 -37.43706) (xy 278.846788 -37.44214) (xy 278.850948 -37.444435) (xy 278.859896 -37.447627)
			(xy 278.864568 -37.44849) (xy 278.932894 -37.459666) (xy 278.942467 -37.460795) (xy 278.961265 -37.456601)
			(xy 278.96947 -37.451538) (xy 278.969724 -37.451284) (xy 278.99741 -37.433232) (xy 279.056528 -37.403678)
			(xy 279.08758 -37.392356) (xy 279.114411 -37.383494) (xy 279.169536 -37.371069) (xy 279.225696 -37.364816)
			(xy 279.25395 -37.364416) (xy 285.153862 -37.364416) (xy 285.163889 -37.364003) (xy 285.182422 -37.356341)
			(xy 285.19661 -37.342168) (xy 285.204292 -37.323643) (xy 285.204662 -37.313616) (xy 285.204662 -31.63316)
			(xy 285.2039 -31.629096) (xy 285.201617 -31.613896) (xy 285.1992 -31.583252) (xy 285.199074 -31.567882)
			(xy 285.199194 -31.552512) (xy 285.201612 -31.521867) (xy 285.2039 -31.506668) (xy 285.204662 -31.502604)
			(xy 285.204662 -30.681168) (xy 285.204539 -30.676355) (xy 285.20275 -30.666897) (xy 285.201106 -30.662372)
			(xy 285.191454 -30.637734) (xy 285.185358 -30.630876) (xy 285.167234 -30.609787) (xy 285.13665 -30.563349)
			(xy 285.113128 -30.512965) (xy 285.097165 -30.459701) (xy 285.0891 -30.404684) (xy 285.089102 -30.34908)
			(xy 285.097173 -30.294064) (xy 285.11314 -30.240801) (xy 285.136667 -30.190419) (xy 285.167256 -30.143984)
			(xy 285.185358 -30.122876) (xy 285.191454 -30.116018) (xy 285.201106 -30.09138) (xy 285.202796 -30.086867)
			(xy 285.204595 -30.077402) (xy 285.204662 -30.072584) (xy 285.204662 -29.909008) (xy 285.190946 -29.874972)
			(xy 285.185104 -29.868368) (xy 285.16706 -29.847301) (xy 285.136621 -29.800931) (xy 285.113217 -29.750643)
			(xy 285.09734 -29.697496) (xy 285.089327 -29.64261) (xy 285.088838 -29.614876) (xy 285.088838 -29.614368)
			(xy 285.089445 -29.583501) (xy 285.099412 -29.522576) (xy 285.119065 -29.464054) (xy 285.147891 -29.409462)
			(xy 285.166054 -29.384498) (xy 285.170724 -29.377758) (xy 285.17591 -29.362212) (xy 285.176214 -29.354018)
			(xy 285.176214 -29.062934) (xy 285.17591 -29.054738) (xy 285.170738 -29.039185) (xy 285.166054 -29.032454)
			(xy 285.149852 -29.01024) (xy 285.123317 -28.962087) (xy 285.103962 -28.910625) (xy 285.092187 -28.85692)
			(xy 285.088237 -28.802081) (xy 285.092193 -28.747242) (xy 285.103973 -28.693538) (xy 285.123333 -28.642079)
			(xy 285.149873 -28.593928) (xy 285.166054 -28.571698) (xy 285.170724 -28.564958) (xy 285.17591 -28.549412)
			(xy 285.176214 -28.541218) (xy 285.176214 -28.368752) (xy 285.176442 -28.361714) (xy 285.180317 -28.348183)
			(xy 285.183834 -28.342082) (xy 285.196788 -28.322016) (xy 285.200443 -28.315757) (xy 285.204429 -28.301829)
			(xy 285.204662 -28.294584) (xy 285.204662 -27.872436) (xy 285.204226 -27.862372) (xy 285.196491 -27.843788)
			(xy 285.189676 -27.836368) (xy 284.950154 -27.596846) (xy 284.942755 -27.590002) (xy 284.924157 -27.582277)
			(xy 284.914086 -27.58186) (xy 275.599398 -27.58186) (xy 275.587066 -27.582445) (xy 275.565218 -27.593882)
			(xy 275.557742 -27.603704) (xy 275.540582 -27.627665) (xy 275.501076 -27.6714) (xy 275.456285 -27.709706)
			(xy 275.40695 -27.74195) (xy 275.353887 -27.767598) (xy 275.297972 -27.786227) (xy 275.240129 -27.797529)
			(xy 275.181314 -27.801317) (xy 275.122499 -27.797529) (xy 275.064656 -27.786227) (xy 275.008741 -27.767598)
			(xy 274.955678 -27.74195) (xy 274.906343 -27.709706) (xy 274.861552 -27.6714) (xy 274.822046 -27.627665)
			(xy 274.804886 -27.603704) (xy 274.797274 -27.594032) (xy 274.775514 -27.582612) (xy 274.76323 -27.58186)
			(xy 270.627856 -27.58186) (xy 270.617791 -27.582293) (xy 270.599204 -27.590025) (xy 270.591788 -27.596846)
			(xy 270.322802 -27.865832) (xy 270.316452 -27.877262) (xy 270.314674 -27.88412) (xy 270.306948 -27.912348)
			(xy 270.284034 -27.9662) (xy 270.253166 -28.015921) (xy 270.215068 -28.060345) (xy 270.170633 -28.098431)
			(xy 270.120903 -28.129285) (xy 270.067045 -28.152183) (xy 270.03883 -28.159964) (xy 270.031972 -28.161742)
			(xy 270.020542 -28.168092) (xy 270.004794 -28.18384) (xy 269.997955 -28.191241) (xy 269.990236 -28.209839)
			(xy 269.989808 -28.219908) (xy 269.989808 -29.114242) (xy 277.047452 -29.114242) (xy 277.047452 -28.250642)
			(xy 277.047942 -28.220674) (xy 277.055765 -28.161252) (xy 277.071278 -28.103359) (xy 277.094214 -28.047986)
			(xy 277.124181 -27.99608) (xy 277.160668 -27.94853) (xy 277.203048 -27.90615) (xy 277.250598 -27.869663)
			(xy 277.302504 -27.839696) (xy 277.357877 -27.81676) (xy 277.41577 -27.801247) (xy 277.475192 -27.793424)
			(xy 277.535128 -27.793424) (xy 277.59455 -27.801247) (xy 277.652443 -27.81676) (xy 277.707816 -27.839696)
			(xy 277.759722 -27.869663) (xy 277.807272 -27.90615) (xy 277.849652 -27.94853) (xy 277.886139 -27.99608)
			(xy 277.916106 -28.047986) (xy 277.939042 -28.103359) (xy 277.954555 -28.161252) (xy 277.962378 -28.220674)
			(xy 277.962868 -28.250642) (xy 277.962868 -28.469082) (xy 281.952444 -28.469082) (xy 281.956515 -28.41346)
			(xy 281.968641 -28.359023) (xy 281.988564 -28.306932) (xy 282.01586 -28.258297) (xy 282.049946 -28.214154)
			(xy 282.090095 -28.175445) (xy 282.135453 -28.142994) (xy 282.185053 -28.117493) (xy 282.237837 -28.099486)
			(xy 282.29268 -28.089356) (xy 282.348414 -28.087319) (xy 282.403851 -28.093419) (xy 282.457808 -28.107525)
			(xy 282.509137 -28.129337) (xy 282.556743 -28.158391) (xy 282.599611 -28.194066) (xy 282.636828 -28.235603)
			(xy 282.667601 -28.282116) (xy 282.691273 -28.332613) (xy 282.707341 -28.38602) (xy 282.715461 -28.441196)
			(xy 282.71597 -28.469082) (xy 282.715461 -28.496968) (xy 282.707341 -28.552144) (xy 282.691273 -28.605551)
			(xy 282.667601 -28.656048) (xy 282.636828 -28.702561) (xy 282.599611 -28.744098) (xy 282.556743 -28.779773)
			(xy 282.509137 -28.808827) (xy 282.457808 -28.830639) (xy 282.403851 -28.844745) (xy 282.348414 -28.850845)
			(xy 282.29268 -28.848808) (xy 282.237837 -28.838678) (xy 282.185053 -28.820671) (xy 282.135453 -28.79517)
			(xy 282.090095 -28.762719) (xy 282.049946 -28.72401) (xy 282.01586 -28.679867) (xy 281.988564 -28.631232)
			(xy 281.968641 -28.579141) (xy 281.956515 -28.524704) (xy 281.952444 -28.469082) (xy 277.962868 -28.469082)
			(xy 277.962868 -29.114242) (xy 277.962378 -29.14421) (xy 277.954555 -29.203632) (xy 277.939042 -29.261525)
			(xy 277.916106 -29.316898) (xy 277.886139 -29.368804) (xy 277.849652 -29.416354) (xy 277.807272 -29.458734)
			(xy 277.759722 -29.495221) (xy 277.707816 -29.525188) (xy 277.652443 -29.548124) (xy 277.59455 -29.563637)
			(xy 277.535128 -29.57146) (xy 277.475192 -29.57146) (xy 277.41577 -29.563637) (xy 277.357877 -29.548124)
			(xy 277.302504 -29.525188) (xy 277.250598 -29.495221) (xy 277.203048 -29.458734) (xy 277.160668 -29.416354)
			(xy 277.124181 -29.368804) (xy 277.094214 -29.316898) (xy 277.071278 -29.261525) (xy 277.055765 -29.203632)
			(xy 277.047942 -29.14421) (xy 277.047452 -29.114242) (xy 269.989808 -29.114242) (xy 269.989808 -29.186378)
			(xy 270.011906 -29.214064) (xy 270.029432 -29.217874) (xy 270.055729 -29.224333) (xy 270.106306 -29.243671)
			(xy 270.153642 -29.269965) (xy 270.196785 -29.302686) (xy 270.23487 -29.341177) (xy 270.267132 -29.384665)
			(xy 270.292922 -29.432277) (xy 270.311723 -29.483057) (xy 270.323157 -29.535984) (xy 270.326994 -29.589996)
			(xy 270.323158 -29.644009) (xy 270.311725 -29.696936) (xy 270.292925 -29.747716) (xy 270.267136 -29.795329)
			(xy 270.234875 -29.838818) (xy 270.196791 -29.87731) (xy 270.153648 -29.910031) (xy 270.106312 -29.936326)
			(xy 270.055736 -29.955665) (xy 270.029432 -29.962094) (xy 270.011906 -29.965904) (xy 269.989808 -29.99359)
			(xy 269.989808 -30.92069) (xy 279.68956 -30.92069) (xy 279.68956 -30.05709) (xy 279.69005 -30.027122)
			(xy 279.697873 -29.9677) (xy 279.713386 -29.909807) (xy 279.736322 -29.854434) (xy 279.766289 -29.802528)
			(xy 279.802776 -29.754978) (xy 279.845156 -29.712598) (xy 279.892706 -29.676111) (xy 279.944612 -29.646144)
			(xy 279.999985 -29.623208) (xy 280.057878 -29.607695) (xy 280.1173 -29.599872) (xy 280.177236 -29.599872)
			(xy 280.236658 -29.607695) (xy 280.294551 -29.623208) (xy 280.349924 -29.646144) (xy 280.40183 -29.676111)
			(xy 280.44938 -29.712598) (xy 280.49176 -29.754978) (xy 280.528247 -29.802528) (xy 280.558214 -29.854434)
			(xy 280.58115 -29.909807) (xy 280.596663 -29.9677) (xy 280.604486 -30.027122) (xy 280.604976 -30.05709)
			(xy 280.604976 -30.92069) (xy 280.604486 -30.950658) (xy 280.596663 -31.01008) (xy 280.58115 -31.067973)
			(xy 280.558214 -31.123346) (xy 280.528247 -31.175252) (xy 280.49176 -31.222802) (xy 280.44938 -31.265182)
			(xy 280.40183 -31.301669) (xy 280.349924 -31.331636) (xy 280.294551 -31.354572) (xy 280.236658 -31.370085)
			(xy 280.177236 -31.377908) (xy 280.1173 -31.377908) (xy 280.057878 -31.370085) (xy 279.999985 -31.354572)
			(xy 279.944612 -31.331636) (xy 279.892706 -31.301669) (xy 279.845156 -31.265182) (xy 279.802776 -31.222802)
			(xy 279.766289 -31.175252) (xy 279.736322 -31.123346) (xy 279.713386 -31.067973) (xy 279.697873 -31.01008)
			(xy 279.69005 -30.950658) (xy 279.68956 -30.92069) (xy 269.989808 -30.92069) (xy 269.989808 -31.232602)
			(xy 270.015208 -31.261304) (xy 270.034512 -31.26359) (xy 270.06192 -31.267417) (xy 270.115313 -31.281958)
			(xy 270.166045 -31.304061) (xy 270.213052 -31.333262) (xy 270.255346 -31.368949) (xy 270.29204 -31.410371)
			(xy 270.322365 -31.456661) (xy 270.345683 -31.506846) (xy 270.361506 -31.559874) (xy 270.369502 -31.614631)
			(xy 270.369502 -31.66997) (xy 270.361506 -31.724727) (xy 270.345683 -31.777755) (xy 270.322365 -31.82794)
			(xy 270.29204 -31.87423) (xy 270.255345 -31.915652) (xy 270.213051 -31.951338) (xy 270.166044 -31.980539)
			(xy 270.115312 -32.002642) (xy 270.061919 -32.017183) (xy 270.034512 -32.021018) (xy 270.015208 -32.023304)
			(xy 269.989808 -32.052006) (xy 269.989808 -32.714184) (xy 277.047452 -32.714184) (xy 277.047452 -31.850584)
			(xy 277.047942 -31.820616) (xy 277.055765 -31.761194) (xy 277.071278 -31.703301) (xy 277.094214 -31.647928)
			(xy 277.124181 -31.596022) (xy 277.160668 -31.548472) (xy 277.203048 -31.506092) (xy 277.250598 -31.469605)
			(xy 277.302504 -31.439638) (xy 277.357877 -31.416702) (xy 277.41577 -31.401189) (xy 277.475192 -31.393366)
			(xy 277.535128 -31.393366) (xy 277.59455 -31.401189) (xy 277.652443 -31.416702) (xy 277.707816 -31.439638)
			(xy 277.759722 -31.469605) (xy 277.807272 -31.506092) (xy 277.849652 -31.548472) (xy 277.886139 -31.596022)
			(xy 277.916106 -31.647928) (xy 277.939042 -31.703301) (xy 277.954555 -31.761194) (xy 277.962378 -31.820616)
			(xy 277.962868 -31.850584) (xy 277.962868 -32.714184) (xy 277.962378 -32.744152) (xy 277.954555 -32.803574)
			(xy 277.939042 -32.861467) (xy 277.916106 -32.91684) (xy 277.886139 -32.968746) (xy 277.849652 -33.016296)
			(xy 277.807272 -33.058676) (xy 277.759722 -33.095163) (xy 277.707816 -33.12513) (xy 277.652443 -33.148066)
			(xy 277.59455 -33.163579) (xy 277.535128 -33.171402) (xy 277.475192 -33.171402) (xy 277.41577 -33.163579)
			(xy 277.357877 -33.148066) (xy 277.302504 -33.12513) (xy 277.250598 -33.095163) (xy 277.203048 -33.058676)
			(xy 277.160668 -33.016296) (xy 277.124181 -32.968746) (xy 277.094214 -32.91684) (xy 277.071278 -32.861467)
			(xy 277.055765 -32.803574) (xy 277.047942 -32.744152) (xy 277.047452 -32.714184) (xy 269.989808 -32.714184)
			(xy 269.989808 -34.520886) (xy 279.68956 -34.520886) (xy 279.68956 -33.657286) (xy 279.69005 -33.627318)
			(xy 279.697873 -33.567896) (xy 279.713386 -33.510003) (xy 279.736322 -33.45463) (xy 279.766289 -33.402724)
			(xy 279.802776 -33.355174) (xy 279.845156 -33.312794) (xy 279.892706 -33.276307) (xy 279.944612 -33.24634)
			(xy 279.999985 -33.223404) (xy 280.057878 -33.207891) (xy 280.1173 -33.200068) (xy 280.177236 -33.200068)
			(xy 280.236658 -33.207891) (xy 280.294551 -33.223404) (xy 280.349924 -33.24634) (xy 280.40183 -33.276307)
			(xy 280.44938 -33.312794) (xy 280.49176 -33.355174) (xy 280.528247 -33.402724) (xy 280.558214 -33.45463)
			(xy 280.58115 -33.510003) (xy 280.596663 -33.567896) (xy 280.604486 -33.627318) (xy 280.604976 -33.657286)
			(xy 280.604976 -34.520886) (xy 280.604486 -34.550854) (xy 280.596663 -34.610276) (xy 280.58115 -34.668169)
			(xy 280.558214 -34.723542) (xy 280.528247 -34.775448) (xy 280.49176 -34.822998) (xy 280.44938 -34.865378)
			(xy 280.40183 -34.901865) (xy 280.349924 -34.931832) (xy 280.294551 -34.954768) (xy 280.236658 -34.970281)
			(xy 280.177236 -34.978104) (xy 280.1173 -34.978104) (xy 280.057878 -34.970281) (xy 279.999985 -34.954768)
			(xy 279.944612 -34.931832) (xy 279.892706 -34.901865) (xy 279.845156 -34.865378) (xy 279.802776 -34.822998)
			(xy 279.766289 -34.775448) (xy 279.736322 -34.723542) (xy 279.713386 -34.668169) (xy 279.697873 -34.610276)
			(xy 279.69005 -34.550854) (xy 279.68956 -34.520886) (xy 269.989808 -34.520886) (xy 269.989808 -36.60013)
			(xy 270.198603 -36.60013) (xy 270.202607 -36.512245) (xy 270.214587 -36.425088) (xy 270.234442 -36.339381)
			(xy 270.262009 -36.255836) (xy 270.297059 -36.175143) (xy 270.339301 -36.097971) (xy 270.388386 -36.024961)
			(xy 270.443907 -35.956717) (xy 270.505404 -35.893804) (xy 270.572366 -35.836744) (xy 270.64424 -35.78601)
			(xy 270.72043 -35.742022) (xy 270.800304 -35.705144) (xy 270.883201 -35.675683) (xy 270.968433 -35.653881)
			(xy 271.055295 -35.639921) (xy 271.143066 -35.633917) (xy 271.23102 -35.63592) (xy 271.318427 -35.645912)
			(xy 271.404563 -35.663812) (xy 271.488715 -35.68947) (xy 271.570185 -35.722674) (xy 271.648298 -35.763148)
			(xy 271.722406 -35.810559) (xy 271.791897 -35.864512) (xy 271.804988 -35.876738) (xy 276.917148 -35.876738)
			(xy 276.921219 -35.821116) (xy 276.933345 -35.766679) (xy 276.953268 -35.714588) (xy 276.980564 -35.665953)
			(xy 277.01465 -35.62181) (xy 277.054799 -35.583101) (xy 277.100157 -35.55065) (xy 277.149757 -35.525149)
			(xy 277.202541 -35.507142) (xy 277.257384 -35.497012) (xy 277.313118 -35.494975) (xy 277.368555 -35.501075)
			(xy 277.422512 -35.515181) (xy 277.473841 -35.536993) (xy 277.521447 -35.566047) (xy 277.564315 -35.601722)
			(xy 277.601532 -35.643259) (xy 277.632305 -35.689772) (xy 277.655977 -35.740269) (xy 277.672045 -35.793676)
			(xy 277.680165 -35.848852) (xy 277.680674 -35.876738) (xy 280.988768 -35.876738) (xy 280.992839 -35.821116)
			(xy 281.004965 -35.766679) (xy 281.024888 -35.714588) (xy 281.052184 -35.665953) (xy 281.08627 -35.62181)
			(xy 281.126419 -35.583101) (xy 281.171777 -35.55065) (xy 281.221377 -35.525149) (xy 281.274161 -35.507142)
			(xy 281.329004 -35.497012) (xy 281.384738 -35.494975) (xy 281.440175 -35.501075) (xy 281.494132 -35.515181)
			(xy 281.545461 -35.536993) (xy 281.593067 -35.566047) (xy 281.635935 -35.601722) (xy 281.673152 -35.643259)
			(xy 281.703925 -35.689772) (xy 281.727597 -35.740269) (xy 281.743665 -35.793676) (xy 281.751785 -35.848852)
			(xy 281.752294 -35.876738) (xy 281.751785 -35.904624) (xy 281.743665 -35.9598) (xy 281.727597 -36.013207)
			(xy 281.703925 -36.063704) (xy 281.673152 -36.110217) (xy 281.635935 -36.151754) (xy 281.593067 -36.187429)
			(xy 281.545461 -36.216483) (xy 281.494132 -36.238295) (xy 281.440175 -36.252401) (xy 281.384738 -36.258501)
			(xy 281.329004 -36.256464) (xy 281.274161 -36.246334) (xy 281.221377 -36.228327) (xy 281.171777 -36.202826)
			(xy 281.126419 -36.170375) (xy 281.08627 -36.131666) (xy 281.052184 -36.087523) (xy 281.024888 -36.038888)
			(xy 281.004965 -35.986797) (xy 280.992839 -35.93236) (xy 280.988768 -35.876738) (xy 277.680674 -35.876738)
			(xy 277.680165 -35.904624) (xy 277.672045 -35.9598) (xy 277.655977 -36.013207) (xy 277.632305 -36.063704)
			(xy 277.601532 -36.110217) (xy 277.564315 -36.151754) (xy 277.521447 -36.187429) (xy 277.473841 -36.216483)
			(xy 277.422512 -36.238295) (xy 277.368555 -36.252401) (xy 277.313118 -36.258501) (xy 277.257384 -36.256464)
			(xy 277.202541 -36.246334) (xy 277.149757 -36.228327) (xy 277.100157 -36.202826) (xy 277.054799 -36.170375)
			(xy 277.01465 -36.131666) (xy 276.980564 -36.087523) (xy 276.953268 -36.038888) (xy 276.933345 -35.986797)
			(xy 276.921219 -35.93236) (xy 276.917148 -35.876738) (xy 271.804988 -35.876738) (xy 271.856193 -35.92456)
			(xy 271.914762 -35.990207) (xy 271.967119 -36.060907) (xy 272.012831 -36.136076) (xy 272.051517 -36.21509)
			(xy 272.082858 -36.297295) (xy 272.106593 -36.382009) (xy 272.122527 -36.46853) (xy 272.12631 -36.50996)
			(xy 278.813766 -36.50996) (xy 278.817837 -36.454338) (xy 278.829963 -36.399901) (xy 278.849886 -36.34781)
			(xy 278.877182 -36.299175) (xy 278.911268 -36.255032) (xy 278.951417 -36.216323) (xy 278.996775 -36.183872)
			(xy 279.046375 -36.158371) (xy 279.099159 -36.140364) (xy 279.154002 -36.130234) (xy 279.209736 -36.128197)
			(xy 279.265173 -36.134297) (xy 279.31913 -36.148403) (xy 279.370459 -36.170215) (xy 279.418065 -36.199269)
			(xy 279.460933 -36.234944) (xy 279.49815 -36.276481) (xy 279.528923 -36.322994) (xy 279.552595 -36.373491)
			(xy 279.568663 -36.426898) (xy 279.572588 -36.453572) (xy 282.128466 -36.453572) (xy 282.132537 -36.39795)
			(xy 282.144663 -36.343513) (xy 282.164586 -36.291422) (xy 282.191882 -36.242787) (xy 282.225968 -36.198644)
			(xy 282.266117 -36.159935) (xy 282.311475 -36.127484) (xy 282.361075 -36.101983) (xy 282.413859 -36.083976)
			(xy 282.468702 -36.073846) (xy 282.524436 -36.071809) (xy 282.579873 -36.077909) (xy 282.63383 -36.092015)
			(xy 282.685159 -36.113827) (xy 282.732765 -36.142881) (xy 282.775633 -36.178556) (xy 282.81285 -36.220093)
			(xy 282.843623 -36.266606) (xy 282.867295 -36.317103) (xy 282.883363 -36.37051) (xy 282.891483 -36.425686)
			(xy 282.891992 -36.453572) (xy 282.891483 -36.481458) (xy 282.883363 -36.536634) (xy 282.867295 -36.590041)
			(xy 282.843623 -36.640538) (xy 282.81285 -36.687051) (xy 282.775633 -36.728588) (xy 282.732765 -36.764263)
			(xy 282.685159 -36.793317) (xy 282.63383 -36.815129) (xy 282.579873 -36.829235) (xy 282.524436 -36.835335)
			(xy 282.468702 -36.833298) (xy 282.413859 -36.823168) (xy 282.361075 -36.805161) (xy 282.311475 -36.77966)
			(xy 282.266117 -36.747209) (xy 282.225968 -36.7085) (xy 282.191882 -36.664357) (xy 282.164586 -36.615722)
			(xy 282.144663 -36.563631) (xy 282.132537 -36.509194) (xy 282.128466 -36.453572) (xy 279.572588 -36.453572)
			(xy 279.576783 -36.482074) (xy 279.577292 -36.50996) (xy 279.576783 -36.537846) (xy 279.568663 -36.593022)
			(xy 279.552595 -36.646429) (xy 279.528923 -36.696926) (xy 279.49815 -36.743439) (xy 279.460933 -36.784976)
			(xy 279.418065 -36.820651) (xy 279.370459 -36.849705) (xy 279.31913 -36.871517) (xy 279.265173 -36.885623)
			(xy 279.209736 -36.891723) (xy 279.154002 -36.889686) (xy 279.099159 -36.879556) (xy 279.046375 -36.861549)
			(xy 278.996775 -36.836048) (xy 278.951417 -36.803597) (xy 278.911268 -36.764888) (xy 278.877182 -36.720745)
			(xy 278.849886 -36.67211) (xy 278.829963 -36.620019) (xy 278.817837 -36.565582) (xy 278.813766 -36.50996)
			(xy 272.12631 -36.50996) (xy 272.130527 -36.556142) (xy 272.131028 -36.60013) (xy 272.130527 -36.644118)
			(xy 272.122527 -36.73173) (xy 272.106593 -36.818251) (xy 272.082858 -36.902965) (xy 272.051517 -36.98517)
			(xy 272.012831 -37.064184) (xy 271.967119 -37.139353) (xy 271.914762 -37.210053) (xy 271.856193 -37.2757)
			(xy 271.791897 -37.335748) (xy 271.722406 -37.389701) (xy 271.648298 -37.437112) (xy 271.570185 -37.477586)
			(xy 271.488715 -37.51079) (xy 271.404563 -37.536448) (xy 271.318427 -37.554348) (xy 271.23102 -37.56434)
			(xy 271.143066 -37.566343) (xy 271.055295 -37.560339) (xy 270.968433 -37.546379) (xy 270.883201 -37.524577)
			(xy 270.800304 -37.495116) (xy 270.72043 -37.458238) (xy 270.64424 -37.41425) (xy 270.572366 -37.363516)
			(xy 270.505404 -37.306456) (xy 270.443907 -37.243543) (xy 270.388386 -37.175299) (xy 270.339301 -37.102289)
			(xy 270.297059 -37.025117) (xy 270.262009 -36.944424) (xy 270.234442 -36.860879) (xy 270.214587 -36.775172)
			(xy 270.202607 -36.688015) (xy 270.198603 -36.60013) (xy 269.989808 -36.60013) (xy 269.989808 -39.97198)
			(xy 284.095696 -39.97198) (xy 284.099767 -39.916358) (xy 284.111893 -39.861921) (xy 284.131816 -39.80983)
			(xy 284.159112 -39.761195) (xy 284.193198 -39.717052) (xy 284.233347 -39.678343) (xy 284.278705 -39.645892)
			(xy 284.328305 -39.620391) (xy 284.381089 -39.602384) (xy 284.435932 -39.592254) (xy 284.491666 -39.590217)
			(xy 284.547103 -39.596317) (xy 284.60106 -39.610423) (xy 284.652389 -39.632235) (xy 284.699995 -39.661289)
			(xy 284.742863 -39.696964) (xy 284.78008 -39.738501) (xy 284.810853 -39.785014) (xy 284.834525 -39.835511)
			(xy 284.850593 -39.888918) (xy 284.858713 -39.944094) (xy 284.859222 -39.97198) (xy 284.858713 -39.999866)
			(xy 284.850593 -40.055042) (xy 284.834525 -40.108449) (xy 284.810853 -40.158946) (xy 284.78008 -40.205459)
			(xy 284.742863 -40.246996) (xy 284.699995 -40.282671) (xy 284.652389 -40.311725) (xy 284.60106 -40.333537)
			(xy 284.547103 -40.347643) (xy 284.491666 -40.353743) (xy 284.435932 -40.351706) (xy 284.381089 -40.341576)
			(xy 284.328305 -40.323569) (xy 284.278705 -40.298068) (xy 284.233347 -40.265617) (xy 284.193198 -40.226908)
			(xy 284.159112 -40.182765) (xy 284.131816 -40.13413) (xy 284.111893 -40.082039) (xy 284.099767 -40.027602)
			(xy 284.095696 -39.97198) (xy 269.989808 -39.97198) (xy 269.989808 -40.452802) (xy 269.990232 -40.462872)
			(xy 269.997948 -40.481475) (xy 270.004794 -40.48887) (xy 270.223996 -40.708072) (xy 270.231393 -40.714922)
			(xy 270.249991 -40.722662) (xy 270.260064 -40.723058) (xy 279.281382 -40.723058) (xy 279.291444 -40.723498)
			(xy 279.310022 -40.73124) (xy 279.31745 -40.738044) (xy 280.25852 -41.679114) (xy 280.265373 -41.686509)
			(xy 280.273115 -41.705108) (xy 280.273506 -41.715182) (xy 280.273506 -43.566842) (xy 281.533344 -43.566842)
			(xy 281.537415 -43.51122) (xy 281.549541 -43.456783) (xy 281.569464 -43.404692) (xy 281.59676 -43.356057)
			(xy 281.630846 -43.311914) (xy 281.670995 -43.273205) (xy 281.716353 -43.240754) (xy 281.765953 -43.215253)
			(xy 281.818737 -43.197246) (xy 281.87358 -43.187116) (xy 281.929314 -43.185079) (xy 281.984751 -43.191179)
			(xy 282.038708 -43.205285) (xy 282.090037 -43.227097) (xy 282.137643 -43.256151) (xy 282.180511 -43.291826)
			(xy 282.217728 -43.333363) (xy 282.248501 -43.379876) (xy 282.272173 -43.430373) (xy 282.288241 -43.48378)
			(xy 282.296361 -43.538956) (xy 282.29687 -43.566842) (xy 282.296361 -43.594728) (xy 282.288241 -43.649904)
			(xy 282.272173 -43.703311) (xy 282.248501 -43.753808) (xy 282.217728 -43.800321) (xy 282.180511 -43.841858)
			(xy 282.162424 -43.85691) (xy 282.919676 -43.85691) (xy 282.923747 -43.801288) (xy 282.935873 -43.746851)
			(xy 282.955796 -43.69476) (xy 282.983092 -43.646125) (xy 283.017178 -43.601982) (xy 283.057327 -43.563273)
			(xy 283.102685 -43.530822) (xy 283.152285 -43.505321) (xy 283.205069 -43.487314) (xy 283.259912 -43.477184)
			(xy 283.315646 -43.475147) (xy 283.371083 -43.481247) (xy 283.42504 -43.495353) (xy 283.476369 -43.517165)
			(xy 283.523975 -43.546219) (xy 283.566843 -43.581894) (xy 283.60406 -43.623431) (xy 283.634833 -43.669944)
			(xy 283.658505 -43.720441) (xy 283.674573 -43.773848) (xy 283.682693 -43.829024) (xy 283.683202 -43.85691)
			(xy 283.682693 -43.884796) (xy 283.674573 -43.939972) (xy 283.658505 -43.993379) (xy 283.634833 -44.043876)
			(xy 283.60406 -44.090389) (xy 283.566843 -44.131926) (xy 283.523975 -44.167601) (xy 283.476369 -44.196655)
			(xy 283.42504 -44.218467) (xy 283.371083 -44.232573) (xy 283.315646 -44.238673) (xy 283.259912 -44.236636)
			(xy 283.205069 -44.226506) (xy 283.152285 -44.208499) (xy 283.102685 -44.182998) (xy 283.057327 -44.150547)
			(xy 283.017178 -44.111838) (xy 282.983092 -44.067695) (xy 282.955796 -44.01906) (xy 282.935873 -43.966969)
			(xy 282.923747 -43.912532) (xy 282.919676 -43.85691) (xy 282.162424 -43.85691) (xy 282.137643 -43.877533)
			(xy 282.090037 -43.906587) (xy 282.038708 -43.928399) (xy 281.984751 -43.942505) (xy 281.929314 -43.948605)
			(xy 281.87358 -43.946568) (xy 281.818737 -43.936438) (xy 281.765953 -43.918431) (xy 281.716353 -43.89293)
			(xy 281.670995 -43.860479) (xy 281.630846 -43.82177) (xy 281.59676 -43.777627) (xy 281.569464 -43.728992)
			(xy 281.549541 -43.676901) (xy 281.537415 -43.622464) (xy 281.533344 -43.566842) (xy 280.273506 -43.566842)
			(xy 280.273506 -45.35424) (xy 282.903674 -45.35424) (xy 282.907745 -45.298618) (xy 282.919871 -45.244181)
			(xy 282.939794 -45.19209) (xy 282.96709 -45.143455) (xy 283.001176 -45.099312) (xy 283.041325 -45.060603)
			(xy 283.086683 -45.028152) (xy 283.136283 -45.002651) (xy 283.189067 -44.984644) (xy 283.24391 -44.974514)
			(xy 283.299644 -44.972477) (xy 283.355081 -44.978577) (xy 283.409038 -44.992683) (xy 283.460367 -45.014495)
			(xy 283.507973 -45.043549) (xy 283.550841 -45.079224) (xy 283.588058 -45.120761) (xy 283.618831 -45.167274)
			(xy 283.642503 -45.217771) (xy 283.658571 -45.271178) (xy 283.666691 -45.326354) (xy 283.6672 -45.35424)
			(xy 283.666691 -45.382126) (xy 283.658571 -45.437302) (xy 283.642503 -45.490709) (xy 283.618831 -45.541206)
			(xy 283.588058 -45.587719) (xy 283.550841 -45.629256) (xy 283.507973 -45.664931) (xy 283.460367 -45.693985)
			(xy 283.409038 -45.715797) (xy 283.355081 -45.729903) (xy 283.299644 -45.736003) (xy 283.24391 -45.733966)
			(xy 283.189067 -45.723836) (xy 283.136283 -45.705829) (xy 283.086683 -45.680328) (xy 283.041325 -45.647877)
			(xy 283.001176 -45.609168) (xy 282.96709 -45.565025) (xy 282.939794 -45.51639) (xy 282.919871 -45.464299)
			(xy 282.907745 -45.409862) (xy 282.903674 -45.35424) (xy 280.273506 -45.35424) (xy 280.273506 -46.693836)
			(xy 282.876244 -46.693836) (xy 282.87673 -46.666585) (xy 282.884486 -46.612637) (xy 282.899841 -46.560342)
			(xy 282.922483 -46.510765) (xy 282.951949 -46.464915) (xy 282.98764 -46.423724) (xy 283.028831 -46.388033)
			(xy 283.074681 -46.358567) (xy 283.124258 -46.335925) (xy 283.176553 -46.32057) (xy 283.230501 -46.312814)
			(xy 283.285003 -46.312814) (xy 283.338951 -46.32057) (xy 283.391246 -46.335925) (xy 283.440823 -46.358567)
			(xy 283.486673 -46.388033) (xy 283.527864 -46.423724) (xy 283.563555 -46.464915) (xy 283.593021 -46.510765)
			(xy 283.615663 -46.560342) (xy 283.631018 -46.612637) (xy 283.638774 -46.666585) (xy 283.63926 -46.693836)
			(xy 283.638793 -46.720264) (xy 283.631483 -46.772612) (xy 283.617008 -46.823447) (xy 283.595646 -46.871793)
			(xy 283.58211 -46.894496) (xy 283.576014 -46.904402) (xy 283.573474 -46.927262) (xy 283.607764 -47.023782)
			(xy 283.623766 -47.040038) (xy 283.634942 -47.043848) (xy 283.65945 -47.05292) (xy 283.705902 -47.076862)
			(xy 283.748655 -47.106917) (xy 283.786907 -47.142524) (xy 283.819943 -47.183017) (xy 283.847147 -47.227638)
			(xy 283.868009 -47.275553) (xy 283.882139 -47.325866) (xy 283.889273 -47.377636) (xy 283.889704 -47.403766)
			(xy 283.889218 -47.431017) (xy 283.881462 -47.484965) (xy 283.866107 -47.53726) (xy 283.843465 -47.586837)
			(xy 283.813999 -47.632687) (xy 283.778308 -47.673878) (xy 283.737117 -47.709569) (xy 283.691267 -47.739035)
			(xy 283.64169 -47.761677) (xy 283.589395 -47.777032) (xy 283.535447 -47.784788) (xy 283.480945 -47.784788)
			(xy 283.426997 -47.777032) (xy 283.374702 -47.761677) (xy 283.325125 -47.739035) (xy 283.279275 -47.709569)
			(xy 283.238084 -47.673878) (xy 283.202393 -47.632687) (xy 283.172927 -47.586837) (xy 283.150285 -47.53726)
			(xy 283.13493 -47.484965) (xy 283.127174 -47.431017) (xy 283.126688 -47.403766) (xy 283.127163 -47.377339)
			(xy 283.134472 -47.324991) (xy 283.148945 -47.274156) (xy 283.170304 -47.225809) (xy 283.183838 -47.203106)
			(xy 283.189934 -47.1932) (xy 283.192474 -47.17034) (xy 283.158184 -47.07382) (xy 283.142182 -47.057564)
			(xy 283.131006 -47.053754) (xy 283.106488 -47.04471) (xy 283.060036 -47.020762) (xy 283.017286 -46.990701)
			(xy 282.979036 -46.95509) (xy 282.946001 -46.914594) (xy 282.918799 -46.869971) (xy 282.897938 -46.822053)
			(xy 282.883809 -46.771739) (xy 282.876675 -46.719967) (xy 282.876244 -46.693836) (xy 280.273506 -46.693836)
			(xy 280.273506 -48.30699) (xy 282.753814 -48.30699) (xy 282.757885 -48.251368) (xy 282.770011 -48.196931)
			(xy 282.789934 -48.14484) (xy 282.81723 -48.096205) (xy 282.851316 -48.052062) (xy 282.891465 -48.013353)
			(xy 282.936823 -47.980902) (xy 282.986423 -47.955401) (xy 283.039207 -47.937394) (xy 283.09405 -47.927264)
			(xy 283.149784 -47.925227) (xy 283.205221 -47.931327) (xy 283.259178 -47.945433) (xy 283.310507 -47.967245)
			(xy 283.358113 -47.996299) (xy 283.400981 -48.031974) (xy 283.438198 -48.073511) (xy 283.468971 -48.120024)
			(xy 283.492643 -48.170521) (xy 283.508711 -48.223928) (xy 283.516831 -48.279104) (xy 283.51734 -48.30699)
			(xy 283.516831 -48.334876) (xy 283.508711 -48.390052) (xy 283.492643 -48.443459) (xy 283.468971 -48.493956)
			(xy 283.438198 -48.540469) (xy 283.400981 -48.582006) (xy 283.358113 -48.617681) (xy 283.310507 -48.646735)
			(xy 283.259178 -48.668547) (xy 283.205221 -48.682653) (xy 283.149784 -48.688753) (xy 283.09405 -48.686716)
			(xy 283.039207 -48.676586) (xy 282.986423 -48.658579) (xy 282.936823 -48.633078) (xy 282.891465 -48.600627)
			(xy 282.851316 -48.561918) (xy 282.81723 -48.517775) (xy 282.789934 -48.46914) (xy 282.770011 -48.417049)
			(xy 282.757885 -48.362612) (xy 282.753814 -48.30699) (xy 280.273506 -48.30699) (xy 280.273506 -48.89246)
			(xy 281.413964 -48.89246) (xy 281.418035 -48.836838) (xy 281.430161 -48.782401) (xy 281.450084 -48.73031)
			(xy 281.47738 -48.681675) (xy 281.511466 -48.637532) (xy 281.551615 -48.598823) (xy 281.596973 -48.566372)
			(xy 281.646573 -48.540871) (xy 281.699357 -48.522864) (xy 281.7542 -48.512734) (xy 281.809934 -48.510697)
			(xy 281.865371 -48.516797) (xy 281.919328 -48.530903) (xy 281.970657 -48.552715) (xy 282.018263 -48.581769)
			(xy 282.061131 -48.617444) (xy 282.098348 -48.658981) (xy 282.129121 -48.705494) (xy 282.152793 -48.755991)
			(xy 282.168861 -48.809398) (xy 282.176981 -48.864574) (xy 282.17749 -48.89246) (xy 282.176981 -48.920346)
			(xy 282.168861 -48.975522) (xy 282.152793 -49.028929) (xy 282.129121 -49.079426) (xy 282.098348 -49.125939)
			(xy 282.061131 -49.167476) (xy 282.018263 -49.203151) (xy 281.970657 -49.232205) (xy 281.919328 -49.254017)
			(xy 281.865371 -49.268123) (xy 281.809934 -49.274223) (xy 281.7542 -49.272186) (xy 281.699357 -49.262056)
			(xy 281.646573 -49.244049) (xy 281.596973 -49.218548) (xy 281.551615 -49.186097) (xy 281.511466 -49.147388)
			(xy 281.47738 -49.103245) (xy 281.450084 -49.05461) (xy 281.430161 -49.002519) (xy 281.418035 -48.948082)
			(xy 281.413964 -48.89246) (xy 280.273506 -48.89246) (xy 280.273506 -51.198018) (xy 280.273933 -51.208087)
			(xy 280.281652 -51.226686) (xy 280.288492 -51.234086) (xy 280.432764 -51.378358) (xy 280.440164 -51.385199)
			(xy 280.458763 -51.392917) (xy 280.468832 -51.393344)
		)
		(stroke
			(width 0)
			(type solid)
		)
		(fill yes)
		(layer "In9.Cu")
		(net "GND")
	)
	(gr_poly
		(pts
			(xy 256.932684 -51.393344) (xy 256.941916 -51.392947) (xy 256.95918 -51.386401) (xy 256.972999 -51.374155)
			(xy 256.977642 -51.366166) (xy 257.025902 -51.274218) (xy 257.024378 -51.246278) (xy 257.01625 -51.234594)
			(xy 257.004799 -51.217281) (xy 256.985323 -51.180623) (xy 256.977388 -51.161442) (xy 256.975356 -51.156108)
			(xy 256.969511 -51.140481) (xy 256.960231 -51.108431) (xy 256.956814 -51.0921) (xy 256.956814 -51.091338)
			(xy 256.953736 -51.079744) (xy 256.938759 -51.061049) (xy 256.928112 -51.055524) (xy 256.852674 -51.021234)
			(xy 256.841264 -51.016807) (xy 256.816854 -51.017989) (xy 256.805938 -51.02352) (xy 256.783989 -51.035828)
			(xy 256.737546 -51.055204) (xy 256.688961 -51.068312) (xy 256.639075 -51.074924) (xy 256.613914 -51.075336)
			(xy 256.586658 -51.074874) (xy 256.532702 -51.067118) (xy 256.480399 -51.051762) (xy 256.430813 -51.029119)
			(xy 256.384955 -50.999649) (xy 256.343757 -50.963953) (xy 256.308059 -50.922757) (xy 256.278588 -50.876899)
			(xy 256.255943 -50.827315) (xy 256.240585 -50.775012) (xy 256.232827 -50.721056) (xy 256.232827 -50.666544)
			(xy 256.240585 -50.612588) (xy 256.255943 -50.560285) (xy 256.278588 -50.510701) (xy 256.308059 -50.464843)
			(xy 256.343757 -50.423647) (xy 256.384955 -50.387951) (xy 256.430813 -50.358481) (xy 256.480399 -50.335838)
			(xy 256.532702 -50.320482) (xy 256.586658 -50.312726) (xy 256.613914 -50.31232) (xy 256.64024 -50.312756)
			(xy 256.692395 -50.319984) (xy 256.74306 -50.334313) (xy 256.791274 -50.355473) (xy 256.836121 -50.38306)
			(xy 256.876749 -50.416552) (xy 256.912386 -50.455311) (xy 256.942356 -50.498602) (xy 256.96609 -50.545603)
			(xy 256.983135 -50.59542) (xy 256.988564 -50.621184) (xy 256.988564 -50.621692) (xy 256.991627 -50.633337)
			(xy 257.006616 -50.652137) (xy 257.017266 -50.65776) (xy 257.092704 -50.69205) (xy 257.104114 -50.696483)
			(xy 257.12853 -50.69531) (xy 257.13944 -50.689764) (xy 257.161389 -50.677456) (xy 257.207831 -50.658077)
			(xy 257.256416 -50.644967) (xy 257.306303 -50.638352) (xy 257.331464 -50.637948) (xy 257.358494 -50.638422)
			(xy 257.412013 -50.646062) (xy 257.463917 -50.66118) (xy 257.513167 -50.683472) (xy 257.558778 -50.712493)
			(xy 257.599836 -50.747661) (xy 257.635519 -50.788273) (xy 257.665112 -50.833515) (xy 257.688023 -50.882481)
			(xy 257.703793 -50.934191) (xy 257.712106 -50.987608) (xy 257.712972 -51.01463) (xy 257.712972 -51.01971)
			(xy 257.712464 -51.048258) (xy 257.703948 -51.104716) (xy 257.687109 -51.159273) (xy 257.662324 -51.210709)
			(xy 257.646678 -51.234594) (xy 257.63855 -51.246278) (xy 257.637026 -51.274218) (xy 257.685286 -51.366166)
			(xy 257.689933 -51.374152) (xy 257.703754 -51.386393) (xy 257.721013 -51.392949) (xy 257.730244 -51.393344)
			(xy 258.622292 -51.393344) (xy 258.632261 -51.392872) (xy 258.650709 -51.385308) (xy 258.658106 -51.378612)
			(xy 259.176266 -50.860452) (xy 259.180076 -50.852578) (xy 259.189982 -50.833528) (xy 259.190236 -50.833274)
			(xy 259.194046 -50.82667) (xy 259.197348 -50.821082) (xy 259.201412 -50.806858) (xy 259.204714 -50.795174)
			(xy 259.204714 -50.1904) (xy 259.204459 -50.182988) (xy 259.200196 -50.16879) (xy 259.196332 -50.16246)
			(xy 259.181498 -50.139007) (xy 259.158037 -50.088719) (xy 259.142115 -50.03556) (xy 259.134069 -49.980654)
			(xy 259.134068 -49.925162) (xy 259.142112 -49.870257) (xy 259.158031 -49.817097) (xy 259.181489 -49.766807)
			(xy 259.196332 -49.74336) (xy 259.200192 -49.737029) (xy 259.204445 -49.722831) (xy 259.204714 -49.71542)
			(xy 259.204714 -49.1744) (xy 259.204459 -49.166988) (xy 259.200196 -49.15279) (xy 259.196332 -49.14646)
			(xy 259.181498 -49.123007) (xy 259.158037 -49.072719) (xy 259.142115 -49.01956) (xy 259.134069 -48.964654)
			(xy 259.134068 -48.909162) (xy 259.142112 -48.854257) (xy 259.158031 -48.801097) (xy 259.181489 -48.750807)
			(xy 259.196332 -48.72736) (xy 259.200192 -48.721029) (xy 259.204445 -48.706831) (xy 259.204714 -48.69942)
			(xy 259.204714 -47.629572) (xy 259.202174 -47.61865) (xy 259.19938 -47.613062) (xy 259.186657 -47.586292)
			(xy 259.168683 -47.529813) (xy 259.159588 -47.471246) (xy 259.159586 -47.411976) (xy 259.168678 -47.353408)
			(xy 259.186649 -47.296928) (xy 259.19938 -47.270162) (xy 259.202174 -47.264574) (xy 259.204714 -47.253652)
			(xy 259.204714 -46.1264) (xy 259.204459 -46.118988) (xy 259.200196 -46.10479) (xy 259.196332 -46.09846)
			(xy 259.181498 -46.075007) (xy 259.158037 -46.024719) (xy 259.142115 -45.97156) (xy 259.134069 -45.916654)
			(xy 259.134068 -45.861162) (xy 259.142112 -45.806257) (xy 259.158031 -45.753097) (xy 259.181489 -45.702807)
			(xy 259.196332 -45.67936) (xy 259.200192 -45.673029) (xy 259.204445 -45.658831) (xy 259.204714 -45.65142)
			(xy 259.204714 -45.1104) (xy 259.204459 -45.102988) (xy 259.200196 -45.08879) (xy 259.196332 -45.08246)
			(xy 259.181498 -45.059007) (xy 259.158037 -45.008719) (xy 259.142115 -44.95556) (xy 259.134069 -44.900654)
			(xy 259.134068 -44.845162) (xy 259.142112 -44.790257) (xy 259.158031 -44.737097) (xy 259.181489 -44.686807)
			(xy 259.196332 -44.66336) (xy 259.200192 -44.657029) (xy 259.204445 -44.642831) (xy 259.204714 -44.63542)
			(xy 259.204714 -44.0944) (xy 259.204459 -44.086988) (xy 259.200196 -44.07279) (xy 259.196332 -44.06646)
			(xy 259.181498 -44.043007) (xy 259.158037 -43.992719) (xy 259.142115 -43.93956) (xy 259.134069 -43.884654)
			(xy 259.134068 -43.829162) (xy 259.142112 -43.774257) (xy 259.158031 -43.721097) (xy 259.181489 -43.670807)
			(xy 259.196332 -43.64736) (xy 259.200192 -43.641029) (xy 259.204445 -43.626831) (xy 259.204714 -43.61942)
			(xy 259.204714 -43.0784) (xy 259.204459 -43.070988) (xy 259.200196 -43.05679) (xy 259.196332 -43.05046)
			(xy 259.181498 -43.027007) (xy 259.158037 -42.976719) (xy 259.142115 -42.92356) (xy 259.134069 -42.868654)
			(xy 259.134068 -42.813162) (xy 259.142112 -42.758257) (xy 259.158031 -42.705097) (xy 259.181489 -42.654807)
			(xy 259.196332 -42.63136) (xy 259.200192 -42.625029) (xy 259.204445 -42.610831) (xy 259.204714 -42.60342)
			(xy 259.204714 -41.423844) (xy 259.20431 -41.41399) (xy 259.196999 -41.395692) (xy 259.19049 -41.388284)
			(xy 259.17525 -41.37279) (xy 259.172161 -41.369736) (xy 259.16514 -41.364622) (xy 259.16128 -41.36263)
			(xy 259.138674 -41.351708) (xy 259.130292 -41.350692) (xy 259.102847 -41.346884) (xy 259.049376 -41.332367)
			(xy 258.998565 -41.310272) (xy 258.951483 -41.281064) (xy 258.909117 -41.245356) (xy 258.872359 -41.203899)
			(xy 258.84198 -41.157562) (xy 258.818619 -41.107321) (xy 258.802767 -41.054231) (xy 258.794757 -40.999406)
			(xy 258.794756 -40.944) (xy 258.802766 -40.889175) (xy 258.818617 -40.836084) (xy 258.841977 -40.785843)
			(xy 258.872355 -40.739506) (xy 258.909113 -40.698048) (xy 258.951478 -40.662339) (xy 258.99856 -40.63313)
			(xy 259.049371 -40.611035) (xy 259.102842 -40.596517) (xy 259.130292 -40.592756) (xy 259.138674 -40.59174)
			(xy 259.16128 -40.580818) (xy 259.165139 -40.578823) (xy 259.172166 -40.573717) (xy 259.17525 -40.570658)
			(xy 259.19049 -40.555164) (xy 259.197003 -40.547757) (xy 259.204316 -40.52946) (xy 259.204714 -40.519604)
			(xy 259.204714 -38.432232) (xy 259.2043 -38.422205) (xy 259.196636 -38.403675) (xy 259.182463 -38.38949)
			(xy 259.16394 -38.381809) (xy 259.153914 -38.381432) (xy 257.484118 -38.381432) (xy 257.474979 -38.381811)
			(xy 257.457863 -38.388225) (xy 257.44409 -38.400241) (xy 257.439414 -38.408102) (xy 257.39725 -38.486842)
			(xy 257.394237 -38.492877) (xy 257.391158 -38.506004) (xy 257.391154 -38.51275) (xy 257.391662 -38.527228)
			(xy 257.399536 -38.539166) (xy 257.414669 -38.562785) (xy 257.438593 -38.613521) (xy 257.454837 -38.667212)
			(xy 257.463051 -38.722701) (xy 257.463544 -38.750748) (xy 257.463055 -38.777998) (xy 257.455293 -38.831942)
			(xy 257.439934 -38.884233) (xy 257.417291 -38.933807) (xy 257.387824 -38.979654) (xy 257.352133 -39.020841)
			(xy 257.310944 -39.056531) (xy 257.265096 -39.085997) (xy 257.215522 -39.108638) (xy 257.163231 -39.123996)
			(xy 257.109286 -39.131756) (xy 257.082036 -39.132256) (xy 257.053736 -39.131737) (xy 256.997758 -39.123368)
			(xy 256.943629 -39.106824) (xy 256.892538 -39.082468) (xy 256.845604 -39.050832) (xy 256.803857 -39.012612)
			(xy 256.768212 -38.968646) (xy 256.75336 -38.94455) (xy 256.746756 -38.933374) (xy 256.725166 -38.920166)
			(xy 256.679954 -38.917626) (xy 256.615692 -38.913816) (xy 256.592832 -38.92423) (xy 256.585212 -38.93439)
			(xy 256.567023 -38.957266) (xy 256.524868 -38.997741) (xy 256.477035 -39.031316) (xy 256.424642 -39.057207)
			(xy 256.368915 -39.074808) (xy 256.311156 -39.083708) (xy 256.281936 -39.08425) (xy 256.254682 -39.083767)
			(xy 256.200728 -39.076015) (xy 256.148427 -39.060663) (xy 256.098842 -39.038024) (xy 256.052984 -39.00856)
			(xy 256.011786 -38.972869) (xy 255.976087 -38.931678) (xy 255.946613 -38.885826) (xy 255.923964 -38.836247)
			(xy 255.908602 -38.783948) (xy 255.900839 -38.729996) (xy 255.900428 -38.702742) (xy 255.900987 -38.672656)
			(xy 255.91043 -38.613231) (xy 255.929105 -38.556031) (xy 255.942338 -38.529006) (xy 255.948434 -38.517068)
			(xy 255.947418 -38.490906) (xy 255.895094 -38.405562) (xy 255.89026 -38.398404) (xy 255.876816 -38.387578)
			(xy 255.860544 -38.381819) (xy 255.851914 -38.381432) (xy 253.485142 -38.381432) (xy 253.476284 -38.381851)
			(xy 253.459644 -38.387946) (xy 253.45263 -38.39337) (xy 253.241048 -38.604952) (xy 253.163578 -38.682168)
			(xy 253.139678 -38.705332) (xy 253.086872 -38.745848) (xy 253.029228 -38.779123) (xy 252.967732 -38.804587)
			(xy 252.903439 -38.821803) (xy 252.837447 -38.830476) (xy 252.804168 -38.831012) (xy 251.188728 -38.831012)
			(xy 251.155452 -38.830464) (xy 251.089469 -38.82177) (xy 251.025185 -38.804542) (xy 250.963699 -38.779073)
			(xy 250.906061 -38.745798) (xy 250.853258 -38.705287) (xy 250.829318 -38.682168) (xy 249.98172 -37.83457)
			(xy 249.958557 -37.810669) (xy 249.918042 -37.757863) (xy 249.884769 -37.700219) (xy 249.859307 -37.638723)
			(xy 249.842093 -37.57443) (xy 249.833421 -37.508439) (xy 249.832876 -37.47516) (xy 249.832903 -37.463333)
			(xy 249.833919 -37.439701) (xy 249.834908 -37.427916) (xy 249.835162 -37.42563) (xy 249.835162 -37.42436)
			(xy 249.83874 -37.393446) (xy 249.852473 -37.332746) (xy 249.873512 -37.274176) (xy 249.901541 -37.218612)
			(xy 249.936142 -37.166884) (xy 249.976798 -37.119765) (xy 250.022901 -37.077961) (xy 250.073761 -37.042096)
			(xy 250.128618 -37.012706) (xy 250.186652 -36.990231) (xy 250.246995 -36.975006) (xy 250.308744 -36.967261)
			(xy 250.33986 -36.966652) (xy 250.34113 -36.966652) (xy 250.373363 -36.967147) (xy 250.437312 -36.975297)
			(xy 250.468638 -36.982908) (xy 250.501233 -36.99194) (xy 250.563869 -37.017466) (xy 250.622563 -37.051079)
			(xy 250.676276 -37.092187) (xy 250.70054 -37.11575) (xy 251.384308 -37.799518) (xy 251.391703 -37.806372)
			(xy 251.410302 -37.814116) (xy 251.420376 -37.814504) (xy 252.049788 -37.814504) (xy 252.06054 -37.814031)
			(xy 252.080154 -37.805222) (xy 252.087634 -37.797486) (xy 252.13818 -37.741352) (xy 252.144746 -37.733234)
			(xy 252.151302 -37.713431) (xy 252.15088 -37.702998) (xy 252.15088 -37.702236) (xy 252.149914 -37.692295)
			(xy 252.148898 -37.672346) (xy 252.148848 -37.662358) (xy 252.149337 -37.635108) (xy 252.157098 -37.581162)
			(xy 252.172456 -37.52887) (xy 252.195099 -37.479295) (xy 252.224566 -37.433447) (xy 252.260257 -37.392258)
			(xy 252.301445 -37.356567) (xy 252.347293 -37.3271) (xy 252.396868 -37.304457) (xy 252.44916 -37.289098)
			(xy 252.503106 -37.281337) (xy 252.530356 -37.28085) (xy 252.559407 -37.281398) (xy 252.616835 -37.290213)
			(xy 252.672265 -37.307631) (xy 252.724413 -37.33325) (xy 252.772076 -37.366476) (xy 252.814152 -37.406544)
			(xy 252.832362 -37.429186) (xy 252.838458 -37.43706) (xy 252.84684 -37.44214) (xy 252.850999 -37.444439)
			(xy 252.859945 -37.447639) (xy 252.86462 -37.44849) (xy 252.932946 -37.459666) (xy 252.942522 -37.460804)
			(xy 252.96133 -37.456624) (xy 252.969522 -37.451538) (xy 252.969776 -37.451284) (xy 252.997461 -37.433229)
			(xy 253.056577 -37.40367) (xy 253.087632 -37.392356) (xy 253.114463 -37.383492) (xy 253.169587 -37.371062)
			(xy 253.225748 -37.364803) (xy 253.254002 -37.364416) (xy 259.153914 -37.364416) (xy 259.163921 -37.363926)
			(xy 259.182411 -37.356264) (xy 259.196563 -37.342113) (xy 259.204226 -37.323623) (xy 259.204714 -37.313616)
			(xy 259.204714 -31.63316) (xy 259.203952 -31.629096) (xy 259.201669 -31.613896) (xy 259.199252 -31.583252)
			(xy 259.199126 -31.567882) (xy 259.199246 -31.552512) (xy 259.201664 -31.521867) (xy 259.203952 -31.506668)
			(xy 259.204714 -31.502604) (xy 259.204714 -30.681168) (xy 259.204591 -30.676355) (xy 259.2028 -30.666897)
			(xy 259.201158 -30.662372) (xy 259.191506 -30.637734) (xy 259.18541 -30.630876) (xy 259.167288 -30.609786)
			(xy 259.136708 -30.563347) (xy 259.113189 -30.512963) (xy 259.097228 -30.459699) (xy 259.089164 -30.404684)
			(xy 259.089166 -30.34908) (xy 259.097236 -30.294066) (xy 259.113201 -30.240804) (xy 259.136725 -30.190421)
			(xy 259.16731 -30.143985) (xy 259.18541 -30.122876) (xy 259.191506 -30.116018) (xy 259.201158 -30.09138)
			(xy 259.202846 -30.086867) (xy 259.204643 -30.077402) (xy 259.204714 -30.072584) (xy 259.204714 -29.909008)
			(xy 259.190998 -29.874972) (xy 259.185156 -29.868368) (xy 259.16711 -29.847302) (xy 259.136667 -29.800934)
			(xy 259.113259 -29.750645) (xy 259.097381 -29.697498) (xy 259.089366 -29.642611) (xy 259.08889 -29.614876)
			(xy 259.08889 -29.614368) (xy 259.089496 -29.583501) (xy 259.099463 -29.522575) (xy 259.119114 -29.464052)
			(xy 259.147936 -29.409458) (xy 259.166106 -29.384498) (xy 259.17078 -29.377759) (xy 259.175971 -29.362213)
			(xy 259.176266 -29.354018) (xy 259.176266 -29.062934) (xy 259.175961 -29.054739) (xy 259.170785 -29.039188)
			(xy 259.166106 -29.032454) (xy 259.149906 -29.010239) (xy 259.123374 -28.962085) (xy 259.104021 -28.910624)
			(xy 259.092248 -28.856919) (xy 259.088299 -28.802081) (xy 259.092254 -28.747243) (xy 259.104032 -28.69354)
			(xy 259.12339 -28.64208) (xy 259.149927 -28.593929) (xy 259.166106 -28.571698) (xy 259.17078 -28.564959)
			(xy 259.175971 -28.549413) (xy 259.176266 -28.541218) (xy 259.176266 -28.368752) (xy 259.176493 -28.361714)
			(xy 259.180365 -28.348181) (xy 259.183886 -28.342082) (xy 259.19684 -28.322016) (xy 259.200497 -28.315758)
			(xy 259.204488 -28.30183) (xy 259.204714 -28.294584) (xy 259.204714 -27.872436) (xy 259.20428 -27.862371)
			(xy 259.196551 -27.843782) (xy 259.189728 -27.836368) (xy 258.950206 -27.596846) (xy 258.94281 -27.589994)
			(xy 258.924212 -27.58225) (xy 258.914138 -27.58186) (xy 249.59945 -27.58186) (xy 249.587124 -27.582455)
			(xy 249.565294 -27.593904) (xy 249.557794 -27.603704) (xy 249.540634 -27.627665) (xy 249.501128 -27.6714)
			(xy 249.456337 -27.709706) (xy 249.407002 -27.74195) (xy 249.353939 -27.767598) (xy 249.298024 -27.786227)
			(xy 249.240181 -27.797529) (xy 249.181366 -27.801317) (xy 249.122551 -27.797529) (xy 249.064708 -27.786227)
			(xy 249.008793 -27.767598) (xy 248.95573 -27.74195) (xy 248.906395 -27.709706) (xy 248.861604 -27.6714)
			(xy 248.822098 -27.627665) (xy 248.804938 -27.603704) (xy 248.797323 -27.59404) (xy 248.775562 -27.582641)
			(xy 248.763282 -27.58186) (xy 244.627908 -27.58186) (xy 244.617838 -27.582283) (xy 244.599238 -27.590002)
			(xy 244.59184 -27.596846) (xy 244.322854 -27.865832) (xy 244.316504 -27.877262) (xy 244.314726 -27.88412)
			(xy 244.307 -27.91235) (xy 244.284089 -27.966205) (xy 244.253222 -28.015929) (xy 244.215126 -28.060359)
			(xy 244.170692 -28.09845) (xy 244.120963 -28.12931) (xy 244.067106 -28.152215) (xy 244.038882 -28.159964)
			(xy 244.032024 -28.161742) (xy 244.020594 -28.168092) (xy 244.004846 -28.18384) (xy 243.998001 -28.191239)
			(xy 243.990274 -28.209837) (xy 243.98986 -28.219908) (xy 243.98986 -29.114242) (xy 251.047504 -29.114242)
			(xy 251.047504 -28.250642) (xy 251.047994 -28.220674) (xy 251.055817 -28.161252) (xy 251.07133 -28.103359)
			(xy 251.094266 -28.047986) (xy 251.124233 -27.99608) (xy 251.16072 -27.94853) (xy 251.2031 -27.90615)
			(xy 251.25065 -27.869663) (xy 251.302556 -27.839696) (xy 251.357929 -27.81676) (xy 251.415822 -27.801247)
			(xy 251.475244 -27.793424) (xy 251.53518 -27.793424) (xy 251.594602 -27.801247) (xy 251.652495 -27.81676)
			(xy 251.707868 -27.839696) (xy 251.759774 -27.869663) (xy 251.807324 -27.90615) (xy 251.849704 -27.94853)
			(xy 251.886191 -27.99608) (xy 251.916158 -28.047986) (xy 251.939094 -28.103359) (xy 251.954607 -28.161252)
			(xy 251.96243 -28.220674) (xy 251.96292 -28.250642) (xy 251.96292 -28.469082) (xy 255.952496 -28.469082)
			(xy 255.956567 -28.41346) (xy 255.968693 -28.359023) (xy 255.988616 -28.306932) (xy 256.015912 -28.258297)
			(xy 256.049998 -28.214154) (xy 256.090147 -28.175445) (xy 256.135505 -28.142994) (xy 256.185105 -28.117493)
			(xy 256.237889 -28.099486) (xy 256.292732 -28.089356) (xy 256.348466 -28.087319) (xy 256.403903 -28.093419)
			(xy 256.45786 -28.107525) (xy 256.509189 -28.129337) (xy 256.556795 -28.158391) (xy 256.599663 -28.194066)
			(xy 256.63688 -28.235603) (xy 256.667653 -28.282116) (xy 256.691325 -28.332613) (xy 256.707393 -28.38602)
			(xy 256.715513 -28.441196) (xy 256.716022 -28.469082) (xy 256.715513 -28.496968) (xy 256.707393 -28.552144)
			(xy 256.691325 -28.605551) (xy 256.667653 -28.656048) (xy 256.63688 -28.702561) (xy 256.599663 -28.744098)
			(xy 256.556795 -28.779773) (xy 256.509189 -28.808827) (xy 256.45786 -28.830639) (xy 256.403903 -28.844745)
			(xy 256.348466 -28.850845) (xy 256.292732 -28.848808) (xy 256.237889 -28.838678) (xy 256.185105 -28.820671)
			(xy 256.135505 -28.79517) (xy 256.090147 -28.762719) (xy 256.049998 -28.72401) (xy 256.015912 -28.679867)
			(xy 255.988616 -28.631232) (xy 255.968693 -28.579141) (xy 255.956567 -28.524704) (xy 255.952496 -28.469082)
			(xy 251.96292 -28.469082) (xy 251.96292 -29.114242) (xy 251.96243 -29.14421) (xy 251.954607 -29.203632)
			(xy 251.939094 -29.261525) (xy 251.916158 -29.316898) (xy 251.886191 -29.368804) (xy 251.849704 -29.416354)
			(xy 251.807324 -29.458734) (xy 251.759774 -29.495221) (xy 251.707868 -29.525188) (xy 251.652495 -29.548124)
			(xy 251.594602 -29.563637) (xy 251.53518 -29.57146) (xy 251.475244 -29.57146) (xy 251.415822 -29.563637)
			(xy 251.357929 -29.548124) (xy 251.302556 -29.525188) (xy 251.25065 -29.495221) (xy 251.2031 -29.458734)
			(xy 251.16072 -29.416354) (xy 251.124233 -29.368804) (xy 251.094266 -29.316898) (xy 251.07133 -29.261525)
			(xy 251.055817 -29.203632) (xy 251.047994 -29.14421) (xy 251.047504 -29.114242) (xy 243.98986 -29.114242)
			(xy 243.98986 -29.186378) (xy 244.011958 -29.214064) (xy 244.029484 -29.217874) (xy 244.055778 -29.224335)
			(xy 244.10635 -29.243679) (xy 244.153679 -29.269976) (xy 244.196817 -29.302698) (xy 244.234897 -29.34119)
			(xy 244.267153 -29.384677) (xy 244.292939 -29.432287) (xy 244.311737 -29.483064) (xy 244.323169 -29.535988)
			(xy 244.327005 -29.589996) (xy 244.32317 -29.644005) (xy 244.311739 -29.696929) (xy 244.292942 -29.747706)
			(xy 244.267157 -29.795317) (xy 244.234901 -29.838805) (xy 244.196822 -29.877297) (xy 244.153685 -29.910021)
			(xy 244.106356 -29.936318) (xy 244.055785 -29.955662) (xy 244.029484 -29.962094) (xy 244.011958 -29.965904)
			(xy 243.98986 -29.99359) (xy 243.98986 -30.92069) (xy 253.689612 -30.92069) (xy 253.689612 -30.05709)
			(xy 253.690102 -30.027122) (xy 253.697925 -29.9677) (xy 253.713438 -29.909807) (xy 253.736374 -29.854434)
			(xy 253.766341 -29.802528) (xy 253.802828 -29.754978) (xy 253.845208 -29.712598) (xy 253.892758 -29.676111)
			(xy 253.944664 -29.646144) (xy 254.000037 -29.623208) (xy 254.05793 -29.607695) (xy 254.117352 -29.599872)
			(xy 254.177288 -29.599872) (xy 254.23671 -29.607695) (xy 254.294603 -29.623208) (xy 254.349976 -29.646144)
			(xy 254.401882 -29.676111) (xy 254.449432 -29.712598) (xy 254.491812 -29.754978) (xy 254.528299 -29.802528)
			(xy 254.558266 -29.854434) (xy 254.581202 -29.909807) (xy 254.596715 -29.9677) (xy 254.604538 -30.027122)
			(xy 254.605028 -30.05709) (xy 254.605028 -30.92069) (xy 254.604538 -30.950658) (xy 254.596715 -31.01008)
			(xy 254.581202 -31.067973) (xy 254.558266 -31.123346) (xy 254.528299 -31.175252) (xy 254.491812 -31.222802)
			(xy 254.449432 -31.265182) (xy 254.401882 -31.301669) (xy 254.349976 -31.331636) (xy 254.294603 -31.354572)
			(xy 254.23671 -31.370085) (xy 254.177288 -31.377908) (xy 254.117352 -31.377908) (xy 254.05793 -31.370085)
			(xy 254.000037 -31.354572) (xy 253.944664 -31.331636) (xy 253.892758 -31.301669) (xy 253.845208 -31.265182)
			(xy 253.802828 -31.222802) (xy 253.766341 -31.175252) (xy 253.736374 -31.123346) (xy 253.713438 -31.067973)
			(xy 253.697925 -31.01008) (xy 253.690102 -30.950658) (xy 253.689612 -30.92069) (xy 243.98986 -30.92069)
			(xy 243.98986 -32.714184) (xy 251.047504 -32.714184) (xy 251.047504 -31.850584) (xy 251.047994 -31.820616)
			(xy 251.055817 -31.761194) (xy 251.07133 -31.703301) (xy 251.094266 -31.647928) (xy 251.124233 -31.596022)
			(xy 251.16072 -31.548472) (xy 251.2031 -31.506092) (xy 251.25065 -31.469605) (xy 251.302556 -31.439638)
			(xy 251.357929 -31.416702) (xy 251.415822 -31.401189) (xy 251.475244 -31.393366) (xy 251.53518 -31.393366)
			(xy 251.594602 -31.401189) (xy 251.652495 -31.416702) (xy 251.707868 -31.439638) (xy 251.759774 -31.469605)
			(xy 251.807324 -31.506092) (xy 251.849704 -31.548472) (xy 251.886191 -31.596022) (xy 251.916158 -31.647928)
			(xy 251.939094 -31.703301) (xy 251.954607 -31.761194) (xy 251.96243 -31.820616) (xy 251.96292 -31.850584)
			(xy 251.96292 -32.714184) (xy 251.96243 -32.744152) (xy 251.954607 -32.803574) (xy 251.939094 -32.861467)
			(xy 251.916158 -32.91684) (xy 251.886191 -32.968746) (xy 251.849704 -33.016296) (xy 251.807324 -33.058676)
			(xy 251.759774 -33.095163) (xy 251.707868 -33.12513) (xy 251.652495 -33.148066) (xy 251.594602 -33.163579)
			(xy 251.53518 -33.171402) (xy 251.475244 -33.171402) (xy 251.415822 -33.163579) (xy 251.357929 -33.148066)
			(xy 251.302556 -33.12513) (xy 251.25065 -33.095163) (xy 251.2031 -33.058676) (xy 251.16072 -33.016296)
			(xy 251.124233 -32.968746) (xy 251.094266 -32.91684) (xy 251.07133 -32.861467) (xy 251.055817 -32.803574)
			(xy 251.047994 -32.744152) (xy 251.047504 -32.714184) (xy 243.98986 -32.714184) (xy 243.98986 -34.520886)
			(xy 253.689612 -34.520886) (xy 253.689612 -33.657286) (xy 253.690102 -33.627318) (xy 253.697925 -33.567896)
			(xy 253.713438 -33.510003) (xy 253.736374 -33.45463) (xy 253.766341 -33.402724) (xy 253.802828 -33.355174)
			(xy 253.845208 -33.312794) (xy 253.892758 -33.276307) (xy 253.944664 -33.24634) (xy 254.000037 -33.223404)
			(xy 254.05793 -33.207891) (xy 254.117352 -33.200068) (xy 254.177288 -33.200068) (xy 254.23671 -33.207891)
			(xy 254.294603 -33.223404) (xy 254.349976 -33.24634) (xy 254.401882 -33.276307) (xy 254.449432 -33.312794)
			(xy 254.491812 -33.355174) (xy 254.528299 -33.402724) (xy 254.558266 -33.45463) (xy 254.581202 -33.510003)
			(xy 254.596715 -33.567896) (xy 254.604538 -33.627318) (xy 254.605028 -33.657286) (xy 254.605028 -34.520886)
			(xy 254.604538 -34.550854) (xy 254.596715 -34.610276) (xy 254.581202 -34.668169) (xy 254.558266 -34.723542)
			(xy 254.528299 -34.775448) (xy 254.491812 -34.822998) (xy 254.449432 -34.865378) (xy 254.401882 -34.901865)
			(xy 254.349976 -34.931832) (xy 254.294603 -34.954768) (xy 254.23671 -34.970281) (xy 254.177288 -34.978104)
			(xy 254.117352 -34.978104) (xy 254.05793 -34.970281) (xy 254.000037 -34.954768) (xy 253.944664 -34.931832)
			(xy 253.892758 -34.901865) (xy 253.845208 -34.865378) (xy 253.802828 -34.822998) (xy 253.766341 -34.775448)
			(xy 253.736374 -34.723542) (xy 253.713438 -34.668169) (xy 253.697925 -34.610276) (xy 253.690102 -34.550854)
			(xy 253.689612 -34.520886) (xy 243.98986 -34.520886) (xy 243.98986 -36.60013) (xy 244.198655 -36.60013)
			(xy 244.202659 -36.512245) (xy 244.214639 -36.425088) (xy 244.234494 -36.339381) (xy 244.262061 -36.255836)
			(xy 244.297111 -36.175143) (xy 244.339353 -36.097971) (xy 244.388438 -36.024961) (xy 244.443959 -35.956717)
			(xy 244.505456 -35.893804) (xy 244.572418 -35.836744) (xy 244.644292 -35.78601) (xy 244.720482 -35.742022)
			(xy 244.800356 -35.705144) (xy 244.883253 -35.675683) (xy 244.968485 -35.653881) (xy 245.055347 -35.639921)
			(xy 245.143118 -35.633917) (xy 245.231072 -35.63592) (xy 245.318479 -35.645912) (xy 245.404615 -35.663812)
			(xy 245.488767 -35.68947) (xy 245.570237 -35.722674) (xy 245.64835 -35.763148) (xy 245.722458 -35.810559)
			(xy 245.791949 -35.864512) (xy 245.80504 -35.876738) (xy 250.9172 -35.876738) (xy 250.921271 -35.821116)
			(xy 250.933397 -35.766679) (xy 250.95332 -35.714588) (xy 250.980616 -35.665953) (xy 251.014702 -35.62181)
			(xy 251.054851 -35.583101) (xy 251.100209 -35.55065) (xy 251.149809 -35.525149) (xy 251.202593 -35.507142)
			(xy 251.257436 -35.497012) (xy 251.31317 -35.494975) (xy 251.368607 -35.501075) (xy 251.422564 -35.515181)
			(xy 251.473893 -35.536993) (xy 251.521499 -35.566047) (xy 251.564367 -35.601722) (xy 251.601584 -35.643259)
			(xy 251.632357 -35.689772) (xy 251.656029 -35.740269) (xy 251.672097 -35.793676) (xy 251.680217 -35.848852)
			(xy 251.680726 -35.876738) (xy 254.98882 -35.876738) (xy 254.992891 -35.821116) (xy 255.005017 -35.766679)
			(xy 255.02494 -35.714588) (xy 255.052236 -35.665953) (xy 255.086322 -35.62181) (xy 255.126471 -35.583101)
			(xy 255.171829 -35.55065) (xy 255.221429 -35.525149) (xy 255.274213 -35.507142) (xy 255.329056 -35.497012)
			(xy 255.38479 -35.494975) (xy 255.440227 -35.501075) (xy 255.494184 -35.515181) (xy 255.545513 -35.536993)
			(xy 255.593119 -35.566047) (xy 255.635987 -35.601722) (xy 255.673204 -35.643259) (xy 255.703977 -35.689772)
			(xy 255.727649 -35.740269) (xy 255.743717 -35.793676) (xy 255.751837 -35.848852) (xy 255.752346 -35.876738)
			(xy 255.751837 -35.904624) (xy 255.743717 -35.9598) (xy 255.727649 -36.013207) (xy 255.703977 -36.063704)
			(xy 255.673204 -36.110217) (xy 255.635987 -36.151754) (xy 255.593119 -36.187429) (xy 255.545513 -36.216483)
			(xy 255.494184 -36.238295) (xy 255.440227 -36.252401) (xy 255.38479 -36.258501) (xy 255.329056 -36.256464)
			(xy 255.274213 -36.246334) (xy 255.221429 -36.228327) (xy 255.171829 -36.202826) (xy 255.126471 -36.170375)
			(xy 255.086322 -36.131666) (xy 255.052236 -36.087523) (xy 255.02494 -36.038888) (xy 255.005017 -35.986797)
			(xy 254.992891 -35.93236) (xy 254.98882 -35.876738) (xy 251.680726 -35.876738) (xy 251.680217 -35.904624)
			(xy 251.672097 -35.9598) (xy 251.656029 -36.013207) (xy 251.632357 -36.063704) (xy 251.601584 -36.110217)
			(xy 251.564367 -36.151754) (xy 251.521499 -36.187429) (xy 251.473893 -36.216483) (xy 251.422564 -36.238295)
			(xy 251.368607 -36.252401) (xy 251.31317 -36.258501) (xy 251.257436 -36.256464) (xy 251.202593 -36.246334)
			(xy 251.149809 -36.228327) (xy 251.100209 -36.202826) (xy 251.054851 -36.170375) (xy 251.014702 -36.131666)
			(xy 250.980616 -36.087523) (xy 250.95332 -36.038888) (xy 250.933397 -35.986797) (xy 250.921271 -35.93236)
			(xy 250.9172 -35.876738) (xy 245.80504 -35.876738) (xy 245.856245 -35.92456) (xy 245.914814 -35.990207)
			(xy 245.967171 -36.060907) (xy 246.012883 -36.136076) (xy 246.051569 -36.21509) (xy 246.08291 -36.297295)
			(xy 246.106645 -36.382009) (xy 246.122579 -36.46853) (xy 246.126362 -36.50996) (xy 252.813818 -36.50996)
			(xy 252.817889 -36.454338) (xy 252.830015 -36.399901) (xy 252.849938 -36.34781) (xy 252.877234 -36.299175)
			(xy 252.91132 -36.255032) (xy 252.951469 -36.216323) (xy 252.996827 -36.183872) (xy 253.046427 -36.158371)
			(xy 253.099211 -36.140364) (xy 253.154054 -36.130234) (xy 253.209788 -36.128197) (xy 253.265225 -36.134297)
			(xy 253.319182 -36.148403) (xy 253.370511 -36.170215) (xy 253.418117 -36.199269) (xy 253.460985 -36.234944)
			(xy 253.498202 -36.276481) (xy 253.528975 -36.322994) (xy 253.552647 -36.373491) (xy 253.568715 -36.426898)
			(xy 253.57264 -36.453572) (xy 256.128518 -36.453572) (xy 256.132589 -36.39795) (xy 256.144715 -36.343513)
			(xy 256.164638 -36.291422) (xy 256.191934 -36.242787) (xy 256.22602 -36.198644) (xy 256.266169 -36.159935)
			(xy 256.311527 -36.127484) (xy 256.361127 -36.101983) (xy 256.413911 -36.083976) (xy 256.468754 -36.073846)
			(xy 256.524488 -36.071809) (xy 256.579925 -36.077909) (xy 256.633882 -36.092015) (xy 256.685211 -36.113827)
			(xy 256.732817 -36.142881) (xy 256.775685 -36.178556) (xy 256.812902 -36.220093) (xy 256.843675 -36.266606)
			(xy 256.867347 -36.317103) (xy 256.883415 -36.37051) (xy 256.891535 -36.425686) (xy 256.892044 -36.453572)
			(xy 256.891535 -36.481458) (xy 256.883415 -36.536634) (xy 256.867347 -36.590041) (xy 256.843675 -36.640538)
			(xy 256.812902 -36.687051) (xy 256.775685 -36.728588) (xy 256.732817 -36.764263) (xy 256.685211 -36.793317)
			(xy 256.633882 -36.815129) (xy 256.579925 -36.829235) (xy 256.524488 -36.835335) (xy 256.468754 -36.833298)
			(xy 256.413911 -36.823168) (xy 256.361127 -36.805161) (xy 256.311527 -36.77966) (xy 256.266169 -36.747209)
			(xy 256.22602 -36.7085) (xy 256.191934 -36.664357) (xy 256.164638 -36.615722) (xy 256.144715 -36.563631)
			(xy 256.132589 -36.509194) (xy 256.128518 -36.453572) (xy 253.57264 -36.453572) (xy 253.576835 -36.482074)
			(xy 253.577344 -36.50996) (xy 253.576835 -36.537846) (xy 253.568715 -36.593022) (xy 253.552647 -36.646429)
			(xy 253.528975 -36.696926) (xy 253.498202 -36.743439) (xy 253.460985 -36.784976) (xy 253.418117 -36.820651)
			(xy 253.370511 -36.849705) (xy 253.319182 -36.871517) (xy 253.265225 -36.885623) (xy 253.209788 -36.891723)
			(xy 253.154054 -36.889686) (xy 253.099211 -36.879556) (xy 253.046427 -36.861549) (xy 252.996827 -36.836048)
			(xy 252.951469 -36.803597) (xy 252.91132 -36.764888) (xy 252.877234 -36.720745) (xy 252.849938 -36.67211)
			(xy 252.830015 -36.620019) (xy 252.817889 -36.565582) (xy 252.813818 -36.50996) (xy 246.126362 -36.50996)
			(xy 246.130579 -36.556142) (xy 246.13108 -36.60013) (xy 246.130579 -36.644118) (xy 246.122579 -36.73173)
			(xy 246.106645 -36.818251) (xy 246.08291 -36.902965) (xy 246.051569 -36.98517) (xy 246.012883 -37.064184)
			(xy 245.967171 -37.139353) (xy 245.914814 -37.210053) (xy 245.856245 -37.2757) (xy 245.791949 -37.335748)
			(xy 245.722458 -37.389701) (xy 245.64835 -37.437112) (xy 245.570237 -37.477586) (xy 245.488767 -37.51079)
			(xy 245.404615 -37.536448) (xy 245.318479 -37.554348) (xy 245.231072 -37.56434) (xy 245.143118 -37.566343)
			(xy 245.055347 -37.560339) (xy 244.968485 -37.546379) (xy 244.883253 -37.524577) (xy 244.800356 -37.495116)
			(xy 244.720482 -37.458238) (xy 244.644292 -37.41425) (xy 244.572418 -37.363516) (xy 244.505456 -37.306456)
			(xy 244.443959 -37.243543) (xy 244.388438 -37.175299) (xy 244.339353 -37.102289) (xy 244.297111 -37.025117)
			(xy 244.262061 -36.944424) (xy 244.234494 -36.860879) (xy 244.214639 -36.775172) (xy 244.202659 -36.688015)
			(xy 244.198655 -36.60013) (xy 243.98986 -36.60013) (xy 243.98986 -39.97198) (xy 258.095748 -39.97198)
			(xy 258.099819 -39.916358) (xy 258.111945 -39.861921) (xy 258.131868 -39.80983) (xy 258.159164 -39.761195)
			(xy 258.19325 -39.717052) (xy 258.233399 -39.678343) (xy 258.278757 -39.645892) (xy 258.328357 -39.620391)
			(xy 258.381141 -39.602384) (xy 258.435984 -39.592254) (xy 258.491718 -39.590217) (xy 258.547155 -39.596317)
			(xy 258.601112 -39.610423) (xy 258.652441 -39.632235) (xy 258.700047 -39.661289) (xy 258.742915 -39.696964)
			(xy 258.780132 -39.738501) (xy 258.810905 -39.785014) (xy 258.834577 -39.835511) (xy 258.850645 -39.888918)
			(xy 258.858765 -39.944094) (xy 258.859274 -39.97198) (xy 258.858765 -39.999866) (xy 258.850645 -40.055042)
			(xy 258.834577 -40.108449) (xy 258.810905 -40.158946) (xy 258.780132 -40.205459) (xy 258.742915 -40.246996)
			(xy 258.700047 -40.282671) (xy 258.652441 -40.311725) (xy 258.601112 -40.333537) (xy 258.547155 -40.347643)
			(xy 258.491718 -40.353743) (xy 258.435984 -40.351706) (xy 258.381141 -40.341576) (xy 258.328357 -40.323569)
			(xy 258.278757 -40.298068) (xy 258.233399 -40.265617) (xy 258.19325 -40.226908) (xy 258.159164 -40.182765)
			(xy 258.131868 -40.13413) (xy 258.111945 -40.082039) (xy 258.099819 -40.027602) (xy 258.095748 -39.97198)
			(xy 243.98986 -39.97198) (xy 243.98986 -40.452802) (xy 243.990285 -40.462871) (xy 243.998007 -40.481469)
			(xy 244.004846 -40.48887) (xy 244.224048 -40.708072) (xy 244.231448 -40.714914) (xy 244.250046 -40.722635)
			(xy 244.260116 -40.723058) (xy 253.281434 -40.723058) (xy 253.2915 -40.723489) (xy 253.31009 -40.731218)
			(xy 253.317502 -40.738044) (xy 254.258572 -41.679114) (xy 254.265419 -41.686512) (xy 254.273153 -41.70511)
			(xy 254.273558 -41.715182) (xy 254.273558 -41.947592) (xy 254.273812 -41.954196) (xy 254.273812 -43.85691)
			(xy 256.919728 -43.85691) (xy 256.923799 -43.801288) (xy 256.935925 -43.746851) (xy 256.955848 -43.69476)
			(xy 256.983144 -43.646125) (xy 257.01723 -43.601982) (xy 257.057379 -43.563273) (xy 257.102737 -43.530822)
			(xy 257.152337 -43.505321) (xy 257.205121 -43.487314) (xy 257.259964 -43.477184) (xy 257.315698 -43.475147)
			(xy 257.371135 -43.481247) (xy 257.425092 -43.495353) (xy 257.476421 -43.517165) (xy 257.524027 -43.546219)
			(xy 257.566895 -43.581894) (xy 257.604112 -43.623431) (xy 257.634885 -43.669944) (xy 257.658557 -43.720441)
			(xy 257.674625 -43.773848) (xy 257.682745 -43.829024) (xy 257.683254 -43.85691) (xy 257.682745 -43.884796)
			(xy 257.674625 -43.939972) (xy 257.658557 -43.993379) (xy 257.634885 -44.043876) (xy 257.604112 -44.090389)
			(xy 257.566895 -44.131926) (xy 257.524027 -44.167601) (xy 257.476421 -44.196655) (xy 257.425092 -44.218467)
			(xy 257.371135 -44.232573) (xy 257.315698 -44.238673) (xy 257.259964 -44.236636) (xy 257.205121 -44.226506)
			(xy 257.152337 -44.208499) (xy 257.102737 -44.182998) (xy 257.057379 -44.150547) (xy 257.01723 -44.111838)
			(xy 256.983144 -44.067695) (xy 256.955848 -44.01906) (xy 256.935925 -43.966969) (xy 256.923799 -43.912532)
			(xy 256.919728 -43.85691) (xy 254.273812 -43.85691) (xy 254.273812 -45.35424) (xy 256.903726 -45.35424)
			(xy 256.907797 -45.298618) (xy 256.919923 -45.244181) (xy 256.939846 -45.19209) (xy 256.967142 -45.143455)
			(xy 257.001228 -45.099312) (xy 257.041377 -45.060603) (xy 257.086735 -45.028152) (xy 257.136335 -45.002651)
			(xy 257.189119 -44.984644) (xy 257.243962 -44.974514) (xy 257.299696 -44.972477) (xy 257.355133 -44.978577)
			(xy 257.40909 -44.992683) (xy 257.460419 -45.014495) (xy 257.508025 -45.043549) (xy 257.550893 -45.079224)
			(xy 257.58811 -45.120761) (xy 257.618883 -45.167274) (xy 257.642555 -45.217771) (xy 257.658623 -45.271178)
			(xy 257.666743 -45.326354) (xy 257.667252 -45.35424) (xy 257.666743 -45.382126) (xy 257.658623 -45.437302)
			(xy 257.642555 -45.490709) (xy 257.618883 -45.541206) (xy 257.58811 -45.587719) (xy 257.550893 -45.629256)
			(xy 257.508025 -45.664931) (xy 257.460419 -45.693985) (xy 257.40909 -45.715797) (xy 257.355133 -45.729903)
			(xy 257.299696 -45.736003) (xy 257.243962 -45.733966) (xy 257.189119 -45.723836) (xy 257.136335 -45.705829)
			(xy 257.086735 -45.680328) (xy 257.041377 -45.647877) (xy 257.001228 -45.609168) (xy 256.967142 -45.565025)
			(xy 256.939846 -45.51639) (xy 256.919923 -45.464299) (xy 256.907797 -45.409862) (xy 256.903726 -45.35424)
			(xy 254.273812 -45.35424) (xy 254.273812 -46.693836) (xy 256.876296 -46.693836) (xy 256.876782 -46.666585)
			(xy 256.884538 -46.612637) (xy 256.899893 -46.560342) (xy 256.922535 -46.510765) (xy 256.952001 -46.464915)
			(xy 256.987692 -46.423724) (xy 257.028883 -46.388033) (xy 257.074733 -46.358567) (xy 257.12431 -46.335925)
			(xy 257.176605 -46.32057) (xy 257.230553 -46.312814) (xy 257.285055 -46.312814) (xy 257.339003 -46.32057)
			(xy 257.391298 -46.335925) (xy 257.440875 -46.358567) (xy 257.486725 -46.388033) (xy 257.527916 -46.423724)
			(xy 257.563607 -46.464915) (xy 257.593073 -46.510765) (xy 257.615715 -46.560342) (xy 257.63107 -46.612637)
			(xy 257.638826 -46.666585) (xy 257.639312 -46.693836) (xy 257.638838 -46.720263) (xy 257.631528 -46.772611)
			(xy 257.617056 -46.823446) (xy 257.595696 -46.871793) (xy 257.582162 -46.894496) (xy 257.576066 -46.904402)
			(xy 257.573526 -46.927262) (xy 257.607816 -47.023782) (xy 257.623818 -47.040038) (xy 257.634994 -47.043848)
			(xy 257.659513 -47.052891) (xy 257.705964 -47.076839) (xy 257.748715 -47.106899) (xy 257.786965 -47.142511)
			(xy 257.82 -47.183007) (xy 257.847202 -47.227631) (xy 257.868063 -47.275548) (xy 257.882192 -47.325863)
			(xy 257.889325 -47.377635) (xy 257.889756 -47.403766) (xy 257.88927 -47.431017) (xy 257.881514 -47.484965)
			(xy 257.866159 -47.53726) (xy 257.843517 -47.586837) (xy 257.814051 -47.632687) (xy 257.77836 -47.673878)
			(xy 257.737169 -47.709569) (xy 257.691319 -47.739035) (xy 257.641742 -47.761677) (xy 257.589447 -47.777032)
			(xy 257.535499 -47.784788) (xy 257.480997 -47.784788) (xy 257.427049 -47.777032) (xy 257.374754 -47.761677)
			(xy 257.325177 -47.739035) (xy 257.279327 -47.709569) (xy 257.238136 -47.673878) (xy 257.202445 -47.632687)
			(xy 257.172979 -47.586837) (xy 257.150337 -47.53726) (xy 257.134982 -47.484965) (xy 257.127226 -47.431017)
			(xy 257.12674 -47.403766) (xy 257.127208 -47.377338) (xy 257.134518 -47.324991) (xy 257.148993 -47.274155)
			(xy 257.170354 -47.225809) (xy 257.18389 -47.203106) (xy 257.189986 -47.1932) (xy 257.192526 -47.17034)
			(xy 257.158236 -47.07382) (xy 257.142234 -47.057564) (xy 257.131058 -47.053754) (xy 257.106551 -47.04468)
			(xy 257.060098 -47.020739) (xy 257.017346 -46.990683) (xy 256.979094 -46.955077) (xy 256.946057 -46.914584)
			(xy 256.918854 -46.869964) (xy 256.897991 -46.822049) (xy 256.883861 -46.771736) (xy 256.876727 -46.719966)
			(xy 256.876296 -46.693836) (xy 254.273812 -46.693836) (xy 254.273812 -48.300132) (xy 254.273558 -48.30699)
			(xy 256.753866 -48.30699) (xy 256.757937 -48.251368) (xy 256.770063 -48.196931) (xy 256.789986 -48.14484)
			(xy 256.817282 -48.096205) (xy 256.851368 -48.052062) (xy 256.891517 -48.013353) (xy 256.936875 -47.980902)
			(xy 256.986475 -47.955401) (xy 257.039259 -47.937394) (xy 257.094102 -47.927264) (xy 257.149836 -47.925227)
			(xy 257.205273 -47.931327) (xy 257.25923 -47.945433) (xy 257.310559 -47.967245) (xy 257.358165 -47.996299)
			(xy 257.401033 -48.031974) (xy 257.43825 -48.073511) (xy 257.469023 -48.120024) (xy 257.492695 -48.170521)
			(xy 257.508763 -48.223928) (xy 257.516883 -48.279104) (xy 257.517392 -48.30699) (xy 257.516883 -48.334876)
			(xy 257.508763 -48.390052) (xy 257.492695 -48.443459) (xy 257.469023 -48.493956) (xy 257.43825 -48.540469)
			(xy 257.401033 -48.582006) (xy 257.358165 -48.617681) (xy 257.310559 -48.646735) (xy 257.25923 -48.668547)
			(xy 257.205273 -48.682653) (xy 257.149836 -48.688753) (xy 257.094102 -48.686716) (xy 257.039259 -48.676586)
			(xy 256.986475 -48.658579) (xy 256.936875 -48.633078) (xy 256.891517 -48.600627) (xy 256.851368 -48.561918)
			(xy 256.817282 -48.517775) (xy 256.789986 -48.46914) (xy 256.770063 -48.417049) (xy 256.757937 -48.362612)
			(xy 256.753866 -48.30699) (xy 254.273558 -48.30699) (xy 254.273558 -48.8442) (xy 254.387348 -48.8442)
			(xy 254.391419 -48.788578) (xy 254.403545 -48.734141) (xy 254.423468 -48.68205) (xy 254.450764 -48.633415)
			(xy 254.48485 -48.589272) (xy 254.524999 -48.550563) (xy 254.570357 -48.518112) (xy 254.619957 -48.492611)
			(xy 254.672741 -48.474604) (xy 254.727584 -48.464474) (xy 254.783318 -48.462437) (xy 254.838755 -48.468537)
			(xy 254.892712 -48.482643) (xy 254.944041 -48.504455) (xy 254.991647 -48.533509) (xy 255.034515 -48.569184)
			(xy 255.071732 -48.610721) (xy 255.102505 -48.657234) (xy 255.126177 -48.707731) (xy 255.142245 -48.761138)
			(xy 255.150365 -48.816314) (xy 255.150874 -48.8442) (xy 255.150365 -48.872086) (xy 255.147367 -48.89246)
			(xy 255.414016 -48.89246) (xy 255.418087 -48.836838) (xy 255.430213 -48.782401) (xy 255.450136 -48.73031)
			(xy 255.477432 -48.681675) (xy 255.511518 -48.637532) (xy 255.551667 -48.598823) (xy 255.597025 -48.566372)
			(xy 255.646625 -48.540871) (xy 255.699409 -48.522864) (xy 255.754252 -48.512734) (xy 255.809986 -48.510697)
			(xy 255.865423 -48.516797) (xy 255.91938 -48.530903) (xy 255.970709 -48.552715) (xy 256.018315 -48.581769)
			(xy 256.061183 -48.617444) (xy 256.0984 -48.658981) (xy 256.129173 -48.705494) (xy 256.152845 -48.755991)
			(xy 256.168913 -48.809398) (xy 256.177033 -48.864574) (xy 256.177542 -48.89246) (xy 256.177033 -48.920346)
			(xy 256.168913 -48.975522) (xy 256.152845 -49.028929) (xy 256.129173 -49.079426) (xy 256.0984 -49.125939)
			(xy 256.061183 -49.167476) (xy 256.018315 -49.203151) (xy 255.970709 -49.232205) (xy 255.91938 -49.254017)
			(xy 255.865423 -49.268123) (xy 255.809986 -49.274223) (xy 255.754252 -49.272186) (xy 255.699409 -49.262056)
			(xy 255.646625 -49.244049) (xy 255.597025 -49.218548) (xy 255.551667 -49.186097) (xy 255.511518 -49.147388)
			(xy 255.477432 -49.103245) (xy 255.450136 -49.05461) (xy 255.430213 -49.002519) (xy 255.418087 -48.948082)
			(xy 255.414016 -48.89246) (xy 255.147367 -48.89246) (xy 255.142245 -48.927262) (xy 255.126177 -48.980669)
			(xy 255.102505 -49.031166) (xy 255.071732 -49.077679) (xy 255.034515 -49.119216) (xy 254.991647 -49.154891)
			(xy 254.944041 -49.183945) (xy 254.892712 -49.205757) (xy 254.838755 -49.219863) (xy 254.783318 -49.225963)
			(xy 254.727584 -49.223926) (xy 254.672741 -49.213796) (xy 254.619957 -49.195789) (xy 254.570357 -49.170288)
			(xy 254.524999 -49.137837) (xy 254.48485 -49.099128) (xy 254.450764 -49.054985) (xy 254.423468 -49.00635)
			(xy 254.403545 -48.954259) (xy 254.391419 -48.899822) (xy 254.387348 -48.8442) (xy 254.273558 -48.8442)
			(xy 254.273558 -49.199038) (xy 254.273812 -49.205896) (xy 254.273812 -51.198272) (xy 254.274249 -51.208336)
			(xy 254.281983 -51.22692) (xy 254.288798 -51.23434) (xy 254.432816 -51.378358) (xy 254.440213 -51.385207)
			(xy 254.458812 -51.392942) (xy 254.468884 -51.393344)
		)
		(stroke
			(width 0)
			(type solid)
		)
		(fill yes)
		(layer "In9.Cu")
		(net "GND")
	)
	(gr_poly
		(pts
			(xy 425.032678 -51.393344) (xy 425.041911 -51.392948) (xy 425.059177 -51.386403) (xy 425.072997 -51.374158)
			(xy 425.077636 -51.366166) (xy 425.119292 -51.286664) (xy 425.123202 -51.278383) (xy 425.12548 -51.260225)
			(xy 425.121259 -51.242418) (xy 425.116498 -51.234594) (xy 425.116244 -51.23434) (xy 425.100747 -51.2107)
			(xy 425.076144 -51.159812) (xy 425.059312 -51.105852) (xy 425.050621 -51.05) (xy 425.04995 -51.021742)
			(xy 425.04995 -51.01463) (xy 425.050762 -50.987604) (xy 425.059072 -50.934177) (xy 425.074841 -50.882459)
			(xy 425.097753 -50.833486) (xy 425.12735 -50.788237) (xy 425.163039 -50.74762) (xy 425.204104 -50.712448)
			(xy 425.249723 -50.683426) (xy 425.298983 -50.661135) (xy 425.350897 -50.646021) (xy 425.404424 -50.638388)
			(xy 425.458492 -50.638388) (xy 425.512019 -50.646021) (xy 425.563933 -50.661135) (xy 425.613193 -50.683426)
			(xy 425.658812 -50.712448) (xy 425.699877 -50.74762) (xy 425.735566 -50.788237) (xy 425.765163 -50.833486)
			(xy 425.788075 -50.882459) (xy 425.803844 -50.934177) (xy 425.812154 -50.987604) (xy 425.812966 -51.01463)
			(xy 425.812966 -51.01971) (xy 425.812458 -51.048258) (xy 425.803942 -51.104716) (xy 425.787103 -51.159273)
			(xy 425.762317 -51.210708) (xy 425.746672 -51.234594) (xy 425.738544 -51.246278) (xy 425.73702 -51.274218)
			(xy 425.78528 -51.366166) (xy 425.789927 -51.374153) (xy 425.803747 -51.386396) (xy 425.821007 -51.392953)
			(xy 425.830238 -51.393344) (xy 426.722286 -51.393344) (xy 426.732248 -51.392855) (xy 426.750671 -51.385267)
			(xy 426.7581 -51.378612) (xy 427.27626 -50.860452) (xy 427.28007 -50.852578) (xy 427.289976 -50.833528)
			(xy 427.29023 -50.833274) (xy 427.29404 -50.82667) (xy 427.297342 -50.821082) (xy 427.301406 -50.806858)
			(xy 427.304708 -50.795174) (xy 427.304708 -50.1904) (xy 427.304453 -50.182988) (xy 427.30019 -50.168791)
			(xy 427.296326 -50.16246) (xy 427.281492 -50.139007) (xy 427.258032 -50.088718) (xy 427.24211 -50.03556)
			(xy 427.234064 -49.980654) (xy 427.234063 -49.925162) (xy 427.242107 -49.870257) (xy 427.258026 -49.817097)
			(xy 427.281484 -49.766807) (xy 427.296326 -49.74336) (xy 427.300187 -49.737029) (xy 427.304439 -49.722831)
			(xy 427.304708 -49.71542) (xy 427.304708 -49.1744) (xy 427.304453 -49.166988) (xy 427.30019 -49.152791)
			(xy 427.296326 -49.14646) (xy 427.281492 -49.123007) (xy 427.258032 -49.072718) (xy 427.24211 -49.01956)
			(xy 427.234064 -48.964654) (xy 427.234063 -48.909162) (xy 427.242107 -48.854257) (xy 427.258026 -48.801097)
			(xy 427.281484 -48.750807) (xy 427.296326 -48.72736) (xy 427.300187 -48.721029) (xy 427.304439 -48.706831)
			(xy 427.304708 -48.69942) (xy 427.304708 -47.629572) (xy 427.302168 -47.61865) (xy 427.299374 -47.613062)
			(xy 427.286648 -47.586293) (xy 427.26867 -47.529814) (xy 427.259572 -47.471246) (xy 427.259571 -47.411975)
			(xy 427.268665 -47.353407) (xy 427.28664 -47.296927) (xy 427.299374 -47.270162) (xy 427.302168 -47.264574)
			(xy 427.304708 -47.253652) (xy 427.304708 -46.1264) (xy 427.304453 -46.118988) (xy 427.30019 -46.104791)
			(xy 427.296326 -46.09846) (xy 427.281492 -46.075007) (xy 427.258032 -46.024718) (xy 427.24211 -45.97156)
			(xy 427.234064 -45.916654) (xy 427.234063 -45.861162) (xy 427.242107 -45.806257) (xy 427.258026 -45.753097)
			(xy 427.281484 -45.702807) (xy 427.296326 -45.67936) (xy 427.300187 -45.673029) (xy 427.304439 -45.658831)
			(xy 427.304708 -45.65142) (xy 427.304708 -45.1104) (xy 427.304453 -45.102988) (xy 427.30019 -45.088791)
			(xy 427.296326 -45.08246) (xy 427.281492 -45.059007) (xy 427.258032 -45.008718) (xy 427.24211 -44.95556)
			(xy 427.234064 -44.900654) (xy 427.234063 -44.845162) (xy 427.242107 -44.790257) (xy 427.258026 -44.737097)
			(xy 427.281484 -44.686807) (xy 427.296326 -44.66336) (xy 427.300187 -44.657029) (xy 427.304439 -44.642831)
			(xy 427.304708 -44.63542) (xy 427.304708 -44.0944) (xy 427.304453 -44.086988) (xy 427.30019 -44.072791)
			(xy 427.296326 -44.06646) (xy 427.281492 -44.043007) (xy 427.258032 -43.992718) (xy 427.24211 -43.93956)
			(xy 427.234064 -43.884654) (xy 427.234063 -43.829162) (xy 427.242107 -43.774257) (xy 427.258026 -43.721097)
			(xy 427.281484 -43.670807) (xy 427.296326 -43.64736) (xy 427.300187 -43.641029) (xy 427.304439 -43.626831)
			(xy 427.304708 -43.61942) (xy 427.304708 -43.0784) (xy 427.304453 -43.070988) (xy 427.30019 -43.056791)
			(xy 427.296326 -43.05046) (xy 427.281492 -43.027007) (xy 427.258032 -42.976718) (xy 427.24211 -42.92356)
			(xy 427.234064 -42.868654) (xy 427.234063 -42.813162) (xy 427.242107 -42.758257) (xy 427.258026 -42.705097)
			(xy 427.281484 -42.654807) (xy 427.296326 -42.63136) (xy 427.300187 -42.625029) (xy 427.304439 -42.610831)
			(xy 427.304708 -42.60342) (xy 427.304708 -41.423844) (xy 427.304323 -41.414077) (xy 427.297153 -41.395911)
			(xy 427.290738 -41.388538) (xy 427.26991 -41.366948) (xy 427.261528 -41.362884) (xy 427.23816 -41.351454)
			(xy 427.229778 -41.350438) (xy 427.202379 -41.346598) (xy 427.149005 -41.332035) (xy 427.098294 -41.309915)
			(xy 427.05131 -41.280703) (xy 427.009037 -41.245012) (xy 426.972362 -41.203589) (xy 426.942054 -41.157304)
			(xy 426.918749 -41.107127) (xy 426.902935 -41.05411) (xy 426.894944 -40.999365) (xy 426.894944 -40.94404)
			(xy 426.902934 -40.889295) (xy 426.918747 -40.836278) (xy 426.942051 -40.786101) (xy 426.972358 -40.739815)
			(xy 427.009033 -40.698392) (xy 427.051305 -40.6627) (xy 427.098289 -40.633488) (xy 427.148999 -40.611367)
			(xy 427.202373 -40.596803) (xy 427.229778 -40.59301) (xy 427.23816 -40.591994) (xy 427.261782 -40.580564)
			(xy 427.265808 -40.578497) (xy 427.273095 -40.573131) (xy 427.27626 -40.569896) (xy 427.290738 -40.55491)
			(xy 427.297162 -40.547537) (xy 427.304361 -40.529375) (xy 427.304708 -40.519604) (xy 427.304708 -38.432232)
			(xy 427.304294 -38.422206) (xy 427.29663 -38.403677) (xy 427.282457 -38.389492) (xy 427.263934 -38.381814)
			(xy 427.253908 -38.381432) (xy 425.584112 -38.381432) (xy 425.574973 -38.381812) (xy 425.557859 -38.388227)
			(xy 425.544088 -38.400243) (xy 425.539408 -38.408102) (xy 425.497244 -38.486842) (xy 425.494232 -38.492877)
			(xy 425.491152 -38.506004) (xy 425.491148 -38.51275) (xy 425.491656 -38.527228) (xy 425.49953 -38.539166)
			(xy 425.514663 -38.562785) (xy 425.538587 -38.613521) (xy 425.554831 -38.667212) (xy 425.563046 -38.722701)
			(xy 425.563538 -38.750748) (xy 425.563049 -38.777998) (xy 425.555287 -38.831942) (xy 425.539928 -38.884233)
			(xy 425.517285 -38.933806) (xy 425.487818 -38.979652) (xy 425.452126 -39.020839) (xy 425.410938 -39.056528)
			(xy 425.36509 -39.085993) (xy 425.315516 -39.108634) (xy 425.263224 -39.123991) (xy 425.20928 -39.13175)
			(xy 425.18203 -39.132256) (xy 425.15373 -39.131737) (xy 425.097752 -39.123367) (xy 425.043625 -39.106823)
			(xy 424.992534 -39.082465) (xy 424.945601 -39.05083) (xy 424.903854 -39.01261) (xy 424.86821 -38.968643)
			(xy 424.853354 -38.94455) (xy 424.84675 -38.933374) (xy 424.82516 -38.920166) (xy 424.779948 -38.917626)
			(xy 424.715686 -38.913816) (xy 424.692826 -38.92423) (xy 424.685206 -38.93439) (xy 424.667017 -38.957266)
			(xy 424.624862 -38.99774) (xy 424.577029 -39.031315) (xy 424.524636 -39.057205) (xy 424.468909 -39.074805)
			(xy 424.41115 -39.083703) (xy 424.38193 -39.08425) (xy 424.354676 -39.083766) (xy 424.300723 -39.076013)
			(xy 424.248422 -39.060661) (xy 424.198839 -39.038023) (xy 424.152981 -39.008558) (xy 424.111784 -38.972867)
			(xy 424.076085 -38.931676) (xy 424.046612 -38.885825) (xy 424.023964 -38.836245) (xy 424.008602 -38.783947)
			(xy 424.000839 -38.729996) (xy 424.000422 -38.702742) (xy 424.000981 -38.672656) (xy 424.010427 -38.613232)
			(xy 424.029106 -38.556034) (xy 424.042332 -38.529006) (xy 424.048428 -38.517068) (xy 424.047412 -38.490906)
			(xy 423.995088 -38.405562) (xy 423.990253 -38.398405) (xy 423.97681 -38.38758) (xy 423.960537 -38.381824)
			(xy 423.951908 -38.381432) (xy 421.585136 -38.381432) (xy 421.576278 -38.381852) (xy 421.55964 -38.387948)
			(xy 421.552624 -38.39337) (xy 421.341042 -38.604952) (xy 421.263572 -38.682168) (xy 421.239672 -38.705331)
			(xy 421.186866 -38.745848) (xy 421.129221 -38.779122) (xy 421.067726 -38.804584) (xy 421.003432 -38.821799)
			(xy 420.937441 -38.830472) (xy 420.904162 -38.831012) (xy 419.288722 -38.831012) (xy 419.255446 -38.830463)
			(xy 419.189464 -38.821769) (xy 419.12518 -38.80454) (xy 419.063694 -38.77907) (xy 419.006057 -38.745795)
			(xy 418.953255 -38.705284) (xy 418.929312 -38.682168) (xy 418.081714 -37.83457) (xy 418.058177 -37.810281)
			(xy 418.017075 -37.756569) (xy 417.983453 -37.697884) (xy 417.957903 -37.635261) (xy 417.948872 -37.602668)
			(xy 417.941271 -37.57134) (xy 417.933114 -37.507393) (xy 417.932616 -37.47516) (xy 417.93308 -37.44447)
			(xy 417.940474 -37.383537) (xy 417.955149 -37.323938) (xy 417.976892 -37.266538) (xy 418.005387 -37.212173)
			(xy 418.040219 -37.161634) (xy 418.080882 -37.115656) (xy 418.126785 -37.074907) (xy 418.177258 -37.03998)
			(xy 418.231569 -37.011384) (xy 418.288928 -36.989533) (xy 418.3485 -36.974746) (xy 418.409419 -36.967238)
			(xy 418.440108 -36.966652) (xy 418.441124 -36.966652) (xy 418.473357 -36.967147) (xy 418.537307 -36.975296)
			(xy 418.568632 -36.982908) (xy 418.601227 -36.99194) (xy 418.663864 -37.017465) (xy 418.722558 -37.051078)
			(xy 418.776271 -37.092185) (xy 418.800534 -37.11575) (xy 419.484302 -37.799518) (xy 419.491697 -37.806373)
			(xy 419.510296 -37.81412) (xy 419.52037 -37.814504) (xy 420.149782 -37.814504) (xy 420.160534 -37.814032)
			(xy 420.18015 -37.805225) (xy 420.187628 -37.797486) (xy 420.238174 -37.741352) (xy 420.244741 -37.733234)
			(xy 420.251298 -37.713431) (xy 420.250874 -37.702998) (xy 420.250874 -37.702236) (xy 420.249908 -37.692295)
			(xy 420.248892 -37.672346) (xy 420.248842 -37.662358) (xy 420.249308 -37.635108) (xy 420.25707 -37.581165)
			(xy 420.272431 -37.528875) (xy 420.295076 -37.479303) (xy 420.324546 -37.433459) (xy 420.36024 -37.392275)
			(xy 420.401433 -37.356591) (xy 420.447284 -37.327132) (xy 420.496861 -37.304498) (xy 420.549155 -37.289151)
			(xy 420.6031 -37.281402) (xy 420.63035 -37.28085) (xy 420.659401 -37.281398) (xy 420.71683 -37.290212)
			(xy 420.77226 -37.30763) (xy 420.824409 -37.333247) (xy 420.872073 -37.366474) (xy 420.91415 -37.406541)
			(xy 420.932356 -37.429186) (xy 420.938452 -37.43706) (xy 420.946834 -37.44214) (xy 420.950993 -37.444439)
			(xy 420.959939 -37.44764) (xy 420.964614 -37.44849) (xy 421.03294 -37.459666) (xy 421.042516 -37.460805)
			(xy 421.061325 -37.456627) (xy 421.069516 -37.451538) (xy 421.06977 -37.451284) (xy 421.097455 -37.433229)
			(xy 421.156571 -37.403669) (xy 421.187626 -37.392356) (xy 421.214456 -37.383492) (xy 421.269581 -37.371061)
			(xy 421.325742 -37.364801) (xy 421.353996 -37.364416) (xy 427.253908 -37.364416) (xy 427.263916 -37.363927)
			(xy 427.282408 -37.356267) (xy 427.296562 -37.342114) (xy 427.304225 -37.323624) (xy 427.304708 -37.313616)
			(xy 427.304708 -31.63316) (xy 427.303946 -31.629096) (xy 427.301663 -31.613896) (xy 427.299246 -31.583252)
			(xy 427.29912 -31.567882) (xy 427.29924 -31.552512) (xy 427.301658 -31.521867) (xy 427.303946 -31.506668)
			(xy 427.304708 -31.502604) (xy 427.304708 -30.681168) (xy 427.304585 -30.676355) (xy 427.302794 -30.666898)
			(xy 427.301152 -30.662372) (xy 427.2915 -30.637734) (xy 427.285404 -30.630876) (xy 427.267282 -30.609786)
			(xy 427.236702 -30.563347) (xy 427.213184 -30.512963) (xy 427.197223 -30.459699) (xy 427.189159 -30.404684)
			(xy 427.189162 -30.34908) (xy 427.197231 -30.294066) (xy 427.213196 -30.240804) (xy 427.23672 -30.190422)
			(xy 427.267304 -30.143985) (xy 427.285404 -30.122876) (xy 427.2915 -30.116018) (xy 427.301152 -30.09138)
			(xy 427.30284 -30.086867) (xy 427.304637 -30.077402) (xy 427.304708 -30.072584) (xy 427.304708 -29.909008)
			(xy 427.290992 -29.874972) (xy 427.28515 -29.868368) (xy 427.267104 -29.847302) (xy 427.236661 -29.800933)
			(xy 427.213254 -29.750645) (xy 427.197376 -29.697497) (xy 427.189361 -29.642611) (xy 427.188884 -29.614876)
			(xy 427.188884 -29.614368) (xy 427.18949 -29.583501) (xy 427.199457 -29.522575) (xy 427.219108 -29.464051)
			(xy 427.24793 -29.409457) (xy 427.2661 -29.384498) (xy 427.270774 -29.377759) (xy 427.275966 -29.362213)
			(xy 427.27626 -29.354018) (xy 427.27626 -29.062934) (xy 427.275955 -29.054739) (xy 427.270778 -29.039189)
			(xy 427.2661 -29.032454) (xy 427.249897 -29.010241) (xy 427.223358 -28.962088) (xy 427.204 -28.910626)
			(xy 427.192224 -28.856921) (xy 427.188274 -28.802081) (xy 427.19223 -28.747242) (xy 427.204011 -28.693537)
			(xy 427.223374 -28.642077) (xy 427.249917 -28.593927) (xy 427.2661 -28.571698) (xy 427.270774 -28.564959)
			(xy 427.275966 -28.549413) (xy 427.27626 -28.541218) (xy 427.27626 -28.368752) (xy 427.276487 -28.361714)
			(xy 427.280358 -28.34818) (xy 427.28388 -28.342082) (xy 427.296834 -28.322016) (xy 427.300492 -28.315758)
			(xy 427.304483 -28.30183) (xy 427.304708 -28.294584) (xy 427.304708 -27.872436) (xy 427.304274 -27.862371)
			(xy 427.296544 -27.843782) (xy 427.289722 -27.836368) (xy 427.0502 -27.596846) (xy 427.042804 -27.589995)
			(xy 427.024205 -27.582253) (xy 427.014132 -27.58186) (xy 417.699444 -27.58186) (xy 417.687119 -27.582456)
			(xy 417.66529 -27.593907) (xy 417.657788 -27.603704) (xy 417.640628 -27.627665) (xy 417.601122 -27.6714)
			(xy 417.556331 -27.709706) (xy 417.506996 -27.74195) (xy 417.453933 -27.767598) (xy 417.398018 -27.786227)
			(xy 417.340175 -27.797529) (xy 417.28136 -27.801317) (xy 417.222545 -27.797529) (xy 417.164702 -27.786227)
			(xy 417.108787 -27.767598) (xy 417.055724 -27.74195) (xy 417.006389 -27.709706) (xy 416.961598 -27.6714)
			(xy 416.922092 -27.627665) (xy 416.904932 -27.603704) (xy 416.897317 -27.594041) (xy 416.875556 -27.582644)
			(xy 416.863276 -27.58186) (xy 412.727902 -27.58186) (xy 412.717833 -27.582284) (xy 412.699234 -27.590005)
			(xy 412.691834 -27.596846) (xy 412.422848 -27.865832) (xy 412.416498 -27.877262) (xy 412.41472 -27.88412)
			(xy 412.406994 -27.91235) (xy 412.384082 -27.966204) (xy 412.353216 -28.015928) (xy 412.315119 -28.060357)
			(xy 412.270685 -28.098448) (xy 412.220956 -28.129307) (xy 412.167099 -28.152211) (xy 412.138876 -28.159964)
			(xy 412.132018 -28.161742) (xy 412.120588 -28.168092) (xy 412.10484 -28.18384) (xy 412.097996 -28.191239)
			(xy 412.09027 -28.209837) (xy 412.089854 -28.219908) (xy 412.089854 -29.114242) (xy 419.147244 -29.114242)
			(xy 419.147244 -28.250642) (xy 419.147734 -28.220658) (xy 419.155562 -28.161202) (xy 419.171083 -28.103277)
			(xy 419.194032 -28.047873) (xy 419.224016 -27.995939) (xy 419.260522 -27.948363) (xy 419.302927 -27.905958)
			(xy 419.350503 -27.869452) (xy 419.402437 -27.839468) (xy 419.457841 -27.816519) (xy 419.515766 -27.800998)
			(xy 419.575222 -27.79317) (xy 419.63519 -27.79317) (xy 419.694646 -27.800998) (xy 419.752571 -27.816519)
			(xy 419.807975 -27.839468) (xy 419.859909 -27.869452) (xy 419.907485 -27.905958) (xy 419.94989 -27.948363)
			(xy 419.986396 -27.995939) (xy 420.01638 -28.047873) (xy 420.039329 -28.103277) (xy 420.05485 -28.161202)
			(xy 420.062678 -28.220658) (xy 420.063168 -28.250642) (xy 420.063168 -28.469082) (xy 424.05249 -28.469082)
			(xy 424.056561 -28.41346) (xy 424.068687 -28.359023) (xy 424.08861 -28.306932) (xy 424.115906 -28.258297)
			(xy 424.149992 -28.214154) (xy 424.190141 -28.175445) (xy 424.235499 -28.142994) (xy 424.285099 -28.117493)
			(xy 424.337883 -28.099486) (xy 424.392726 -28.089356) (xy 424.44846 -28.087319) (xy 424.503897 -28.093419)
			(xy 424.557854 -28.107525) (xy 424.609183 -28.129337) (xy 424.656789 -28.158391) (xy 424.699657 -28.194066)
			(xy 424.736874 -28.235603) (xy 424.767647 -28.282116) (xy 424.791319 -28.332613) (xy 424.807387 -28.38602)
			(xy 424.815507 -28.441196) (xy 424.816016 -28.469082) (xy 424.815507 -28.496968) (xy 424.807387 -28.552144)
			(xy 424.791319 -28.605551) (xy 424.767647 -28.656048) (xy 424.736874 -28.702561) (xy 424.699657 -28.744098)
			(xy 424.656789 -28.779773) (xy 424.609183 -28.808827) (xy 424.557854 -28.830639) (xy 424.503897 -28.844745)
			(xy 424.44846 -28.850845) (xy 424.392726 -28.848808) (xy 424.337883 -28.838678) (xy 424.285099 -28.820671)
			(xy 424.235499 -28.79517) (xy 424.190141 -28.762719) (xy 424.149992 -28.72401) (xy 424.115906 -28.679867)
			(xy 424.08861 -28.631232) (xy 424.068687 -28.579141) (xy 424.056561 -28.524704) (xy 424.05249 -28.469082)
			(xy 420.063168 -28.469082) (xy 420.063168 -29.114242) (xy 420.062678 -29.144226) (xy 420.05485 -29.203682)
			(xy 420.039329 -29.261607) (xy 420.01638 -29.317011) (xy 419.986396 -29.368945) (xy 419.94989 -29.416521)
			(xy 419.907485 -29.458926) (xy 419.859909 -29.495432) (xy 419.807975 -29.525416) (xy 419.752571 -29.548365)
			(xy 419.694646 -29.563886) (xy 419.63519 -29.571714) (xy 419.575222 -29.571714) (xy 419.515766 -29.563886)
			(xy 419.457841 -29.548365) (xy 419.402437 -29.525416) (xy 419.350503 -29.495432) (xy 419.302927 -29.458926)
			(xy 419.260522 -29.416521) (xy 419.224016 -29.368945) (xy 419.194032 -29.317011) (xy 419.171083 -29.261607)
			(xy 419.155562 -29.203682) (xy 419.147734 -29.144226) (xy 419.147244 -29.114242) (xy 412.089854 -29.114242)
			(xy 412.089854 -29.186378) (xy 412.111952 -29.214064) (xy 412.129478 -29.217874) (xy 412.155772 -29.224335)
			(xy 412.206345 -29.243678) (xy 412.253675 -29.269974) (xy 412.296813 -29.302697) (xy 412.334894 -29.341188)
			(xy 412.367151 -29.384676) (xy 412.392937 -29.432286) (xy 412.411735 -29.483063) (xy 412.423167 -29.535988)
			(xy 412.427004 -29.589996) (xy 412.423168 -29.644005) (xy 412.411737 -29.69693) (xy 412.39294 -29.747707)
			(xy 412.367154 -29.795318) (xy 412.334898 -29.838806) (xy 412.296819 -29.877298) (xy 412.253681 -29.910022)
			(xy 412.206351 -29.936319) (xy 412.155779 -29.955663) (xy 412.129478 -29.962094) (xy 412.111952 -29.965904)
			(xy 412.089854 -29.99359) (xy 412.089854 -30.92069) (xy 421.789352 -30.92069) (xy 421.789352 -30.05709)
			(xy 421.789842 -30.027106) (xy 421.79767 -29.96765) (xy 421.813191 -29.909725) (xy 421.83614 -29.854321)
			(xy 421.866124 -29.802387) (xy 421.90263 -29.754811) (xy 421.945035 -29.712406) (xy 421.992611 -29.6759)
			(xy 422.044545 -29.645916) (xy 422.099949 -29.622967) (xy 422.157874 -29.607446) (xy 422.21733 -29.599618)
			(xy 422.277298 -29.599618) (xy 422.336754 -29.607446) (xy 422.394679 -29.622967) (xy 422.450083 -29.645916)
			(xy 422.502017 -29.6759) (xy 422.549593 -29.712406) (xy 422.591998 -29.754811) (xy 422.628504 -29.802387)
			(xy 422.658488 -29.854321) (xy 422.681437 -29.909725) (xy 422.696958 -29.96765) (xy 422.704786 -30.027106)
			(xy 422.705276 -30.05709) (xy 422.705276 -30.92069) (xy 422.704786 -30.950674) (xy 422.696958 -31.01013)
			(xy 422.681437 -31.068055) (xy 422.658488 -31.123459) (xy 422.628504 -31.175393) (xy 422.591998 -31.222969)
			(xy 422.549593 -31.265374) (xy 422.502017 -31.30188) (xy 422.450083 -31.331864) (xy 422.394679 -31.354813)
			(xy 422.336754 -31.370334) (xy 422.277298 -31.378162) (xy 422.21733 -31.378162) (xy 422.157874 -31.370334)
			(xy 422.099949 -31.354813) (xy 422.044545 -31.331864) (xy 421.992611 -31.30188) (xy 421.945035 -31.265374)
			(xy 421.90263 -31.222969) (xy 421.866124 -31.175393) (xy 421.83614 -31.123459) (xy 421.813191 -31.068055)
			(xy 421.79767 -31.01013) (xy 421.789842 -30.950674) (xy 421.789352 -30.92069) (xy 412.089854 -30.92069)
			(xy 412.089854 -31.232602) (xy 412.115254 -31.261304) (xy 412.134558 -31.26359) (xy 412.161968 -31.267414)
			(xy 412.215368 -31.281949) (xy 412.266107 -31.304048) (xy 412.31312 -31.333247) (xy 412.35542 -31.368933)
			(xy 412.392121 -31.410356) (xy 412.42245 -31.456648) (xy 412.445773 -31.506836) (xy 412.461598 -31.559867)
			(xy 412.469595 -31.614629) (xy 412.469595 -31.669972) (xy 412.461598 -31.724734) (xy 412.445772 -31.777765)
			(xy 412.42245 -31.827953) (xy 412.39212 -31.874245) (xy 412.35542 -31.915668) (xy 412.313119 -31.951353)
			(xy 412.266106 -31.980552) (xy 412.215367 -32.002651) (xy 412.161967 -32.017187) (xy 412.134558 -32.021018)
			(xy 412.115254 -32.023304) (xy 412.089854 -32.052006) (xy 412.089854 -32.714184) (xy 419.147244 -32.714184)
			(xy 419.147244 -31.850584) (xy 419.147734 -31.8206) (xy 419.155562 -31.761144) (xy 419.171083 -31.703219)
			(xy 419.194032 -31.647815) (xy 419.224016 -31.595881) (xy 419.260522 -31.548305) (xy 419.302927 -31.5059)
			(xy 419.350503 -31.469394) (xy 419.402437 -31.43941) (xy 419.457841 -31.416461) (xy 419.515766 -31.40094)
			(xy 419.575222 -31.393112) (xy 419.63519 -31.393112) (xy 419.694646 -31.40094) (xy 419.752571 -31.416461)
			(xy 419.807975 -31.43941) (xy 419.859909 -31.469394) (xy 419.907485 -31.5059) (xy 419.94989 -31.548305)
			(xy 419.986396 -31.595881) (xy 420.01638 -31.647815) (xy 420.039329 -31.703219) (xy 420.05485 -31.761144)
			(xy 420.062678 -31.8206) (xy 420.063168 -31.850584) (xy 420.063168 -32.714184) (xy 420.062678 -32.744168)
			(xy 420.05485 -32.803624) (xy 420.039329 -32.861549) (xy 420.01638 -32.916953) (xy 419.986396 -32.968887)
			(xy 419.94989 -33.016463) (xy 419.907485 -33.058868) (xy 419.859909 -33.095374) (xy 419.807975 -33.125358)
			(xy 419.752571 -33.148307) (xy 419.694646 -33.163828) (xy 419.63519 -33.171656) (xy 419.575222 -33.171656)
			(xy 419.515766 -33.163828) (xy 419.457841 -33.148307) (xy 419.402437 -33.125358) (xy 419.350503 -33.095374)
			(xy 419.302927 -33.058868) (xy 419.260522 -33.016463) (xy 419.224016 -32.968887) (xy 419.194032 -32.916953)
			(xy 419.171083 -32.861549) (xy 419.155562 -32.803624) (xy 419.147734 -32.744168) (xy 419.147244 -32.714184)
			(xy 412.089854 -32.714184) (xy 412.089854 -34.520886) (xy 421.789352 -34.520886) (xy 421.789352 -33.657286)
			(xy 421.789842 -33.627302) (xy 421.79767 -33.567846) (xy 421.813191 -33.509921) (xy 421.83614 -33.454517)
			(xy 421.866124 -33.402583) (xy 421.90263 -33.355007) (xy 421.945035 -33.312602) (xy 421.992611 -33.276096)
			(xy 422.044545 -33.246112) (xy 422.099949 -33.223163) (xy 422.157874 -33.207642) (xy 422.21733 -33.199814)
			(xy 422.277298 -33.199814) (xy 422.336754 -33.207642) (xy 422.394679 -33.223163) (xy 422.450083 -33.246112)
			(xy 422.502017 -33.276096) (xy 422.549593 -33.312602) (xy 422.591998 -33.355007) (xy 422.628504 -33.402583)
			(xy 422.658488 -33.454517) (xy 422.681437 -33.509921) (xy 422.696958 -33.567846) (xy 422.704786 -33.627302)
			(xy 422.705276 -33.657286) (xy 422.705276 -34.520886) (xy 422.704786 -34.55087) (xy 422.696958 -34.610326)
			(xy 422.681437 -34.668251) (xy 422.658488 -34.723655) (xy 422.628504 -34.775589) (xy 422.591998 -34.823165)
			(xy 422.549593 -34.86557) (xy 422.502017 -34.902076) (xy 422.450083 -34.93206) (xy 422.394679 -34.955009)
			(xy 422.336754 -34.97053) (xy 422.277298 -34.978358) (xy 422.21733 -34.978358) (xy 422.157874 -34.97053)
			(xy 422.099949 -34.955009) (xy 422.044545 -34.93206) (xy 421.992611 -34.902076) (xy 421.945035 -34.86557)
			(xy 421.90263 -34.823165) (xy 421.866124 -34.775589) (xy 421.83614 -34.723655) (xy 421.813191 -34.668251)
			(xy 421.79767 -34.610326) (xy 421.789842 -34.55087) (xy 421.789352 -34.520886) (xy 412.089854 -34.520886)
			(xy 412.089854 -36.60013) (xy 412.298649 -36.60013) (xy 412.302653 -36.512245) (xy 412.314633 -36.425088)
			(xy 412.334488 -36.339381) (xy 412.362055 -36.255836) (xy 412.397105 -36.175143) (xy 412.439347 -36.097971)
			(xy 412.488432 -36.024961) (xy 412.543953 -35.956717) (xy 412.60545 -35.893804) (xy 412.672412 -35.836744)
			(xy 412.744286 -35.78601) (xy 412.820476 -35.742022) (xy 412.90035 -35.705144) (xy 412.983247 -35.675683)
			(xy 413.068479 -35.653881) (xy 413.155341 -35.639921) (xy 413.243112 -35.633917) (xy 413.331066 -35.63592)
			(xy 413.418473 -35.645912) (xy 413.504609 -35.663812) (xy 413.588761 -35.68947) (xy 413.670231 -35.722674)
			(xy 413.748344 -35.763148) (xy 413.822452 -35.810559) (xy 413.891943 -35.864512) (xy 413.905034 -35.876738)
			(xy 419.017194 -35.876738) (xy 419.021265 -35.821116) (xy 419.033391 -35.766679) (xy 419.053314 -35.714588)
			(xy 419.08061 -35.665953) (xy 419.114696 -35.62181) (xy 419.154845 -35.583101) (xy 419.200203 -35.55065)
			(xy 419.249803 -35.525149) (xy 419.302587 -35.507142) (xy 419.35743 -35.497012) (xy 419.413164 -35.494975)
			(xy 419.468601 -35.501075) (xy 419.522558 -35.515181) (xy 419.573887 -35.536993) (xy 419.621493 -35.566047)
			(xy 419.664361 -35.601722) (xy 419.701578 -35.643259) (xy 419.732351 -35.689772) (xy 419.756023 -35.740269)
			(xy 419.772091 -35.793676) (xy 419.780211 -35.848852) (xy 419.78072 -35.876738) (xy 423.088814 -35.876738)
			(xy 423.092885 -35.821116) (xy 423.105011 -35.766679) (xy 423.124934 -35.714588) (xy 423.15223 -35.665953)
			(xy 423.186316 -35.62181) (xy 423.226465 -35.583101) (xy 423.271823 -35.55065) (xy 423.321423 -35.525149)
			(xy 423.374207 -35.507142) (xy 423.42905 -35.497012) (xy 423.484784 -35.494975) (xy 423.540221 -35.501075)
			(xy 423.594178 -35.515181) (xy 423.645507 -35.536993) (xy 423.693113 -35.566047) (xy 423.735981 -35.601722)
			(xy 423.773198 -35.643259) (xy 423.803971 -35.689772) (xy 423.827643 -35.740269) (xy 423.843711 -35.793676)
			(xy 423.851831 -35.848852) (xy 423.85234 -35.876738) (xy 423.851831 -35.904624) (xy 423.843711 -35.9598)
			(xy 423.827643 -36.013207) (xy 423.803971 -36.063704) (xy 423.773198 -36.110217) (xy 423.735981 -36.151754)
			(xy 423.693113 -36.187429) (xy 423.645507 -36.216483) (xy 423.594178 -36.238295) (xy 423.540221 -36.252401)
			(xy 423.484784 -36.258501) (xy 423.42905 -36.256464) (xy 423.374207 -36.246334) (xy 423.321423 -36.228327)
			(xy 423.271823 -36.202826) (xy 423.226465 -36.170375) (xy 423.186316 -36.131666) (xy 423.15223 -36.087523)
			(xy 423.124934 -36.038888) (xy 423.105011 -35.986797) (xy 423.092885 -35.93236) (xy 423.088814 -35.876738)
			(xy 419.78072 -35.876738) (xy 419.780211 -35.904624) (xy 419.772091 -35.9598) (xy 419.756023 -36.013207)
			(xy 419.732351 -36.063704) (xy 419.701578 -36.110217) (xy 419.664361 -36.151754) (xy 419.621493 -36.187429)
			(xy 419.573887 -36.216483) (xy 419.522558 -36.238295) (xy 419.468601 -36.252401) (xy 419.413164 -36.258501)
			(xy 419.35743 -36.256464) (xy 419.302587 -36.246334) (xy 419.249803 -36.228327) (xy 419.200203 -36.202826)
			(xy 419.154845 -36.170375) (xy 419.114696 -36.131666) (xy 419.08061 -36.087523) (xy 419.053314 -36.038888)
			(xy 419.033391 -35.986797) (xy 419.021265 -35.93236) (xy 419.017194 -35.876738) (xy 413.905034 -35.876738)
			(xy 413.956239 -35.92456) (xy 414.014808 -35.990207) (xy 414.067165 -36.060907) (xy 414.112877 -36.136076)
			(xy 414.151563 -36.21509) (xy 414.182904 -36.297295) (xy 414.206639 -36.382009) (xy 414.222573 -36.46853)
			(xy 414.226356 -36.50996) (xy 420.913812 -36.50996) (xy 420.917883 -36.454338) (xy 420.930009 -36.399901)
			(xy 420.949932 -36.34781) (xy 420.977228 -36.299175) (xy 421.011314 -36.255032) (xy 421.051463 -36.216323)
			(xy 421.096821 -36.183872) (xy 421.146421 -36.158371) (xy 421.199205 -36.140364) (xy 421.254048 -36.130234)
			(xy 421.309782 -36.128197) (xy 421.365219 -36.134297) (xy 421.419176 -36.148403) (xy 421.470505 -36.170215)
			(xy 421.518111 -36.199269) (xy 421.560979 -36.234944) (xy 421.598196 -36.276481) (xy 421.628969 -36.322994)
			(xy 421.652641 -36.373491) (xy 421.668709 -36.426898) (xy 421.672634 -36.453572) (xy 424.228512 -36.453572)
			(xy 424.232583 -36.39795) (xy 424.244709 -36.343513) (xy 424.264632 -36.291422) (xy 424.291928 -36.242787)
			(xy 424.326014 -36.198644) (xy 424.366163 -36.159935) (xy 424.411521 -36.127484) (xy 424.461121 -36.101983)
			(xy 424.513905 -36.083976) (xy 424.568748 -36.073846) (xy 424.624482 -36.071809) (xy 424.679919 -36.077909)
			(xy 424.733876 -36.092015) (xy 424.785205 -36.113827) (xy 424.832811 -36.142881) (xy 424.875679 -36.178556)
			(xy 424.912896 -36.220093) (xy 424.943669 -36.266606) (xy 424.967341 -36.317103) (xy 424.983409 -36.37051)
			(xy 424.991529 -36.425686) (xy 424.992038 -36.453572) (xy 424.991529 -36.481458) (xy 424.983409 -36.536634)
			(xy 424.967341 -36.590041) (xy 424.943669 -36.640538) (xy 424.912896 -36.687051) (xy 424.875679 -36.728588)
			(xy 424.832811 -36.764263) (xy 424.785205 -36.793317) (xy 424.733876 -36.815129) (xy 424.679919 -36.829235)
			(xy 424.624482 -36.835335) (xy 424.568748 -36.833298) (xy 424.513905 -36.823168) (xy 424.461121 -36.805161)
			(xy 424.411521 -36.77966) (xy 424.366163 -36.747209) (xy 424.326014 -36.7085) (xy 424.291928 -36.664357)
			(xy 424.264632 -36.615722) (xy 424.244709 -36.563631) (xy 424.232583 -36.509194) (xy 424.228512 -36.453572)
			(xy 421.672634 -36.453572) (xy 421.676829 -36.482074) (xy 421.677338 -36.50996) (xy 421.676829 -36.537846)
			(xy 421.668709 -36.593022) (xy 421.652641 -36.646429) (xy 421.628969 -36.696926) (xy 421.598196 -36.743439)
			(xy 421.560979 -36.784976) (xy 421.518111 -36.820651) (xy 421.470505 -36.849705) (xy 421.419176 -36.871517)
			(xy 421.365219 -36.885623) (xy 421.309782 -36.891723) (xy 421.254048 -36.889686) (xy 421.199205 -36.879556)
			(xy 421.146421 -36.861549) (xy 421.096821 -36.836048) (xy 421.051463 -36.803597) (xy 421.011314 -36.764888)
			(xy 420.977228 -36.720745) (xy 420.949932 -36.67211) (xy 420.930009 -36.620019) (xy 420.917883 -36.565582)
			(xy 420.913812 -36.50996) (xy 414.226356 -36.50996) (xy 414.230573 -36.556142) (xy 414.231074 -36.60013)
			(xy 414.230573 -36.644118) (xy 414.222573 -36.73173) (xy 414.206639 -36.818251) (xy 414.182904 -36.902965)
			(xy 414.151563 -36.98517) (xy 414.112877 -37.064184) (xy 414.067165 -37.139353) (xy 414.014808 -37.210053)
			(xy 413.956239 -37.2757) (xy 413.891943 -37.335748) (xy 413.822452 -37.389701) (xy 413.748344 -37.437112)
			(xy 413.670231 -37.477586) (xy 413.588761 -37.51079) (xy 413.504609 -37.536448) (xy 413.418473 -37.554348)
			(xy 413.331066 -37.56434) (xy 413.243112 -37.566343) (xy 413.155341 -37.560339) (xy 413.068479 -37.546379)
			(xy 412.983247 -37.524577) (xy 412.90035 -37.495116) (xy 412.820476 -37.458238) (xy 412.744286 -37.41425)
			(xy 412.672412 -37.363516) (xy 412.60545 -37.306456) (xy 412.543953 -37.243543) (xy 412.488432 -37.175299)
			(xy 412.439347 -37.102289) (xy 412.397105 -37.025117) (xy 412.362055 -36.944424) (xy 412.334488 -36.860879)
			(xy 412.314633 -36.775172) (xy 412.302653 -36.688015) (xy 412.298649 -36.60013) (xy 412.089854 -36.60013)
			(xy 412.089854 -39.97198) (xy 426.195742 -39.97198) (xy 426.199813 -39.916358) (xy 426.211939 -39.861921)
			(xy 426.231862 -39.80983) (xy 426.259158 -39.761195) (xy 426.293244 -39.717052) (xy 426.333393 -39.678343)
			(xy 426.378751 -39.645892) (xy 426.428351 -39.620391) (xy 426.481135 -39.602384) (xy 426.535978 -39.592254)
			(xy 426.591712 -39.590217) (xy 426.647149 -39.596317) (xy 426.701106 -39.610423) (xy 426.752435 -39.632235)
			(xy 426.800041 -39.661289) (xy 426.842909 -39.696964) (xy 426.880126 -39.738501) (xy 426.910899 -39.785014)
			(xy 426.934571 -39.835511) (xy 426.950639 -39.888918) (xy 426.958759 -39.944094) (xy 426.959268 -39.97198)
			(xy 426.958759 -39.999866) (xy 426.950639 -40.055042) (xy 426.934571 -40.108449) (xy 426.910899 -40.158946)
			(xy 426.880126 -40.205459) (xy 426.842909 -40.246996) (xy 426.800041 -40.282671) (xy 426.752435 -40.311725)
			(xy 426.701106 -40.333537) (xy 426.647149 -40.347643) (xy 426.591712 -40.353743) (xy 426.535978 -40.351706)
			(xy 426.481135 -40.341576) (xy 426.428351 -40.323569) (xy 426.378751 -40.298068) (xy 426.333393 -40.265617)
			(xy 426.293244 -40.226908) (xy 426.259158 -40.182765) (xy 426.231862 -40.13413) (xy 426.211939 -40.082039)
			(xy 426.199813 -40.027602) (xy 426.195742 -39.97198) (xy 412.089854 -39.97198) (xy 412.089854 -40.452802)
			(xy 412.090279 -40.462871) (xy 412.098 -40.48147) (xy 412.10484 -40.48887) (xy 412.324042 -40.708072)
			(xy 412.331441 -40.714915) (xy 412.35004 -40.722639) (xy 412.36011 -40.723058) (xy 421.381428 -40.723058)
			(xy 421.391495 -40.723488) (xy 421.410086 -40.731216) (xy 421.417496 -40.738044) (xy 422.358566 -41.679114)
			(xy 422.365414 -41.686512) (xy 422.373149 -41.70511) (xy 422.373552 -41.715182) (xy 422.373552 -43.566842)
			(xy 423.63339 -43.566842) (xy 423.637461 -43.51122) (xy 423.649587 -43.456783) (xy 423.66951 -43.404692)
			(xy 423.696806 -43.356057) (xy 423.730892 -43.311914) (xy 423.771041 -43.273205) (xy 423.816399 -43.240754)
			(xy 423.865999 -43.215253) (xy 423.918783 -43.197246) (xy 423.973626 -43.187116) (xy 424.02936 -43.185079)
			(xy 424.084797 -43.191179) (xy 424.138754 -43.205285) (xy 424.190083 -43.227097) (xy 424.237689 -43.256151)
			(xy 424.280557 -43.291826) (xy 424.317774 -43.333363) (xy 424.348547 -43.379876) (xy 424.372219 -43.430373)
			(xy 424.388287 -43.48378) (xy 424.396407 -43.538956) (xy 424.396916 -43.566842) (xy 424.396407 -43.594728)
			(xy 424.388287 -43.649904) (xy 424.372219 -43.703311) (xy 424.348547 -43.753808) (xy 424.317774 -43.800321)
			(xy 424.280557 -43.841858) (xy 424.26247 -43.85691) (xy 425.019722 -43.85691) (xy 425.023793 -43.801288)
			(xy 425.035919 -43.746851) (xy 425.055842 -43.69476) (xy 425.083138 -43.646125) (xy 425.117224 -43.601982)
			(xy 425.157373 -43.563273) (xy 425.202731 -43.530822) (xy 425.252331 -43.505321) (xy 425.305115 -43.487314)
			(xy 425.359958 -43.477184) (xy 425.415692 -43.475147) (xy 425.471129 -43.481247) (xy 425.525086 -43.495353)
			(xy 425.576415 -43.517165) (xy 425.624021 -43.546219) (xy 425.666889 -43.581894) (xy 425.704106 -43.623431)
			(xy 425.734879 -43.669944) (xy 425.758551 -43.720441) (xy 425.774619 -43.773848) (xy 425.782739 -43.829024)
			(xy 425.783248 -43.85691) (xy 425.782739 -43.884796) (xy 425.774619 -43.939972) (xy 425.758551 -43.993379)
			(xy 425.734879 -44.043876) (xy 425.704106 -44.090389) (xy 425.666889 -44.131926) (xy 425.624021 -44.167601)
			(xy 425.576415 -44.196655) (xy 425.525086 -44.218467) (xy 425.471129 -44.232573) (xy 425.415692 -44.238673)
			(xy 425.359958 -44.236636) (xy 425.305115 -44.226506) (xy 425.252331 -44.208499) (xy 425.202731 -44.182998)
			(xy 425.157373 -44.150547) (xy 425.117224 -44.111838) (xy 425.083138 -44.067695) (xy 425.055842 -44.01906)
			(xy 425.035919 -43.966969) (xy 425.023793 -43.912532) (xy 425.019722 -43.85691) (xy 424.26247 -43.85691)
			(xy 424.237689 -43.877533) (xy 424.190083 -43.906587) (xy 424.138754 -43.928399) (xy 424.084797 -43.942505)
			(xy 424.02936 -43.948605) (xy 423.973626 -43.946568) (xy 423.918783 -43.936438) (xy 423.865999 -43.918431)
			(xy 423.816399 -43.89293) (xy 423.771041 -43.860479) (xy 423.730892 -43.82177) (xy 423.696806 -43.777627)
			(xy 423.66951 -43.728992) (xy 423.649587 -43.676901) (xy 423.637461 -43.622464) (xy 423.63339 -43.566842)
			(xy 422.373552 -43.566842) (xy 422.373552 -45.35424) (xy 425.00372 -45.35424) (xy 425.007791 -45.298618)
			(xy 425.019917 -45.244181) (xy 425.03984 -45.19209) (xy 425.067136 -45.143455) (xy 425.101222 -45.099312)
			(xy 425.141371 -45.060603) (xy 425.186729 -45.028152) (xy 425.236329 -45.002651) (xy 425.289113 -44.984644)
			(xy 425.343956 -44.974514) (xy 425.39969 -44.972477) (xy 425.455127 -44.978577) (xy 425.509084 -44.992683)
			(xy 425.560413 -45.014495) (xy 425.608019 -45.043549) (xy 425.650887 -45.079224) (xy 425.688104 -45.120761)
			(xy 425.718877 -45.167274) (xy 425.742549 -45.217771) (xy 425.758617 -45.271178) (xy 425.766737 -45.326354)
			(xy 425.767246 -45.35424) (xy 425.766737 -45.382126) (xy 425.758617 -45.437302) (xy 425.742549 -45.490709)
			(xy 425.718877 -45.541206) (xy 425.688104 -45.587719) (xy 425.650887 -45.629256) (xy 425.608019 -45.664931)
			(xy 425.560413 -45.693985) (xy 425.509084 -45.715797) (xy 425.455127 -45.729903) (xy 425.39969 -45.736003)
			(xy 425.343956 -45.733966) (xy 425.289113 -45.723836) (xy 425.236329 -45.705829) (xy 425.186729 -45.680328)
			(xy 425.141371 -45.647877) (xy 425.101222 -45.609168) (xy 425.067136 -45.565025) (xy 425.03984 -45.51639)
			(xy 425.019917 -45.464299) (xy 425.007791 -45.409862) (xy 425.00372 -45.35424) (xy 422.373552 -45.35424)
			(xy 422.373552 -46.693836) (xy 424.97629 -46.693836) (xy 424.976776 -46.666585) (xy 424.984532 -46.612637)
			(xy 424.999887 -46.560342) (xy 425.022529 -46.510765) (xy 425.051995 -46.464915) (xy 425.087686 -46.423724)
			(xy 425.128877 -46.388033) (xy 425.174727 -46.358567) (xy 425.224304 -46.335925) (xy 425.276599 -46.32057)
			(xy 425.330547 -46.312814) (xy 425.385049 -46.312814) (xy 425.438997 -46.32057) (xy 425.491292 -46.335925)
			(xy 425.540869 -46.358567) (xy 425.586719 -46.388033) (xy 425.62791 -46.423724) (xy 425.663601 -46.464915)
			(xy 425.693067 -46.510765) (xy 425.715709 -46.560342) (xy 425.731064 -46.612637) (xy 425.73882 -46.666585)
			(xy 425.739306 -46.693836) (xy 425.738832 -46.720264) (xy 425.731523 -46.772611) (xy 425.71705 -46.823446)
			(xy 425.695691 -46.871793) (xy 425.682156 -46.894496) (xy 425.67606 -46.904402) (xy 425.67352 -46.927262)
			(xy 425.70781 -47.023782) (xy 425.723812 -47.040038) (xy 425.734988 -47.043848) (xy 425.759506 -47.052894)
			(xy 425.805957 -47.076841) (xy 425.848708 -47.106901) (xy 425.886958 -47.142512) (xy 425.919993 -47.183008)
			(xy 425.947196 -47.227631) (xy 425.968056 -47.275549) (xy 425.982186 -47.325864) (xy 425.989319 -47.377635)
			(xy 425.98975 -47.403766) (xy 425.989264 -47.431017) (xy 425.981508 -47.484965) (xy 425.966153 -47.53726)
			(xy 425.943511 -47.586837) (xy 425.914045 -47.632687) (xy 425.878354 -47.673878) (xy 425.837163 -47.709569)
			(xy 425.791313 -47.739035) (xy 425.741736 -47.761677) (xy 425.689441 -47.777032) (xy 425.635493 -47.784788)
			(xy 425.580991 -47.784788) (xy 425.527043 -47.777032) (xy 425.474748 -47.761677) (xy 425.425171 -47.739035)
			(xy 425.379321 -47.709569) (xy 425.33813 -47.673878) (xy 425.302439 -47.632687) (xy 425.272973 -47.586837)
			(xy 425.250331 -47.53726) (xy 425.234976 -47.484965) (xy 425.22722 -47.431017) (xy 425.226734 -47.403766)
			(xy 425.227203 -47.377338) (xy 425.234513 -47.324991) (xy 425.248987 -47.274156) (xy 425.270349 -47.225809)
			(xy 425.283884 -47.203106) (xy 425.28998 -47.1932) (xy 425.29252 -47.17034) (xy 425.25823 -47.07382)
			(xy 425.242228 -47.057564) (xy 425.231052 -47.053754) (xy 425.206544 -47.044684) (xy 425.160091 -47.020741)
			(xy 425.117339 -46.990685) (xy 425.079087 -46.955078) (xy 425.046051 -46.914585) (xy 425.018847 -46.869964)
			(xy 424.997985 -46.822049) (xy 424.983855 -46.771736) (xy 424.976721 -46.719966) (xy 424.97629 -46.693836)
			(xy 422.373552 -46.693836) (xy 422.373552 -48.30699) (xy 424.85386 -48.30699) (xy 424.857931 -48.251368)
			(xy 424.870057 -48.196931) (xy 424.88998 -48.14484) (xy 424.917276 -48.096205) (xy 424.951362 -48.052062)
			(xy 424.991511 -48.013353) (xy 425.036869 -47.980902) (xy 425.086469 -47.955401) (xy 425.139253 -47.937394)
			(xy 425.194096 -47.927264) (xy 425.24983 -47.925227) (xy 425.305267 -47.931327) (xy 425.359224 -47.945433)
			(xy 425.410553 -47.967245) (xy 425.458159 -47.996299) (xy 425.501027 -48.031974) (xy 425.538244 -48.073511)
			(xy 425.569017 -48.120024) (xy 425.592689 -48.170521) (xy 425.608757 -48.223928) (xy 425.616877 -48.279104)
			(xy 425.617386 -48.30699) (xy 425.616877 -48.334876) (xy 425.608757 -48.390052) (xy 425.592689 -48.443459)
			(xy 425.569017 -48.493956) (xy 425.538244 -48.540469) (xy 425.501027 -48.582006) (xy 425.458159 -48.617681)
			(xy 425.410553 -48.646735) (xy 425.359224 -48.668547) (xy 425.305267 -48.682653) (xy 425.24983 -48.688753)
			(xy 425.194096 -48.686716) (xy 425.139253 -48.676586) (xy 425.086469 -48.658579) (xy 425.036869 -48.633078)
			(xy 424.991511 -48.600627) (xy 424.951362 -48.561918) (xy 424.917276 -48.517775) (xy 424.88998 -48.46914)
			(xy 424.870057 -48.417049) (xy 424.857931 -48.362612) (xy 424.85386 -48.30699) (xy 422.373552 -48.30699)
			(xy 422.373552 -48.8442) (xy 422.487342 -48.8442) (xy 422.491413 -48.788578) (xy 422.503539 -48.734141)
			(xy 422.523462 -48.68205) (xy 422.550758 -48.633415) (xy 422.584844 -48.589272) (xy 422.624993 -48.550563)
			(xy 422.670351 -48.518112) (xy 422.719951 -48.492611) (xy 422.772735 -48.474604) (xy 422.827578 -48.464474)
			(xy 422.883312 -48.462437) (xy 422.938749 -48.468537) (xy 422.992706 -48.482643) (xy 423.044035 -48.504455)
			(xy 423.091641 -48.533509) (xy 423.134509 -48.569184) (xy 423.171726 -48.610721) (xy 423.202499 -48.657234)
			(xy 423.226171 -48.707731) (xy 423.242239 -48.761138) (xy 423.250359 -48.816314) (xy 423.250868 -48.8442)
			(xy 423.250359 -48.872086) (xy 423.247361 -48.89246) (xy 423.51401 -48.89246) (xy 423.518081 -48.836838)
			(xy 423.530207 -48.782401) (xy 423.55013 -48.73031) (xy 423.577426 -48.681675) (xy 423.611512 -48.637532)
			(xy 423.651661 -48.598823) (xy 423.697019 -48.566372) (xy 423.746619 -48.540871) (xy 423.799403 -48.522864)
			(xy 423.854246 -48.512734) (xy 423.90998 -48.510697) (xy 423.965417 -48.516797) (xy 424.019374 -48.530903)
			(xy 424.070703 -48.552715) (xy 424.118309 -48.581769) (xy 424.161177 -48.617444) (xy 424.198394 -48.658981)
			(xy 424.229167 -48.705494) (xy 424.252839 -48.755991) (xy 424.268907 -48.809398) (xy 424.277027 -48.864574)
			(xy 424.277536 -48.89246) (xy 424.277027 -48.920346) (xy 424.268907 -48.975522) (xy 424.252839 -49.028929)
			(xy 424.229167 -49.079426) (xy 424.198394 -49.125939) (xy 424.161177 -49.167476) (xy 424.118309 -49.203151)
			(xy 424.070703 -49.232205) (xy 424.019374 -49.254017) (xy 423.965417 -49.268123) (xy 423.90998 -49.274223)
			(xy 423.854246 -49.272186) (xy 423.799403 -49.262056) (xy 423.746619 -49.244049) (xy 423.697019 -49.218548)
			(xy 423.651661 -49.186097) (xy 423.611512 -49.147388) (xy 423.577426 -49.103245) (xy 423.55013 -49.05461)
			(xy 423.530207 -49.002519) (xy 423.518081 -48.948082) (xy 423.51401 -48.89246) (xy 423.247361 -48.89246)
			(xy 423.242239 -48.927262) (xy 423.226171 -48.980669) (xy 423.202499 -49.031166) (xy 423.171726 -49.077679)
			(xy 423.134509 -49.119216) (xy 423.091641 -49.154891) (xy 423.044035 -49.183945) (xy 422.992706 -49.205757)
			(xy 422.938749 -49.219863) (xy 422.883312 -49.225963) (xy 422.827578 -49.223926) (xy 422.772735 -49.213796)
			(xy 422.719951 -49.195789) (xy 422.670351 -49.170288) (xy 422.624993 -49.137837) (xy 422.584844 -49.099128)
			(xy 422.550758 -49.054985) (xy 422.523462 -49.00635) (xy 422.503539 -48.954259) (xy 422.491413 -48.899822)
			(xy 422.487342 -48.8442) (xy 422.373552 -48.8442) (xy 422.373552 -50.502312) (xy 423.116754 -50.502312)
			(xy 423.120825 -50.44669) (xy 423.132951 -50.392253) (xy 423.152874 -50.340162) (xy 423.18017 -50.291527)
			(xy 423.214256 -50.247384) (xy 423.254405 -50.208675) (xy 423.299763 -50.176224) (xy 423.349363 -50.150723)
			(xy 423.402147 -50.132716) (xy 423.45699 -50.122586) (xy 423.512724 -50.120549) (xy 423.568161 -50.126649)
			(xy 423.622118 -50.140755) (xy 423.673447 -50.162567) (xy 423.721053 -50.191621) (xy 423.763921 -50.227296)
			(xy 423.801138 -50.268833) (xy 423.831911 -50.315346) (xy 423.855583 -50.365843) (xy 423.871651 -50.41925)
			(xy 423.879771 -50.474426) (xy 423.88028 -50.502312) (xy 423.879771 -50.530198) (xy 423.871651 -50.585374)
			(xy 423.855583 -50.638781) (xy 423.831911 -50.689278) (xy 423.801138 -50.735791) (xy 423.763921 -50.777328)
			(xy 423.721053 -50.813003) (xy 423.673447 -50.842057) (xy 423.622118 -50.863869) (xy 423.568161 -50.877975)
			(xy 423.512724 -50.884075) (xy 423.45699 -50.882038) (xy 423.402147 -50.871908) (xy 423.349363 -50.853901)
			(xy 423.299763 -50.8284) (xy 423.254405 -50.795949) (xy 423.214256 -50.75724) (xy 423.18017 -50.713097)
			(xy 423.152874 -50.664462) (xy 423.132951 -50.612371) (xy 423.120825 -50.557934) (xy 423.116754 -50.502312)
			(xy 422.373552 -50.502312) (xy 422.373552 -51.198018) (xy 422.37398 -51.208086) (xy 422.381705 -51.22668)
			(xy 422.388538 -51.234086) (xy 422.53281 -51.378358) (xy 422.540207 -51.385207) (xy 422.558805 -51.392945)
			(xy 422.568878 -51.393344)
		)
		(stroke
			(width 0)
			(type solid)
		)
		(fill yes)
		(layer "In9.Cu")
		(net "GND")
	)
	(gr_poly
		(pts
			(xy 308.93258 -51.393344) (xy 308.941812 -51.392948) (xy 308.959078 -51.386403) (xy 308.972898 -51.374157)
			(xy 308.977538 -51.366166) (xy 309.019194 -51.286664) (xy 309.023103 -51.278383) (xy 309.025382 -51.260225)
			(xy 309.021161 -51.242418) (xy 309.0164 -51.234594) (xy 309.016146 -51.23434) (xy 309.000649 -51.2107)
			(xy 308.976045 -51.159812) (xy 308.959214 -51.105852) (xy 308.950522 -51.05) (xy 308.949852 -51.021742)
			(xy 308.949852 -51.01463) (xy 308.950664 -50.987604) (xy 308.958974 -50.934177) (xy 308.974743 -50.882459)
			(xy 308.997655 -50.833486) (xy 309.027252 -50.788237) (xy 309.062941 -50.74762) (xy 309.104006 -50.712448)
			(xy 309.149625 -50.683426) (xy 309.198885 -50.661135) (xy 309.250799 -50.646021) (xy 309.304326 -50.638388)
			(xy 309.358394 -50.638388) (xy 309.411921 -50.646021) (xy 309.463835 -50.661135) (xy 309.513095 -50.683426)
			(xy 309.558714 -50.712448) (xy 309.599779 -50.74762) (xy 309.635468 -50.788237) (xy 309.665065 -50.833486)
			(xy 309.687977 -50.882459) (xy 309.703746 -50.934177) (xy 309.712056 -50.987604) (xy 309.712868 -51.01463)
			(xy 309.712868 -51.01971) (xy 309.71236 -51.048258) (xy 309.703844 -51.104716) (xy 309.687005 -51.159273)
			(xy 309.662219 -51.210709) (xy 309.646574 -51.234594) (xy 309.638446 -51.246278) (xy 309.636922 -51.274218)
			(xy 309.685182 -51.366166) (xy 309.689829 -51.374152) (xy 309.703649 -51.386395) (xy 309.720909 -51.392952)
			(xy 309.73014 -51.393344) (xy 310.622188 -51.393344) (xy 310.632149 -51.392855) (xy 310.650572 -51.385267)
			(xy 310.658002 -51.378612) (xy 311.176162 -50.860452) (xy 311.179972 -50.852578) (xy 311.189878 -50.833528)
			(xy 311.190132 -50.833274) (xy 311.193942 -50.82667) (xy 311.197244 -50.821082) (xy 311.201308 -50.806858)
			(xy 311.20461 -50.795174) (xy 311.20461 -50.1904) (xy 311.204355 -50.182988) (xy 311.200092 -50.168791)
			(xy 311.196228 -50.16246) (xy 311.181394 -50.139007) (xy 311.157934 -50.088718) (xy 311.142012 -50.03556)
			(xy 311.133966 -49.980654) (xy 311.133964 -49.925162) (xy 311.142008 -49.870257) (xy 311.157928 -49.817097)
			(xy 311.181386 -49.766807) (xy 311.196228 -49.74336) (xy 311.200089 -49.737029) (xy 311.204341 -49.722831)
			(xy 311.20461 -49.71542) (xy 311.20461 -49.1744) (xy 311.204355 -49.166988) (xy 311.200092 -49.152791)
			(xy 311.196228 -49.14646) (xy 311.181394 -49.123007) (xy 311.157934 -49.072718) (xy 311.142012 -49.01956)
			(xy 311.133966 -48.964654) (xy 311.133964 -48.909162) (xy 311.142008 -48.854257) (xy 311.157928 -48.801097)
			(xy 311.181386 -48.750807) (xy 311.196228 -48.72736) (xy 311.200089 -48.721029) (xy 311.204341 -48.706831)
			(xy 311.20461 -48.69942) (xy 311.20461 -47.629572) (xy 311.20207 -47.61865) (xy 311.199276 -47.613062)
			(xy 311.18655 -47.586293) (xy 311.168572 -47.529814) (xy 311.159474 -47.471246) (xy 311.159472 -47.411975)
			(xy 311.168567 -47.353407) (xy 311.186542 -47.296927) (xy 311.199276 -47.270162) (xy 311.20207 -47.264574)
			(xy 311.20461 -47.253652) (xy 311.20461 -46.1264) (xy 311.204355 -46.118988) (xy 311.200092 -46.104791)
			(xy 311.196228 -46.09846) (xy 311.181394 -46.075007) (xy 311.157934 -46.024718) (xy 311.142012 -45.97156)
			(xy 311.133966 -45.916654) (xy 311.133964 -45.861162) (xy 311.142008 -45.806257) (xy 311.157928 -45.753097)
			(xy 311.181386 -45.702807) (xy 311.196228 -45.67936) (xy 311.200089 -45.673029) (xy 311.204341 -45.658831)
			(xy 311.20461 -45.65142) (xy 311.20461 -45.1104) (xy 311.204355 -45.102988) (xy 311.200092 -45.088791)
			(xy 311.196228 -45.08246) (xy 311.181394 -45.059007) (xy 311.157934 -45.008718) (xy 311.142012 -44.95556)
			(xy 311.133966 -44.900654) (xy 311.133964 -44.845162) (xy 311.142008 -44.790257) (xy 311.157928 -44.737097)
			(xy 311.181386 -44.686807) (xy 311.196228 -44.66336) (xy 311.200089 -44.657029) (xy 311.204341 -44.642831)
			(xy 311.20461 -44.63542) (xy 311.20461 -44.0944) (xy 311.204355 -44.086988) (xy 311.200092 -44.072791)
			(xy 311.196228 -44.06646) (xy 311.181394 -44.043007) (xy 311.157934 -43.992718) (xy 311.142012 -43.93956)
			(xy 311.133966 -43.884654) (xy 311.133964 -43.829162) (xy 311.142008 -43.774257) (xy 311.157928 -43.721097)
			(xy 311.181386 -43.670807) (xy 311.196228 -43.64736) (xy 311.200089 -43.641029) (xy 311.204341 -43.626831)
			(xy 311.20461 -43.61942) (xy 311.20461 -43.0784) (xy 311.204355 -43.070988) (xy 311.200092 -43.056791)
			(xy 311.196228 -43.05046) (xy 311.181394 -43.027007) (xy 311.157934 -42.976718) (xy 311.142012 -42.92356)
			(xy 311.133966 -42.868654) (xy 311.133964 -42.813162) (xy 311.142008 -42.758257) (xy 311.157928 -42.705097)
			(xy 311.181386 -42.654807) (xy 311.196228 -42.63136) (xy 311.200089 -42.625029) (xy 311.204341 -42.610831)
			(xy 311.20461 -42.60342) (xy 311.20461 -41.423844) (xy 311.204225 -41.414077) (xy 311.197055 -41.395911)
			(xy 311.19064 -41.388538) (xy 311.169812 -41.366948) (xy 311.16143 -41.362884) (xy 311.138062 -41.351454)
			(xy 311.12968 -41.350438) (xy 311.102281 -41.346598) (xy 311.048907 -41.332035) (xy 310.998196 -41.309915)
			(xy 310.951211 -41.280704) (xy 310.908938 -41.245013) (xy 310.872263 -41.20359) (xy 310.841955 -41.157305)
			(xy 310.818649 -41.107128) (xy 310.802836 -41.054111) (xy 310.794845 -40.999366) (xy 310.794844 -40.94404)
			(xy 310.802834 -40.889295) (xy 310.818647 -40.836278) (xy 310.841952 -40.7861) (xy 310.872259 -40.739815)
			(xy 310.908934 -40.698392) (xy 310.951206 -40.6627) (xy 310.99819 -40.633487) (xy 311.048901 -40.611367)
			(xy 311.102275 -40.596803) (xy 311.12968 -40.59301) (xy 311.138062 -40.591994) (xy 311.161684 -40.580564)
			(xy 311.16571 -40.578497) (xy 311.172996 -40.57313) (xy 311.176162 -40.569896) (xy 311.19064 -40.55491)
			(xy 311.197063 -40.547537) (xy 311.204262 -40.529375) (xy 311.20461 -40.519604) (xy 311.20461 -38.432232)
			(xy 311.204196 -38.422206) (xy 311.196532 -38.403676) (xy 311.182359 -38.389491) (xy 311.163836 -38.381812)
			(xy 311.15381 -38.381432) (xy 309.484014 -38.381432) (xy 309.474875 -38.381812) (xy 309.457761 -38.388226)
			(xy 309.443989 -38.400242) (xy 309.43931 -38.408102) (xy 309.397146 -38.486842) (xy 309.394133 -38.492877)
			(xy 309.391054 -38.506004) (xy 309.39105 -38.51275) (xy 309.391558 -38.527228) (xy 309.399432 -38.539166)
			(xy 309.414565 -38.562785) (xy 309.438489 -38.613521) (xy 309.454733 -38.667212) (xy 309.462947 -38.722701)
			(xy 309.46344 -38.750748) (xy 309.462951 -38.777998) (xy 309.455189 -38.831942) (xy 309.43983 -38.884233)
			(xy 309.417187 -38.933806) (xy 309.38772 -38.979653) (xy 309.352029 -39.02084) (xy 309.31084 -39.056529)
			(xy 309.264992 -39.085994) (xy 309.215418 -39.108636) (xy 309.163126 -39.123992) (xy 309.109182 -39.131752)
			(xy 309.081932 -39.132256) (xy 309.053632 -39.131737) (xy 308.997654 -39.123368) (xy 308.943526 -39.106823)
			(xy 308.892435 -39.082466) (xy 308.845502 -39.050831) (xy 308.803755 -39.012611) (xy 308.76811 -38.968644)
			(xy 308.753256 -38.94455) (xy 308.746652 -38.933374) (xy 308.725062 -38.920166) (xy 308.67985 -38.917626)
			(xy 308.615588 -38.913816) (xy 308.592728 -38.92423) (xy 308.585108 -38.93439) (xy 308.566919 -38.957266)
			(xy 308.524764 -38.99774) (xy 308.476931 -39.031315) (xy 308.424538 -39.057205) (xy 308.368811 -39.074806)
			(xy 308.311052 -39.083705) (xy 308.281832 -39.08425) (xy 308.254578 -39.083766) (xy 308.200625 -39.076014)
			(xy 308.148324 -39.060662) (xy 308.09874 -39.038023) (xy 308.052882 -39.008558) (xy 308.011685 -38.972868)
			(xy 307.975986 -38.931677) (xy 307.946512 -38.885825) (xy 307.923864 -38.836246) (xy 307.908502 -38.783948)
			(xy 307.900739 -38.729996) (xy 307.900324 -38.702742) (xy 307.900883 -38.672656) (xy 307.910329 -38.613232)
			(xy 307.929008 -38.556034) (xy 307.942234 -38.529006) (xy 307.94833 -38.517068) (xy 307.947314 -38.490906)
			(xy 307.89499 -38.405562) (xy 307.890155 -38.398405) (xy 307.876712 -38.387579) (xy 307.860439 -38.381822)
			(xy 307.85181 -38.381432) (xy 305.485038 -38.381432) (xy 305.47618 -38.381852) (xy 305.459542 -38.387948)
			(xy 305.452526 -38.39337) (xy 305.240944 -38.604952) (xy 305.163474 -38.682168) (xy 305.139574 -38.705332)
			(xy 305.086768 -38.745848) (xy 305.029123 -38.779122) (xy 304.967628 -38.804585) (xy 304.903334 -38.8218)
			(xy 304.837343 -38.830473) (xy 304.804064 -38.831012) (xy 303.188624 -38.831012) (xy 303.155348 -38.830464)
			(xy 303.089366 -38.82177) (xy 303.025082 -38.804541) (xy 302.963596 -38.779071) (xy 302.905959 -38.745796)
			(xy 302.853156 -38.705285) (xy 302.829214 -38.682168) (xy 301.981616 -37.83457) (xy 301.958453 -37.810669)
			(xy 301.917939 -37.757863) (xy 301.884666 -37.700218) (xy 301.859204 -37.638723) (xy 301.84199 -37.57443)
			(xy 301.833318 -37.508439) (xy 301.832772 -37.47516) (xy 301.832799 -37.463333) (xy 301.833815 -37.439701)
			(xy 301.834804 -37.427916) (xy 301.835058 -37.42563) (xy 301.835058 -37.42436) (xy 301.838636 -37.393446)
			(xy 301.852369 -37.332746) (xy 301.873408 -37.274176) (xy 301.901437 -37.218611) (xy 301.936038 -37.166883)
			(xy 301.976694 -37.119764) (xy 302.022797 -37.077959) (xy 302.073657 -37.042094) (xy 302.128514 -37.012704)
			(xy 302.186547 -36.990228) (xy 302.24689 -36.975003) (xy 302.30864 -36.967257) (xy 302.339756 -36.966652)
			(xy 302.341026 -36.966652) (xy 302.373259 -36.967147) (xy 302.437209 -36.975296) (xy 302.468534 -36.982908)
			(xy 302.501129 -36.99194) (xy 302.563766 -37.017465) (xy 302.62246 -37.051079) (xy 302.676173 -37.092185)
			(xy 302.700436 -37.11575) (xy 303.384204 -37.799518) (xy 303.391599 -37.806373) (xy 303.410198 -37.814119)
			(xy 303.420272 -37.814504) (xy 304.049684 -37.814504) (xy 304.060436 -37.814032) (xy 304.080051 -37.805224)
			(xy 304.08753 -37.797486) (xy 304.138076 -37.741352) (xy 304.144643 -37.733234) (xy 304.151199 -37.713431)
			(xy 304.150776 -37.702998) (xy 304.150776 -37.702236) (xy 304.14981 -37.692295) (xy 304.148794 -37.672346)
			(xy 304.148744 -37.662358) (xy 304.149233 -37.635107) (xy 304.156994 -37.581162) (xy 304.172352 -37.528869)
			(xy 304.194995 -37.479294) (xy 304.224462 -37.433446) (xy 304.260152 -37.392257) (xy 304.301341 -37.356565)
			(xy 304.347189 -37.327098) (xy 304.396764 -37.304454) (xy 304.449056 -37.289095) (xy 304.503001 -37.281333)
			(xy 304.530252 -37.28085) (xy 304.559303 -37.281398) (xy 304.616732 -37.290213) (xy 304.672161 -37.30763)
			(xy 304.724311 -37.333248) (xy 304.771974 -37.366475) (xy 304.81405 -37.406542) (xy 304.832258 -37.429186)
			(xy 304.838354 -37.43706) (xy 304.846736 -37.44214) (xy 304.850895 -37.444439) (xy 304.859841 -37.44764)
			(xy 304.864516 -37.44849) (xy 304.932842 -37.459666) (xy 304.942418 -37.460805) (xy 304.961227 -37.456626)
			(xy 304.969418 -37.451538) (xy 304.969672 -37.451284) (xy 304.997357 -37.433229) (xy 305.056473 -37.40367)
			(xy 305.087528 -37.392356) (xy 305.114358 -37.383492) (xy 305.169483 -37.371061) (xy 305.225644 -37.364802)
			(xy 305.253898 -37.364416) (xy 311.15381 -37.364416) (xy 311.163818 -37.363927) (xy 311.182309 -37.356266)
			(xy 311.196463 -37.342114) (xy 311.204126 -37.323623) (xy 311.20461 -37.313616) (xy 311.20461 -31.63316)
			(xy 311.203848 -31.629096) (xy 311.201565 -31.613896) (xy 311.199148 -31.583252) (xy 311.199022 -31.567882)
			(xy 311.199142 -31.552512) (xy 311.20156 -31.521867) (xy 311.203848 -31.506668) (xy 311.20461 -31.502604)
			(xy 311.20461 -30.681168) (xy 311.204487 -30.676355) (xy 311.202696 -30.666897) (xy 311.201054 -30.662372)
			(xy 311.191402 -30.637734) (xy 311.185306 -30.630876) (xy 311.167184 -30.609786) (xy 311.136604 -30.563347)
			(xy 311.113085 -30.512963) (xy 311.097125 -30.459699) (xy 311.089061 -30.404684) (xy 311.089063 -30.34908)
			(xy 311.097133 -30.294066) (xy 311.113098 -30.240804) (xy 311.136622 -30.190422) (xy 311.167206 -30.143985)
			(xy 311.185306 -30.122876) (xy 311.191402 -30.116018) (xy 311.201054 -30.09138) (xy 311.202742 -30.086867)
			(xy 311.204539 -30.077402) (xy 311.20461 -30.072584) (xy 311.20461 -29.909008) (xy 311.190894 -29.874972)
			(xy 311.185052 -29.868368) (xy 311.167006 -29.847302) (xy 311.136563 -29.800933) (xy 311.113156 -29.750645)
			(xy 311.097278 -29.697497) (xy 311.089263 -29.642611) (xy 311.088786 -29.614876) (xy 311.088786 -29.614368)
			(xy 311.089392 -29.583501) (xy 311.099359 -29.522575) (xy 311.11901 -29.464051) (xy 311.147832 -29.409457)
			(xy 311.166002 -29.384498) (xy 311.170676 -29.377759) (xy 311.175867 -29.362213) (xy 311.176162 -29.354018)
			(xy 311.176162 -29.062934) (xy 311.175857 -29.054739) (xy 311.17068 -29.039189) (xy 311.166002 -29.032454)
			(xy 311.149798 -29.010241) (xy 311.12326 -28.962088) (xy 311.103902 -28.910627) (xy 311.092126 -28.856921)
			(xy 311.088175 -28.802081) (xy 311.092132 -28.747242) (xy 311.103913 -28.693537) (xy 311.123276 -28.642077)
			(xy 311.149819 -28.593927) (xy 311.166002 -28.571698) (xy 311.170676 -28.564959) (xy 311.175867 -28.549413)
			(xy 311.176162 -28.541218) (xy 311.176162 -28.368752) (xy 311.176389 -28.361714) (xy 311.180261 -28.348181)
			(xy 311.183782 -28.342082) (xy 311.196736 -28.322016) (xy 311.200393 -28.315758) (xy 311.204384 -28.30183)
			(xy 311.20461 -28.294584) (xy 311.20461 -27.872436) (xy 311.204176 -27.862371) (xy 311.196446 -27.843782)
			(xy 311.189624 -27.836368) (xy 310.950102 -27.596846) (xy 310.942706 -27.589994) (xy 310.924107 -27.582252)
			(xy 310.914034 -27.58186) (xy 301.599346 -27.58186) (xy 301.587021 -27.582456) (xy 301.565191 -27.593906)
			(xy 301.55769 -27.603704) (xy 301.54053 -27.627665) (xy 301.501024 -27.6714) (xy 301.456233 -27.709706)
			(xy 301.406898 -27.74195) (xy 301.353835 -27.767598) (xy 301.29792 -27.786227) (xy 301.240077 -27.797529)
			(xy 301.181262 -27.801317) (xy 301.122447 -27.797529) (xy 301.064604 -27.786227) (xy 301.008689 -27.767598)
			(xy 300.955626 -27.74195) (xy 300.906291 -27.709706) (xy 300.8615 -27.6714) (xy 300.821994 -27.627665)
			(xy 300.804834 -27.603704) (xy 300.797219 -27.594041) (xy 300.775458 -27.582643) (xy 300.763178 -27.58186)
			(xy 296.627804 -27.58186) (xy 296.617735 -27.582284) (xy 296.599135 -27.590004) (xy 296.591736 -27.596846)
			(xy 296.32275 -27.865832) (xy 296.3164 -27.877262) (xy 296.314622 -27.88412) (xy 296.306896 -27.91235)
			(xy 296.283984 -27.966204) (xy 296.253118 -28.015929) (xy 296.215021 -28.060357) (xy 296.170588 -28.098448)
			(xy 296.120859 -28.129308) (xy 296.067001 -28.152213) (xy 296.038778 -28.159964) (xy 296.03192 -28.161742)
			(xy 296.02049 -28.168092) (xy 296.004742 -28.18384) (xy 295.997897 -28.191239) (xy 295.990171 -28.209837)
			(xy 295.989756 -28.219908) (xy 295.989756 -29.114242) (xy 303.0474 -29.114242) (xy 303.0474 -28.250642)
			(xy 303.04789 -28.220674) (xy 303.055713 -28.161252) (xy 303.071226 -28.103359) (xy 303.094162 -28.047986)
			(xy 303.124129 -27.99608) (xy 303.160616 -27.94853) (xy 303.202996 -27.90615) (xy 303.250546 -27.869663)
			(xy 303.302452 -27.839696) (xy 303.357825 -27.81676) (xy 303.415718 -27.801247) (xy 303.47514 -27.793424)
			(xy 303.535076 -27.793424) (xy 303.594498 -27.801247) (xy 303.652391 -27.81676) (xy 303.707764 -27.839696)
			(xy 303.75967 -27.869663) (xy 303.80722 -27.90615) (xy 303.8496 -27.94853) (xy 303.886087 -27.99608)
			(xy 303.916054 -28.047986) (xy 303.93899 -28.103359) (xy 303.954503 -28.161252) (xy 303.962326 -28.220674)
			(xy 303.962816 -28.250642) (xy 303.962816 -28.469082) (xy 307.952392 -28.469082) (xy 307.956463 -28.41346)
			(xy 307.968589 -28.359023) (xy 307.988512 -28.306932) (xy 308.015808 -28.258297) (xy 308.049894 -28.214154)
			(xy 308.090043 -28.175445) (xy 308.135401 -28.142994) (xy 308.185001 -28.117493) (xy 308.237785 -28.099486)
			(xy 308.292628 -28.089356) (xy 308.348362 -28.087319) (xy 308.403799 -28.093419) (xy 308.457756 -28.107525)
			(xy 308.509085 -28.129337) (xy 308.556691 -28.158391) (xy 308.599559 -28.194066) (xy 308.636776 -28.235603)
			(xy 308.667549 -28.282116) (xy 308.691221 -28.332613) (xy 308.707289 -28.38602) (xy 308.715409 -28.441196)
			(xy 308.715918 -28.469082) (xy 308.715409 -28.496968) (xy 308.707289 -28.552144) (xy 308.691221 -28.605551)
			(xy 308.667549 -28.656048) (xy 308.636776 -28.702561) (xy 308.599559 -28.744098) (xy 308.556691 -28.779773)
			(xy 308.509085 -28.808827) (xy 308.457756 -28.830639) (xy 308.403799 -28.844745) (xy 308.348362 -28.850845)
			(xy 308.292628 -28.848808) (xy 308.237785 -28.838678) (xy 308.185001 -28.820671) (xy 308.135401 -28.79517)
			(xy 308.090043 -28.762719) (xy 308.049894 -28.72401) (xy 308.015808 -28.679867) (xy 307.988512 -28.631232)
			(xy 307.968589 -28.579141) (xy 307.956463 -28.524704) (xy 307.952392 -28.469082) (xy 303.962816 -28.469082)
			(xy 303.962816 -29.114242) (xy 303.962326 -29.14421) (xy 303.954503 -29.203632) (xy 303.93899 -29.261525)
			(xy 303.916054 -29.316898) (xy 303.886087 -29.368804) (xy 303.8496 -29.416354) (xy 303.80722 -29.458734)
			(xy 303.75967 -29.495221) (xy 303.707764 -29.525188) (xy 303.652391 -29.548124) (xy 303.594498 -29.563637)
			(xy 303.535076 -29.57146) (xy 303.47514 -29.57146) (xy 303.415718 -29.563637) (xy 303.357825 -29.548124)
			(xy 303.302452 -29.525188) (xy 303.250546 -29.495221) (xy 303.202996 -29.458734) (xy 303.160616 -29.416354)
			(xy 303.124129 -29.368804) (xy 303.094162 -29.316898) (xy 303.071226 -29.261525) (xy 303.055713 -29.203632)
			(xy 303.04789 -29.14421) (xy 303.0474 -29.114242) (xy 295.989756 -29.114242) (xy 295.989756 -29.186378)
			(xy 296.011854 -29.214064) (xy 296.02938 -29.217874) (xy 296.055674 -29.224335) (xy 296.106246 -29.243678)
			(xy 296.153577 -29.269975) (xy 296.196715 -29.302697) (xy 296.234795 -29.341189) (xy 296.267051 -29.384676)
			(xy 296.292838 -29.432286) (xy 296.311636 -29.483063) (xy 296.323068 -29.535988) (xy 296.326905 -29.589996)
			(xy 296.323069 -29.644005) (xy 296.311638 -29.69693) (xy 296.292841 -29.747707) (xy 296.267055 -29.795318)
			(xy 296.234799 -29.838806) (xy 296.19672 -29.877298) (xy 296.153583 -29.910021) (xy 296.106253 -29.936319)
			(xy 296.055681 -29.955663) (xy 296.02938 -29.962094) (xy 296.011854 -29.965904) (xy 295.989756 -29.99359)
			(xy 295.989756 -30.92069) (xy 305.689508 -30.92069) (xy 305.689508 -30.05709) (xy 305.689998 -30.027122)
			(xy 305.697821 -29.9677) (xy 305.713334 -29.909807) (xy 305.73627 -29.854434) (xy 305.766237 -29.802528)
			(xy 305.802724 -29.754978) (xy 305.845104 -29.712598) (xy 305.892654 -29.676111) (xy 305.94456 -29.646144)
			(xy 305.999933 -29.623208) (xy 306.057826 -29.607695) (xy 306.117248 -29.599872) (xy 306.177184 -29.599872)
			(xy 306.236606 -29.607695) (xy 306.294499 -29.623208) (xy 306.349872 -29.646144) (xy 306.401778 -29.676111)
			(xy 306.449328 -29.712598) (xy 306.491708 -29.754978) (xy 306.528195 -29.802528) (xy 306.558162 -29.854434)
			(xy 306.581098 -29.909807) (xy 306.596611 -29.9677) (xy 306.604434 -30.027122) (xy 306.604924 -30.05709)
			(xy 306.604924 -30.92069) (xy 306.604434 -30.950658) (xy 306.596611 -31.01008) (xy 306.581098 -31.067973)
			(xy 306.558162 -31.123346) (xy 306.528195 -31.175252) (xy 306.491708 -31.222802) (xy 306.449328 -31.265182)
			(xy 306.401778 -31.301669) (xy 306.349872 -31.331636) (xy 306.294499 -31.354572) (xy 306.236606 -31.370085)
			(xy 306.177184 -31.377908) (xy 306.117248 -31.377908) (xy 306.057826 -31.370085) (xy 305.999933 -31.354572)
			(xy 305.94456 -31.331636) (xy 305.892654 -31.301669) (xy 305.845104 -31.265182) (xy 305.802724 -31.222802)
			(xy 305.766237 -31.175252) (xy 305.73627 -31.123346) (xy 305.713334 -31.067973) (xy 305.697821 -31.01008)
			(xy 305.689998 -30.950658) (xy 305.689508 -30.92069) (xy 295.989756 -30.92069) (xy 295.989756 -31.232602)
			(xy 296.015156 -31.261304) (xy 296.03446 -31.26359) (xy 296.06187 -31.267414) (xy 296.11527 -31.28195)
			(xy 296.166008 -31.304049) (xy 296.213021 -31.333248) (xy 296.255321 -31.368933) (xy 296.292021 -31.410357)
			(xy 296.322351 -31.456648) (xy 296.345673 -31.506836) (xy 296.361498 -31.559868) (xy 296.369495 -31.614629)
			(xy 296.369495 -31.669972) (xy 296.361498 -31.724733) (xy 296.345673 -31.777765) (xy 296.32235 -31.827953)
			(xy 296.292021 -31.874244) (xy 296.255321 -31.915667) (xy 296.21302 -31.951353) (xy 296.166007 -31.980552)
			(xy 296.115269 -32.002651) (xy 296.061869 -32.017187) (xy 296.03446 -32.021018) (xy 296.015156 -32.023304)
			(xy 295.989756 -32.052006) (xy 295.989756 -32.714184) (xy 303.0474 -32.714184) (xy 303.0474 -31.850584)
			(xy 303.04789 -31.820616) (xy 303.055713 -31.761194) (xy 303.071226 -31.703301) (xy 303.094162 -31.647928)
			(xy 303.124129 -31.596022) (xy 303.160616 -31.548472) (xy 303.202996 -31.506092) (xy 303.250546 -31.469605)
			(xy 303.302452 -31.439638) (xy 303.357825 -31.416702) (xy 303.415718 -31.401189) (xy 303.47514 -31.393366)
			(xy 303.535076 -31.393366) (xy 303.594498 -31.401189) (xy 303.652391 -31.416702) (xy 303.707764 -31.439638)
			(xy 303.75967 -31.469605) (xy 303.80722 -31.506092) (xy 303.8496 -31.548472) (xy 303.886087 -31.596022)
			(xy 303.916054 -31.647928) (xy 303.93899 -31.703301) (xy 303.954503 -31.761194) (xy 303.962326 -31.820616)
			(xy 303.962816 -31.850584) (xy 303.962816 -32.714184) (xy 303.962326 -32.744152) (xy 303.954503 -32.803574)
			(xy 303.93899 -32.861467) (xy 303.916054 -32.91684) (xy 303.886087 -32.968746) (xy 303.8496 -33.016296)
			(xy 303.80722 -33.058676) (xy 303.75967 -33.095163) (xy 303.707764 -33.12513) (xy 303.652391 -33.148066)
			(xy 303.594498 -33.163579) (xy 303.535076 -33.171402) (xy 303.47514 -33.171402) (xy 303.415718 -33.163579)
			(xy 303.357825 -33.148066) (xy 303.302452 -33.12513) (xy 303.250546 -33.095163) (xy 303.202996 -33.058676)
			(xy 303.160616 -33.016296) (xy 303.124129 -32.968746) (xy 303.094162 -32.91684) (xy 303.071226 -32.861467)
			(xy 303.055713 -32.803574) (xy 303.04789 -32.744152) (xy 303.0474 -32.714184) (xy 295.989756 -32.714184)
			(xy 295.989756 -34.520886) (xy 305.689508 -34.520886) (xy 305.689508 -33.657286) (xy 305.689998 -33.627318)
			(xy 305.697821 -33.567896) (xy 305.713334 -33.510003) (xy 305.73627 -33.45463) (xy 305.766237 -33.402724)
			(xy 305.802724 -33.355174) (xy 305.845104 -33.312794) (xy 305.892654 -33.276307) (xy 305.94456 -33.24634)
			(xy 305.999933 -33.223404) (xy 306.057826 -33.207891) (xy 306.117248 -33.200068) (xy 306.177184 -33.200068)
			(xy 306.236606 -33.207891) (xy 306.294499 -33.223404) (xy 306.349872 -33.24634) (xy 306.401778 -33.276307)
			(xy 306.449328 -33.312794) (xy 306.491708 -33.355174) (xy 306.528195 -33.402724) (xy 306.558162 -33.45463)
			(xy 306.581098 -33.510003) (xy 306.596611 -33.567896) (xy 306.604434 -33.627318) (xy 306.604924 -33.657286)
			(xy 306.604924 -34.520886) (xy 306.604434 -34.550854) (xy 306.596611 -34.610276) (xy 306.581098 -34.668169)
			(xy 306.558162 -34.723542) (xy 306.528195 -34.775448) (xy 306.491708 -34.822998) (xy 306.449328 -34.865378)
			(xy 306.401778 -34.901865) (xy 306.349872 -34.931832) (xy 306.294499 -34.954768) (xy 306.236606 -34.970281)
			(xy 306.177184 -34.978104) (xy 306.117248 -34.978104) (xy 306.057826 -34.970281) (xy 305.999933 -34.954768)
			(xy 305.94456 -34.931832) (xy 305.892654 -34.901865) (xy 305.845104 -34.865378) (xy 305.802724 -34.822998)
			(xy 305.766237 -34.775448) (xy 305.73627 -34.723542) (xy 305.713334 -34.668169) (xy 305.697821 -34.610276)
			(xy 305.689998 -34.550854) (xy 305.689508 -34.520886) (xy 295.989756 -34.520886) (xy 295.989756 -36.60013)
			(xy 296.198551 -36.60013) (xy 296.202555 -36.512245) (xy 296.214535 -36.425088) (xy 296.23439 -36.339381)
			(xy 296.261957 -36.255836) (xy 296.297007 -36.175143) (xy 296.339249 -36.097971) (xy 296.388334 -36.024961)
			(xy 296.443855 -35.956717) (xy 296.505352 -35.893804) (xy 296.572314 -35.836744) (xy 296.644188 -35.78601)
			(xy 296.720378 -35.742022) (xy 296.800252 -35.705144) (xy 296.883149 -35.675683) (xy 296.968381 -35.653881)
			(xy 297.055243 -35.639921) (xy 297.143014 -35.633917) (xy 297.230968 -35.63592) (xy 297.318375 -35.645912)
			(xy 297.404511 -35.663812) (xy 297.488663 -35.68947) (xy 297.570133 -35.722674) (xy 297.648246 -35.763148)
			(xy 297.722354 -35.810559) (xy 297.791845 -35.864512) (xy 297.804936 -35.876738) (xy 302.917096 -35.876738)
			(xy 302.921167 -35.821116) (xy 302.933293 -35.766679) (xy 302.953216 -35.714588) (xy 302.980512 -35.665953)
			(xy 303.014598 -35.62181) (xy 303.054747 -35.583101) (xy 303.100105 -35.55065) (xy 303.149705 -35.525149)
			(xy 303.202489 -35.507142) (xy 303.257332 -35.497012) (xy 303.313066 -35.494975) (xy 303.368503 -35.501075)
			(xy 303.42246 -35.515181) (xy 303.473789 -35.536993) (xy 303.521395 -35.566047) (xy 303.564263 -35.601722)
			(xy 303.60148 -35.643259) (xy 303.632253 -35.689772) (xy 303.655925 -35.740269) (xy 303.671993 -35.793676)
			(xy 303.680113 -35.848852) (xy 303.680622 -35.876738) (xy 306.988716 -35.876738) (xy 306.992787 -35.821116)
			(xy 307.004913 -35.766679) (xy 307.024836 -35.714588) (xy 307.052132 -35.665953) (xy 307.086218 -35.62181)
			(xy 307.126367 -35.583101) (xy 307.171725 -35.55065) (xy 307.221325 -35.525149) (xy 307.274109 -35.507142)
			(xy 307.328952 -35.497012) (xy 307.384686 -35.494975) (xy 307.440123 -35.501075) (xy 307.49408 -35.515181)
			(xy 307.545409 -35.536993) (xy 307.593015 -35.566047) (xy 307.635883 -35.601722) (xy 307.6731 -35.643259)
			(xy 307.703873 -35.689772) (xy 307.727545 -35.740269) (xy 307.743613 -35.793676) (xy 307.751733 -35.848852)
			(xy 307.752242 -35.876738) (xy 307.751733 -35.904624) (xy 307.743613 -35.9598) (xy 307.727545 -36.013207)
			(xy 307.703873 -36.063704) (xy 307.6731 -36.110217) (xy 307.635883 -36.151754) (xy 307.593015 -36.187429)
			(xy 307.545409 -36.216483) (xy 307.49408 -36.238295) (xy 307.440123 -36.252401) (xy 307.384686 -36.258501)
			(xy 307.328952 -36.256464) (xy 307.274109 -36.246334) (xy 307.221325 -36.228327) (xy 307.171725 -36.202826)
			(xy 307.126367 -36.170375) (xy 307.086218 -36.131666) (xy 307.052132 -36.087523) (xy 307.024836 -36.038888)
			(xy 307.004913 -35.986797) (xy 306.992787 -35.93236) (xy 306.988716 -35.876738) (xy 303.680622 -35.876738)
			(xy 303.680113 -35.904624) (xy 303.671993 -35.9598) (xy 303.655925 -36.013207) (xy 303.632253 -36.063704)
			(xy 303.60148 -36.110217) (xy 303.564263 -36.151754) (xy 303.521395 -36.187429) (xy 303.473789 -36.216483)
			(xy 303.42246 -36.238295) (xy 303.368503 -36.252401) (xy 303.313066 -36.258501) (xy 303.257332 -36.256464)
			(xy 303.202489 -36.246334) (xy 303.149705 -36.228327) (xy 303.100105 -36.202826) (xy 303.054747 -36.170375)
			(xy 303.014598 -36.131666) (xy 302.980512 -36.087523) (xy 302.953216 -36.038888) (xy 302.933293 -35.986797)
			(xy 302.921167 -35.93236) (xy 302.917096 -35.876738) (xy 297.804936 -35.876738) (xy 297.856141 -35.92456)
			(xy 297.91471 -35.990207) (xy 297.967067 -36.060907) (xy 298.012779 -36.136076) (xy 298.051465 -36.21509)
			(xy 298.082806 -36.297295) (xy 298.106541 -36.382009) (xy 298.122475 -36.46853) (xy 298.126258 -36.50996)
			(xy 304.813714 -36.50996) (xy 304.817785 -36.454338) (xy 304.829911 -36.399901) (xy 304.849834 -36.34781)
			(xy 304.87713 -36.299175) (xy 304.911216 -36.255032) (xy 304.951365 -36.216323) (xy 304.996723 -36.183872)
			(xy 305.046323 -36.158371) (xy 305.099107 -36.140364) (xy 305.15395 -36.130234) (xy 305.209684 -36.128197)
			(xy 305.265121 -36.134297) (xy 305.319078 -36.148403) (xy 305.370407 -36.170215) (xy 305.418013 -36.199269)
			(xy 305.460881 -36.234944) (xy 305.498098 -36.276481) (xy 305.528871 -36.322994) (xy 305.552543 -36.373491)
			(xy 305.568611 -36.426898) (xy 305.572536 -36.453572) (xy 308.128414 -36.453572) (xy 308.132485 -36.39795)
			(xy 308.144611 -36.343513) (xy 308.164534 -36.291422) (xy 308.19183 -36.242787) (xy 308.225916 -36.198644)
			(xy 308.266065 -36.159935) (xy 308.311423 -36.127484) (xy 308.361023 -36.101983) (xy 308.413807 -36.083976)
			(xy 308.46865 -36.073846) (xy 308.524384 -36.071809) (xy 308.579821 -36.077909) (xy 308.633778 -36.092015)
			(xy 308.685107 -36.113827) (xy 308.732713 -36.142881) (xy 308.775581 -36.178556) (xy 308.812798 -36.220093)
			(xy 308.843571 -36.266606) (xy 308.867243 -36.317103) (xy 308.883311 -36.37051) (xy 308.891431 -36.425686)
			(xy 308.89194 -36.453572) (xy 308.891431 -36.481458) (xy 308.883311 -36.536634) (xy 308.867243 -36.590041)
			(xy 308.843571 -36.640538) (xy 308.812798 -36.687051) (xy 308.775581 -36.728588) (xy 308.732713 -36.764263)
			(xy 308.685107 -36.793317) (xy 308.633778 -36.815129) (xy 308.579821 -36.829235) (xy 308.524384 -36.835335)
			(xy 308.46865 -36.833298) (xy 308.413807 -36.823168) (xy 308.361023 -36.805161) (xy 308.311423 -36.77966)
			(xy 308.266065 -36.747209) (xy 308.225916 -36.7085) (xy 308.19183 -36.664357) (xy 308.164534 -36.615722)
			(xy 308.144611 -36.563631) (xy 308.132485 -36.509194) (xy 308.128414 -36.453572) (xy 305.572536 -36.453572)
			(xy 305.576731 -36.482074) (xy 305.57724 -36.50996) (xy 305.576731 -36.537846) (xy 305.568611 -36.593022)
			(xy 305.552543 -36.646429) (xy 305.528871 -36.696926) (xy 305.498098 -36.743439) (xy 305.460881 -36.784976)
			(xy 305.418013 -36.820651) (xy 305.370407 -36.849705) (xy 305.319078 -36.871517) (xy 305.265121 -36.885623)
			(xy 305.209684 -36.891723) (xy 305.15395 -36.889686) (xy 305.099107 -36.879556) (xy 305.046323 -36.861549)
			(xy 304.996723 -36.836048) (xy 304.951365 -36.803597) (xy 304.911216 -36.764888) (xy 304.87713 -36.720745)
			(xy 304.849834 -36.67211) (xy 304.829911 -36.620019) (xy 304.817785 -36.565582) (xy 304.813714 -36.50996)
			(xy 298.126258 -36.50996) (xy 298.130475 -36.556142) (xy 298.130976 -36.60013) (xy 298.130475 -36.644118)
			(xy 298.122475 -36.73173) (xy 298.106541 -36.818251) (xy 298.082806 -36.902965) (xy 298.051465 -36.98517)
			(xy 298.012779 -37.064184) (xy 297.967067 -37.139353) (xy 297.91471 -37.210053) (xy 297.856141 -37.2757)
			(xy 297.791845 -37.335748) (xy 297.722354 -37.389701) (xy 297.648246 -37.437112) (xy 297.570133 -37.477586)
			(xy 297.488663 -37.51079) (xy 297.404511 -37.536448) (xy 297.318375 -37.554348) (xy 297.230968 -37.56434)
			(xy 297.143014 -37.566343) (xy 297.055243 -37.560339) (xy 296.968381 -37.546379) (xy 296.883149 -37.524577)
			(xy 296.800252 -37.495116) (xy 296.720378 -37.458238) (xy 296.644188 -37.41425) (xy 296.572314 -37.363516)
			(xy 296.505352 -37.306456) (xy 296.443855 -37.243543) (xy 296.388334 -37.175299) (xy 296.339249 -37.102289)
			(xy 296.297007 -37.025117) (xy 296.261957 -36.944424) (xy 296.23439 -36.860879) (xy 296.214535 -36.775172)
			(xy 296.202555 -36.688015) (xy 296.198551 -36.60013) (xy 295.989756 -36.60013) (xy 295.989756 -39.97198)
			(xy 310.095644 -39.97198) (xy 310.099715 -39.916358) (xy 310.111841 -39.861921) (xy 310.131764 -39.80983)
			(xy 310.15906 -39.761195) (xy 310.193146 -39.717052) (xy 310.233295 -39.678343) (xy 310.278653 -39.645892)
			(xy 310.328253 -39.620391) (xy 310.381037 -39.602384) (xy 310.43588 -39.592254) (xy 310.491614 -39.590217)
			(xy 310.547051 -39.596317) (xy 310.601008 -39.610423) (xy 310.652337 -39.632235) (xy 310.699943 -39.661289)
			(xy 310.742811 -39.696964) (xy 310.780028 -39.738501) (xy 310.810801 -39.785014) (xy 310.834473 -39.835511)
			(xy 310.850541 -39.888918) (xy 310.858661 -39.944094) (xy 310.85917 -39.97198) (xy 310.858661 -39.999866)
			(xy 310.850541 -40.055042) (xy 310.834473 -40.108449) (xy 310.810801 -40.158946) (xy 310.780028 -40.205459)
			(xy 310.742811 -40.246996) (xy 310.699943 -40.282671) (xy 310.652337 -40.311725) (xy 310.601008 -40.333537)
			(xy 310.547051 -40.347643) (xy 310.491614 -40.353743) (xy 310.43588 -40.351706) (xy 310.381037 -40.341576)
			(xy 310.328253 -40.323569) (xy 310.278653 -40.298068) (xy 310.233295 -40.265617) (xy 310.193146 -40.226908)
			(xy 310.15906 -40.182765) (xy 310.131764 -40.13413) (xy 310.111841 -40.082039) (xy 310.099715 -40.027602)
			(xy 310.095644 -39.97198) (xy 295.989756 -39.97198) (xy 295.989756 -40.452802) (xy 295.990181 -40.462871)
			(xy 295.997902 -40.481469) (xy 296.004742 -40.48887) (xy 296.223944 -40.708072) (xy 296.231343 -40.714915)
			(xy 296.249942 -40.722638) (xy 296.260012 -40.723058) (xy 305.28133 -40.723058) (xy 305.291397 -40.723488)
			(xy 305.309988 -40.731217) (xy 305.317398 -40.738044) (xy 306.258468 -41.679114) (xy 306.265316 -41.686512)
			(xy 306.27305 -41.70511) (xy 306.273454 -41.715182) (xy 306.273454 -41.946576) (xy 306.273708 -41.954196)
			(xy 306.273708 -43.566842) (xy 307.533292 -43.566842) (xy 307.537363 -43.51122) (xy 307.549489 -43.456783)
			(xy 307.569412 -43.404692) (xy 307.596708 -43.356057) (xy 307.630794 -43.311914) (xy 307.670943 -43.273205)
			(xy 307.716301 -43.240754) (xy 307.765901 -43.215253) (xy 307.818685 -43.197246) (xy 307.873528 -43.187116)
			(xy 307.929262 -43.185079) (xy 307.984699 -43.191179) (xy 308.038656 -43.205285) (xy 308.089985 -43.227097)
			(xy 308.137591 -43.256151) (xy 308.180459 -43.291826) (xy 308.217676 -43.333363) (xy 308.248449 -43.379876)
			(xy 308.272121 -43.430373) (xy 308.288189 -43.48378) (xy 308.296309 -43.538956) (xy 308.296818 -43.566842)
			(xy 308.296309 -43.594728) (xy 308.288189 -43.649904) (xy 308.272121 -43.703311) (xy 308.248449 -43.753808)
			(xy 308.217676 -43.800321) (xy 308.180459 -43.841858) (xy 308.162372 -43.85691) (xy 308.919624 -43.85691)
			(xy 308.923695 -43.801288) (xy 308.935821 -43.746851) (xy 308.955744 -43.69476) (xy 308.98304 -43.646125)
			(xy 309.017126 -43.601982) (xy 309.057275 -43.563273) (xy 309.102633 -43.530822) (xy 309.152233 -43.505321)
			(xy 309.205017 -43.487314) (xy 309.25986 -43.477184) (xy 309.315594 -43.475147) (xy 309.371031 -43.481247)
			(xy 309.424988 -43.495353) (xy 309.476317 -43.517165) (xy 309.523923 -43.546219) (xy 309.566791 -43.581894)
			(xy 309.604008 -43.623431) (xy 309.634781 -43.669944) (xy 309.658453 -43.720441) (xy 309.674521 -43.773848)
			(xy 309.682641 -43.829024) (xy 309.68315 -43.85691) (xy 309.682641 -43.884796) (xy 309.674521 -43.939972)
			(xy 309.658453 -43.993379) (xy 309.634781 -44.043876) (xy 309.604008 -44.090389) (xy 309.566791 -44.131926)
			(xy 309.523923 -44.167601) (xy 309.476317 -44.196655) (xy 309.424988 -44.218467) (xy 309.371031 -44.232573)
			(xy 309.315594 -44.238673) (xy 309.25986 -44.236636) (xy 309.205017 -44.226506) (xy 309.152233 -44.208499)
			(xy 309.102633 -44.182998) (xy 309.057275 -44.150547) (xy 309.017126 -44.111838) (xy 308.98304 -44.067695)
			(xy 308.955744 -44.01906) (xy 308.935821 -43.966969) (xy 308.923695 -43.912532) (xy 308.919624 -43.85691)
			(xy 308.162372 -43.85691) (xy 308.137591 -43.877533) (xy 308.089985 -43.906587) (xy 308.038656 -43.928399)
			(xy 307.984699 -43.942505) (xy 307.929262 -43.948605) (xy 307.873528 -43.946568) (xy 307.818685 -43.936438)
			(xy 307.765901 -43.918431) (xy 307.716301 -43.89293) (xy 307.670943 -43.860479) (xy 307.630794 -43.82177)
			(xy 307.596708 -43.777627) (xy 307.569412 -43.728992) (xy 307.549489 -43.676901) (xy 307.537363 -43.622464)
			(xy 307.533292 -43.566842) (xy 306.273708 -43.566842) (xy 306.273708 -45.35424) (xy 308.903622 -45.35424)
			(xy 308.907693 -45.298618) (xy 308.919819 -45.244181) (xy 308.939742 -45.19209) (xy 308.967038 -45.143455)
			(xy 309.001124 -45.099312) (xy 309.041273 -45.060603) (xy 309.086631 -45.028152) (xy 309.136231 -45.002651)
			(xy 309.189015 -44.984644) (xy 309.243858 -44.974514) (xy 309.299592 -44.972477) (xy 309.355029 -44.978577)
			(xy 309.408986 -44.992683) (xy 309.460315 -45.014495) (xy 309.507921 -45.043549) (xy 309.550789 -45.079224)
			(xy 309.588006 -45.120761) (xy 309.618779 -45.167274) (xy 309.642451 -45.217771) (xy 309.658519 -45.271178)
			(xy 309.666639 -45.326354) (xy 309.667148 -45.35424) (xy 309.666639 -45.382126) (xy 309.658519 -45.437302)
			(xy 309.642451 -45.490709) (xy 309.618779 -45.541206) (xy 309.588006 -45.587719) (xy 309.550789 -45.629256)
			(xy 309.507921 -45.664931) (xy 309.460315 -45.693985) (xy 309.408986 -45.715797) (xy 309.355029 -45.729903)
			(xy 309.299592 -45.736003) (xy 309.243858 -45.733966) (xy 309.189015 -45.723836) (xy 309.136231 -45.705829)
			(xy 309.086631 -45.680328) (xy 309.041273 -45.647877) (xy 309.001124 -45.609168) (xy 308.967038 -45.565025)
			(xy 308.939742 -45.51639) (xy 308.919819 -45.464299) (xy 308.907693 -45.409862) (xy 308.903622 -45.35424)
			(xy 306.273708 -45.35424) (xy 306.273708 -46.693836) (xy 308.876192 -46.693836) (xy 308.876678 -46.666585)
			(xy 308.884434 -46.612637) (xy 308.899789 -46.560342) (xy 308.922431 -46.510765) (xy 308.951897 -46.464915)
			(xy 308.987588 -46.423724) (xy 309.028779 -46.388033) (xy 309.074629 -46.358567) (xy 309.124206 -46.335925)
			(xy 309.176501 -46.32057) (xy 309.230449 -46.312814) (xy 309.284951 -46.312814) (xy 309.338899 -46.32057)
			(xy 309.391194 -46.335925) (xy 309.440771 -46.358567) (xy 309.486621 -46.388033) (xy 309.527812 -46.423724)
			(xy 309.563503 -46.464915) (xy 309.592969 -46.510765) (xy 309.615611 -46.560342) (xy 309.630966 -46.612637)
			(xy 309.638722 -46.666585) (xy 309.639208 -46.693836) (xy 309.638734 -46.720264) (xy 309.631425 -46.772611)
			(xy 309.616952 -46.823446) (xy 309.595593 -46.871793) (xy 309.582058 -46.894496) (xy 309.575962 -46.904402)
			(xy 309.573422 -46.927262) (xy 309.607712 -47.023782) (xy 309.623714 -47.040038) (xy 309.63489 -47.043848)
			(xy 309.659408 -47.052893) (xy 309.70586 -47.07684) (xy 309.74861 -47.106901) (xy 309.786861 -47.142512)
			(xy 309.819896 -47.183008) (xy 309.847098 -47.227631) (xy 309.867959 -47.275548) (xy 309.882088 -47.325863)
			(xy 309.889221 -47.377635) (xy 309.889652 -47.403766) (xy 309.889166 -47.431017) (xy 309.88141 -47.484965)
			(xy 309.866055 -47.53726) (xy 309.843413 -47.586837) (xy 309.813947 -47.632687) (xy 309.778256 -47.673878)
			(xy 309.737065 -47.709569) (xy 309.691215 -47.739035) (xy 309.641638 -47.761677) (xy 309.589343 -47.777032)
			(xy 309.535395 -47.784788) (xy 309.480893 -47.784788) (xy 309.426945 -47.777032) (xy 309.37465 -47.761677)
			(xy 309.325073 -47.739035) (xy 309.279223 -47.709569) (xy 309.238032 -47.673878) (xy 309.202341 -47.632687)
			(xy 309.172875 -47.586837) (xy 309.150233 -47.53726) (xy 309.134878 -47.484965) (xy 309.127122 -47.431017)
			(xy 309.126636 -47.403766) (xy 309.127105 -47.377338) (xy 309.134415 -47.324991) (xy 309.148889 -47.274156)
			(xy 309.170251 -47.225809) (xy 309.183786 -47.203106) (xy 309.189882 -47.1932) (xy 309.192422 -47.17034)
			(xy 309.158132 -47.07382) (xy 309.14213 -47.057564) (xy 309.130954 -47.053754) (xy 309.106446 -47.044683)
			(xy 309.059994 -47.02074) (xy 309.017242 -46.990685) (xy 308.97899 -46.955078) (xy 308.945953 -46.914585)
			(xy 308.918749 -46.869964) (xy 308.897887 -46.822049) (xy 308.883757 -46.771736) (xy 308.876623 -46.719966)
			(xy 308.876192 -46.693836) (xy 306.273708 -46.693836) (xy 306.273708 -48.300132) (xy 306.273487 -48.30699)
			(xy 308.753762 -48.30699) (xy 308.757833 -48.251368) (xy 308.769959 -48.196931) (xy 308.789882 -48.14484)
			(xy 308.817178 -48.096205) (xy 308.851264 -48.052062) (xy 308.891413 -48.013353) (xy 308.936771 -47.980902)
			(xy 308.986371 -47.955401) (xy 309.039155 -47.937394) (xy 309.093998 -47.927264) (xy 309.149732 -47.925227)
			(xy 309.205169 -47.931327) (xy 309.259126 -47.945433) (xy 309.310455 -47.967245) (xy 309.358061 -47.996299)
			(xy 309.400929 -48.031974) (xy 309.438146 -48.073511) (xy 309.468919 -48.120024) (xy 309.492591 -48.170521)
			(xy 309.508659 -48.223928) (xy 309.516779 -48.279104) (xy 309.517288 -48.30699) (xy 309.516779 -48.334876)
			(xy 309.508659 -48.390052) (xy 309.492591 -48.443459) (xy 309.468919 -48.493956) (xy 309.438146 -48.540469)
			(xy 309.400929 -48.582006) (xy 309.358061 -48.617681) (xy 309.310455 -48.646735) (xy 309.259126 -48.668547)
			(xy 309.205169 -48.682653) (xy 309.149732 -48.688753) (xy 309.093998 -48.686716) (xy 309.039155 -48.676586)
			(xy 308.986371 -48.658579) (xy 308.936771 -48.633078) (xy 308.891413 -48.600627) (xy 308.851264 -48.561918)
			(xy 308.817178 -48.517775) (xy 308.789882 -48.46914) (xy 308.769959 -48.417049) (xy 308.757833 -48.362612)
			(xy 308.753762 -48.30699) (xy 306.273487 -48.30699) (xy 306.273454 -48.308006) (xy 306.273454 -48.8442)
			(xy 306.387244 -48.8442) (xy 306.391315 -48.788578) (xy 306.403441 -48.734141) (xy 306.423364 -48.68205)
			(xy 306.45066 -48.633415) (xy 306.484746 -48.589272) (xy 306.524895 -48.550563) (xy 306.570253 -48.518112)
			(xy 306.619853 -48.492611) (xy 306.672637 -48.474604) (xy 306.72748 -48.464474) (xy 306.783214 -48.462437)
			(xy 306.838651 -48.468537) (xy 306.892608 -48.482643) (xy 306.943937 -48.504455) (xy 306.991543 -48.533509)
			(xy 307.034411 -48.569184) (xy 307.071628 -48.610721) (xy 307.102401 -48.657234) (xy 307.126073 -48.707731)
			(xy 307.142141 -48.761138) (xy 307.150261 -48.816314) (xy 307.15077 -48.8442) (xy 307.150261 -48.872086)
			(xy 307.147263 -48.89246) (xy 307.413912 -48.89246) (xy 307.417983 -48.836838) (xy 307.430109 -48.782401)
			(xy 307.450032 -48.73031) (xy 307.477328 -48.681675) (xy 307.511414 -48.637532) (xy 307.551563 -48.598823)
			(xy 307.596921 -48.566372) (xy 307.646521 -48.540871) (xy 307.699305 -48.522864) (xy 307.754148 -48.512734)
			(xy 307.809882 -48.510697) (xy 307.865319 -48.516797) (xy 307.919276 -48.530903) (xy 307.970605 -48.552715)
			(xy 308.018211 -48.581769) (xy 308.061079 -48.617444) (xy 308.098296 -48.658981) (xy 308.129069 -48.705494)
			(xy 308.152741 -48.755991) (xy 308.168809 -48.809398) (xy 308.176929 -48.864574) (xy 308.177438 -48.89246)
			(xy 308.176929 -48.920346) (xy 308.168809 -48.975522) (xy 308.152741 -49.028929) (xy 308.129069 -49.079426)
			(xy 308.098296 -49.125939) (xy 308.061079 -49.167476) (xy 308.018211 -49.203151) (xy 307.970605 -49.232205)
			(xy 307.919276 -49.254017) (xy 307.865319 -49.268123) (xy 307.809882 -49.274223) (xy 307.754148 -49.272186)
			(xy 307.699305 -49.262056) (xy 307.646521 -49.244049) (xy 307.596921 -49.218548) (xy 307.551563 -49.186097)
			(xy 307.511414 -49.147388) (xy 307.477328 -49.103245) (xy 307.450032 -49.05461) (xy 307.430109 -49.002519)
			(xy 307.417983 -48.948082) (xy 307.413912 -48.89246) (xy 307.147263 -48.89246) (xy 307.142141 -48.927262)
			(xy 307.126073 -48.980669) (xy 307.102401 -49.031166) (xy 307.071628 -49.077679) (xy 307.034411 -49.119216)
			(xy 306.991543 -49.154891) (xy 306.943937 -49.183945) (xy 306.892608 -49.205757) (xy 306.838651 -49.219863)
			(xy 306.783214 -49.225963) (xy 306.72748 -49.223926) (xy 306.672637 -49.213796) (xy 306.619853 -49.195789)
			(xy 306.570253 -49.170288) (xy 306.524895 -49.137837) (xy 306.484746 -49.099128) (xy 306.45066 -49.054985)
			(xy 306.423364 -49.00635) (xy 306.403441 -48.954259) (xy 306.391315 -48.899822) (xy 306.387244 -48.8442)
			(xy 306.273454 -48.8442) (xy 306.273454 -49.198022) (xy 306.273708 -49.205896) (xy 306.273708 -50.462434)
			(xy 307.026054 -50.462434) (xy 307.030125 -50.406812) (xy 307.042251 -50.352375) (xy 307.062174 -50.300284)
			(xy 307.08947 -50.251649) (xy 307.123556 -50.207506) (xy 307.163705 -50.168797) (xy 307.209063 -50.136346)
			(xy 307.258663 -50.110845) (xy 307.311447 -50.092838) (xy 307.36629 -50.082708) (xy 307.422024 -50.080671)
			(xy 307.477461 -50.086771) (xy 307.531418 -50.100877) (xy 307.582747 -50.122689) (xy 307.630353 -50.151743)
			(xy 307.673221 -50.187418) (xy 307.710438 -50.228955) (xy 307.741211 -50.275468) (xy 307.764883 -50.325965)
			(xy 307.780951 -50.379372) (xy 307.789071 -50.434548) (xy 307.78958 -50.462434) (xy 307.789071 -50.49032)
			(xy 307.780951 -50.545496) (xy 307.764883 -50.598903) (xy 307.741211 -50.6494) (xy 307.710438 -50.695913)
			(xy 307.673221 -50.73745) (xy 307.630353 -50.773125) (xy 307.582747 -50.802179) (xy 307.531418 -50.823991)
			(xy 307.477461 -50.838097) (xy 307.422024 -50.844197) (xy 307.36629 -50.84216) (xy 307.311447 -50.83203)
			(xy 307.258663 -50.814023) (xy 307.209063 -50.788522) (xy 307.163705 -50.756071) (xy 307.123556 -50.717362)
			(xy 307.08947 -50.673219) (xy 307.062174 -50.624584) (xy 307.042251 -50.572493) (xy 307.030125 -50.518056)
			(xy 307.026054 -50.462434) (xy 306.273708 -50.462434) (xy 306.273708 -51.198272) (xy 306.274195 -51.208234)
			(xy 306.281785 -51.226656) (xy 306.28844 -51.234086) (xy 306.432712 -51.378358) (xy 306.440109 -51.385207)
			(xy 306.458708 -51.392944) (xy 306.46878 -51.393344)
		)
		(stroke
			(width 0)
			(type solid)
		)
		(fill yes)
		(layer "In9.Cu")
		(net "GND")
	)
	(gr_poly
		(pts
			(xy 192.832736 -51.393344) (xy 192.841892 -51.392907) (xy 192.859011 -51.386395) (xy 192.872776 -51.374311)
			(xy 192.87744 -51.36642) (xy 192.913508 -51.298094) (xy 192.914016 -51.297586) (xy 192.919858 -51.286664)
			(xy 192.922646 -51.28064) (xy 192.925341 -51.267647) (xy 192.925192 -51.26101) (xy 192.924938 -51.255422)
			(xy 192.924176 -51.246024) (xy 192.91681 -51.234848) (xy 192.916302 -51.23434) (xy 192.900666 -51.210451)
			(xy 192.875901 -51.159011) (xy 192.859075 -51.104455) (xy 192.850563 -51.048002) (xy 192.850008 -51.019456)
			(xy 192.850494 -50.992205) (xy 192.85825 -50.938257) (xy 192.873605 -50.885962) (xy 192.896247 -50.836385)
			(xy 192.925713 -50.790535) (xy 192.961404 -50.749344) (xy 193.002595 -50.713653) (xy 193.048445 -50.684187)
			(xy 193.098022 -50.661545) (xy 193.150317 -50.64619) (xy 193.204265 -50.638434) (xy 193.258767 -50.638434)
			(xy 193.312715 -50.64619) (xy 193.36501 -50.661545) (xy 193.414587 -50.684187) (xy 193.460437 -50.713653)
			(xy 193.501628 -50.749344) (xy 193.537319 -50.790535) (xy 193.566785 -50.836385) (xy 193.589427 -50.885962)
			(xy 193.604782 -50.938257) (xy 193.612538 -50.992205) (xy 193.613024 -51.019456) (xy 193.612464 -51.048043)
			(xy 193.603895 -51.104571) (xy 193.587001 -51.159192) (xy 193.56216 -51.210688) (xy 193.546476 -51.234594)
			(xy 193.542666 -51.240182) (xy 193.538348 -51.252882) (xy 193.53784 -51.26101) (xy 193.537737 -51.267745)
			(xy 193.540694 -51.280881) (xy 193.543682 -51.286918) (xy 193.543682 -51.287172) (xy 193.585592 -51.36642)
			(xy 193.590223 -51.374344) (xy 193.603972 -51.386481) (xy 193.621126 -51.39297) (xy 193.630296 -51.393344)
			(xy 194.522344 -51.393344) (xy 194.532309 -51.392863) (xy 194.550743 -51.385286) (xy 194.558158 -51.378612)
			(xy 195.076318 -50.860452) (xy 195.080128 -50.852578) (xy 195.093844 -50.826924) (xy 195.0974 -50.821082)
			(xy 195.103496 -50.799238) (xy 195.104766 -50.788316) (xy 195.104766 -50.1904) (xy 195.104512 -50.182988)
			(xy 195.100252 -50.168788) (xy 195.096384 -50.16246) (xy 195.081551 -50.139007) (xy 195.058094 -50.088717)
			(xy 195.042174 -50.035559) (xy 195.034129 -49.980654) (xy 195.034128 -49.925163) (xy 195.042171 -49.870258)
			(xy 195.058088 -49.817098) (xy 195.081543 -49.766808) (xy 195.096384 -49.74336) (xy 195.100247 -49.73703)
			(xy 195.104503 -49.722831) (xy 195.104766 -49.71542) (xy 195.104766 -49.1744) (xy 195.104766 -49.173384)
			(xy 195.104376 -49.166235) (xy 195.100112 -49.152574) (xy 195.096384 -49.14646) (xy 195.081551 -49.123007)
			(xy 195.058094 -49.072717) (xy 195.042174 -49.019559) (xy 195.034129 -48.964654) (xy 195.034128 -48.909163)
			(xy 195.042171 -48.854258) (xy 195.058088 -48.801098) (xy 195.081543 -48.750808) (xy 195.096384 -48.72736)
			(xy 195.100122 -48.721251) (xy 195.104385 -48.707587) (xy 195.104766 -48.700436) (xy 195.104766 -47.628048)
			(xy 195.104512 -47.622968) (xy 195.092545 -47.599661) (xy 195.074332 -47.550538) (xy 195.062958 -47.499396)
			(xy 195.058634 -47.447184) (xy 195.061441 -47.394868) (xy 195.071327 -47.343418) (xy 195.088107 -47.293787)
			(xy 195.099432 -47.270162) (xy 195.101913 -47.264776) (xy 195.104606 -47.25323) (xy 195.104766 -47.247302)
			(xy 195.104766 -46.1264) (xy 195.104766 -46.125384) (xy 195.104376 -46.118235) (xy 195.100112 -46.104574)
			(xy 195.096384 -46.09846) (xy 195.081551 -46.075007) (xy 195.058094 -46.024717) (xy 195.042174 -45.971559)
			(xy 195.034129 -45.916654) (xy 195.034128 -45.861163) (xy 195.042171 -45.806258) (xy 195.058088 -45.753098)
			(xy 195.081543 -45.702808) (xy 195.096384 -45.67936) (xy 195.100122 -45.673251) (xy 195.104385 -45.659587)
			(xy 195.104766 -45.652436) (xy 195.104766 -45.1104) (xy 195.104766 -45.109384) (xy 195.104376 -45.102235)
			(xy 195.100112 -45.088574) (xy 195.096384 -45.08246) (xy 195.081551 -45.059007) (xy 195.058094 -45.008717)
			(xy 195.042174 -44.955559) (xy 195.034129 -44.900654) (xy 195.034128 -44.845163) (xy 195.042171 -44.790258)
			(xy 195.058088 -44.737098) (xy 195.081543 -44.686808) (xy 195.096384 -44.66336) (xy 195.100122 -44.657251)
			(xy 195.104385 -44.643587) (xy 195.104766 -44.636436) (xy 195.104766 -44.0944) (xy 195.104766 -44.093384)
			(xy 195.104376 -44.086235) (xy 195.100112 -44.072574) (xy 195.096384 -44.06646) (xy 195.081551 -44.043007)
			(xy 195.058094 -43.992717) (xy 195.042174 -43.939559) (xy 195.034129 -43.884654) (xy 195.034128 -43.829163)
			(xy 195.042171 -43.774258) (xy 195.058088 -43.721098) (xy 195.081543 -43.670808) (xy 195.096384 -43.64736)
			(xy 195.100122 -43.641251) (xy 195.104385 -43.627587) (xy 195.104766 -43.620436) (xy 195.104766 -43.0784)
			(xy 195.104766 -43.077384) (xy 195.104376 -43.070235) (xy 195.100112 -43.056574) (xy 195.096384 -43.05046)
			(xy 195.081551 -43.027007) (xy 195.058094 -42.976717) (xy 195.042174 -42.923559) (xy 195.034129 -42.868654)
			(xy 195.034128 -42.813163) (xy 195.042171 -42.758258) (xy 195.058088 -42.705098) (xy 195.081543 -42.654808)
			(xy 195.096384 -42.63136) (xy 195.100122 -42.625251) (xy 195.104385 -42.611587) (xy 195.104766 -42.604436)
			(xy 195.104766 -41.423844) (xy 195.104258 -41.416478) (xy 195.102888 -41.409032) (xy 195.096434 -41.395345)
			(xy 195.091558 -41.389554) (xy 195.076318 -41.373552) (xy 195.073879 -41.370993) (xy 195.068398 -41.366529)
			(xy 195.065396 -41.364662) (xy 195.06184 -41.362884) (xy 195.038472 -41.351454) (xy 195.03009 -41.350438)
			(xy 195.00268 -41.346612) (xy 194.949282 -41.33207) (xy 194.898546 -41.309966) (xy 194.851536 -41.280763)
			(xy 194.809238 -41.245075) (xy 194.77254 -41.203649) (xy 194.742212 -41.157356) (xy 194.718892 -41.107167)
			(xy 194.703067 -41.054136) (xy 194.695071 -40.999374) (xy 194.69507 -40.944032) (xy 194.703066 -40.88927)
			(xy 194.71889 -40.836238) (xy 194.74221 -40.786049) (xy 194.772536 -40.739755) (xy 194.809233 -40.698329)
			(xy 194.851531 -40.66264) (xy 194.898541 -40.633437) (xy 194.949277 -40.611332) (xy 195.002675 -40.596789)
			(xy 195.03009 -40.59301) (xy 195.038472 -40.591994) (xy 195.06184 -40.580564) (xy 195.065396 -40.578786)
			(xy 195.076318 -40.569896) (xy 195.091558 -40.553894) (xy 195.09649 -40.548137) (xy 195.102968 -40.534439)
			(xy 195.104258 -40.52697) (xy 195.104766 -40.519604) (xy 195.104766 -38.432232) (xy 195.104351 -38.422209)
			(xy 195.096686 -38.403687) (xy 195.082511 -38.389513) (xy 195.063989 -38.381848) (xy 195.053966 -38.381432)
			(xy 193.38417 -38.381432) (xy 193.379852 -38.381686) (xy 193.379344 -38.381686) (xy 193.367521 -38.383395)
			(xy 193.347245 -38.39597) (xy 193.340482 -38.405816) (xy 193.297048 -38.487096) (xy 193.291946 -38.497897)
			(xy 193.291289 -38.521745) (xy 193.295778 -38.532816) (xy 193.299334 -38.538912) (xy 193.299588 -38.539166)
			(xy 193.299588 -38.53942) (xy 193.314712 -38.563007) (xy 193.338624 -38.61368) (xy 193.35486 -38.667307)
			(xy 193.36307 -38.722733) (xy 193.363596 -38.750748) (xy 193.363106 -38.777997) (xy 193.355344 -38.831938)
			(xy 193.339985 -38.884227) (xy 193.317341 -38.933797) (xy 193.287873 -38.979641) (xy 193.252182 -39.020824)
			(xy 193.210992 -39.056509) (xy 193.165144 -39.08597) (xy 193.11557 -39.108606) (xy 193.06328 -39.123957)
			(xy 193.009337 -39.131711) (xy 192.982088 -39.132256) (xy 192.954593 -39.131775) (xy 192.900172 -39.123881)
			(xy 192.847447 -39.108259) (xy 192.79751 -39.085231) (xy 192.751395 -39.055274) (xy 192.710057 -39.01901)
			(xy 192.674351 -38.977187) (xy 192.659254 -38.954202) (xy 192.655698 -38.948614) (xy 192.648332 -38.941502)
			(xy 192.633346 -38.932104) (xy 192.632838 -38.932104) (xy 192.62344 -38.926262) (xy 192.618062 -38.923181)
			(xy 192.606245 -38.919455) (xy 192.600072 -38.918896) (xy 192.529206 -38.914324) (xy 192.522094 -38.914324)
			(xy 192.517416 -38.914774) (xy 192.508338 -38.917203) (xy 192.50406 -38.91915) (xy 192.498695 -38.921892)
			(xy 192.489332 -38.929471) (xy 192.485518 -38.934136) (xy 192.485264 -38.93439) (xy 192.483486 -38.93693)
			(xy 192.465283 -38.959441) (xy 192.423235 -38.999232) (xy 192.375663 -39.032221) (xy 192.323659 -39.057653)
			(xy 192.268411 -39.074946) (xy 192.211187 -39.083703) (xy 192.182242 -39.08425) (xy 192.181988 -39.08425)
			(xy 192.154736 -39.083763) (xy 192.100788 -39.076006) (xy 192.048492 -39.06065) (xy 191.998913 -39.038009)
			(xy 191.953062 -39.008543) (xy 191.911869 -38.972852) (xy 191.876175 -38.931663) (xy 191.846706 -38.885813)
			(xy 191.82406 -38.836236) (xy 191.808701 -38.783942) (xy 191.800939 -38.729994) (xy 191.80048 -38.702742)
			(xy 191.801039 -38.672656) (xy 191.810484 -38.613231) (xy 191.829161 -38.556032) (xy 191.84239 -38.529006)
			(xy 191.845153 -38.523102) (xy 191.847968 -38.510379) (xy 191.847978 -38.50386) (xy 191.84747 -38.490906)
			(xy 191.795146 -38.405816) (xy 191.791288 -38.399945) (xy 191.780981 -38.390406) (xy 191.774826 -38.38702)
			(xy 191.774318 -38.386766) (xy 191.768992 -38.384307) (xy 191.757576 -38.38162) (xy 191.751712 -38.381432)
			(xy 189.385448 -38.381432) (xy 189.38057 -38.381528) (xy 189.370981 -38.383316) (xy 189.366398 -38.384988)
			(xy 189.357254 -38.388798) (xy 189.084204 -38.661848) (xy 189.06363 -38.682168) (xy 189.039731 -38.705334)
			(xy 188.986926 -38.745856) (xy 188.929283 -38.779137) (xy 188.867787 -38.804607) (xy 188.803493 -38.821829)
			(xy 188.737501 -38.830509) (xy 188.70422 -38.831012) (xy 187.08878 -38.831012) (xy 187.055502 -38.830467)
			(xy 186.989517 -38.82178) (xy 186.925228 -38.804557) (xy 186.863737 -38.779092) (xy 186.806095 -38.745821)
			(xy 186.753287 -38.705312) (xy 186.72937 -38.682168) (xy 185.881772 -37.83457) (xy 185.858607 -37.81067)
			(xy 185.818088 -37.757865) (xy 185.784811 -37.700222) (xy 185.759347 -37.638726) (xy 185.742131 -37.574432)
			(xy 185.733457 -37.50844) (xy 185.732928 -37.47516) (xy 185.732955 -37.463333) (xy 185.733971 -37.439701)
			(xy 185.73496 -37.427916) (xy 185.735214 -37.42563) (xy 185.735214 -37.42436) (xy 185.738792 -37.393445)
			(xy 185.752524 -37.332743) (xy 185.773562 -37.27417) (xy 185.801591 -37.218603) (xy 185.836192 -37.166872)
			(xy 185.876847 -37.11975) (xy 185.922949 -37.077941) (xy 185.973809 -37.042072) (xy 186.028666 -37.012677)
			(xy 186.0867 -36.990197) (xy 186.147044 -36.974967) (xy 186.208795 -36.967216) (xy 186.239912 -36.966652)
			(xy 186.250834 -36.966906) (xy 186.283317 -36.96802) (xy 186.347619 -36.977493) (xy 186.410187 -36.995092)
			(xy 186.469999 -37.020528) (xy 186.526079 -37.053386) (xy 186.577508 -37.093128) (xy 186.600846 -37.11575)
			(xy 186.686444 -37.201602) (xy 187.28436 -37.799518) (xy 187.289186 -37.803836) (xy 187.29597 -37.808753)
			(xy 187.311801 -37.814215) (xy 187.320174 -37.814504) (xy 187.950094 -37.814504) (xy 187.95365 -37.81425)
			(xy 187.96341 -37.813114) (xy 187.981041 -37.804483) (xy 187.98794 -37.797486) (xy 188.038232 -37.741098)
			(xy 188.041628 -37.737095) (xy 188.04688 -37.728007) (xy 188.048646 -37.723064) (xy 188.051948 -37.71265)
			(xy 188.050932 -37.701982) (xy 188.0489 -37.667946) (xy 188.0489 -37.660834) (xy 188.049492 -37.633656)
			(xy 188.057429 -37.579878) (xy 188.07292 -37.527772) (xy 188.09565 -37.478392) (xy 188.125159 -37.432738)
			(xy 188.16085 -37.391735) (xy 188.201999 -37.356214) (xy 188.247774 -37.326893) (xy 188.297248 -37.304367)
			(xy 188.349418 -37.289092) (xy 188.403228 -37.281377) (xy 188.430408 -37.28085) (xy 188.45946 -37.281395)
			(xy 188.516893 -37.290204) (xy 188.572327 -37.307616) (xy 188.624481 -37.333231) (xy 188.67215 -37.366455)
			(xy 188.714231 -37.406521) (xy 188.732414 -37.429186) (xy 188.73851 -37.43706) (xy 188.74613 -37.441632)
			(xy 188.750326 -37.444039) (xy 188.759405 -37.447373) (xy 188.764164 -37.448236) (xy 188.772038 -37.449506)
			(xy 188.780674 -37.450776) (xy 188.781182 -37.450776) (xy 188.781944 -37.45103) (xy 188.788802 -37.451538)
			(xy 188.854334 -37.451538) (xy 188.858077 -37.45146) (xy 188.865476 -37.450315) (xy 188.869066 -37.449252)
			(xy 188.875416 -37.447474) (xy 188.88075 -37.444172) (xy 188.894466 -37.436044) (xy 188.894974 -37.435536)
			(xy 188.917096 -37.422783) (xy 188.963411 -37.401276) (xy 188.98743 -37.39261) (xy 188.988446 -37.392102)
			(xy 188.993018 -37.390578) (xy 188.994034 -37.39007) (xy 189.022303 -37.381157) (xy 189.080353 -37.369169)
			(xy 189.139402 -37.363998) (xy 189.16904 -37.364416) (xy 195.053966 -37.364416) (xy 195.063993 -37.364002)
			(xy 195.082524 -37.356339) (xy 195.096711 -37.342166) (xy 195.104393 -37.323643) (xy 195.104766 -37.313616)
			(xy 195.104766 -31.63316) (xy 195.104004 -31.629096) (xy 195.101721 -31.613896) (xy 195.099304 -31.583252)
			(xy 195.099178 -31.567882) (xy 195.099298 -31.552512) (xy 195.101716 -31.521867) (xy 195.104004 -31.506668)
			(xy 195.104766 -31.502604) (xy 195.104766 -30.680914) (xy 195.104626 -30.676165) (xy 195.102838 -30.666835)
			(xy 195.10121 -30.662372) (xy 195.09105 -30.636972) (xy 195.085208 -30.630368) (xy 195.067158 -30.609303)
			(xy 195.036707 -30.562937) (xy 195.01329 -30.512651) (xy 194.9974 -30.459505) (xy 194.989371 -30.404618)
			(xy 194.989374 -30.349146) (xy 194.997407 -30.29426) (xy 195.013303 -30.241115) (xy 195.036725 -30.190831)
			(xy 195.06718 -30.144468) (xy 195.085208 -30.123384) (xy 195.09105 -30.11678) (xy 195.10121 -30.09138)
			(xy 195.102882 -30.086928) (xy 195.104681 -30.077592) (xy 195.104766 -30.072838) (xy 195.104766 -29.918914)
			(xy 195.104626 -29.914165) (xy 195.102838 -29.904835) (xy 195.10121 -29.900372) (xy 195.09105 -29.874972)
			(xy 195.085208 -29.868368) (xy 195.067164 -29.847301) (xy 195.036724 -29.800931) (xy 195.01332 -29.750643)
			(xy 194.997444 -29.697496) (xy 194.98943 -29.64261) (xy 194.988942 -29.614876) (xy 194.988942 -29.614368)
			(xy 194.989354 -29.589299) (xy 194.995949 -29.539596) (xy 195.008996 -29.491185) (xy 195.028269 -29.444899)
			(xy 195.053437 -29.401535) (xy 195.068444 -29.38145) (xy 195.072027 -29.375367) (xy 195.076023 -29.361833)
			(xy 195.076318 -29.35478) (xy 195.076318 -29.07157) (xy 195.076223 -29.067425) (xy 195.074821 -29.059253)
			(xy 195.073524 -29.055314) (xy 195.065904 -29.032708) (xy 195.064126 -29.029914) (xy 195.046384 -29.005055)
			(xy 195.018203 -28.950877) (xy 194.999007 -28.892902) (xy 194.989288 -28.832611) (xy 194.988688 -28.802076)
			(xy 194.98929 -28.771542) (xy 194.999014 -28.711252) (xy 195.018211 -28.653279) (xy 195.046391 -28.599101)
			(xy 195.064126 -28.574238) (xy 195.065904 -28.571444) (xy 195.073524 -28.548838) (xy 195.074787 -28.544891)
			(xy 195.07619 -28.536724) (xy 195.076318 -28.532582) (xy 195.076318 -28.368752) (xy 195.076546 -28.361714)
			(xy 195.080421 -28.348183) (xy 195.083938 -28.342082) (xy 195.097654 -28.320492) (xy 195.099932 -28.316392)
			(xy 195.103122 -28.307573) (xy 195.104004 -28.302966) (xy 195.104004 -28.302458) (xy 195.104766 -28.294584)
			(xy 195.104766 -27.872436) (xy 195.104597 -27.866427) (xy 195.101768 -27.854747) (xy 195.099178 -27.849322)
			(xy 195.09734 -27.845847) (xy 195.092749 -27.839466) (xy 195.090034 -27.836622) (xy 194.852798 -27.599386)
			(xy 194.846606 -27.593635) (xy 194.831425 -27.586235) (xy 194.82308 -27.584908) (xy 194.806062 -27.582876)
			(xy 194.79895 -27.582114) (xy 194.795648 -27.58186) (xy 185.511694 -27.58186) (xy 185.505606 -27.582066)
			(xy 185.493793 -27.585016) (xy 185.488326 -27.587702) (xy 185.488072 -27.587702) (xy 185.468768 -27.597862)
			(xy 185.458608 -27.60472) (xy 185.454544 -27.608276) (xy 185.450988 -27.613102) (xy 185.432453 -27.637628)
			(xy 185.389868 -27.681967) (xy 185.341732 -27.720206) (xy 185.28891 -27.751658) (xy 185.232353 -27.775756)
			(xy 185.17308 -27.792066) (xy 185.112156 -27.800296) (xy 185.05068 -27.800296) (xy 184.989756 -27.792066)
			(xy 184.930483 -27.775756) (xy 184.873926 -27.751658) (xy 184.821104 -27.720206) (xy 184.772968 -27.681967)
			(xy 184.730383 -27.637628) (xy 184.711848 -27.613102) (xy 184.708292 -27.608276) (xy 184.704228 -27.60472)
			(xy 184.694068 -27.597862) (xy 184.674764 -27.587702) (xy 184.67451 -27.587702) (xy 184.669038 -27.58503)
			(xy 184.657228 -27.582078) (xy 184.651142 -27.58186) (xy 180.52796 -27.58186) (xy 180.521729 -27.582069)
			(xy 180.50965 -27.585147) (xy 180.504084 -27.587956) (xy 180.497226 -27.591512) (xy 180.22316 -27.865578)
			(xy 180.216302 -27.877516) (xy 180.214778 -27.88412) (xy 180.207052 -27.912348) (xy 180.184138 -27.9662)
			(xy 180.153271 -28.015922) (xy 180.115172 -28.060346) (xy 180.070737 -28.098432) (xy 180.021007 -28.129287)
			(xy 179.967149 -28.152185) (xy 179.938934 -28.159964) (xy 179.93233 -28.161488) (xy 179.920392 -28.168346)
			(xy 179.904644 -28.184094) (xy 179.901937 -28.186945) (xy 179.897343 -28.193322) (xy 179.8955 -28.196794)
			(xy 179.892922 -28.202222) (xy 179.89011 -28.213902) (xy 179.889912 -28.219908) (xy 179.889912 -29.114242)
			(xy 186.947556 -29.114242) (xy 186.947556 -28.250642) (xy 186.948046 -28.220674) (xy 186.955869 -28.161252)
			(xy 186.971382 -28.103359) (xy 186.994318 -28.047986) (xy 187.024285 -27.99608) (xy 187.060772 -27.94853)
			(xy 187.103152 -27.90615) (xy 187.150702 -27.869663) (xy 187.202608 -27.839696) (xy 187.257981 -27.81676)
			(xy 187.315874 -27.801247) (xy 187.375296 -27.793424) (xy 187.435232 -27.793424) (xy 187.494654 -27.801247)
			(xy 187.552547 -27.81676) (xy 187.60792 -27.839696) (xy 187.659826 -27.869663) (xy 187.707376 -27.90615)
			(xy 187.749756 -27.94853) (xy 187.786243 -27.99608) (xy 187.81621 -28.047986) (xy 187.839146 -28.103359)
			(xy 187.854659 -28.161252) (xy 187.862482 -28.220674) (xy 187.862972 -28.250642) (xy 187.862972 -28.469082)
			(xy 191.852548 -28.469082) (xy 191.856619 -28.41346) (xy 191.868745 -28.359023) (xy 191.888668 -28.306932)
			(xy 191.915964 -28.258297) (xy 191.95005 -28.214154) (xy 191.990199 -28.175445) (xy 192.035557 -28.142994)
			(xy 192.085157 -28.117493) (xy 192.137941 -28.099486) (xy 192.192784 -28.089356) (xy 192.248518 -28.087319)
			(xy 192.303955 -28.093419) (xy 192.357912 -28.107525) (xy 192.409241 -28.129337) (xy 192.456847 -28.158391)
			(xy 192.499715 -28.194066) (xy 192.536932 -28.235603) (xy 192.567705 -28.282116) (xy 192.591377 -28.332613)
			(xy 192.607445 -28.38602) (xy 192.615565 -28.441196) (xy 192.616074 -28.469082) (xy 192.615565 -28.496968)
			(xy 192.607445 -28.552144) (xy 192.591377 -28.605551) (xy 192.567705 -28.656048) (xy 192.536932 -28.702561)
			(xy 192.499715 -28.744098) (xy 192.456847 -28.779773) (xy 192.409241 -28.808827) (xy 192.357912 -28.830639)
			(xy 192.303955 -28.844745) (xy 192.248518 -28.850845) (xy 192.192784 -28.848808) (xy 192.137941 -28.838678)
			(xy 192.085157 -28.820671) (xy 192.035557 -28.79517) (xy 191.990199 -28.762719) (xy 191.95005 -28.72401)
			(xy 191.915964 -28.679867) (xy 191.888668 -28.631232) (xy 191.868745 -28.579141) (xy 191.856619 -28.524704)
			(xy 191.852548 -28.469082) (xy 187.862972 -28.469082) (xy 187.862972 -29.114242) (xy 187.862482 -29.14421)
			(xy 187.854659 -29.203632) (xy 187.839146 -29.261525) (xy 187.81621 -29.316898) (xy 187.786243 -29.368804)
			(xy 187.749756 -29.416354) (xy 187.707376 -29.458734) (xy 187.659826 -29.495221) (xy 187.60792 -29.525188)
			(xy 187.552547 -29.548124) (xy 187.494654 -29.563637) (xy 187.435232 -29.57146) (xy 187.375296 -29.57146)
			(xy 187.315874 -29.563637) (xy 187.257981 -29.548124) (xy 187.202608 -29.525188) (xy 187.150702 -29.495221)
			(xy 187.103152 -29.458734) (xy 187.060772 -29.416354) (xy 187.024285 -29.368804) (xy 186.994318 -29.316898)
			(xy 186.971382 -29.261525) (xy 186.955869 -29.203632) (xy 186.948046 -29.14421) (xy 186.947556 -29.114242)
			(xy 179.889912 -29.114242) (xy 179.889912 -29.186378) (xy 179.91201 -29.21381) (xy 179.929536 -29.217874)
			(xy 179.955833 -29.224333) (xy 180.006409 -29.243672) (xy 180.053745 -29.269966) (xy 180.096888 -29.302687)
			(xy 180.134972 -29.341178) (xy 180.167234 -29.384666) (xy 180.193023 -29.432278) (xy 180.211824 -29.483057)
			(xy 180.223257 -29.535985) (xy 180.227095 -29.589996) (xy 180.223259 -29.644008) (xy 180.211826 -29.696936)
			(xy 180.193026 -29.747715) (xy 180.167237 -29.795328) (xy 180.134977 -29.838817) (xy 180.096893 -29.877309)
			(xy 180.053751 -29.910031) (xy 180.006416 -29.936325) (xy 179.955839 -29.955665) (xy 179.929536 -29.962094)
			(xy 179.91201 -29.966158) (xy 179.889912 -29.99359) (xy 179.889912 -30.92069) (xy 189.589664 -30.92069)
			(xy 189.589664 -30.05709) (xy 189.590154 -30.027122) (xy 189.597977 -29.9677) (xy 189.61349 -29.909807)
			(xy 189.636426 -29.854434) (xy 189.666393 -29.802528) (xy 189.70288 -29.754978) (xy 189.74526 -29.712598)
			(xy 189.79281 -29.676111) (xy 189.844716 -29.646144) (xy 189.900089 -29.623208) (xy 189.957982 -29.607695)
			(xy 190.017404 -29.599872) (xy 190.07734 -29.599872) (xy 190.136762 -29.607695) (xy 190.194655 -29.623208)
			(xy 190.250028 -29.646144) (xy 190.301934 -29.676111) (xy 190.349484 -29.712598) (xy 190.391864 -29.754978)
			(xy 190.428351 -29.802528) (xy 190.458318 -29.854434) (xy 190.481254 -29.909807) (xy 190.496767 -29.9677)
			(xy 190.50459 -30.027122) (xy 190.50508 -30.05709) (xy 190.50508 -30.92069) (xy 190.50459 -30.950658)
			(xy 190.496767 -31.01008) (xy 190.481254 -31.067973) (xy 190.458318 -31.123346) (xy 190.428351 -31.175252)
			(xy 190.391864 -31.222802) (xy 190.349484 -31.265182) (xy 190.301934 -31.301669) (xy 190.250028 -31.331636)
			(xy 190.194655 -31.354572) (xy 190.136762 -31.370085) (xy 190.07734 -31.377908) (xy 190.017404 -31.377908)
			(xy 189.957982 -31.370085) (xy 189.900089 -31.354572) (xy 189.844716 -31.331636) (xy 189.79281 -31.301669)
			(xy 189.74526 -31.265182) (xy 189.70288 -31.222802) (xy 189.666393 -31.175252) (xy 189.636426 -31.123346)
			(xy 189.61349 -31.067973) (xy 189.597977 -31.01008) (xy 189.590154 -30.950658) (xy 189.589664 -30.92069)
			(xy 179.889912 -30.92069) (xy 179.889912 -31.232602) (xy 179.915312 -31.261304) (xy 179.934616 -31.26359)
			(xy 179.962023 -31.267417) (xy 180.015416 -31.281959) (xy 180.066148 -31.304062) (xy 180.113154 -31.333264)
			(xy 180.155448 -31.36895) (xy 180.192142 -31.410372) (xy 180.222466 -31.456662) (xy 180.245784 -31.506847)
			(xy 180.261607 -31.559874) (xy 180.269602 -31.614632) (xy 180.269602 -31.669969) (xy 180.261607 -31.724727)
			(xy 180.245784 -31.777754) (xy 180.222466 -31.827939) (xy 180.192141 -31.874228) (xy 180.155447 -31.915651)
			(xy 180.113153 -31.951337) (xy 180.066147 -31.980538) (xy 180.015415 -32.002641) (xy 179.962022 -32.017183)
			(xy 179.934616 -32.021018) (xy 179.915312 -32.023304) (xy 179.889912 -32.052006) (xy 179.889912 -32.714184)
			(xy 186.947556 -32.714184) (xy 186.947556 -31.850584) (xy 186.948046 -31.820616) (xy 186.955869 -31.761194)
			(xy 186.971382 -31.703301) (xy 186.994318 -31.647928) (xy 187.024285 -31.596022) (xy 187.060772 -31.548472)
			(xy 187.103152 -31.506092) (xy 187.150702 -31.469605) (xy 187.202608 -31.439638) (xy 187.257981 -31.416702)
			(xy 187.315874 -31.401189) (xy 187.375296 -31.393366) (xy 187.435232 -31.393366) (xy 187.494654 -31.401189)
			(xy 187.552547 -31.416702) (xy 187.60792 -31.439638) (xy 187.659826 -31.469605) (xy 187.707376 -31.506092)
			(xy 187.749756 -31.548472) (xy 187.786243 -31.596022) (xy 187.81621 -31.647928) (xy 187.839146 -31.703301)
			(xy 187.854659 -31.761194) (xy 187.862482 -31.820616) (xy 187.862972 -31.850584) (xy 187.862972 -32.714184)
			(xy 187.862482 -32.744152) (xy 187.854659 -32.803574) (xy 187.839146 -32.861467) (xy 187.81621 -32.91684)
			(xy 187.786243 -32.968746) (xy 187.749756 -33.016296) (xy 187.707376 -33.058676) (xy 187.659826 -33.095163)
			(xy 187.60792 -33.12513) (xy 187.552547 -33.148066) (xy 187.494654 -33.163579) (xy 187.435232 -33.171402)
			(xy 187.375296 -33.171402) (xy 187.315874 -33.163579) (xy 187.257981 -33.148066) (xy 187.202608 -33.12513)
			(xy 187.150702 -33.095163) (xy 187.103152 -33.058676) (xy 187.060772 -33.016296) (xy 187.024285 -32.968746)
			(xy 186.994318 -32.91684) (xy 186.971382 -32.861467) (xy 186.955869 -32.803574) (xy 186.948046 -32.744152)
			(xy 186.947556 -32.714184) (xy 179.889912 -32.714184) (xy 179.889912 -34.520886) (xy 189.589664 -34.520886)
			(xy 189.589664 -33.657286) (xy 189.590154 -33.627318) (xy 189.597977 -33.567896) (xy 189.61349 -33.510003)
			(xy 189.636426 -33.45463) (xy 189.666393 -33.402724) (xy 189.70288 -33.355174) (xy 189.74526 -33.312794)
			(xy 189.79281 -33.276307) (xy 189.844716 -33.24634) (xy 189.900089 -33.223404) (xy 189.957982 -33.207891)
			(xy 190.017404 -33.200068) (xy 190.07734 -33.200068) (xy 190.136762 -33.207891) (xy 190.194655 -33.223404)
			(xy 190.250028 -33.24634) (xy 190.301934 -33.276307) (xy 190.349484 -33.312794) (xy 190.391864 -33.355174)
			(xy 190.428351 -33.402724) (xy 190.458318 -33.45463) (xy 190.481254 -33.510003) (xy 190.496767 -33.567896)
			(xy 190.50459 -33.627318) (xy 190.50508 -33.657286) (xy 190.50508 -34.520886) (xy 190.50459 -34.550854)
			(xy 190.496767 -34.610276) (xy 190.481254 -34.668169) (xy 190.458318 -34.723542) (xy 190.428351 -34.775448)
			(xy 190.391864 -34.822998) (xy 190.349484 -34.865378) (xy 190.301934 -34.901865) (xy 190.250028 -34.931832)
			(xy 190.194655 -34.954768) (xy 190.136762 -34.970281) (xy 190.07734 -34.978104) (xy 190.017404 -34.978104)
			(xy 189.957982 -34.970281) (xy 189.900089 -34.954768) (xy 189.844716 -34.931832) (xy 189.79281 -34.901865)
			(xy 189.74526 -34.865378) (xy 189.70288 -34.822998) (xy 189.666393 -34.775448) (xy 189.636426 -34.723542)
			(xy 189.61349 -34.668169) (xy 189.597977 -34.610276) (xy 189.590154 -34.550854) (xy 189.589664 -34.520886)
			(xy 179.889912 -34.520886) (xy 179.889912 -36.60013) (xy 180.098199 -36.60013) (xy 180.102204 -36.512222)
			(xy 180.114187 -36.425042) (xy 180.134047 -36.339313) (xy 180.161622 -36.255745) (xy 180.196681 -36.175031)
			(xy 180.238934 -36.097839) (xy 180.288032 -36.02481) (xy 180.343568 -35.956548) (xy 180.40508 -35.893618)
			(xy 180.472061 -35.836544) (xy 180.543954 -35.785796) (xy 180.620163 -35.741796) (xy 180.700058 -35.704909)
			(xy 180.782977 -35.67544) (xy 180.868232 -35.653633) (xy 180.955116 -35.639669) (xy 181.04291 -35.633663)
			(xy 181.130887 -35.635667) (xy 181.218317 -35.645662) (xy 181.304476 -35.663566) (xy 181.38865 -35.68923)
			(xy 181.470141 -35.722443) (xy 181.548275 -35.762929) (xy 181.622403 -35.810351) (xy 181.691911 -35.864318)
			(xy 181.70521 -35.876738) (xy 186.817252 -35.876738) (xy 186.821323 -35.821116) (xy 186.833449 -35.766679)
			(xy 186.853372 -35.714588) (xy 186.880668 -35.665953) (xy 186.914754 -35.62181) (xy 186.954903 -35.583101)
			(xy 187.000261 -35.55065) (xy 187.049861 -35.525149) (xy 187.102645 -35.507142) (xy 187.157488 -35.497012)
			(xy 187.213222 -35.494975) (xy 187.268659 -35.501075) (xy 187.322616 -35.515181) (xy 187.373945 -35.536993)
			(xy 187.421551 -35.566047) (xy 187.464419 -35.601722) (xy 187.501636 -35.643259) (xy 187.532409 -35.689772)
			(xy 187.556081 -35.740269) (xy 187.572149 -35.793676) (xy 187.580269 -35.848852) (xy 187.580778 -35.876738)
			(xy 190.888872 -35.876738) (xy 190.892943 -35.821116) (xy 190.905069 -35.766679) (xy 190.924992 -35.714588)
			(xy 190.952288 -35.665953) (xy 190.986374 -35.62181) (xy 191.026523 -35.583101) (xy 191.071881 -35.55065)
			(xy 191.121481 -35.525149) (xy 191.174265 -35.507142) (xy 191.229108 -35.497012) (xy 191.284842 -35.494975)
			(xy 191.340279 -35.501075) (xy 191.394236 -35.515181) (xy 191.445565 -35.536993) (xy 191.493171 -35.566047)
			(xy 191.536039 -35.601722) (xy 191.573256 -35.643259) (xy 191.604029 -35.689772) (xy 191.627701 -35.740269)
			(xy 191.643769 -35.793676) (xy 191.651889 -35.848852) (xy 191.652398 -35.876738) (xy 191.651889 -35.904624)
			(xy 191.643769 -35.9598) (xy 191.627701 -36.013207) (xy 191.604029 -36.063704) (xy 191.573256 -36.110217)
			(xy 191.536039 -36.151754) (xy 191.493171 -36.187429) (xy 191.445565 -36.216483) (xy 191.394236 -36.238295)
			(xy 191.340279 -36.252401) (xy 191.284842 -36.258501) (xy 191.229108 -36.256464) (xy 191.174265 -36.246334)
			(xy 191.121481 -36.228327) (xy 191.071881 -36.202826) (xy 191.026523 -36.170375) (xy 190.986374 -36.131666)
			(xy 190.952288 -36.087523) (xy 190.924992 -36.038888) (xy 190.905069 -35.986797) (xy 190.892943 -35.93236)
			(xy 190.888872 -35.876738) (xy 187.580778 -35.876738) (xy 187.580269 -35.904624) (xy 187.572149 -35.9598)
			(xy 187.556081 -36.013207) (xy 187.532409 -36.063704) (xy 187.501636 -36.110217) (xy 187.464419 -36.151754)
			(xy 187.421551 -36.187429) (xy 187.373945 -36.216483) (xy 187.322616 -36.238295) (xy 187.268659 -36.252401)
			(xy 187.213222 -36.258501) (xy 187.157488 -36.256464) (xy 187.102645 -36.246334) (xy 187.049861 -36.228327)
			(xy 187.000261 -36.202826) (xy 186.954903 -36.170375) (xy 186.914754 -36.131666) (xy 186.880668 -36.087523)
			(xy 186.853372 -36.038888) (xy 186.833449 -35.986797) (xy 186.821323 -35.93236) (xy 186.817252 -35.876738)
			(xy 181.70521 -35.876738) (xy 181.756225 -35.924383) (xy 181.814809 -35.990047) (xy 181.86718 -36.060766)
			(xy 181.912903 -36.135954) (xy 181.9516 -36.214989) (xy 181.982949 -36.297215) (xy 182.006691 -36.381951)
			(xy 182.022629 -36.468495) (xy 182.026415 -36.50996) (xy 188.71387 -36.50996) (xy 188.717941 -36.454338)
			(xy 188.730067 -36.399901) (xy 188.74999 -36.34781) (xy 188.777286 -36.299175) (xy 188.811372 -36.255032)
			(xy 188.851521 -36.216323) (xy 188.896879 -36.183872) (xy 188.946479 -36.158371) (xy 188.999263 -36.140364)
			(xy 189.054106 -36.130234) (xy 189.10984 -36.128197) (xy 189.165277 -36.134297) (xy 189.219234 -36.148403)
			(xy 189.270563 -36.170215) (xy 189.318169 -36.199269) (xy 189.361037 -36.234944) (xy 189.398254 -36.276481)
			(xy 189.429027 -36.322994) (xy 189.452699 -36.373491) (xy 189.468767 -36.426898) (xy 189.472692 -36.453572)
			(xy 192.02857 -36.453572) (xy 192.032641 -36.39795) (xy 192.044767 -36.343513) (xy 192.06469 -36.291422)
			(xy 192.091986 -36.242787) (xy 192.126072 -36.198644) (xy 192.166221 -36.159935) (xy 192.211579 -36.127484)
			(xy 192.261179 -36.101983) (xy 192.313963 -36.083976) (xy 192.368806 -36.073846) (xy 192.42454 -36.071809)
			(xy 192.479977 -36.077909) (xy 192.533934 -36.092015) (xy 192.585263 -36.113827) (xy 192.632869 -36.142881)
			(xy 192.675737 -36.178556) (xy 192.712954 -36.220093) (xy 192.743727 -36.266606) (xy 192.767399 -36.317103)
			(xy 192.783467 -36.37051) (xy 192.791587 -36.425686) (xy 192.792096 -36.453572) (xy 192.791587 -36.481458)
			(xy 192.783467 -36.536634) (xy 192.767399 -36.590041) (xy 192.743727 -36.640538) (xy 192.712954 -36.687051)
			(xy 192.675737 -36.728588) (xy 192.632869 -36.764263) (xy 192.585263 -36.793317) (xy 192.533934 -36.815129)
			(xy 192.479977 -36.829235) (xy 192.42454 -36.835335) (xy 192.368806 -36.833298) (xy 192.313963 -36.823168)
			(xy 192.261179 -36.805161) (xy 192.211579 -36.77966) (xy 192.166221 -36.747209) (xy 192.126072 -36.7085)
			(xy 192.091986 -36.664357) (xy 192.06469 -36.615722) (xy 192.044767 -36.563631) (xy 192.032641 -36.509194)
			(xy 192.02857 -36.453572) (xy 189.472692 -36.453572) (xy 189.476887 -36.482074) (xy 189.477396 -36.50996)
			(xy 189.476887 -36.537846) (xy 189.468767 -36.593022) (xy 189.452699 -36.646429) (xy 189.429027 -36.696926)
			(xy 189.398254 -36.743439) (xy 189.361037 -36.784976) (xy 189.318169 -36.820651) (xy 189.270563 -36.849705)
			(xy 189.219234 -36.871517) (xy 189.165277 -36.885623) (xy 189.10984 -36.891723) (xy 189.054106 -36.889686)
			(xy 188.999263 -36.879556) (xy 188.946479 -36.861549) (xy 188.896879 -36.836048) (xy 188.851521 -36.803597)
			(xy 188.811372 -36.764888) (xy 188.777286 -36.720745) (xy 188.74999 -36.67211) (xy 188.730067 -36.620019)
			(xy 188.717941 -36.565582) (xy 188.71387 -36.50996) (xy 182.026415 -36.50996) (xy 182.030631 -36.55613)
			(xy 182.031132 -36.60013) (xy 182.030631 -36.64413) (xy 182.022629 -36.731765) (xy 182.006691 -36.818309)
			(xy 181.982949 -36.903045) (xy 181.9516 -36.985271) (xy 181.912903 -37.064306) (xy 181.86718 -37.139494)
			(xy 181.814809 -37.210213) (xy 181.756225 -37.275877) (xy 181.691911 -37.335942) (xy 181.622403 -37.389909)
			(xy 181.548275 -37.437331) (xy 181.470141 -37.477817) (xy 181.38865 -37.51103) (xy 181.304476 -37.536694)
			(xy 181.218317 -37.554598) (xy 181.130887 -37.564593) (xy 181.04291 -37.566597) (xy 180.955116 -37.560591)
			(xy 180.868232 -37.546627) (xy 180.782977 -37.52482) (xy 180.700058 -37.495351) (xy 180.620163 -37.458464)
			(xy 180.543954 -37.414464) (xy 180.472061 -37.363716) (xy 180.40508 -37.306642) (xy 180.343568 -37.243712)
			(xy 180.288032 -37.17545) (xy 180.238934 -37.102421) (xy 180.196681 -37.025229) (xy 180.161622 -36.944515)
			(xy 180.134047 -36.860947) (xy 180.114187 -36.775218) (xy 180.102204 -36.688038) (xy 180.098199 -36.60013)
			(xy 179.889912 -36.60013) (xy 179.889912 -39.97198) (xy 193.9958 -39.97198) (xy 193.999871 -39.916358)
			(xy 194.011997 -39.861921) (xy 194.03192 -39.80983) (xy 194.059216 -39.761195) (xy 194.093302 -39.717052)
			(xy 194.133451 -39.678343) (xy 194.178809 -39.645892) (xy 194.228409 -39.620391) (xy 194.281193 -39.602384)
			(xy 194.336036 -39.592254) (xy 194.39177 -39.590217) (xy 194.447207 -39.596317) (xy 194.501164 -39.610423)
			(xy 194.552493 -39.632235) (xy 194.600099 -39.661289) (xy 194.642967 -39.696964) (xy 194.680184 -39.738501)
			(xy 194.710957 -39.785014) (xy 194.734629 -39.835511) (xy 194.750697 -39.888918) (xy 194.758817 -39.944094)
			(xy 194.759326 -39.97198) (xy 194.758817 -39.999866) (xy 194.750697 -40.055042) (xy 194.734629 -40.108449)
			(xy 194.710957 -40.158946) (xy 194.680184 -40.205459) (xy 194.642967 -40.246996) (xy 194.600099 -40.282671)
			(xy 194.552493 -40.311725) (xy 194.501164 -40.333537) (xy 194.447207 -40.347643) (xy 194.39177 -40.353743)
			(xy 194.336036 -40.351706) (xy 194.281193 -40.341576) (xy 194.228409 -40.323569) (xy 194.178809 -40.298068)
			(xy 194.133451 -40.265617) (xy 194.093302 -40.226908) (xy 194.059216 -40.182765) (xy 194.03192 -40.13413)
			(xy 194.011997 -40.082039) (xy 193.999871 -40.027602) (xy 193.9958 -39.97198) (xy 179.889912 -39.97198)
			(xy 179.889912 -40.452802) (xy 179.890928 -40.462454) (xy 179.892556 -40.469698) (xy 179.899397 -40.482867)
			(xy 179.90439 -40.488362) (xy 180.124608 -40.70858) (xy 180.130105 -40.713571) (xy 180.14327 -40.720422)
			(xy 180.150516 -40.722042) (xy 180.160168 -40.723058) (xy 189.181486 -40.723058) (xy 189.191548 -40.723498)
			(xy 189.210124 -40.731241) (xy 189.217554 -40.738044) (xy 190.158624 -41.679114) (xy 190.165476 -41.68651)
			(xy 190.173218 -41.705109) (xy 190.17361 -41.715182) (xy 190.17361 -43.85691) (xy 192.81978 -43.85691)
			(xy 192.823851 -43.801288) (xy 192.835977 -43.746851) (xy 192.8559 -43.69476) (xy 192.883196 -43.646125)
			(xy 192.917282 -43.601982) (xy 192.957431 -43.563273) (xy 193.002789 -43.530822) (xy 193.052389 -43.505321)
			(xy 193.105173 -43.487314) (xy 193.160016 -43.477184) (xy 193.21575 -43.475147) (xy 193.271187 -43.481247)
			(xy 193.325144 -43.495353) (xy 193.376473 -43.517165) (xy 193.424079 -43.546219) (xy 193.466947 -43.581894)
			(xy 193.504164 -43.623431) (xy 193.534937 -43.669944) (xy 193.558609 -43.720441) (xy 193.574677 -43.773848)
			(xy 193.582797 -43.829024) (xy 193.583306 -43.85691) (xy 193.582797 -43.884796) (xy 193.574677 -43.939972)
			(xy 193.558609 -43.993379) (xy 193.534937 -44.043876) (xy 193.504164 -44.090389) (xy 193.466947 -44.131926)
			(xy 193.424079 -44.167601) (xy 193.376473 -44.196655) (xy 193.325144 -44.218467) (xy 193.271187 -44.232573)
			(xy 193.21575 -44.238673) (xy 193.160016 -44.236636) (xy 193.105173 -44.226506) (xy 193.052389 -44.208499)
			(xy 193.002789 -44.182998) (xy 192.957431 -44.150547) (xy 192.917282 -44.111838) (xy 192.883196 -44.067695)
			(xy 192.8559 -44.01906) (xy 192.835977 -43.966969) (xy 192.823851 -43.912532) (xy 192.81978 -43.85691)
			(xy 190.17361 -43.85691) (xy 190.17361 -45.35424) (xy 192.803778 -45.35424) (xy 192.807849 -45.298618)
			(xy 192.819975 -45.244181) (xy 192.839898 -45.19209) (xy 192.867194 -45.143455) (xy 192.90128 -45.099312)
			(xy 192.941429 -45.060603) (xy 192.986787 -45.028152) (xy 193.036387 -45.002651) (xy 193.089171 -44.984644)
			(xy 193.144014 -44.974514) (xy 193.199748 -44.972477) (xy 193.255185 -44.978577) (xy 193.309142 -44.992683)
			(xy 193.360471 -45.014495) (xy 193.408077 -45.043549) (xy 193.450945 -45.079224) (xy 193.488162 -45.120761)
			(xy 193.518935 -45.167274) (xy 193.542607 -45.217771) (xy 193.558675 -45.271178) (xy 193.566795 -45.326354)
			(xy 193.567304 -45.35424) (xy 193.566795 -45.382126) (xy 193.558675 -45.437302) (xy 193.542607 -45.490709)
			(xy 193.518935 -45.541206) (xy 193.488162 -45.587719) (xy 193.450945 -45.629256) (xy 193.408077 -45.664931)
			(xy 193.360471 -45.693985) (xy 193.309142 -45.715797) (xy 193.255185 -45.729903) (xy 193.199748 -45.736003)
			(xy 193.144014 -45.733966) (xy 193.089171 -45.723836) (xy 193.036387 -45.705829) (xy 192.986787 -45.680328)
			(xy 192.941429 -45.647877) (xy 192.90128 -45.609168) (xy 192.867194 -45.565025) (xy 192.839898 -45.51639)
			(xy 192.819975 -45.464299) (xy 192.807849 -45.409862) (xy 192.803778 -45.35424) (xy 190.17361 -45.35424)
			(xy 190.17361 -46.693836) (xy 192.776348 -46.693836) (xy 192.776834 -46.666585) (xy 192.78459 -46.612637)
			(xy 192.799945 -46.560342) (xy 192.822587 -46.510765) (xy 192.852053 -46.464915) (xy 192.887744 -46.423724)
			(xy 192.928935 -46.388033) (xy 192.974785 -46.358567) (xy 193.024362 -46.335925) (xy 193.076657 -46.32057)
			(xy 193.130605 -46.312814) (xy 193.185107 -46.312814) (xy 193.239055 -46.32057) (xy 193.29135 -46.335925)
			(xy 193.340927 -46.358567) (xy 193.386777 -46.388033) (xy 193.427968 -46.423724) (xy 193.463659 -46.464915)
			(xy 193.493125 -46.510765) (xy 193.515767 -46.560342) (xy 193.531122 -46.612637) (xy 193.538878 -46.666585)
			(xy 193.539364 -46.693836) (xy 193.538896 -46.720264) (xy 193.531586 -46.772611) (xy 193.517111 -46.823446)
			(xy 193.49575 -46.871793) (xy 193.482214 -46.894496) (xy 193.48196 -46.89475) (xy 193.476623 -46.904768)
			(xy 193.474365 -46.927318) (xy 193.477642 -46.938184) (xy 193.503804 -47.01286) (xy 193.508165 -47.023388)
			(xy 193.524269 -47.039471) (xy 193.534792 -47.043848) (xy 193.535046 -47.043848) (xy 193.559555 -47.052918)
			(xy 193.606007 -47.07686) (xy 193.648759 -47.106916) (xy 193.687011 -47.142523) (xy 193.720048 -47.183016)
			(xy 193.747251 -47.227637) (xy 193.768113 -47.275552) (xy 193.782243 -47.325866) (xy 193.789377 -47.377636)
			(xy 193.789808 -47.403766) (xy 193.789322 -47.431017) (xy 193.781566 -47.484965) (xy 193.766211 -47.53726)
			(xy 193.743569 -47.586837) (xy 193.714103 -47.632687) (xy 193.678412 -47.673878) (xy 193.637221 -47.709569)
			(xy 193.591371 -47.739035) (xy 193.541794 -47.761677) (xy 193.489499 -47.777032) (xy 193.435551 -47.784788)
			(xy 193.381049 -47.784788) (xy 193.327101 -47.777032) (xy 193.274806 -47.761677) (xy 193.225229 -47.739035)
			(xy 193.179379 -47.709569) (xy 193.138188 -47.673878) (xy 193.102497 -47.632687) (xy 193.073031 -47.586837)
			(xy 193.050389 -47.53726) (xy 193.035034 -47.484965) (xy 193.027278 -47.431017) (xy 193.026792 -47.403766)
			(xy 193.027267 -47.377339) (xy 193.034576 -47.324991) (xy 193.049049 -47.274156) (xy 193.070408 -47.225809)
			(xy 193.083942 -47.203106) (xy 193.084196 -47.202852) (xy 193.089531 -47.192834) (xy 193.091788 -47.170284)
			(xy 193.088514 -47.159418) (xy 193.062352 -47.084742) (xy 193.057965 -47.074228) (xy 193.041879 -47.058139)
			(xy 193.031364 -47.053754) (xy 193.03111 -47.053754) (xy 193.006593 -47.044708) (xy 192.960141 -47.02076)
			(xy 192.917391 -46.9907) (xy 192.87914 -46.955089) (xy 192.846105 -46.914594) (xy 192.818903 -46.86997)
			(xy 192.798042 -46.822053) (xy 192.783913 -46.771738) (xy 192.776779 -46.719966) (xy 192.776348 -46.693836)
			(xy 190.17361 -46.693836) (xy 190.17361 -48.30699) (xy 192.653918 -48.30699) (xy 192.657989 -48.251368)
			(xy 192.670115 -48.196931) (xy 192.690038 -48.14484) (xy 192.717334 -48.096205) (xy 192.75142 -48.052062)
			(xy 192.791569 -48.013353) (xy 192.836927 -47.980902) (xy 192.886527 -47.955401) (xy 192.939311 -47.937394)
			(xy 192.994154 -47.927264) (xy 193.049888 -47.925227) (xy 193.105325 -47.931327) (xy 193.159282 -47.945433)
			(xy 193.210611 -47.967245) (xy 193.258217 -47.996299) (xy 193.301085 -48.031974) (xy 193.338302 -48.073511)
			(xy 193.369075 -48.120024) (xy 193.392747 -48.170521) (xy 193.408815 -48.223928) (xy 193.416935 -48.279104)
			(xy 193.417444 -48.30699) (xy 193.416935 -48.334876) (xy 193.408815 -48.390052) (xy 193.392747 -48.443459)
			(xy 193.369075 -48.493956) (xy 193.338302 -48.540469) (xy 193.301085 -48.582006) (xy 193.258217 -48.617681)
			(xy 193.210611 -48.646735) (xy 193.159282 -48.668547) (xy 193.105325 -48.682653) (xy 193.049888 -48.688753)
			(xy 192.994154 -48.686716) (xy 192.939311 -48.676586) (xy 192.886527 -48.658579) (xy 192.836927 -48.633078)
			(xy 192.791569 -48.600627) (xy 192.75142 -48.561918) (xy 192.717334 -48.517775) (xy 192.690038 -48.46914)
			(xy 192.670115 -48.417049) (xy 192.657989 -48.362612) (xy 192.653918 -48.30699) (xy 190.17361 -48.30699)
			(xy 190.17361 -48.8442) (xy 190.2874 -48.8442) (xy 190.291471 -48.788578) (xy 190.303597 -48.734141)
			(xy 190.32352 -48.68205) (xy 190.350816 -48.633415) (xy 190.384902 -48.589272) (xy 190.425051 -48.550563)
			(xy 190.470409 -48.518112) (xy 190.520009 -48.492611) (xy 190.572793 -48.474604) (xy 190.627636 -48.464474)
			(xy 190.68337 -48.462437) (xy 190.738807 -48.468537) (xy 190.792764 -48.482643) (xy 190.844093 -48.504455)
			(xy 190.891699 -48.533509) (xy 190.934567 -48.569184) (xy 190.971784 -48.610721) (xy 191.002557 -48.657234)
			(xy 191.026229 -48.707731) (xy 191.042297 -48.761138) (xy 191.050417 -48.816314) (xy 191.050926 -48.8442)
			(xy 191.050417 -48.872086) (xy 191.047419 -48.89246) (xy 191.314068 -48.89246) (xy 191.318139 -48.836838)
			(xy 191.330265 -48.782401) (xy 191.350188 -48.73031) (xy 191.377484 -48.681675) (xy 191.41157 -48.637532)
			(xy 191.451719 -48.598823) (xy 191.497077 -48.566372) (xy 191.546677 -48.540871) (xy 191.599461 -48.522864)
			(xy 191.654304 -48.512734) (xy 191.710038 -48.510697) (xy 191.765475 -48.516797) (xy 191.819432 -48.530903)
			(xy 191.870761 -48.552715) (xy 191.918367 -48.581769) (xy 191.961235 -48.617444) (xy 191.998452 -48.658981)
			(xy 192.029225 -48.705494) (xy 192.052897 -48.755991) (xy 192.068965 -48.809398) (xy 192.077085 -48.864574)
			(xy 192.077594 -48.89246) (xy 192.077085 -48.920346) (xy 192.068965 -48.975522) (xy 192.052897 -49.028929)
			(xy 192.029225 -49.079426) (xy 191.998452 -49.125939) (xy 191.961235 -49.167476) (xy 191.918367 -49.203151)
			(xy 191.870761 -49.232205) (xy 191.819432 -49.254017) (xy 191.765475 -49.268123) (xy 191.710038 -49.274223)
			(xy 191.654304 -49.272186) (xy 191.599461 -49.262056) (xy 191.546677 -49.244049) (xy 191.497077 -49.218548)
			(xy 191.451719 -49.186097) (xy 191.41157 -49.147388) (xy 191.377484 -49.103245) (xy 191.350188 -49.05461)
			(xy 191.330265 -49.002519) (xy 191.318139 -48.948082) (xy 191.314068 -48.89246) (xy 191.047419 -48.89246)
			(xy 191.042297 -48.927262) (xy 191.026229 -48.980669) (xy 191.002557 -49.031166) (xy 190.971784 -49.077679)
			(xy 190.934567 -49.119216) (xy 190.891699 -49.154891) (xy 190.844093 -49.183945) (xy 190.792764 -49.205757)
			(xy 190.738807 -49.219863) (xy 190.68337 -49.225963) (xy 190.627636 -49.223926) (xy 190.572793 -49.213796)
			(xy 190.520009 -49.195789) (xy 190.470409 -49.170288) (xy 190.425051 -49.137837) (xy 190.384902 -49.099128)
			(xy 190.350816 -49.054985) (xy 190.32352 -49.00635) (xy 190.303597 -48.954259) (xy 190.291471 -48.899822)
			(xy 190.2874 -48.8442) (xy 190.17361 -48.8442) (xy 190.17361 -50.462434) (xy 190.92621 -50.462434)
			(xy 190.930281 -50.406812) (xy 190.942407 -50.352375) (xy 190.96233 -50.300284) (xy 190.989626 -50.251649)
			(xy 191.023712 -50.207506) (xy 191.063861 -50.168797) (xy 191.109219 -50.136346) (xy 191.158819 -50.110845)
			(xy 191.211603 -50.092838) (xy 191.266446 -50.082708) (xy 191.32218 -50.080671) (xy 191.377617 -50.086771)
			(xy 191.431574 -50.100877) (xy 191.482903 -50.122689) (xy 191.530509 -50.151743) (xy 191.573377 -50.187418)
			(xy 191.610594 -50.228955) (xy 191.641367 -50.275468) (xy 191.665039 -50.325965) (xy 191.681107 -50.379372)
			(xy 191.689227 -50.434548) (xy 191.689736 -50.462434) (xy 191.689227 -50.49032) (xy 191.681107 -50.545496)
			(xy 191.665039 -50.598903) (xy 191.641367 -50.6494) (xy 191.610594 -50.695913) (xy 191.573377 -50.73745)
			(xy 191.530509 -50.773125) (xy 191.482903 -50.802179) (xy 191.431574 -50.823991) (xy 191.377617 -50.838097)
			(xy 191.32218 -50.844197) (xy 191.266446 -50.84216) (xy 191.211603 -50.83203) (xy 191.158819 -50.814023)
			(xy 191.109219 -50.788522) (xy 191.063861 -50.756071) (xy 191.023712 -50.717362) (xy 190.989626 -50.673219)
			(xy 190.96233 -50.624584) (xy 190.942407 -50.572493) (xy 190.930281 -50.518056) (xy 190.92621 -50.462434)
			(xy 190.17361 -50.462434) (xy 190.17361 -51.198018) (xy 190.173801 -51.203963) (xy 190.176628 -51.215514)
			(xy 190.179198 -51.220878) (xy 190.181484 -51.225704) (xy 190.186818 -51.232308) (xy 190.333376 -51.378866)
			(xy 190.338875 -51.383854) (xy 190.352041 -51.390701) (xy 190.359284 -51.392328) (xy 190.368936 -51.393344)
		)
		(stroke
			(width 0)
			(type solid)
		)
		(fill yes)
		(layer "In9.Cu")
		(net "GND")
	)
	(gr_poly
		(pts
			(xy 20.69465 -70.0913) (xy 20.704716 -70.090868) (xy 20.723307 -70.08314) (xy 20.730718 -70.076314)
			(xy 20.840446 -69.966586) (xy 20.840954 -69.966078) (xy 20.847541 -69.958698) (xy 20.855002 -69.940399)
			(xy 20.855432 -69.930518) (xy 20.855432 -67.91579) (xy 20.855035 -67.906269) (xy 20.848076 -67.888543)
			(xy 20.835124 -67.874584) (xy 20.82673 -67.87007) (xy 20.730972 -67.823842) (xy 20.70227 -67.827144)
			(xy 20.690586 -67.836288) (xy 20.670275 -67.851904) (xy 20.626262 -67.878129) (xy 20.579133 -67.898224)
			(xy 20.529738 -67.911828) (xy 20.478967 -67.918695) (xy 20.45335 -67.919092) (xy 20.426098 -67.918606)
			(xy 20.37215 -67.91085) (xy 20.319855 -67.895494) (xy 20.270277 -67.872853) (xy 20.224426 -67.843386)
			(xy 20.183236 -67.807694) (xy 20.147544 -67.766504) (xy 20.118077 -67.720653) (xy 20.095436 -67.671075)
			(xy 20.08008 -67.61878) (xy 20.072324 -67.564832) (xy 20.072324 -67.510328) (xy 20.08008 -67.45638)
			(xy 20.095436 -67.404085) (xy 20.118077 -67.354507) (xy 20.147544 -67.308656) (xy 20.183236 -67.267466)
			(xy 20.224426 -67.231774) (xy 20.270277 -67.202307) (xy 20.319855 -67.179666) (xy 20.37215 -67.16431)
			(xy 20.426098 -67.156554) (xy 20.45335 -67.156076) (xy 20.478967 -67.156488) (xy 20.529741 -67.163343)
			(xy 20.57914 -67.176937) (xy 20.626272 -67.197025) (xy 20.67029 -67.223245) (xy 20.690586 -67.23888)
			(xy 20.70227 -67.248024) (xy 20.730972 -67.251326) (xy 20.82673 -67.205098) (xy 20.835135 -67.2006)
			(xy 20.848087 -67.186631) (xy 20.855057 -67.168902) (xy 20.855432 -67.159378) (xy 20.855432 -65.506854)
			(xy 20.841716 -65.483486) (xy 20.830286 -65.476628) (xy 20.829778 -65.476628) (xy 20.756626 -65.433702)
			(xy 20.752235 -65.431316) (xy 20.742769 -65.428113) (xy 20.73783 -65.427352) (xy 20.727416 -65.426082)
			(xy 20.703794 -65.432432) (xy 20.698206 -65.43548) (xy 20.66992 -65.450255) (xy 20.609644 -65.471197)
			(xy 20.546723 -65.481818) (xy 20.514818 -65.48247) (xy 20.514564 -65.48247) (xy 20.487311 -65.482007)
			(xy 20.433359 -65.47425) (xy 20.381061 -65.458895) (xy 20.33148 -65.436252) (xy 20.285626 -65.406784)
			(xy 20.244432 -65.37109) (xy 20.208738 -65.329897) (xy 20.17927 -65.284044) (xy 20.156627 -65.234463)
			(xy 20.14127 -65.182165) (xy 20.133513 -65.128213) (xy 20.133513 -65.073707) (xy 20.14127 -65.019755)
			(xy 20.156627 -64.967457) (xy 20.17927 -64.917876) (xy 20.208738 -64.872023) (xy 20.244432 -64.83083)
			(xy 20.285626 -64.795136) (xy 20.33148 -64.765668) (xy 20.381061 -64.743025) (xy 20.433359 -64.72767)
			(xy 20.487311 -64.719913) (xy 20.514564 -64.719454) (xy 20.514818 -64.719454) (xy 20.546721 -64.720119)
			(xy 20.609637 -64.730756) (xy 20.669916 -64.751681) (xy 20.698206 -64.766444) (xy 20.703794 -64.769492)
			(xy 20.71751 -64.773302) (xy 20.722495 -64.774511) (xy 20.732733 -64.775151) (xy 20.73783 -64.774572)
			(xy 20.747736 -64.773302) (xy 20.830032 -64.725296) (xy 20.830794 -64.724788) (xy 20.838078 -64.719977)
			(xy 20.849135 -64.706485) (xy 20.855047 -64.690074) (xy 20.855432 -64.681354) (xy 20.855432 -52.63261)
			(xy 20.854924 -52.626006) (xy 20.853654 -52.615592) (xy 20.852892 -52.612798) (xy 20.84718 -52.589272)
			(xy 20.841069 -52.541247) (xy 20.8407 -52.51704) (xy 20.8407 -52.499514) (xy 20.840954 -52.49418)
			(xy 20.842732 -52.477162) (xy 20.844002 -52.46624) (xy 20.846288 -52.44973) (xy 20.847304 -52.444904)
			(xy 20.847304 -52.44465) (xy 20.851368 -52.427378) (xy 20.852638 -52.422552) (xy 20.852638 -52.421536)
			(xy 20.853654 -52.418234) (xy 20.855432 -52.41163) (xy 20.855432 -51.580034) (xy 20.855868 -51.56997)
			(xy 20.863603 -51.551386) (xy 20.870418 -51.543966) (xy 21.027136 -51.387248) (xy 21.034534 -51.380402)
			(xy 21.053133 -51.372673) (xy 21.063204 -51.372262) (xy 21.695918 -51.372262) (xy 21.7043 -51.3715)
			(xy 21.711905 -51.369985) (xy 21.725738 -51.362998) (xy 21.731478 -51.357784) (xy 21.804376 -51.284886)
			(xy 21.811223 -51.277488) (xy 21.818956 -51.25889) (xy 21.819362 -51.248818) (xy 21.819362 -51.204114)
			(xy 21.819108 -51.198526) (xy 21.819108 -49.20615) (xy 21.818512 -49.193825) (xy 21.807058 -49.172)
			(xy 21.797264 -49.164494) (xy 21.733764 -49.120044) (xy 21.727263 -49.115866) (xy 21.71253 -49.111223)
			(xy 21.704808 -49.1109) (xy 21.68271 -49.1109) (xy 21.674836 -49.113694) (xy 21.644652 -49.123452)
			(xy 21.582092 -49.13393) (xy 21.550376 -49.134522) (xy 21.546312 -49.134522) (xy 21.519254 -49.133759)
			(xy 21.465752 -49.125533) (xy 21.413952 -49.109825) (xy 21.364891 -49.086953) (xy 21.319558 -49.057375)
			(xy 21.27886 -49.021684) (xy 21.243618 -48.980599) (xy 21.214537 -48.934944) (xy 21.192203 -48.885637)
			(xy 21.177063 -48.833667) (xy 21.169423 -48.780079) (xy 21.168868 -48.753014) (xy 21.169353 -48.725761)
			(xy 21.177108 -48.671811) (xy 21.192461 -48.619513) (xy 21.215101 -48.569933) (xy 21.244567 -48.524079)
			(xy 21.280258 -48.482885) (xy 21.321448 -48.44719) (xy 21.367299 -48.41772) (xy 21.416877 -48.395075)
			(xy 21.469174 -48.379716) (xy 21.523124 -48.371956) (xy 21.550376 -48.371506) (xy 21.551138 -48.371506)
			(xy 21.584754 -48.37226) (xy 21.65093 -48.384144) (xy 21.68271 -48.395128) (xy 21.694394 -48.399446)
			(xy 21.719032 -48.396398) (xy 21.797264 -48.341534) (xy 21.806932 -48.333921) (xy 21.818337 -48.31216)
			(xy 21.819108 -48.299878) (xy 21.819108 -41.95445) (xy 21.818676 -41.944384) (xy 21.81095 -41.925791)
			(xy 21.804122 -41.918382) (xy 20.923758 -41.038018) (xy 20.916646 -41.030652) (xy 20.89785 -41.023032)
			(xy 19.116294 -41.023032) (xy 19.107592 -41.023383) (xy 19.091188 -41.029197) (xy 19.077667 -41.040156)
			(xy 19.07286 -41.047416) (xy 19.027902 -41.121584) (xy 19.023838 -41.13022) (xy 19.020512 -41.140526)
			(xy 19.021944 -41.162115) (xy 19.026632 -41.171876) (xy 19.027394 -41.1734) (xy 19.031712 -41.18229)
			(xy 19.043791 -41.20826) (xy 19.060904 -41.262918) (xy 19.069675 -41.319517) (xy 19.07032 -41.348152)
			(xy 19.07032 -41.34866) (xy 19.07032 -41.35501) (xy 19.069409 -41.383073) (xy 19.060363 -41.438486)
			(xy 19.043292 -41.491975) (xy 19.018564 -41.542384) (xy 18.986714 -41.588623) (xy 18.967958 -41.609518)
			(xy 18.967704 -41.609772) (xy 18.961232 -41.617127) (xy 18.953934 -41.635289) (xy 18.95348 -41.645078)
			(xy 18.95348 -41.724072) (xy 18.960338 -41.741852) (xy 18.967196 -41.748964) (xy 18.986464 -41.770291)
			(xy 19.019025 -41.817654) (xy 19.044112 -41.869365) (xy 19.061158 -41.924254) (xy 19.069777 -41.981079)
			(xy 19.069775 -42.038554) (xy 19.061151 -42.095378) (xy 19.0441 -42.150265) (xy 19.019008 -42.201974)
			(xy 18.986444 -42.249334) (xy 18.967196 -42.27068) (xy 18.960338 -42.277792) (xy 18.95348 -42.295572)
			(xy 18.95348 -42.384472) (xy 18.960338 -42.402252) (xy 18.967196 -42.409364) (xy 18.986465 -42.430692)
			(xy 19.019025 -42.478055) (xy 19.044113 -42.529767) (xy 19.061159 -42.584658) (xy 19.069778 -42.641484)
			(xy 19.07032 -42.670222) (xy 19.069847 -42.697592) (xy 19.062021 -42.751769) (xy 19.046532 -42.804271)
			(xy 19.023699 -42.854021) (xy 18.99399 -42.899997) (xy 18.97634 -42.92092) (xy 18.970244 -42.928032)
			(xy 18.963894 -42.944796) (xy 18.963894 -43.030648) (xy 18.970244 -43.047412) (xy 18.97634 -43.054524)
			(xy 18.993983 -43.075455) (xy 19.023711 -43.12142) (xy 19.046555 -43.171167) (xy 19.062044 -43.223671)
			(xy 19.069861 -43.277851) (xy 19.07032 -43.305222) (xy 19.069834 -43.332473) (xy 19.062078 -43.386421)
			(xy 19.046723 -43.438716) (xy 19.024081 -43.488293) (xy 18.994615 -43.534143) (xy 18.958924 -43.575334)
			(xy 18.917733 -43.611025) (xy 18.871883 -43.640491) (xy 18.822306 -43.663133) (xy 18.770011 -43.678488)
			(xy 18.716063 -43.686244) (xy 18.661561 -43.686244) (xy 18.607613 -43.678488) (xy 18.555318 -43.663133)
			(xy 18.505741 -43.640491) (xy 18.459891 -43.611025) (xy 18.4187 -43.575334) (xy 18.383009 -43.534143)
			(xy 18.353543 -43.488293) (xy 18.330901 -43.438716) (xy 18.315546 -43.386421) (xy 18.30779 -43.332473)
			(xy 18.307304 -43.305222) (xy 18.307781 -43.277854) (xy 18.315615 -43.223681) (xy 18.331111 -43.171184)
			(xy 18.35395 -43.121441) (xy 18.383665 -43.075472) (xy 18.401284 -43.054524) (xy 18.40738 -43.047412)
			(xy 18.41373 -43.030648) (xy 18.41373 -42.944796) (xy 18.40738 -42.928032) (xy 18.401284 -42.92092)
			(xy 18.383642 -42.899989) (xy 18.353914 -42.854022) (xy 18.33107 -42.804276) (xy 18.315577 -42.751772)
			(xy 18.307756 -42.697593) (xy 18.307304 -42.670222) (xy 18.307823 -42.641482) (xy 18.316443 -42.584653)
			(xy 18.333491 -42.52976) (xy 18.358581 -42.478046) (xy 18.391145 -42.430681) (xy 18.410428 -42.409364)
			(xy 18.417286 -42.402252) (xy 18.424144 -42.384472) (xy 18.424144 -42.295572) (xy 18.417286 -42.277792)
			(xy 18.410428 -42.27068) (xy 18.391155 -42.249353) (xy 18.358587 -42.20199) (xy 18.333492 -42.150278)
			(xy 18.316438 -42.095385) (xy 18.307813 -42.038556) (xy 18.30781 -41.981076) (xy 18.316431 -41.924246)
			(xy 18.33348 -41.869352) (xy 18.35857 -41.817637) (xy 18.391135 -41.770272) (xy 18.410428 -41.748964)
			(xy 18.417286 -41.741852) (xy 18.424144 -41.724072) (xy 18.424144 -41.635172) (xy 18.417286 -41.617646)
			(xy 18.410428 -41.61028) (xy 18.391628 -41.589486) (xy 18.359699 -41.543413) (xy 18.334845 -41.493168)
			(xy 18.317599 -41.439831) (xy 18.308331 -41.384547) (xy 18.307304 -41.356534) (xy 18.307304 -41.349422)
			(xy 18.307816 -41.320529) (xy 18.316503 -41.263399) (xy 18.333727 -41.20824) (xy 18.345912 -41.182036)
			(xy 18.353278 -41.166542) (xy 18.35634 -41.157735) (xy 18.356606 -41.139107) (xy 18.353786 -41.13022)
			(xy 18.349722 -41.121584) (xy 18.304764 -41.04767) (xy 18.297906 -41.035986) (xy 18.274792 -41.023032)
			(xy 17.354296 -41.023032) (xy 17.342678 -41.023611) (xy 17.321795 -41.033808) (xy 17.314164 -41.04259)
			(xy 17.257522 -41.11498) (xy 17.252696 -41.137586) (xy 17.25549 -41.14927) (xy 17.260812 -41.171949)
			(xy 17.266542 -41.21818) (xy 17.26692 -41.241472) (xy 17.266459 -41.268727) (xy 17.258705 -41.322681)
			(xy 17.243352 -41.374983) (xy 17.220711 -41.424568) (xy 17.191244 -41.470425) (xy 17.155551 -41.511622)
			(xy 17.114357 -41.54732) (xy 17.068503 -41.576792) (xy 17.018921 -41.599438) (xy 16.96662 -41.614797)
			(xy 16.912666 -41.622556) (xy 16.885412 -41.62298) (xy 16.856673 -41.62246) (xy 16.799844 -41.613838)
			(xy 16.744953 -41.596789) (xy 16.69324 -41.571697) (xy 16.645877 -41.539131) (xy 16.624554 -41.519856)
			(xy 16.617442 -41.512998) (xy 16.599662 -41.50614) (xy 16.510762 -41.50614) (xy 16.492982 -41.512998)
			(xy 16.48587 -41.519856) (xy 16.464542 -41.539124) (xy 16.417178 -41.571684) (xy 16.365466 -41.596772)
			(xy 16.310576 -41.61382) (xy 16.25375 -41.622442) (xy 16.225012 -41.62298) (xy 16.197759 -41.622517)
			(xy 16.143809 -41.614762) (xy 16.091511 -41.599406) (xy 16.041931 -41.576764) (xy 15.996078 -41.547296)
			(xy 15.954887 -41.511602) (xy 15.919194 -41.470409) (xy 15.889728 -41.424555) (xy 15.867088 -41.374974)
			(xy 15.851735 -41.322676) (xy 15.843981 -41.268725) (xy 15.843504 -41.241472) (xy 15.843884 -41.21818)
			(xy 15.849614 -41.171949) (xy 15.854934 -41.14927) (xy 15.857728 -41.137586) (xy 15.852902 -41.11498)
			(xy 15.79626 -41.04259) (xy 15.788672 -41.033755) (xy 15.767762 -41.023558) (xy 15.756128 -41.023032)
			(xy 11.908536 -41.023032) (xy 11.898472 -41.023467) (xy 11.879887 -41.031202) (xy 11.872468 -41.038018)
			(xy 11.854942 -41.055544) (xy 11.849005 -41.061933) (xy 11.841467 -41.077648) (xy 11.84021 -41.086278)
			(xy 11.84021 -41.086532) (xy 11.839664 -41.096368) (xy 11.845207 -41.115251) (xy 11.857482 -41.130635)
			(xy 11.865864 -41.135808) (xy 11.866118 -41.136062) (xy 11.891106 -41.150647) (xy 11.936761 -41.186182)
			(xy 11.976529 -41.228203) (xy 12.009497 -41.275746) (xy 12.03491 -41.327721) (xy 12.052185 -41.382937)
			(xy 12.060926 -41.440128) (xy 12.061444 -41.469056) (xy 12.060962 -41.496295) (xy 12.05322 -41.55022)
			(xy 12.037886 -41.602495) (xy 12.015272 -41.652057) (xy 11.985839 -41.697899) (xy 11.950185 -41.739089)
			(xy 11.909034 -41.774789) (xy 11.863225 -41.804272) (xy 11.813687 -41.82694) (xy 11.761428 -41.842331)
			(xy 11.734546 -41.846754) (xy 11.71575 -41.849548) (xy 11.691112 -41.877996) (xy 11.691112 -43.73626)
			(xy 20.213064 -43.73626) (xy 20.217135 -43.680638) (xy 20.229261 -43.626201) (xy 20.249184 -43.57411)
			(xy 20.27648 -43.525475) (xy 20.310566 -43.481332) (xy 20.350715 -43.442623) (xy 20.396073 -43.410172)
			(xy 20.445673 -43.384671) (xy 20.498457 -43.366664) (xy 20.5533 -43.356534) (xy 20.609034 -43.354497)
			(xy 20.664471 -43.360597) (xy 20.718428 -43.374703) (xy 20.769757 -43.396515) (xy 20.817363 -43.425569)
			(xy 20.860231 -43.461244) (xy 20.897448 -43.502781) (xy 20.928221 -43.549294) (xy 20.951893 -43.599791)
			(xy 20.967961 -43.653198) (xy 20.976081 -43.708374) (xy 20.97659 -43.73626) (xy 20.976081 -43.764146)
			(xy 20.967961 -43.819322) (xy 20.951893 -43.872729) (xy 20.928221 -43.923226) (xy 20.897448 -43.969739)
			(xy 20.860231 -44.011276) (xy 20.817363 -44.046951) (xy 20.769757 -44.076005) (xy 20.718428 -44.097817)
			(xy 20.664471 -44.111923) (xy 20.609034 -44.118023) (xy 20.5533 -44.115986) (xy 20.498457 -44.105856)
			(xy 20.445673 -44.087849) (xy 20.396073 -44.062348) (xy 20.350715 -44.029897) (xy 20.310566 -43.991188)
			(xy 20.27648 -43.947045) (xy 20.249184 -43.89841) (xy 20.229261 -43.846319) (xy 20.217135 -43.791882)
			(xy 20.213064 -43.73626) (xy 11.691112 -43.73626) (xy 11.691112 -45.114464) (xy 20.06549 -45.114464)
			(xy 20.069561 -45.058842) (xy 20.081687 -45.004405) (xy 20.10161 -44.952314) (xy 20.128906 -44.903679)
			(xy 20.162992 -44.859536) (xy 20.203141 -44.820827) (xy 20.248499 -44.788376) (xy 20.298099 -44.762875)
			(xy 20.350883 -44.744868) (xy 20.405726 -44.734738) (xy 20.46146 -44.732701) (xy 20.516897 -44.738801)
			(xy 20.570854 -44.752907) (xy 20.622183 -44.774719) (xy 20.669789 -44.803773) (xy 20.712657 -44.839448)
			(xy 20.749874 -44.880985) (xy 20.780647 -44.927498) (xy 20.804319 -44.977995) (xy 20.820387 -45.031402)
			(xy 20.828507 -45.086578) (xy 20.829016 -45.114464) (xy 20.828507 -45.14235) (xy 20.820387 -45.197526)
			(xy 20.804319 -45.250933) (xy 20.780647 -45.30143) (xy 20.749874 -45.347943) (xy 20.712657 -45.38948)
			(xy 20.669789 -45.425155) (xy 20.622183 -45.454209) (xy 20.570854 -45.476021) (xy 20.516897 -45.490127)
			(xy 20.46146 -45.496227) (xy 20.405726 -45.49419) (xy 20.350883 -45.48406) (xy 20.298099 -45.466053)
			(xy 20.248499 -45.440552) (xy 20.203141 -45.408101) (xy 20.162992 -45.369392) (xy 20.128906 -45.325249)
			(xy 20.10161 -45.276614) (xy 20.081687 -45.224523) (xy 20.069561 -45.170086) (xy 20.06549 -45.114464)
			(xy 11.691112 -45.114464) (xy 11.691112 -45.926248) (xy 11.930886 -45.926248) (xy 11.934957 -45.870626)
			(xy 11.947083 -45.816189) (xy 11.967006 -45.764098) (xy 11.994302 -45.715463) (xy 12.028388 -45.67132)
			(xy 12.068537 -45.632611) (xy 12.113895 -45.60016) (xy 12.163495 -45.574659) (xy 12.216279 -45.556652)
			(xy 12.271122 -45.546522) (xy 12.326856 -45.544485) (xy 12.382293 -45.550585) (xy 12.43625 -45.564691)
			(xy 12.487579 -45.586503) (xy 12.535185 -45.615557) (xy 12.578053 -45.651232) (xy 12.61527 -45.692769)
			(xy 12.646043 -45.739282) (xy 12.669715 -45.789779) (xy 12.685783 -45.843186) (xy 12.693903 -45.898362)
			(xy 12.694412 -45.926248) (xy 12.693903 -45.954134) (xy 12.685783 -46.00931) (xy 12.669715 -46.062717)
			(xy 12.646043 -46.113214) (xy 12.61527 -46.159727) (xy 12.578053 -46.201264) (xy 12.535185 -46.236939)
			(xy 12.487579 -46.265993) (xy 12.43625 -46.287805) (xy 12.382293 -46.301911) (xy 12.326856 -46.308011)
			(xy 12.271122 -46.305974) (xy 12.216279 -46.295844) (xy 12.163495 -46.277837) (xy 12.113895 -46.252336)
			(xy 12.068537 -46.219885) (xy 12.028388 -46.181176) (xy 11.994302 -46.137033) (xy 11.967006 -46.088398)
			(xy 11.947083 -46.036307) (xy 11.934957 -45.98187) (xy 11.930886 -45.926248) (xy 11.691112 -45.926248)
			(xy 11.691112 -46.893226) (xy 20.33727 -46.893226) (xy 20.341341 -46.837604) (xy 20.353467 -46.783167)
			(xy 20.37339 -46.731076) (xy 20.400686 -46.682441) (xy 20.434772 -46.638298) (xy 20.474921 -46.599589)
			(xy 20.520279 -46.567138) (xy 20.569879 -46.541637) (xy 20.622663 -46.52363) (xy 20.677506 -46.5135)
			(xy 20.73324 -46.511463) (xy 20.788677 -46.517563) (xy 20.842634 -46.531669) (xy 20.893963 -46.553481)
			(xy 20.941569 -46.582535) (xy 20.984437 -46.61821) (xy 21.021654 -46.659747) (xy 21.052427 -46.70626)
			(xy 21.076099 -46.756757) (xy 21.092167 -46.810164) (xy 21.100287 -46.86534) (xy 21.100796 -46.893226)
			(xy 21.100287 -46.921112) (xy 21.092167 -46.976288) (xy 21.076099 -47.029695) (xy 21.052427 -47.080192)
			(xy 21.021654 -47.126705) (xy 20.984437 -47.168242) (xy 20.941569 -47.203917) (xy 20.893963 -47.232971)
			(xy 20.842634 -47.254783) (xy 20.788677 -47.268889) (xy 20.73324 -47.274989) (xy 20.677506 -47.272952)
			(xy 20.622663 -47.262822) (xy 20.569879 -47.244815) (xy 20.520279 -47.219314) (xy 20.474921 -47.186863)
			(xy 20.434772 -47.148154) (xy 20.400686 -47.104011) (xy 20.37339 -47.055376) (xy 20.353467 -47.003285)
			(xy 20.341341 -46.948848) (xy 20.33727 -46.893226) (xy 11.691112 -46.893226) (xy 11.691112 -47.936658)
			(xy 18.652998 -47.936658) (xy 18.653484 -47.909407) (xy 18.66124 -47.855459) (xy 18.676595 -47.803164)
			(xy 18.699237 -47.753587) (xy 18.728703 -47.707737) (xy 18.764394 -47.666546) (xy 18.805585 -47.630855)
			(xy 18.851435 -47.601389) (xy 18.901012 -47.578747) (xy 18.953307 -47.563392) (xy 19.007255 -47.555636)
			(xy 19.061757 -47.555636) (xy 19.115705 -47.563392) (xy 19.168 -47.578747) (xy 19.217577 -47.601389)
			(xy 19.263427 -47.630855) (xy 19.304618 -47.666546) (xy 19.340309 -47.707737) (xy 19.369775 -47.753587)
			(xy 19.392417 -47.803164) (xy 19.407772 -47.855459) (xy 19.415528 -47.909407) (xy 19.416014 -47.936658)
			(xy 19.415568 -47.962999) (xy 19.408317 -48.015181) (xy 19.393961 -48.065871) (xy 19.372772 -48.114105)
			(xy 19.345152 -48.158968) (xy 19.311627 -48.199607) (xy 19.272833 -48.235252) (xy 19.251422 -48.250602)
			(xy 19.239601 -48.2593) (xy 19.221168 -48.282126) (xy 19.209986 -48.30925) (xy 19.206979 -48.338435)
			(xy 19.212394 -48.367269) (xy 19.225785 -48.393374) (xy 19.246046 -48.414593) (xy 19.258534 -48.422306)
			(xy 19.283084 -48.436979) (xy 19.327839 -48.472586) (xy 19.36678 -48.514474) (xy 19.399033 -48.561705)
			(xy 19.423877 -48.61322) (xy 19.440754 -48.667865) (xy 19.449287 -48.724418) (xy 19.449796 -48.753014)
			(xy 19.44931 -48.780265) (xy 19.441554 -48.834213) (xy 19.426199 -48.886508) (xy 19.403557 -48.936085)
			(xy 19.374091 -48.981935) (xy 19.3384 -49.023126) (xy 19.297209 -49.058817) (xy 19.251359 -49.088283)
			(xy 19.201782 -49.110925) (xy 19.149487 -49.12628) (xy 19.095539 -49.134036) (xy 19.041037 -49.134036)
			(xy 18.987089 -49.12628) (xy 18.934794 -49.110925) (xy 18.885217 -49.088283) (xy 18.839367 -49.058817)
			(xy 18.798176 -49.023126) (xy 18.762485 -48.981935) (xy 18.733019 -48.936085) (xy 18.710377 -48.886508)
			(xy 18.695022 -48.834213) (xy 18.687266 -48.780265) (xy 18.68678 -48.753014) (xy 18.687207 -48.726672)
			(xy 18.694462 -48.674489) (xy 18.708822 -48.6238) (xy 18.730014 -48.575566) (xy 18.757636 -48.530703)
			(xy 18.791164 -48.490064) (xy 18.82996 -48.45442) (xy 18.851372 -48.43907) (xy 18.863222 -48.430408)
			(xy 18.881657 -48.407574) (xy 18.892838 -48.380442) (xy 18.895842 -48.351249) (xy 18.890421 -48.322408)
			(xy 18.877022 -48.296299) (xy 18.856752 -48.275078) (xy 18.84426 -48.267366) (xy 18.819741 -48.252645)
			(xy 18.774986 -48.217045) (xy 18.736044 -48.175165) (xy 18.703787 -48.127943) (xy 18.678939 -48.076436)
			(xy 18.662054 -48.021798) (xy 18.653512 -47.965252) (xy 18.652998 -47.936658) (xy 11.691112 -47.936658)
			(xy 11.691112 -58.731404) (xy 13.520674 -58.731404) (xy 13.521124 -58.704033) (xy 13.528943 -58.649853)
			(xy 13.544435 -58.597349) (xy 13.567281 -58.547602) (xy 13.59701 -58.501636) (xy 13.614654 -58.480706)
			(xy 13.62075 -58.473594) (xy 13.6271 -58.456576) (xy 13.6271 -58.371232) (xy 13.62075 -58.354214)
			(xy 13.614654 -58.347102) (xy 13.597016 -58.326167) (xy 13.567289 -58.2802) (xy 13.544442 -58.230454)
			(xy 13.528944 -58.177952) (xy 13.521115 -58.123774) (xy 13.521114 -58.069032) (xy 13.528943 -58.014853)
			(xy 13.54444 -57.962351) (xy 13.567286 -57.912605) (xy 13.597012 -57.866638) (xy 13.614654 -57.845706)
			(xy 13.62075 -57.838594) (xy 13.6271 -57.821576) (xy 13.6271 -57.736232) (xy 13.62075 -57.719214)
			(xy 13.614654 -57.712102) (xy 13.597016 -57.691167) (xy 13.567289 -57.6452) (xy 13.544442 -57.595454)
			(xy 13.528944 -57.542952) (xy 13.521115 -57.488774) (xy 13.521114 -57.434032) (xy 13.528943 -57.379853)
			(xy 13.54444 -57.327351) (xy 13.567286 -57.277605) (xy 13.597012 -57.231638) (xy 13.614654 -57.210706)
			(xy 13.62075 -57.203594) (xy 13.6271 -57.186576) (xy 13.6271 -57.101232) (xy 13.62075 -57.084214)
			(xy 13.614654 -57.077102) (xy 13.597011 -57.056173) (xy 13.567298 -57.0102) (xy 13.544462 -56.960452)
			(xy 13.528972 -56.90795) (xy 13.521146 -56.853774) (xy 13.520674 -56.826404) (xy 13.52116 -56.799153)
			(xy 13.528916 -56.745205) (xy 13.544271 -56.69291) (xy 13.566913 -56.643333) (xy 13.596379 -56.597483)
			(xy 13.63207 -56.556292) (xy 13.673261 -56.520601) (xy 13.719111 -56.491135) (xy 13.768688 -56.468493)
			(xy 13.820983 -56.453138) (xy 13.874931 -56.445382) (xy 13.929433 -56.445382) (xy 13.983381 -56.453138)
			(xy 14.035676 -56.468493) (xy 14.085253 -56.491135) (xy 14.131103 -56.520601) (xy 14.172294 -56.556292)
			(xy 14.207985 -56.597483) (xy 14.237451 -56.643333) (xy 14.260093 -56.69291) (xy 14.275448 -56.745205)
			(xy 14.283204 -56.799153) (xy 14.28369 -56.826404) (xy 14.283229 -56.853774) (xy 14.27541 -56.907954)
			(xy 14.25992 -56.960457) (xy 14.237077 -57.010204) (xy 14.207352 -57.05617) (xy 14.18971 -57.077102)
			(xy 14.183614 -57.084214) (xy 14.177264 -57.101232) (xy 14.177264 -57.186576) (xy 14.183614 -57.203594)
			(xy 14.18971 -57.210706) (xy 14.207353 -57.231636) (xy 14.237075 -57.277605) (xy 14.259918 -57.327352)
			(xy 14.275412 -57.379854) (xy 14.28324 -57.434033) (xy 14.283239 -57.488773) (xy 14.275411 -57.542951)
			(xy 14.259916 -57.595453) (xy 14.237072 -57.6452) (xy 14.207349 -57.691169) (xy 14.18971 -57.712102)
			(xy 14.183614 -57.719214) (xy 14.177264 -57.736232) (xy 14.177264 -57.821576) (xy 14.183614 -57.838594)
			(xy 14.18971 -57.845706) (xy 14.207353 -57.866636) (xy 14.237075 -57.912605) (xy 14.259918 -57.962352)
			(xy 14.275412 -58.014854) (xy 14.28324 -58.069033) (xy 14.283239 -58.123773) (xy 14.275411 -58.177951)
			(xy 14.259916 -58.230453) (xy 14.237072 -58.2802) (xy 14.207349 -58.326169) (xy 14.18971 -58.347102)
			(xy 14.183614 -58.354214) (xy 14.177264 -58.371232) (xy 14.177264 -58.456576) (xy 14.183614 -58.473594)
			(xy 14.18971 -58.480706) (xy 14.207367 -58.501624) (xy 14.237076 -58.547601) (xy 14.259908 -58.597352)
			(xy 14.275395 -58.649856) (xy 14.283218 -58.704034) (xy 14.28369 -58.731404) (xy 14.283204 -58.758655)
			(xy 14.27854 -58.791094) (xy 16.176498 -58.791094) (xy 16.176961 -58.763724) (xy 16.18478 -58.709544)
			(xy 16.200269 -58.657041) (xy 16.223112 -58.607295) (xy 16.252837 -58.561328) (xy 16.270478 -58.540396)
			(xy 16.276574 -58.533284) (xy 16.282924 -58.516266) (xy 16.282924 -58.430922) (xy 16.276574 -58.413904)
			(xy 16.270478 -58.406792) (xy 16.252833 -58.385863) (xy 16.223113 -58.339893) (xy 16.200271 -58.290146)
			(xy 16.184777 -58.237644) (xy 16.17695 -58.183466) (xy 16.176951 -58.128725) (xy 16.184779 -58.074547)
			(xy 16.200274 -58.022045) (xy 16.223117 -57.972299) (xy 16.252839 -57.92633) (xy 16.270478 -57.905396)
			(xy 16.276574 -57.898284) (xy 16.282924 -57.881266) (xy 16.282924 -57.795922) (xy 16.276574 -57.778904)
			(xy 16.270478 -57.771792) (xy 16.252818 -57.750877) (xy 16.22311 -57.704899) (xy 16.200279 -57.655147)
			(xy 16.184792 -57.602643) (xy 16.176969 -57.548464) (xy 16.176498 -57.521094) (xy 16.176968 -57.494779)
			(xy 16.184185 -57.442645) (xy 16.198494 -57.391997) (xy 16.219626 -57.343795) (xy 16.247178 -57.298953)
			(xy 16.280629 -57.258321) (xy 16.299688 -57.24017) (xy 16.307103 -57.23266) (xy 16.31562 -57.213371)
			(xy 16.316198 -57.202832) (xy 16.316198 -57.128156) (xy 16.315653 -57.117608) (xy 16.307129 -57.098312)
			(xy 16.299688 -57.090818) (xy 16.280615 -57.072677) (xy 16.247137 -57.032058) (xy 16.219566 -56.987218)
			(xy 16.198426 -56.939012) (xy 16.18412 -56.888356) (xy 16.17692 -56.836213) (xy 16.176498 -56.809894)
			(xy 16.176984 -56.782643) (xy 16.18474 -56.728695) (xy 16.200095 -56.6764) (xy 16.222737 -56.626823)
			(xy 16.252203 -56.580973) (xy 16.287894 -56.539782) (xy 16.329085 -56.504091) (xy 16.374935 -56.474625)
			(xy 16.424512 -56.451983) (xy 16.476807 -56.436628) (xy 16.530755 -56.428872) (xy 16.585257 -56.428872)
			(xy 16.639205 -56.436628) (xy 16.6915 -56.451983) (xy 16.741077 -56.474625) (xy 16.786927 -56.504091)
			(xy 16.828118 -56.539782) (xy 16.863809 -56.580973) (xy 16.893275 -56.626823) (xy 16.915917 -56.6764)
			(xy 16.931272 -56.728695) (xy 16.939028 -56.782643) (xy 16.939514 -56.809894) (xy 16.939099 -56.836211)
			(xy 16.93187 -56.888347) (xy 16.91755 -56.938995) (xy 16.896408 -56.987197) (xy 16.868846 -57.032038)
			(xy 16.835387 -57.072669) (xy 16.816324 -57.090818) (xy 16.808916 -57.098334) (xy 16.800394 -57.117618)
			(xy 16.799814 -57.128156) (xy 16.799814 -57.202832) (xy 16.800362 -57.21338) (xy 16.808884 -57.232675)
			(xy 16.816324 -57.24017) (xy 16.835374 -57.258334) (xy 16.868858 -57.298947) (xy 16.896434 -57.34378)
			(xy 16.917578 -57.391982) (xy 16.931888 -57.442635) (xy 16.935261 -57.467049) (xy 17.118592 -57.467049)
			(xy 17.118592 -57.412551) (xy 17.126348 -57.358606) (xy 17.141702 -57.306315) (xy 17.164341 -57.25674)
			(xy 17.193805 -57.210893) (xy 17.229493 -57.169704) (xy 17.27068 -57.134014) (xy 17.316526 -57.104549)
			(xy 17.3661 -57.081907) (xy 17.418391 -57.066551) (xy 17.472335 -57.058793) (xy 17.499584 -57.058306)
			(xy 17.525901 -57.058721) (xy 17.578037 -57.065949) (xy 17.628686 -57.080269) (xy 17.676888 -57.101411)
			(xy 17.721729 -57.128973) (xy 17.762359 -57.162433) (xy 17.780508 -57.181496) (xy 17.788025 -57.188902)
			(xy 17.807309 -57.197424) (xy 17.817846 -57.198006) (xy 17.892522 -57.198006) (xy 17.903068 -57.197446)
			(xy 17.922364 -57.188932) (xy 17.92986 -57.181496) (xy 17.948013 -57.162435) (xy 17.98863 -57.128956)
			(xy 18.033467 -57.101383) (xy 18.08167 -57.080241) (xy 18.132324 -57.065933) (xy 18.184466 -57.058729)
			(xy 18.210784 -57.058306) (xy 18.238039 -57.05874) (xy 18.291993 -57.066495) (xy 18.327257 -57.076848)
			(xy 19.138646 -57.076848) (xy 19.139129 -57.049478) (xy 19.146941 -56.995299) (xy 19.162426 -56.942796)
			(xy 19.185264 -56.893049) (xy 19.214986 -56.847082) (xy 19.232626 -56.82615) (xy 19.238722 -56.819038)
			(xy 19.245072 -56.80202) (xy 19.245072 -56.716676) (xy 19.238722 -56.699658) (xy 19.232626 -56.692546)
			(xy 19.214999 -56.671604) (xy 19.185284 -56.625634) (xy 19.162446 -56.575889) (xy 19.146952 -56.523391)
			(xy 19.139121 -56.469217) (xy 19.138646 -56.441848) (xy 19.139132 -56.414597) (xy 19.146888 -56.360649)
			(xy 19.162243 -56.308354) (xy 19.184885 -56.258777) (xy 19.214351 -56.212927) (xy 19.250042 -56.171736)
			(xy 19.291233 -56.136045) (xy 19.337083 -56.106579) (xy 19.38666 -56.083937) (xy 19.438955 -56.068582)
			(xy 19.492903 -56.060826) (xy 19.547405 -56.060826) (xy 19.601353 -56.068582) (xy 19.653648 -56.083937)
			(xy 19.703225 -56.106579) (xy 19.749075 -56.136045) (xy 19.790266 -56.171736) (xy 19.825957 -56.212927)
			(xy 19.855423 -56.258777) (xy 19.878065 -56.308354) (xy 19.89342 -56.360649) (xy 19.901176 -56.414597)
			(xy 19.901662 -56.441848) (xy 19.901175 -56.469218) (xy 19.893363 -56.523396) (xy 19.87788 -56.575899)
			(xy 19.855043 -56.625647) (xy 19.825322 -56.671614) (xy 19.807682 -56.692546) (xy 19.801586 -56.699658)
			(xy 19.795236 -56.716676) (xy 19.795236 -56.80202) (xy 19.801586 -56.819038) (xy 19.807682 -56.82615)
			(xy 19.825308 -56.847092) (xy 19.855023 -56.893062) (xy 19.877861 -56.942807) (xy 19.893355 -56.995305)
			(xy 19.901187 -57.049479) (xy 19.901662 -57.076848) (xy 19.901176 -57.104099) (xy 19.89342 -57.158047)
			(xy 19.878065 -57.210342) (xy 19.855423 -57.259919) (xy 19.825957 -57.305769) (xy 19.790266 -57.34696)
			(xy 19.749075 -57.382651) (xy 19.703225 -57.412117) (xy 19.653648 -57.434759) (xy 19.601353 -57.450114)
			(xy 19.547405 -57.45787) (xy 19.492903 -57.45787) (xy 19.438955 -57.450114) (xy 19.38666 -57.434759)
			(xy 19.337083 -57.412117) (xy 19.291233 -57.382651) (xy 19.250042 -57.34696) (xy 19.214351 -57.305769)
			(xy 19.184885 -57.259919) (xy 19.162243 -57.210342) (xy 19.146888 -57.158047) (xy 19.139132 -57.104099)
			(xy 19.138646 -57.076848) (xy 18.327257 -57.076848) (xy 18.344295 -57.08185) (xy 18.393879 -57.104493)
			(xy 18.439736 -57.133962) (xy 18.480932 -57.169657) (xy 18.516629 -57.210851) (xy 18.546099 -57.256707)
			(xy 18.568744 -57.30629) (xy 18.584101 -57.358591) (xy 18.591859 -57.412545) (xy 18.591859 -57.467055)
			(xy 18.584101 -57.521009) (xy 18.568744 -57.57331) (xy 18.546099 -57.622893) (xy 18.516629 -57.668749)
			(xy 18.480932 -57.709943) (xy 18.439736 -57.745638) (xy 18.393879 -57.775107) (xy 18.344295 -57.79775)
			(xy 18.291993 -57.813105) (xy 18.238039 -57.82086) (xy 18.210784 -57.821322) (xy 18.184469 -57.820852)
			(xy 18.132336 -57.813635) (xy 18.081688 -57.799324) (xy 18.033486 -57.778193) (xy 17.988644 -57.750641)
			(xy 17.948011 -57.717191) (xy 17.92986 -57.698132) (xy 17.922351 -57.690715) (xy 17.903062 -57.682198)
			(xy 17.892522 -57.681622) (xy 17.817846 -57.681622) (xy 17.807297 -57.682156) (xy 17.788001 -57.690687)
			(xy 17.780508 -57.698132) (xy 17.762356 -57.717195) (xy 17.721741 -57.750677) (xy 17.676904 -57.778251)
			(xy 17.6287 -57.799393) (xy 17.578045 -57.8137) (xy 17.525903 -57.820901) (xy 17.499584 -57.821322)
			(xy 17.472335 -57.820807) (xy 17.418391 -57.813049) (xy 17.3661 -57.797693) (xy 17.316526 -57.775051)
			(xy 17.27068 -57.745586) (xy 17.229493 -57.709896) (xy 17.193805 -57.668707) (xy 17.164341 -57.62286)
			(xy 17.141702 -57.573285) (xy 17.126348 -57.520994) (xy 17.118592 -57.467049) (xy 16.935261 -57.467049)
			(xy 16.939091 -57.494776) (xy 16.939514 -57.521094) (xy 16.939041 -57.548464) (xy 16.931224 -57.602643)
			(xy 16.915737 -57.655146) (xy 16.892897 -57.704892) (xy 16.863174 -57.75086) (xy 16.845534 -57.771792)
			(xy 16.839438 -57.778904) (xy 16.833088 -57.795922) (xy 16.833088 -57.881266) (xy 16.839438 -57.898284)
			(xy 16.845534 -57.905396) (xy 16.86317 -57.926333) (xy 16.892898 -57.972299) (xy 16.915747 -58.022044)
			(xy 16.931245 -58.074546) (xy 16.939075 -58.128725) (xy 16.939076 -58.183466) (xy 16.931247 -58.237645)
			(xy 16.91575 -58.290147) (xy 16.892903 -58.339893) (xy 16.863176 -58.38586) (xy 16.845534 -58.406792)
			(xy 16.839438 -58.413904) (xy 16.833088 -58.430922) (xy 16.833088 -58.516266) (xy 16.839438 -58.533284)
			(xy 16.845534 -58.540396) (xy 16.86319 -58.561314) (xy 16.892898 -58.607291) (xy 16.91573 -58.657043)
			(xy 16.931217 -58.709546) (xy 16.939042 -58.763724) (xy 16.939514 -58.791094) (xy 16.939028 -58.818345)
			(xy 16.931272 -58.872293) (xy 16.930875 -58.873644) (xy 18.200624 -58.873644) (xy 18.20111 -58.846274)
			(xy 18.208922 -58.792096) (xy 18.224406 -58.739593) (xy 18.247244 -58.689846) (xy 18.276964 -58.643878)
			(xy 18.294604 -58.622946) (xy 18.3007 -58.615834) (xy 18.30705 -58.598816) (xy 18.30705 -58.513472)
			(xy 18.3007 -58.496454) (xy 18.294604 -58.489342) (xy 18.276972 -58.468404) (xy 18.247259 -58.422433)
			(xy 18.224421 -58.372687) (xy 18.208929 -58.320188) (xy 18.201099 -58.266013) (xy 18.200624 -58.238644)
			(xy 18.20111 -58.211393) (xy 18.208866 -58.157445) (xy 18.224221 -58.10515) (xy 18.246863 -58.055573)
			(xy 18.276329 -58.009723) (xy 18.31202 -57.968532) (xy 18.353211 -57.932841) (xy 18.399061 -57.903375)
			(xy 18.448638 -57.880733) (xy 18.500933 -57.865378) (xy 18.554881 -57.857622) (xy 18.609383 -57.857622)
			(xy 18.663331 -57.865378) (xy 18.715626 -57.880733) (xy 18.765203 -57.903375) (xy 18.811053 -57.932841)
			(xy 18.852244 -57.968532) (xy 18.887935 -58.009723) (xy 18.917401 -58.055573) (xy 18.940043 -58.10515)
			(xy 18.955398 -58.157445) (xy 18.963154 -58.211393) (xy 18.96364 -58.238644) (xy 18.963156 -58.266014)
			(xy 18.955345 -58.320193) (xy 18.939861 -58.372696) (xy 18.917022 -58.422443) (xy 18.8873 -58.46841)
			(xy 18.86966 -58.489342) (xy 18.863564 -58.496454) (xy 18.857214 -58.513472) (xy 18.857214 -58.598816)
			(xy 18.863564 -58.615834) (xy 18.86966 -58.622946) (xy 18.887281 -58.643893) (xy 18.916997 -58.689861)
			(xy 18.939837 -58.739605) (xy 18.955332 -58.792102) (xy 18.963164 -58.846276) (xy 18.96364 -58.873644)
			(xy 18.963154 -58.900895) (xy 18.955398 -58.954843) (xy 18.940043 -59.007138) (xy 18.917401 -59.056715)
			(xy 18.887935 -59.102565) (xy 18.852244 -59.143756) (xy 18.811053 -59.179447) (xy 18.765203 -59.208913)
			(xy 18.715626 -59.231555) (xy 18.663331 -59.24691) (xy 18.609383 -59.254666) (xy 18.554881 -59.254666)
			(xy 18.500933 -59.24691) (xy 18.448638 -59.231555) (xy 18.399061 -59.208913) (xy 18.353211 -59.179447)
			(xy 18.31202 -59.143756) (xy 18.276329 -59.102565) (xy 18.246863 -59.056715) (xy 18.224221 -59.007138)
			(xy 18.208866 -58.954843) (xy 18.20111 -58.900895) (xy 18.200624 -58.873644) (xy 16.930875 -58.873644)
			(xy 16.915917 -58.924588) (xy 16.893275 -58.974165) (xy 16.863809 -59.020015) (xy 16.828118 -59.061206)
			(xy 16.786927 -59.096897) (xy 16.741077 -59.126363) (xy 16.6915 -59.149005) (xy 16.639205 -59.16436)
			(xy 16.585257 -59.172116) (xy 16.530755 -59.172116) (xy 16.476807 -59.16436) (xy 16.424512 -59.149005)
			(xy 16.374935 -59.126363) (xy 16.329085 -59.096897) (xy 16.287894 -59.061206) (xy 16.252203 -59.020015)
			(xy 16.222737 -58.974165) (xy 16.200095 -58.924588) (xy 16.18474 -58.872293) (xy 16.176984 -58.818345)
			(xy 16.176498 -58.791094) (xy 14.27854 -58.791094) (xy 14.275448 -58.812603) (xy 14.260093 -58.864898)
			(xy 14.237451 -58.914475) (xy 14.207985 -58.960325) (xy 14.172294 -59.001516) (xy 14.131103 -59.037207)
			(xy 14.085253 -59.066673) (xy 14.035676 -59.089315) (xy 13.983381 -59.10467) (xy 13.929433 -59.112426)
			(xy 13.874931 -59.112426) (xy 13.820983 -59.10467) (xy 13.768688 -59.089315) (xy 13.719111 -59.066673)
			(xy 13.673261 -59.037207) (xy 13.63207 -59.001516) (xy 13.596379 -58.960325) (xy 13.566913 -58.914475)
			(xy 13.544271 -58.864898) (xy 13.528916 -58.812603) (xy 13.52116 -58.758655) (xy 13.520674 -58.731404)
			(xy 11.691112 -58.731404) (xy 11.691112 -60.126454) (xy 17.180249 -60.126454) (xy 17.180249 -60.071946)
			(xy 17.188007 -60.017994) (xy 17.203363 -59.965695) (xy 17.226006 -59.916114) (xy 17.255476 -59.87026)
			(xy 17.29117 -59.829066) (xy 17.332364 -59.793372) (xy 17.378219 -59.763904) (xy 17.427801 -59.741261)
			(xy 17.4801 -59.725905) (xy 17.534052 -59.718149) (xy 17.561306 -59.717686) (xy 17.588676 -59.718152)
			(xy 17.642855 -59.72597) (xy 17.695358 -59.74146) (xy 17.745105 -59.764301) (xy 17.791072 -59.794025)
			(xy 17.812004 -59.811666) (xy 17.819116 -59.817762) (xy 17.836134 -59.824112) (xy 17.921478 -59.824112)
			(xy 17.938496 -59.817762) (xy 17.945608 -59.811666) (xy 17.966541 -59.794025) (xy 18.012509 -59.764301)
			(xy 18.062255 -59.741455) (xy 18.114757 -59.725959) (xy 18.168935 -59.71813) (xy 18.223677 -59.71813)
			(xy 18.277855 -59.725959) (xy 18.330357 -59.741455) (xy 18.380103 -59.764301) (xy 18.426071 -59.794025)
			(xy 18.447004 -59.811666) (xy 18.454116 -59.817762) (xy 18.471134 -59.824112) (xy 18.556478 -59.824112)
			(xy 18.573496 -59.817762) (xy 18.580608 -59.811666) (xy 18.601522 -59.794004) (xy 18.6475 -59.764297)
			(xy 18.697252 -59.741466) (xy 18.749757 -59.72598) (xy 18.803936 -59.718157) (xy 18.831306 -59.717686)
			(xy 18.858557 -59.718184) (xy 18.912503 -59.725941) (xy 18.964796 -59.741297) (xy 19.014372 -59.763938)
			(xy 19.060221 -59.793404) (xy 19.101409 -59.829095) (xy 19.1371 -59.870284) (xy 19.166565 -59.916134)
			(xy 19.189205 -59.96571) (xy 19.20456 -60.018003) (xy 19.212316 -60.071949) (xy 19.212316 -60.126451)
			(xy 19.20456 -60.180397) (xy 19.189205 -60.23269) (xy 19.166565 -60.282266) (xy 19.1371 -60.328116)
			(xy 19.101409 -60.369305) (xy 19.060221 -60.404996) (xy 19.014372 -60.434462) (xy 18.964796 -60.457103)
			(xy 18.912503 -60.472459) (xy 18.858557 -60.480216) (xy 18.831306 -60.480702) (xy 18.803936 -60.480232)
			(xy 18.749757 -60.472415) (xy 18.697254 -60.456927) (xy 18.647507 -60.434086) (xy 18.60154 -60.404363)
			(xy 18.580608 -60.386722) (xy 18.573496 -60.380626) (xy 18.556478 -60.374276) (xy 18.471134 -60.374276)
			(xy 18.454116 -60.380626) (xy 18.447004 -60.386722) (xy 18.426071 -60.404363) (xy 18.380103 -60.434087)
			(xy 18.330357 -60.456933) (xy 18.277855 -60.472429) (xy 18.223677 -60.480258) (xy 18.168935 -60.480258)
			(xy 18.114757 -60.472429) (xy 18.062255 -60.456933) (xy 18.012509 -60.434087) (xy 17.966541 -60.404363)
			(xy 17.945608 -60.386722) (xy 17.938496 -60.380626) (xy 17.921478 -60.374276) (xy 17.836134 -60.374276)
			(xy 17.819116 -60.380626) (xy 17.812004 -60.386722) (xy 17.791084 -60.404376) (xy 17.745108 -60.434085)
			(xy 17.695357 -60.456918) (xy 17.642854 -60.472405) (xy 17.588676 -60.48023) (xy 17.561306 -60.480702)
			(xy 17.534052 -60.480251) (xy 17.4801 -60.472495) (xy 17.427801 -60.457139) (xy 17.378219 -60.434496)
			(xy 17.332364 -60.405028) (xy 17.29117 -60.369334) (xy 17.255476 -60.32814) (xy 17.226006 -60.282286)
			(xy 17.203363 -60.232705) (xy 17.188007 -60.180406) (xy 17.180249 -60.126454) (xy 11.691112 -60.126454)
			(xy 11.691112 -63.245552) (xy 17.104569 -63.245552) (xy 17.104569 -63.191048) (xy 17.112326 -63.137097)
			(xy 17.127683 -63.0848) (xy 17.150325 -63.035221) (xy 17.179793 -62.989369) (xy 17.215487 -62.948177)
			(xy 17.25668 -62.912485) (xy 17.302533 -62.883019) (xy 17.352113 -62.860378) (xy 17.404411 -62.845023)
			(xy 17.458361 -62.837268) (xy 17.485614 -62.836806) (xy 17.512985 -62.837262) (xy 17.567164 -62.845082)
			(xy 17.619667 -62.860574) (xy 17.669414 -62.883417) (xy 17.715381 -62.913144) (xy 17.736312 -62.930786)
			(xy 17.743424 -62.936882) (xy 17.760442 -62.943232) (xy 17.845786 -62.943232) (xy 17.862804 -62.936882)
			(xy 17.869916 -62.930786) (xy 17.890849 -62.913145) (xy 17.936817 -62.883421) (xy 17.986563 -62.860575)
			(xy 18.039065 -62.845079) (xy 18.093243 -62.83725) (xy 18.147985 -62.83725) (xy 18.202163 -62.845079)
			(xy 18.254665 -62.860575) (xy 18.304411 -62.883421) (xy 18.350379 -62.913145) (xy 18.371312 -62.930786)
			(xy 18.378424 -62.936882) (xy 18.395442 -62.943232) (xy 18.480786 -62.943232) (xy 18.497804 -62.936882)
			(xy 18.504916 -62.930786) (xy 18.525867 -62.913171) (xy 18.571835 -62.883456) (xy 18.621578 -62.860615)
			(xy 18.674074 -62.845119) (xy 18.728246 -62.837284) (xy 18.755614 -62.836806) (xy 18.782866 -62.837265)
			(xy 18.836814 -62.845023) (xy 18.889109 -62.86038) (xy 18.938686 -62.883023) (xy 18.984536 -62.912491)
			(xy 19.025726 -62.948183) (xy 19.061418 -62.989375) (xy 19.090884 -63.035226) (xy 19.113525 -63.084804)
			(xy 19.12888 -63.1371) (xy 19.136636 -63.191048) (xy 19.136636 -63.245552) (xy 19.12888 -63.2995)
			(xy 19.113525 -63.351796) (xy 19.090884 -63.401374) (xy 19.061418 -63.447225) (xy 19.025726 -63.488417)
			(xy 18.984536 -63.524109) (xy 18.938686 -63.553577) (xy 18.889109 -63.57622) (xy 18.836814 -63.591577)
			(xy 18.782866 -63.599335) (xy 18.755614 -63.599822) (xy 18.728243 -63.599367) (xy 18.674063 -63.591549)
			(xy 18.621559 -63.576059) (xy 18.571812 -63.553214) (xy 18.525847 -63.523486) (xy 18.504916 -63.505842)
			(xy 18.497804 -63.499746) (xy 18.480786 -63.493396) (xy 18.395442 -63.493396) (xy 18.378424 -63.499746)
			(xy 18.371312 -63.505842) (xy 18.350379 -63.523483) (xy 18.304411 -63.553207) (xy 18.254665 -63.576053)
			(xy 18.202163 -63.591549) (xy 18.147985 -63.599378) (xy 18.093243 -63.599378) (xy 18.039065 -63.591549)
			(xy 17.986563 -63.576053) (xy 17.936817 -63.553207) (xy 17.890849 -63.523483) (xy 17.869916 -63.505842)
			(xy 17.862804 -63.499746) (xy 17.845786 -63.493396) (xy 17.760442 -63.493396) (xy 17.743424 -63.499746)
			(xy 17.736312 -63.505842) (xy 17.715392 -63.523496) (xy 17.669415 -63.553204) (xy 17.619665 -63.576037)
			(xy 17.567161 -63.591525) (xy 17.512984 -63.59935) (xy 17.485614 -63.599822) (xy 17.458361 -63.599332)
			(xy 17.404411 -63.591577) (xy 17.352113 -63.576222) (xy 17.302533 -63.553581) (xy 17.25668 -63.524115)
			(xy 17.215487 -63.488423) (xy 17.179793 -63.447231) (xy 17.150325 -63.401379) (xy 17.127683 -63.3518)
			(xy 17.112326 -63.299503) (xy 17.104569 -63.245552) (xy 11.691112 -63.245552) (xy 11.691112 -65.15989)
			(xy 19.116546 -65.15989) (xy 19.120617 -65.104268) (xy 19.132743 -65.049831) (xy 19.152666 -64.99774)
			(xy 19.179962 -64.949105) (xy 19.214048 -64.904962) (xy 19.254197 -64.866253) (xy 19.299555 -64.833802)
			(xy 19.349155 -64.808301) (xy 19.401939 -64.790294) (xy 19.456782 -64.780164) (xy 19.512516 -64.778127)
			(xy 19.567953 -64.784227) (xy 19.62191 -64.798333) (xy 19.673239 -64.820145) (xy 19.720845 -64.849199)
			(xy 19.763713 -64.884874) (xy 19.80093 -64.926411) (xy 19.831703 -64.972924) (xy 19.855375 -65.023421)
			(xy 19.871443 -65.076828) (xy 19.879563 -65.132004) (xy 19.880072 -65.15989) (xy 19.879563 -65.187776)
			(xy 19.871443 -65.242952) (xy 19.855375 -65.296359) (xy 19.831703 -65.346856) (xy 19.80093 -65.393369)
			(xy 19.763713 -65.434906) (xy 19.720845 -65.470581) (xy 19.673239 -65.499635) (xy 19.62191 -65.521447)
			(xy 19.567953 -65.535553) (xy 19.512516 -65.541653) (xy 19.456782 -65.539616) (xy 19.401939 -65.529486)
			(xy 19.349155 -65.511479) (xy 19.299555 -65.485978) (xy 19.254197 -65.453527) (xy 19.214048 -65.414818)
			(xy 19.179962 -65.370675) (xy 19.152666 -65.32204) (xy 19.132743 -65.269949) (xy 19.120617 -65.215512)
			(xy 19.116546 -65.15989) (xy 11.691112 -65.15989) (xy 11.691112 -65.75552) (xy 14.34668 -65.75552)
			(xy 14.350751 -65.699898) (xy 14.362877 -65.645461) (xy 14.3828 -65.59337) (xy 14.410096 -65.544735)
			(xy 14.444182 -65.500592) (xy 14.484331 -65.461883) (xy 14.529689 -65.429432) (xy 14.579289 -65.403931)
			(xy 14.632073 -65.385924) (xy 14.686916 -65.375794) (xy 14.74265 -65.373757) (xy 14.798087 -65.379857)
			(xy 14.852044 -65.393963) (xy 14.903373 -65.415775) (xy 14.950979 -65.444829) (xy 14.993847 -65.480504)
			(xy 15.031064 -65.522041) (xy 15.061837 -65.568554) (xy 15.085509 -65.619051) (xy 15.101577 -65.672458)
			(xy 15.109697 -65.727634) (xy 15.110206 -65.75552) (xy 15.109697 -65.783406) (xy 15.101577 -65.838582)
			(xy 15.085509 -65.891989) (xy 15.061837 -65.942486) (xy 15.031064 -65.988999) (xy 14.993847 -66.030536)
			(xy 14.950979 -66.066211) (xy 14.903373 -66.095265) (xy 14.852044 -66.117077) (xy 14.798087 -66.131183)
			(xy 14.74265 -66.137283) (xy 14.686916 -66.135246) (xy 14.632073 -66.125116) (xy 14.579289 -66.107109)
			(xy 14.529689 -66.081608) (xy 14.484331 -66.049157) (xy 14.444182 -66.010448) (xy 14.410096 -65.966305)
			(xy 14.3828 -65.91767) (xy 14.362877 -65.865579) (xy 14.350751 -65.811142) (xy 14.34668 -65.75552)
			(xy 11.691112 -65.75552) (xy 11.691112 -67.488054) (xy 18.779234 -67.488054) (xy 18.783305 -67.432432)
			(xy 18.795431 -67.377995) (xy 18.815354 -67.325904) (xy 18.84265 -67.277269) (xy 18.876736 -67.233126)
			(xy 18.916885 -67.194417) (xy 18.962243 -67.161966) (xy 19.011843 -67.136465) (xy 19.064627 -67.118458)
			(xy 19.11947 -67.108328) (xy 19.175204 -67.106291) (xy 19.230641 -67.112391) (xy 19.284598 -67.126497)
			(xy 19.335927 -67.148309) (xy 19.383533 -67.177363) (xy 19.426401 -67.213038) (xy 19.463618 -67.254575)
			(xy 19.494391 -67.301088) (xy 19.518063 -67.351585) (xy 19.534131 -67.404992) (xy 19.542251 -67.460168)
			(xy 19.54276 -67.488054) (xy 19.542251 -67.51594) (xy 19.534131 -67.571116) (xy 19.518063 -67.624523)
			(xy 19.494391 -67.67502) (xy 19.463618 -67.721533) (xy 19.426401 -67.76307) (xy 19.383533 -67.798745)
			(xy 19.335927 -67.827799) (xy 19.284598 -67.849611) (xy 19.230641 -67.863717) (xy 19.175204 -67.869817)
			(xy 19.11947 -67.86778) (xy 19.064627 -67.85765) (xy 19.011843 -67.839643) (xy 18.962243 -67.814142)
			(xy 18.916885 -67.781691) (xy 18.876736 -67.742982) (xy 18.84265 -67.698839) (xy 18.815354 -67.650204)
			(xy 18.795431 -67.598113) (xy 18.783305 -67.543676) (xy 18.779234 -67.488054) (xy 11.691112 -67.488054)
			(xy 11.691112 -70.0405) (xy 11.691532 -70.05052) (xy 11.699202 -70.069035) (xy 11.713375 -70.083205)
			(xy 11.731891 -70.090871) (xy 11.741912 -70.0913)
		)
		(stroke
			(width 0)
			(type solid)
		)
		(fill yes)
		(layer "In9.Cu")
		(net "P12V_SSD0_R")
	)
	(gr_poly
		(pts
			(xy 47.527718 -300.945296) (xy 47.53483 -300.936152) (xy 47.550758 -300.916719) (xy 47.58786 -300.882839)
			(xy 47.630008 -300.85549) (xy 47.676064 -300.83541) (xy 47.724786 -300.823141) (xy 47.77486 -300.819014)
			(xy 47.824934 -300.823141) (xy 47.873656 -300.83541) (xy 47.919712 -300.85549) (xy 47.96186 -300.882839)
			(xy 47.998962 -300.916719) (xy 48.01489 -300.936152) (xy 48.02247 -300.944861) (xy 48.043235 -300.954902)
			(xy 48.054768 -300.955456) (xy 48.444912 -300.955456) (xy 48.456445 -300.954909) (xy 48.477206 -300.944858)
			(xy 48.48479 -300.936152) (xy 48.491137 -300.928205) (xy 48.504739 -300.91308) (xy 48.511968 -300.905926)
			(xy 48.518549 -300.898942) (xy 48.526423 -300.881457) (xy 48.527362 -300.862304) (xy 48.524668 -300.853094)
			(xy 48.517145 -300.829744) (xy 48.508804 -300.781403) (xy 48.508308 -300.732351) (xy 48.515671 -300.683852)
			(xy 48.530703 -300.637157) (xy 48.541432 -300.615096) (xy 48.57115 -300.585378) (xy 48.578671 -300.576974)
			(xy 48.586203 -300.555746) (xy 48.585628 -300.544484) (xy 48.576738 -300.454822) (xy 48.565308 -300.435518)
			(xy 48.555656 -300.428914) (xy 48.535097 -300.414635) (xy 48.498505 -300.380486) (xy 48.467978 -300.34082)
			(xy 48.444335 -300.296704) (xy 48.428211 -300.24932) (xy 48.420039 -300.19994) (xy 48.419512 -300.174914)
			(xy 48.419957 -300.150921) (xy 48.427462 -300.103525) (xy 48.44229 -300.057886) (xy 48.464075 -300.01513)
			(xy 48.49228 -299.976308) (xy 48.526212 -299.942377) (xy 48.565035 -299.914172) (xy 48.607792 -299.892388)
			(xy 48.653431 -299.877561) (xy 48.700827 -299.870057) (xy 48.72482 -299.869606) (xy 48.750718 -299.870154)
			(xy 48.801772 -299.878895) (xy 48.850619 -299.896123) (xy 48.89586 -299.921344) (xy 48.936199 -299.953836)
			(xy 48.970478 -299.992666) (xy 48.997715 -300.036723) (xy 49.01713 -300.084743) (xy 49.028166 -300.135351)
			(xy 49.029874 -300.161198) (xy 49.030382 -300.171104) (xy 49.038256 -300.18863) (xy 49.096168 -300.244002)
			(xy 49.103493 -300.250372) (xy 49.12152 -300.257533) (xy 49.13122 -300.257972) (xy 49.26838 -300.257972)
			(xy 49.278076 -300.257538) (xy 49.296086 -300.250347) (xy 49.303432 -300.244002) (xy 49.361344 -300.18863)
			(xy 49.369218 -300.171104) (xy 49.369726 -300.161198) (xy 49.371407 -300.135559) (xy 49.382272 -300.085345)
			(xy 49.401389 -300.037657) (xy 49.42822 -299.993843) (xy 49.462005 -299.955138) (xy 49.501794 -299.922635)
			(xy 49.546461 -299.897251) (xy 49.594748 -299.879702) (xy 49.645291 -299.870484) (xy 49.67097 -299.869606)
			(xy 49.68113 -299.869606) (xy 49.699418 -299.861732) (xy 49.756568 -299.80382) (xy 49.763259 -299.796413)
			(xy 49.770853 -299.777977) (xy 49.7713 -299.768006) (xy 49.7713 -299.631862) (xy 49.770819 -299.621898)
			(xy 49.763238 -299.603466) (xy 49.756568 -299.596048) (xy 49.699418 -299.538136) (xy 49.68113 -299.530262)
			(xy 49.67097 -299.530262) (xy 49.645926 -299.529443) (xy 49.5966 -299.520642) (xy 49.549374 -299.503904)
			(xy 49.505515 -299.47968) (xy 49.4662 -299.448618) (xy 49.432485 -299.411554) (xy 49.405274 -299.369482)
			(xy 49.385299 -299.323531) (xy 49.373096 -299.274936) (xy 49.368991 -299.224999) (xy 49.373096 -299.175063)
			(xy 49.3853 -299.126468) (xy 49.405275 -299.080517) (xy 49.432485 -299.038445) (xy 49.466201 -299.001381)
			(xy 49.505516 -298.97032) (xy 49.549375 -298.946095) (xy 49.596602 -298.929358) (xy 49.645927 -298.920557)
			(xy 49.67097 -298.919646) (xy 49.68113 -298.919646) (xy 49.699418 -298.911772) (xy 49.756568 -298.85386)
			(xy 49.763307 -298.846488) (xy 49.77089 -298.828027) (xy 49.7713 -298.818046) (xy 49.7713 -298.681648)
			(xy 49.770816 -298.671685) (xy 49.763232 -298.653257) (xy 49.756568 -298.645834) (xy 49.699418 -298.587922)
			(xy 49.68113 -298.580048) (xy 49.67097 -298.580048) (xy 49.645919 -298.579229) (xy 49.596579 -298.570426)
			(xy 49.54934 -298.553683) (xy 49.505468 -298.529452) (xy 49.466142 -298.498382) (xy 49.432417 -298.461308)
			(xy 49.405199 -298.419224) (xy 49.385218 -298.37326) (xy 49.37301 -298.324651) (xy 49.368904 -298.274701)
			(xy 49.37301 -298.22475) (xy 49.385217 -298.176141) (xy 49.405198 -298.130177) (xy 49.432416 -298.088093)
			(xy 49.466141 -298.051018) (xy 49.505467 -298.019948) (xy 49.549339 -297.995717) (xy 49.596578 -297.978975)
			(xy 49.645918 -297.970171) (xy 49.67097 -297.969432) (xy 49.68113 -297.969432) (xy 49.699418 -297.961558)
			(xy 49.756568 -297.903646) (xy 49.763263 -297.89624) (xy 49.770867 -297.877804) (xy 49.7713 -297.867832)
			(xy 49.7713 -297.731688) (xy 49.770824 -297.721721) (xy 49.76325 -297.703283) (xy 49.756568 -297.695874)
			(xy 49.699418 -297.637962) (xy 49.68113 -297.630088) (xy 49.67097 -297.630088) (xy 49.645924 -297.629269)
			(xy 49.596594 -297.620467) (xy 49.549364 -297.603728) (xy 49.505501 -297.579501) (xy 49.466182 -297.548438)
			(xy 49.432464 -297.51137) (xy 49.405252 -297.469295) (xy 49.385275 -297.42334) (xy 49.37307 -297.37474)
			(xy 49.368965 -297.3248) (xy 49.37307 -297.274859) (xy 49.385275 -297.22626) (xy 49.405252 -297.180305)
			(xy 49.432465 -297.138229) (xy 49.466183 -297.101162) (xy 49.505501 -297.070098) (xy 49.549364 -297.045872)
			(xy 49.596595 -297.029133) (xy 49.645924 -297.020331) (xy 49.67097 -297.019472) (xy 49.68113 -297.019472)
			(xy 49.699418 -297.011598) (xy 49.756568 -296.953686) (xy 49.763253 -296.946277) (xy 49.770835 -296.927841)
			(xy 49.7713 -296.917872) (xy 49.7713 -296.781728) (xy 49.770813 -296.771766) (xy 49.763224 -296.753343)
			(xy 49.756568 -296.745914) (xy 49.699418 -296.688002) (xy 49.68113 -296.680128) (xy 49.67097 -296.680128)
			(xy 49.647178 -296.679374) (xy 49.600252 -296.671396) (xy 49.555133 -296.656231) (xy 49.512915 -296.634246)
			(xy 49.474621 -296.605975) (xy 49.44118 -296.572102) (xy 49.413401 -296.53345) (xy 49.391959 -296.490953)
			(xy 49.377374 -296.445644) (xy 49.369998 -296.39862) (xy 49.369472 -296.37482) (xy 49.369567 -296.365077)
			(xy 49.370838 -296.345631) (xy 49.372012 -296.335958) (xy 49.373282 -296.325036) (xy 49.366932 -296.304208)
			(xy 49.309274 -296.238676) (xy 49.301741 -296.230872) (xy 49.282007 -296.221918) (xy 49.271174 -296.221404)
			(xy 49.128426 -296.221404) (xy 49.117591 -296.22191) (xy 49.097862 -296.230872) (xy 49.090326 -296.238676)
			(xy 49.032668 -296.304208) (xy 49.026318 -296.325036) (xy 49.027588 -296.335958) (xy 49.02877 -296.34563)
			(xy 49.03004 -296.365076) (xy 49.030128 -296.37482) (xy 49.029606 -296.400075) (xy 49.021293 -296.449897)
			(xy 49.004892 -296.497671) (xy 48.980851 -296.542094) (xy 48.949827 -296.581954) (xy 48.912665 -296.616164)
			(xy 48.870379 -296.64379) (xy 48.824123 -296.66408) (xy 48.775158 -296.67648) (xy 48.72482 -296.680651)
			(xy 48.674482 -296.67648) (xy 48.625517 -296.66408) (xy 48.579261 -296.64379) (xy 48.536975 -296.616164)
			(xy 48.499813 -296.581954) (xy 48.468789 -296.542094) (xy 48.444748 -296.497671) (xy 48.428347 -296.449897)
			(xy 48.420034 -296.400075) (xy 48.419512 -296.37482) (xy 48.419607 -296.365077) (xy 48.420878 -296.345631)
			(xy 48.422052 -296.335958) (xy 48.423322 -296.325036) (xy 48.416972 -296.304208) (xy 48.359314 -296.238676)
			(xy 48.351784 -296.230866) (xy 48.33205 -296.221896) (xy 48.321214 -296.221404) (xy 48.178466 -296.221404)
			(xy 48.167627 -296.221902) (xy 48.147886 -296.230854) (xy 48.140366 -296.238676) (xy 48.082708 -296.304208)
			(xy 48.076358 -296.325036) (xy 48.077628 -296.335958) (xy 48.07881 -296.34563) (xy 48.080081 -296.365076)
			(xy 48.080168 -296.37482) (xy 48.079646 -296.400075) (xy 48.071333 -296.449897) (xy 48.054932 -296.497671)
			(xy 48.030891 -296.542094) (xy 47.999867 -296.581954) (xy 47.962705 -296.616164) (xy 47.920419 -296.64379)
			(xy 47.874163 -296.66408) (xy 47.825198 -296.67648) (xy 47.77486 -296.680651) (xy 47.724522 -296.67648)
			(xy 47.675557 -296.66408) (xy 47.629301 -296.64379) (xy 47.587015 -296.616164) (xy 47.549853 -296.581954)
			(xy 47.518829 -296.542094) (xy 47.494788 -296.497671) (xy 47.478387 -296.449897) (xy 47.470074 -296.400075)
			(xy 47.469552 -296.37482) (xy 47.469647 -296.365077) (xy 47.470918 -296.345631) (xy 47.472092 -296.335958)
			(xy 47.473362 -296.325036) (xy 47.467012 -296.304208) (xy 47.409354 -296.238676) (xy 47.40182 -296.230876)
			(xy 47.382086 -296.221929) (xy 47.371254 -296.221404) (xy 47.228506 -296.221404) (xy 47.217663 -296.221894)
			(xy 47.19791 -296.230836) (xy 47.190406 -296.238676) (xy 47.132748 -296.304208) (xy 47.126398 -296.325036)
			(xy 47.127668 -296.335958) (xy 47.12885 -296.34563) (xy 47.13012 -296.365076) (xy 47.130208 -296.37482)
			(xy 47.129686 -296.400075) (xy 47.121373 -296.449897) (xy 47.104972 -296.497671) (xy 47.080931 -296.542094)
			(xy 47.049907 -296.581954) (xy 47.012745 -296.616164) (xy 46.970459 -296.64379) (xy 46.924203 -296.66408)
			(xy 46.875238 -296.67648) (xy 46.8249 -296.680651) (xy 46.774562 -296.67648) (xy 46.725597 -296.66408)
			(xy 46.679341 -296.64379) (xy 46.637055 -296.616164) (xy 46.599893 -296.581954) (xy 46.568869 -296.542094)
			(xy 46.544828 -296.497671) (xy 46.528427 -296.449897) (xy 46.520114 -296.400075) (xy 46.519592 -296.37482)
			(xy 46.519687 -296.365077) (xy 46.520958 -296.345631) (xy 46.522132 -296.335958) (xy 46.523402 -296.325036)
			(xy 46.517052 -296.304208) (xy 46.459394 -296.238676) (xy 46.451862 -296.230869) (xy 46.432129 -296.221908)
			(xy 46.421294 -296.221404) (xy 46.278546 -296.221404) (xy 46.267709 -296.221906) (xy 46.247974 -296.230863)
			(xy 46.240446 -296.238676) (xy 46.182788 -296.304208) (xy 46.176438 -296.325036) (xy 46.177708 -296.335958)
			(xy 46.17889 -296.34563) (xy 46.18016 -296.365076) (xy 46.180248 -296.37482) (xy 46.179726 -296.400075)
			(xy 46.171413 -296.449897) (xy 46.155012 -296.497671) (xy 46.130971 -296.542094) (xy 46.099947 -296.581954)
			(xy 46.062785 -296.616164) (xy 46.020499 -296.64379) (xy 45.974243 -296.66408) (xy 45.925278 -296.67648)
			(xy 45.87494 -296.680651) (xy 45.824602 -296.67648) (xy 45.775637 -296.66408) (xy 45.729381 -296.64379)
			(xy 45.687095 -296.616164) (xy 45.649933 -296.581954) (xy 45.618909 -296.542094) (xy 45.594868 -296.497671)
			(xy 45.578467 -296.449897) (xy 45.570154 -296.400075) (xy 45.569632 -296.37482) (xy 45.569727 -296.365077)
			(xy 45.570998 -296.345631) (xy 45.572172 -296.335958) (xy 45.573442 -296.325036) (xy 45.567092 -296.304208)
			(xy 45.509434 -296.238676) (xy 45.501899 -296.230879) (xy 45.482165 -296.22194) (xy 45.471334 -296.221404)
			(xy 45.328586 -296.221404) (xy 45.317745 -296.221898) (xy 45.297998 -296.230845) (xy 45.290486 -296.238676)
			(xy 45.232828 -296.304208) (xy 45.226478 -296.325036) (xy 45.227748 -296.335958) (xy 45.22893 -296.34563)
			(xy 45.230201 -296.365076) (xy 45.230288 -296.37482) (xy 45.229766 -296.400075) (xy 45.221453 -296.449897)
			(xy 45.205052 -296.497671) (xy 45.181011 -296.542094) (xy 45.149987 -296.581954) (xy 45.112825 -296.616164)
			(xy 45.070539 -296.64379) (xy 45.024283 -296.66408) (xy 44.975318 -296.67648) (xy 44.92498 -296.680651)
			(xy 44.874642 -296.67648) (xy 44.825677 -296.66408) (xy 44.779421 -296.64379) (xy 44.737135 -296.616164)
			(xy 44.699973 -296.581954) (xy 44.668949 -296.542094) (xy 44.644908 -296.497671) (xy 44.628507 -296.449897)
			(xy 44.620194 -296.400075) (xy 44.619672 -296.37482) (xy 44.619767 -296.365077) (xy 44.621038 -296.345631)
			(xy 44.622212 -296.335958) (xy 44.623482 -296.325036) (xy 44.617132 -296.304208) (xy 44.559474 -296.238676)
			(xy 44.551941 -296.230872) (xy 44.532207 -296.221918) (xy 44.521374 -296.221404) (xy 44.378372 -296.221404)
			(xy 44.367533 -296.221901) (xy 44.34779 -296.230851) (xy 44.340272 -296.238676) (xy 44.282614 -296.304208)
			(xy 44.276264 -296.325036) (xy 44.277534 -296.335958) (xy 44.278716 -296.34563) (xy 44.279987 -296.365076)
			(xy 44.280074 -296.37482) (xy 44.279552 -296.400075) (xy 44.271239 -296.449897) (xy 44.254838 -296.497671)
			(xy 44.230797 -296.542094) (xy 44.199773 -296.581954) (xy 44.162611 -296.616164) (xy 44.120325 -296.64379)
			(xy 44.074069 -296.66408) (xy 44.025104 -296.67648) (xy 43.974766 -296.680651) (xy 43.924428 -296.67648)
			(xy 43.875463 -296.66408) (xy 43.829207 -296.64379) (xy 43.786921 -296.616164) (xy 43.749759 -296.581954)
			(xy 43.718735 -296.542094) (xy 43.694694 -296.497671) (xy 43.678293 -296.449897) (xy 43.66998 -296.400075)
			(xy 43.669458 -296.37482) (xy 43.669553 -296.365077) (xy 43.670824 -296.345631) (xy 43.671998 -296.335958)
			(xy 43.673268 -296.325036) (xy 43.666918 -296.304208) (xy 43.60926 -296.238676) (xy 43.601726 -296.230874)
			(xy 43.581992 -296.221926) (xy 43.57116 -296.221404) (xy 42.478452 -296.221404) (xy 42.467615 -296.221905)
			(xy 42.447878 -296.23086) (xy 42.440352 -296.238676) (xy 42.382694 -296.304208) (xy 42.376344 -296.325036)
			(xy 42.377614 -296.335958) (xy 42.378796 -296.34563) (xy 42.380067 -296.365076) (xy 42.380154 -296.37482)
			(xy 42.379632 -296.400075) (xy 42.371319 -296.449897) (xy 42.354918 -296.497671) (xy 42.330877 -296.542094)
			(xy 42.299853 -296.581954) (xy 42.262691 -296.616164) (xy 42.220405 -296.64379) (xy 42.174149 -296.66408)
			(xy 42.125184 -296.67648) (xy 42.074846 -296.680651) (xy 42.024508 -296.67648) (xy 41.975543 -296.66408)
			(xy 41.929287 -296.64379) (xy 41.887001 -296.616164) (xy 41.849839 -296.581954) (xy 41.818815 -296.542094)
			(xy 41.794774 -296.497671) (xy 41.778373 -296.449897) (xy 41.77006 -296.400075) (xy 41.769538 -296.37482)
			(xy 41.769633 -296.365077) (xy 41.770904 -296.345631) (xy 41.772078 -296.335958) (xy 41.773348 -296.325036)
			(xy 41.766998 -296.304208) (xy 41.70934 -296.238676) (xy 41.701805 -296.230878) (xy 41.682071 -296.221937)
			(xy 41.67124 -296.221404) (xy 40.578532 -296.221404) (xy 40.567696 -296.221909) (xy 40.547966 -296.230869)
			(xy 40.540432 -296.238676) (xy 40.482774 -296.304208) (xy 40.476424 -296.325036) (xy 40.477694 -296.335958)
			(xy 40.478876 -296.34563) (xy 40.480146 -296.365076) (xy 40.480234 -296.37482) (xy 40.479712 -296.400075)
			(xy 40.471399 -296.449897) (xy 40.454998 -296.497671) (xy 40.430957 -296.542094) (xy 40.399933 -296.581954)
			(xy 40.362771 -296.616164) (xy 40.320485 -296.64379) (xy 40.274229 -296.66408) (xy 40.225264 -296.67648)
			(xy 40.174926 -296.680651) (xy 40.124588 -296.67648) (xy 40.075623 -296.66408) (xy 40.029367 -296.64379)
			(xy 39.987081 -296.616164) (xy 39.949919 -296.581954) (xy 39.918895 -296.542094) (xy 39.894854 -296.497671)
			(xy 39.878453 -296.449897) (xy 39.87014 -296.400075) (xy 39.869618 -296.37482) (xy 39.869713 -296.365077)
			(xy 39.870984 -296.345631) (xy 39.872158 -296.335958) (xy 39.873428 -296.325036) (xy 39.867078 -296.304208)
			(xy 39.80942 -296.238676) (xy 39.801884 -296.230881) (xy 39.78215 -296.221948) (xy 39.77132 -296.221404)
			(xy 39.628572 -296.221404) (xy 39.617733 -296.221901) (xy 39.59799 -296.230851) (xy 39.590472 -296.238676)
			(xy 39.532814 -296.304208) (xy 39.526464 -296.325036) (xy 39.527734 -296.335958) (xy 39.528916 -296.34563)
			(xy 39.530187 -296.365076) (xy 39.530274 -296.37482) (xy 39.529752 -296.400075) (xy 39.521439 -296.449897)
			(xy 39.505038 -296.497671) (xy 39.480997 -296.542094) (xy 39.449973 -296.581954) (xy 39.412811 -296.616164)
			(xy 39.370525 -296.64379) (xy 39.324269 -296.66408) (xy 39.275304 -296.67648) (xy 39.224966 -296.680651)
			(xy 39.174628 -296.67648) (xy 39.125663 -296.66408) (xy 39.079407 -296.64379) (xy 39.037121 -296.616164)
			(xy 38.999959 -296.581954) (xy 38.968935 -296.542094) (xy 38.944894 -296.497671) (xy 38.928493 -296.449897)
			(xy 38.92018 -296.400075) (xy 38.919658 -296.37482) (xy 38.919753 -296.365077) (xy 38.921024 -296.345631)
			(xy 38.922198 -296.335958) (xy 38.923468 -296.325036) (xy 38.917118 -296.304208) (xy 38.85946 -296.238676)
			(xy 38.851926 -296.230874) (xy 38.832192 -296.221926) (xy 38.82136 -296.221404) (xy 38.678358 -296.221404)
			(xy 38.66752 -296.221903) (xy 38.647781 -296.230858) (xy 38.640258 -296.238676) (xy 38.5826 -296.304208)
			(xy 38.57625 -296.325036) (xy 38.57752 -296.335958) (xy 38.578702 -296.34563) (xy 38.579973 -296.365076)
			(xy 38.58006 -296.37482) (xy 38.579538 -296.400075) (xy 38.571225 -296.449897) (xy 38.554824 -296.497671)
			(xy 38.530783 -296.542094) (xy 38.499759 -296.581954) (xy 38.462597 -296.616164) (xy 38.420311 -296.64379)
			(xy 38.374055 -296.66408) (xy 38.32509 -296.67648) (xy 38.274752 -296.680651) (xy 38.224414 -296.67648)
			(xy 38.175449 -296.66408) (xy 38.129193 -296.64379) (xy 38.086907 -296.616164) (xy 38.049745 -296.581954)
			(xy 38.018721 -296.542094) (xy 37.99468 -296.497671) (xy 37.978279 -296.449897) (xy 37.969966 -296.400075)
			(xy 37.969444 -296.37482) (xy 37.969539 -296.365077) (xy 37.97081 -296.345631) (xy 37.971984 -296.335958)
			(xy 37.973254 -296.325036) (xy 37.966904 -296.304208) (xy 37.909246 -296.238676) (xy 37.901711 -296.230877)
			(xy 37.881977 -296.221934) (xy 37.871146 -296.221404) (xy 37.728652 -296.221404) (xy 37.717815 -296.221905)
			(xy 37.698078 -296.23086) (xy 37.690552 -296.238676) (xy 37.632894 -296.304208) (xy 37.626544 -296.325036)
			(xy 37.627814 -296.335958) (xy 37.628996 -296.34563) (xy 37.630267 -296.365076) (xy 37.630354 -296.37482)
			(xy 37.629832 -296.400075) (xy 37.621519 -296.449897) (xy 37.605118 -296.497671) (xy 37.581077 -296.542094)
			(xy 37.550053 -296.581954) (xy 37.512891 -296.616164) (xy 37.470605 -296.64379) (xy 37.424349 -296.66408)
			(xy 37.375384 -296.67648) (xy 37.325046 -296.680651) (xy 37.274708 -296.67648) (xy 37.225743 -296.66408)
			(xy 37.179487 -296.64379) (xy 37.137201 -296.616164) (xy 37.100039 -296.581954) (xy 37.069015 -296.542094)
			(xy 37.044974 -296.497671) (xy 37.028573 -296.449897) (xy 37.02026 -296.400075) (xy 37.019738 -296.37482)
			(xy 37.019833 -296.365077) (xy 37.021104 -296.345631) (xy 37.022278 -296.335958) (xy 37.023548 -296.325036)
			(xy 37.017198 -296.304208) (xy 36.95954 -296.238676) (xy 36.952005 -296.230878) (xy 36.932271 -296.221937)
			(xy 36.92144 -296.221404) (xy 35.382454 -296.221404) (xy 35.359629 -296.221113) (xy 35.314296 -296.215763)
			(xy 35.29203 -296.210736) (xy 35.286188 -296.209212) (xy 32.013906 -296.209212) (xy 32.004804 -296.209591)
			(xy 31.987757 -296.21598) (xy 31.980632 -296.221658) (xy 31.959719 -296.239098) (xy 31.913882 -296.268495)
			(xy 31.864333 -296.291079) (xy 31.812078 -296.306392) (xy 31.758177 -296.314123) (xy 31.73095 -296.314622)
			(xy 31.706771 -296.314256) (xy 31.658799 -296.308151) (xy 31.611986 -296.29602) (xy 31.567087 -296.27806)
			(xy 31.545784 -296.266616) (xy 31.530798 -296.258234) (xy 31.49727 -296.26306) (xy 31.2039 -296.55643)
			(xy 31.197058 -296.56383) (xy 31.189335 -296.582428) (xy 31.188914 -296.592498) (xy 31.188914 -296.695114)
			(xy 33.620962 -296.695114) (xy 33.625033 -296.639492) (xy 33.637159 -296.585055) (xy 33.657082 -296.532964)
			(xy 33.684378 -296.484329) (xy 33.718464 -296.440186) (xy 33.758613 -296.401477) (xy 33.803971 -296.369026)
			(xy 33.853571 -296.343525) (xy 33.906355 -296.325518) (xy 33.961198 -296.315388) (xy 34.016932 -296.313351)
			(xy 34.072369 -296.319451) (xy 34.126326 -296.333557) (xy 34.177655 -296.355369) (xy 34.225261 -296.384423)
			(xy 34.268129 -296.420098) (xy 34.305346 -296.461635) (xy 34.336119 -296.508148) (xy 34.359791 -296.558645)
			(xy 34.375859 -296.612052) (xy 34.383979 -296.667228) (xy 34.384488 -296.695114) (xy 34.383979 -296.723)
			(xy 34.375859 -296.778176) (xy 34.359791 -296.831583) (xy 34.336119 -296.88208) (xy 34.305346 -296.928593)
			(xy 34.268129 -296.97013) (xy 34.225261 -297.005805) (xy 34.177655 -297.034859) (xy 34.126326 -297.056671)
			(xy 34.072369 -297.070777) (xy 34.016932 -297.076877) (xy 33.961198 -297.07484) (xy 33.906355 -297.06471)
			(xy 33.853571 -297.046703) (xy 33.803971 -297.021202) (xy 33.758613 -296.988751) (xy 33.718464 -296.950042)
			(xy 33.684378 -296.905899) (xy 33.657082 -296.857264) (xy 33.637159 -296.805173) (xy 33.625033 -296.750736)
			(xy 33.620962 -296.695114) (xy 31.188914 -296.695114) (xy 31.188914 -297.3245) (xy 35.433795 -297.3245)
			(xy 35.437965 -297.274168) (xy 35.450363 -297.22521) (xy 35.470649 -297.178959) (xy 35.498271 -297.136678)
			(xy 35.532475 -297.09952) (xy 35.572329 -297.068498) (xy 35.616745 -297.044458) (xy 35.664511 -297.028057)
			(xy 35.714326 -297.019741) (xy 35.739578 -297.019218) (xy 35.764974 -297.019712) (xy 35.815065 -297.028128)
			(xy 35.863073 -297.044715) (xy 35.907676 -297.069017) (xy 35.947643 -297.100363) (xy 35.96513 -297.118786)
			(xy 35.97275 -297.127168) (xy 35.992816 -297.135804) (xy 36.09213 -297.133264) (xy 36.111688 -297.123612)
			(xy 36.1188 -297.114976) (xy 36.134612 -297.096424) (xy 36.17074 -297.063703) (xy 36.211277 -297.036634)
			(xy 36.255344 -297.015802) (xy 36.30199 -297.001658) (xy 36.350206 -296.994507) (xy 36.374578 -296.994072)
			(xy 37.324538 -296.994072) (xy 37.350522 -296.994624) (xy 37.401848 -297.002759) (xy 37.451271 -297.018822)
			(xy 37.497572 -297.042419) (xy 37.539613 -297.072968) (xy 37.576357 -297.109716) (xy 37.606901 -297.15176)
			(xy 37.630492 -297.198064) (xy 37.64655 -297.247489) (xy 37.654679 -297.298816) (xy 37.654679 -297.32478)
			(xy 37.968948 -297.32478) (xy 37.972908 -297.275726) (xy 37.984685 -297.227942) (xy 38.003976 -297.182666)
			(xy 38.030279 -297.14107) (xy 38.062914 -297.104233) (xy 38.101035 -297.073108) (xy 38.143656 -297.048501)
			(xy 38.189672 -297.031049) (xy 38.237891 -297.021205) (xy 38.287066 -297.019224) (xy 38.335921 -297.025156)
			(xy 38.383192 -297.038848) (xy 38.427654 -297.059946) (xy 38.468157 -297.087902) (xy 38.50365 -297.121994)
			(xy 38.533215 -297.161338) (xy 38.556086 -297.204915) (xy 38.57167 -297.251596) (xy 38.579565 -297.300173)
			(xy 38.58006 -297.32478) (xy 38.919162 -297.32478) (xy 38.923122 -297.275726) (xy 38.934899 -297.227942)
			(xy 38.95419 -297.182666) (xy 38.980493 -297.14107) (xy 39.013128 -297.104233) (xy 39.051249 -297.073108)
			(xy 39.09387 -297.048501) (xy 39.139886 -297.031049) (xy 39.188105 -297.021205) (xy 39.23728 -297.019224)
			(xy 39.286135 -297.025156) (xy 39.333406 -297.038848) (xy 39.377868 -297.059946) (xy 39.418371 -297.087902)
			(xy 39.453864 -297.121994) (xy 39.483429 -297.161338) (xy 39.5063 -297.204915) (xy 39.521884 -297.251596)
			(xy 39.529779 -297.300173) (xy 39.530274 -297.32478) (xy 41.769042 -297.32478) (xy 41.773002 -297.275726)
			(xy 41.784779 -297.227942) (xy 41.80407 -297.182666) (xy 41.830373 -297.14107) (xy 41.863008 -297.104233)
			(xy 41.901129 -297.073108) (xy 41.94375 -297.048501) (xy 41.989766 -297.031049) (xy 42.037985 -297.021205)
			(xy 42.08716 -297.019224) (xy 42.136015 -297.025156) (xy 42.183286 -297.038848) (xy 42.227748 -297.059946)
			(xy 42.268251 -297.087902) (xy 42.303744 -297.121994) (xy 42.333309 -297.161338) (xy 42.35618 -297.204915)
			(xy 42.371764 -297.251596) (xy 42.379659 -297.300173) (xy 42.380154 -297.32478) (xy 43.668962 -297.32478)
			(xy 43.672922 -297.275726) (xy 43.684699 -297.227942) (xy 43.70399 -297.182666) (xy 43.730293 -297.14107)
			(xy 43.762928 -297.104233) (xy 43.801049 -297.073108) (xy 43.84367 -297.048501) (xy 43.889686 -297.031049)
			(xy 43.937905 -297.021205) (xy 43.98708 -297.019224) (xy 44.035935 -297.025156) (xy 44.083206 -297.038848)
			(xy 44.127668 -297.059946) (xy 44.168171 -297.087902) (xy 44.203664 -297.121994) (xy 44.233229 -297.161338)
			(xy 44.2561 -297.204915) (xy 44.271684 -297.251596) (xy 44.279579 -297.300173) (xy 44.280074 -297.32478)
			(xy 44.619176 -297.32478) (xy 44.623136 -297.275726) (xy 44.634913 -297.227942) (xy 44.654204 -297.182666)
			(xy 44.680507 -297.14107) (xy 44.713142 -297.104233) (xy 44.751263 -297.073108) (xy 44.793884 -297.048501)
			(xy 44.8399 -297.031049) (xy 44.888119 -297.021205) (xy 44.937294 -297.019224) (xy 44.986149 -297.025156)
			(xy 45.03342 -297.038848) (xy 45.077882 -297.059946) (xy 45.118385 -297.087902) (xy 45.153878 -297.121994)
			(xy 45.183443 -297.161338) (xy 45.206314 -297.204915) (xy 45.221898 -297.251596) (xy 45.229793 -297.300173)
			(xy 45.230288 -297.32478) (xy 45.569136 -297.32478) (xy 45.573096 -297.275726) (xy 45.584873 -297.227942)
			(xy 45.604164 -297.182666) (xy 45.630467 -297.14107) (xy 45.663102 -297.104233) (xy 45.701223 -297.073108)
			(xy 45.743844 -297.048501) (xy 45.78986 -297.031049) (xy 45.838079 -297.021205) (xy 45.887254 -297.019224)
			(xy 45.936109 -297.025156) (xy 45.98338 -297.038848) (xy 46.027842 -297.059946) (xy 46.068345 -297.087902)
			(xy 46.103838 -297.121994) (xy 46.133403 -297.161338) (xy 46.156274 -297.204915) (xy 46.171858 -297.251596)
			(xy 46.179753 -297.300173) (xy 46.180248 -297.32478) (xy 46.519096 -297.32478) (xy 46.523056 -297.275726)
			(xy 46.534833 -297.227942) (xy 46.554124 -297.182666) (xy 46.580427 -297.14107) (xy 46.613062 -297.104233)
			(xy 46.651183 -297.073108) (xy 46.693804 -297.048501) (xy 46.73982 -297.031049) (xy 46.788039 -297.021205)
			(xy 46.837214 -297.019224) (xy 46.886069 -297.025156) (xy 46.93334 -297.038848) (xy 46.977802 -297.059946)
			(xy 47.018305 -297.087902) (xy 47.053798 -297.121994) (xy 47.083363 -297.161338) (xy 47.106234 -297.204915)
			(xy 47.121818 -297.251596) (xy 47.129713 -297.300173) (xy 47.130208 -297.32478) (xy 47.469056 -297.32478)
			(xy 47.473016 -297.275726) (xy 47.484793 -297.227942) (xy 47.504084 -297.182666) (xy 47.530387 -297.14107)
			(xy 47.563022 -297.104233) (xy 47.601143 -297.073108) (xy 47.643764 -297.048501) (xy 47.68978 -297.031049)
			(xy 47.737999 -297.021205) (xy 47.787174 -297.019224) (xy 47.836029 -297.025156) (xy 47.8833 -297.038848)
			(xy 47.927762 -297.059946) (xy 47.968265 -297.087902) (xy 48.003758 -297.121994) (xy 48.033323 -297.161338)
			(xy 48.056194 -297.204915) (xy 48.071778 -297.251596) (xy 48.079673 -297.300173) (xy 48.080168 -297.32478)
			(xy 48.419016 -297.32478) (xy 48.422976 -297.275726) (xy 48.434753 -297.227942) (xy 48.454044 -297.182666)
			(xy 48.480347 -297.14107) (xy 48.512982 -297.104233) (xy 48.551103 -297.073108) (xy 48.593724 -297.048501)
			(xy 48.63974 -297.031049) (xy 48.687959 -297.021205) (xy 48.737134 -297.019224) (xy 48.785989 -297.025156)
			(xy 48.83326 -297.038848) (xy 48.877722 -297.059946) (xy 48.918225 -297.087902) (xy 48.953718 -297.121994)
			(xy 48.983283 -297.161338) (xy 49.006154 -297.204915) (xy 49.021738 -297.251596) (xy 49.029633 -297.300173)
			(xy 49.030128 -297.32478) (xy 49.029633 -297.349387) (xy 49.021738 -297.397964) (xy 49.006154 -297.444645)
			(xy 48.983283 -297.488222) (xy 48.953718 -297.527566) (xy 48.918225 -297.561658) (xy 48.877722 -297.589614)
			(xy 48.83326 -297.610712) (xy 48.785989 -297.624404) (xy 48.737134 -297.630336) (xy 48.687959 -297.628355)
			(xy 48.63974 -297.618511) (xy 48.593724 -297.601059) (xy 48.551103 -297.576452) (xy 48.512982 -297.545327)
			(xy 48.480347 -297.50849) (xy 48.454044 -297.466894) (xy 48.434753 -297.421618) (xy 48.422976 -297.373834)
			(xy 48.419016 -297.32478) (xy 48.080168 -297.32478) (xy 48.079673 -297.349387) (xy 48.071778 -297.397964)
			(xy 48.056194 -297.444645) (xy 48.033323 -297.488222) (xy 48.003758 -297.527566) (xy 47.968265 -297.561658)
			(xy 47.927762 -297.589614) (xy 47.8833 -297.610712) (xy 47.836029 -297.624404) (xy 47.787174 -297.630336)
			(xy 47.737999 -297.628355) (xy 47.68978 -297.618511) (xy 47.643764 -297.601059) (xy 47.601143 -297.576452)
			(xy 47.563022 -297.545327) (xy 47.530387 -297.50849) (xy 47.504084 -297.466894) (xy 47.484793 -297.421618)
			(xy 47.473016 -297.373834) (xy 47.469056 -297.32478) (xy 47.130208 -297.32478) (xy 47.129713 -297.349387)
			(xy 47.121818 -297.397964) (xy 47.106234 -297.444645) (xy 47.083363 -297.488222) (xy 47.053798 -297.527566)
			(xy 47.018305 -297.561658) (xy 46.977802 -297.589614) (xy 46.93334 -297.610712) (xy 46.886069 -297.624404)
			(xy 46.837214 -297.630336) (xy 46.788039 -297.628355) (xy 46.73982 -297.618511) (xy 46.693804 -297.601059)
			(xy 46.651183 -297.576452) (xy 46.613062 -297.545327) (xy 46.580427 -297.50849) (xy 46.554124 -297.466894)
			(xy 46.534833 -297.421618) (xy 46.523056 -297.373834) (xy 46.519096 -297.32478) (xy 46.180248 -297.32478)
			(xy 46.179753 -297.349387) (xy 46.171858 -297.397964) (xy 46.156274 -297.444645) (xy 46.133403 -297.488222)
			(xy 46.103838 -297.527566) (xy 46.068345 -297.561658) (xy 46.027842 -297.589614) (xy 45.98338 -297.610712)
			(xy 45.936109 -297.624404) (xy 45.887254 -297.630336) (xy 45.838079 -297.628355) (xy 45.78986 -297.618511)
			(xy 45.743844 -297.601059) (xy 45.701223 -297.576452) (xy 45.663102 -297.545327) (xy 45.630467 -297.50849)
			(xy 45.604164 -297.466894) (xy 45.584873 -297.421618) (xy 45.573096 -297.373834) (xy 45.569136 -297.32478)
			(xy 45.230288 -297.32478) (xy 45.229793 -297.349387) (xy 45.221898 -297.397964) (xy 45.206314 -297.444645)
			(xy 45.183443 -297.488222) (xy 45.153878 -297.527566) (xy 45.118385 -297.561658) (xy 45.077882 -297.589614)
			(xy 45.03342 -297.610712) (xy 44.986149 -297.624404) (xy 44.937294 -297.630336) (xy 44.888119 -297.628355)
			(xy 44.8399 -297.618511) (xy 44.793884 -297.601059) (xy 44.751263 -297.576452) (xy 44.713142 -297.545327)
			(xy 44.680507 -297.50849) (xy 44.654204 -297.466894) (xy 44.634913 -297.421618) (xy 44.623136 -297.373834)
			(xy 44.619176 -297.32478) (xy 44.280074 -297.32478) (xy 44.279579 -297.349387) (xy 44.271684 -297.397964)
			(xy 44.2561 -297.444645) (xy 44.233229 -297.488222) (xy 44.203664 -297.527566) (xy 44.168171 -297.561658)
			(xy 44.127668 -297.589614) (xy 44.083206 -297.610712) (xy 44.035935 -297.624404) (xy 43.98708 -297.630336)
			(xy 43.937905 -297.628355) (xy 43.889686 -297.618511) (xy 43.84367 -297.601059) (xy 43.801049 -297.576452)
			(xy 43.762928 -297.545327) (xy 43.730293 -297.50849) (xy 43.70399 -297.466894) (xy 43.684699 -297.421618)
			(xy 43.672922 -297.373834) (xy 43.668962 -297.32478) (xy 42.380154 -297.32478) (xy 42.379659 -297.349387)
			(xy 42.371764 -297.397964) (xy 42.35618 -297.444645) (xy 42.333309 -297.488222) (xy 42.303744 -297.527566)
			(xy 42.268251 -297.561658) (xy 42.227748 -297.589614) (xy 42.183286 -297.610712) (xy 42.136015 -297.624404)
			(xy 42.08716 -297.630336) (xy 42.037985 -297.628355) (xy 41.989766 -297.618511) (xy 41.94375 -297.601059)
			(xy 41.901129 -297.576452) (xy 41.863008 -297.545327) (xy 41.830373 -297.50849) (xy 41.80407 -297.466894)
			(xy 41.784779 -297.421618) (xy 41.773002 -297.373834) (xy 41.769042 -297.32478) (xy 39.530274 -297.32478)
			(xy 39.529779 -297.349387) (xy 39.521884 -297.397964) (xy 39.5063 -297.444645) (xy 39.483429 -297.488222)
			(xy 39.453864 -297.527566) (xy 39.418371 -297.561658) (xy 39.377868 -297.589614) (xy 39.333406 -297.610712)
			(xy 39.286135 -297.624404) (xy 39.23728 -297.630336) (xy 39.188105 -297.628355) (xy 39.139886 -297.618511)
			(xy 39.09387 -297.601059) (xy 39.051249 -297.576452) (xy 39.013128 -297.545327) (xy 38.980493 -297.50849)
			(xy 38.95419 -297.466894) (xy 38.934899 -297.421618) (xy 38.923122 -297.373834) (xy 38.919162 -297.32478)
			(xy 38.58006 -297.32478) (xy 38.579565 -297.349387) (xy 38.57167 -297.397964) (xy 38.556086 -297.444645)
			(xy 38.533215 -297.488222) (xy 38.50365 -297.527566) (xy 38.468157 -297.561658) (xy 38.427654 -297.589614)
			(xy 38.383192 -297.610712) (xy 38.335921 -297.624404) (xy 38.287066 -297.630336) (xy 38.237891 -297.628355)
			(xy 38.189672 -297.618511) (xy 38.143656 -297.601059) (xy 38.101035 -297.576452) (xy 38.062914 -297.545327)
			(xy 38.030279 -297.50849) (xy 38.003976 -297.466894) (xy 37.984685 -297.421618) (xy 37.972908 -297.373834)
			(xy 37.968948 -297.32478) (xy 37.654679 -297.32478) (xy 37.654679 -297.350784) (xy 37.64655 -297.402111)
			(xy 37.630492 -297.451536) (xy 37.606901 -297.49784) (xy 37.576357 -297.539884) (xy 37.539613 -297.576632)
			(xy 37.497572 -297.607181) (xy 37.451271 -297.630778) (xy 37.401848 -297.646841) (xy 37.350522 -297.654976)
			(xy 37.324538 -297.655488) (xy 36.374578 -297.655488) (xy 36.350206 -297.655043) (xy 36.301987 -297.647903)
			(xy 36.255338 -297.633766) (xy 36.211267 -297.612937) (xy 36.17073 -297.585868) (xy 36.134603 -297.553144)
			(xy 36.1188 -297.534584) (xy 36.111434 -297.525694) (xy 36.09213 -297.516296) (xy 35.992562 -297.513502)
			(xy 35.97275 -297.522138) (xy 35.96513 -297.530266) (xy 35.947651 -297.548698) (xy 35.907685 -297.580046)
			(xy 35.86308 -297.604346) (xy 35.815069 -297.620927) (xy 35.764975 -297.629331) (xy 35.739578 -297.629834)
			(xy 35.714326 -297.629259) (xy 35.664511 -297.620943) (xy 35.616745 -297.604542) (xy 35.572329 -297.580502)
			(xy 35.532475 -297.54948) (xy 35.498271 -297.512322) (xy 35.470649 -297.470041) (xy 35.450363 -297.42379)
			(xy 35.437965 -297.374832) (xy 35.433795 -297.3245) (xy 31.188914 -297.3245) (xy 31.188914 -298.078652)
			(xy 31.189347 -298.088718) (xy 31.197076 -298.107307) (xy 31.2039 -298.11472) (xy 31.45536 -298.36618)
			(xy 31.462761 -298.373019) (xy 31.481359 -298.380735) (xy 31.491428 -298.381166) (xy 36.91763 -298.381166)
			(xy 36.927697 -298.380737) (xy 36.94629 -298.373011) (xy 36.953698 -298.36618) (xy 37.011864 -298.307252)
			(xy 37.019484 -298.28871) (xy 37.01923 -298.278296) (xy 37.01923 -298.27474) (xy 37.019752 -298.249485)
			(xy 37.028065 -298.199663) (xy 37.044466 -298.151889) (xy 37.068507 -298.107466) (xy 37.099531 -298.067606)
			(xy 37.136693 -298.033396) (xy 37.178979 -298.00577) (xy 37.225235 -297.98548) (xy 37.2742 -297.97308)
			(xy 37.324538 -297.968909) (xy 37.374876 -297.97308) (xy 37.423841 -297.98548) (xy 37.470097 -298.00577)
			(xy 37.512383 -298.033396) (xy 37.549545 -298.067606) (xy 37.580569 -298.107466) (xy 37.60461 -298.151889)
			(xy 37.621011 -298.199663) (xy 37.629324 -298.249485) (xy 37.629846 -298.27474) (xy 37.629846 -298.278296)
			(xy 37.629592 -298.28871) (xy 37.637212 -298.307252) (xy 37.695378 -298.36618) (xy 37.70278 -298.373016)
			(xy 37.721378 -298.380725) (xy 37.731446 -298.381166) (xy 37.867844 -298.381166) (xy 37.87791 -298.380734)
			(xy 37.8965 -298.373005) (xy 37.903912 -298.36618) (xy 37.962078 -298.307252) (xy 37.969698 -298.28871)
			(xy 37.969444 -298.278296) (xy 37.969444 -298.27474) (xy 37.969966 -298.249485) (xy 37.978279 -298.199663)
			(xy 37.99468 -298.151889) (xy 38.018721 -298.107466) (xy 38.049745 -298.067606) (xy 38.086907 -298.033396)
			(xy 38.129193 -298.00577) (xy 38.175449 -297.98548) (xy 38.224414 -297.97308) (xy 38.274752 -297.968909)
			(xy 38.32509 -297.97308) (xy 38.374055 -297.98548) (xy 38.420311 -298.00577) (xy 38.462597 -298.033396)
			(xy 38.499759 -298.067606) (xy 38.530783 -298.107466) (xy 38.554824 -298.151889) (xy 38.571225 -298.199663)
			(xy 38.579538 -298.249485) (xy 38.58006 -298.27474) (xy 38.58006 -298.278296) (xy 38.579806 -298.28871)
			(xy 38.587426 -298.307252) (xy 38.645592 -298.36618) (xy 38.652989 -298.37303) (xy 38.671587 -298.38077)
			(xy 38.68166 -298.381166) (xy 38.818058 -298.381166) (xy 38.828123 -298.380732) (xy 38.846709 -298.372999)
			(xy 38.854126 -298.36618) (xy 38.912292 -298.307252) (xy 38.919912 -298.28871) (xy 38.919658 -298.278296)
			(xy 38.919658 -298.27474) (xy 38.92018 -298.249485) (xy 38.928493 -298.199663) (xy 38.944894 -298.151889)
			(xy 38.968935 -298.107466) (xy 38.999959 -298.067606) (xy 39.037121 -298.033396) (xy 39.079407 -298.00577)
			(xy 39.125663 -297.98548) (xy 39.174628 -297.97308) (xy 39.224966 -297.968909) (xy 39.275304 -297.97308)
			(xy 39.324269 -297.98548) (xy 39.370525 -298.00577) (xy 39.412811 -298.033396) (xy 39.449973 -298.067606)
			(xy 39.480997 -298.107466) (xy 39.505038 -298.151889) (xy 39.521439 -298.199663) (xy 39.529752 -298.249485)
			(xy 39.530274 -298.27474) (xy 39.530274 -298.278296) (xy 39.53002 -298.28871) (xy 39.53764 -298.307252)
			(xy 39.595806 -298.36618) (xy 39.603204 -298.373028) (xy 39.621802 -298.380763) (xy 39.631874 -298.381166)
			(xy 39.768018 -298.381166) (xy 39.778086 -298.380739) (xy 39.796683 -298.373016) (xy 39.804086 -298.36618)
			(xy 39.862252 -298.307252) (xy 39.869872 -298.28871) (xy 39.869618 -298.278296) (xy 39.869618 -298.27474)
			(xy 39.87014 -298.249485) (xy 39.878453 -298.199663) (xy 39.894854 -298.151889) (xy 39.918895 -298.107466)
			(xy 39.949919 -298.067606) (xy 39.987081 -298.033396) (xy 40.029367 -298.00577) (xy 40.075623 -297.98548)
			(xy 40.124588 -297.97308) (xy 40.174926 -297.968909) (xy 40.225264 -297.97308) (xy 40.274229 -297.98548)
			(xy 40.320485 -298.00577) (xy 40.362771 -298.033396) (xy 40.399933 -298.067606) (xy 40.430957 -298.107466)
			(xy 40.454998 -298.151889) (xy 40.471399 -298.199663) (xy 40.479712 -298.249485) (xy 40.480234 -298.27474)
			(xy 40.480234 -298.278296) (xy 40.47998 -298.28871) (xy 40.4876 -298.307252) (xy 40.545766 -298.36618)
			(xy 40.553167 -298.373018) (xy 40.571766 -298.380732) (xy 40.581834 -298.381166) (xy 40.717978 -298.381166)
			(xy 40.728041 -298.380728) (xy 40.746622 -298.37299) (xy 40.754046 -298.36618) (xy 40.812212 -298.307252)
			(xy 40.819832 -298.28871) (xy 40.819578 -298.278296) (xy 40.819578 -298.27474) (xy 40.8201 -298.249485)
			(xy 40.828413 -298.199663) (xy 40.844814 -298.151889) (xy 40.868855 -298.107466) (xy 40.899879 -298.067606)
			(xy 40.937041 -298.033396) (xy 40.979327 -298.00577) (xy 41.025583 -297.98548) (xy 41.074548 -297.97308)
			(xy 41.124886 -297.968909) (xy 41.175224 -297.97308) (xy 41.224189 -297.98548) (xy 41.270445 -298.00577)
			(xy 41.312731 -298.033396) (xy 41.349893 -298.067606) (xy 41.380917 -298.107466) (xy 41.404958 -298.151889)
			(xy 41.421359 -298.199663) (xy 41.429672 -298.249485) (xy 41.430194 -298.27474) (xy 41.430194 -298.278296)
			(xy 41.42994 -298.28871) (xy 41.43756 -298.307252) (xy 41.495726 -298.36618) (xy 41.503125 -298.373025)
			(xy 41.521723 -298.380753) (xy 41.531794 -298.381166) (xy 41.667938 -298.381166) (xy 41.678004 -298.380735)
			(xy 41.696596 -298.373007) (xy 41.704006 -298.36618) (xy 41.762172 -298.307252) (xy 41.769792 -298.28871)
			(xy 41.769538 -298.278296) (xy 41.769538 -298.27474) (xy 41.77006 -298.249485) (xy 41.778373 -298.199663)
			(xy 41.794774 -298.151889) (xy 41.818815 -298.107466) (xy 41.849839 -298.067606) (xy 41.887001 -298.033396)
			(xy 41.929287 -298.00577) (xy 41.975543 -297.98548) (xy 42.024508 -297.97308) (xy 42.074846 -297.968909)
			(xy 42.125184 -297.97308) (xy 42.174149 -297.98548) (xy 42.220405 -298.00577) (xy 42.262691 -298.033396)
			(xy 42.299853 -298.067606) (xy 42.330877 -298.107466) (xy 42.354918 -298.151889) (xy 42.371319 -298.199663)
			(xy 42.379632 -298.249485) (xy 42.380154 -298.27474) (xy 42.380154 -298.278296) (xy 42.3799 -298.28871)
			(xy 42.38752 -298.307252) (xy 42.445686 -298.36618) (xy 42.453088 -298.373015) (xy 42.471687 -298.380721)
			(xy 42.481754 -298.381166) (xy 43.567858 -298.381166) (xy 43.577923 -298.380732) (xy 43.596509 -298.372999)
			(xy 43.603926 -298.36618) (xy 43.662092 -298.307252) (xy 43.669712 -298.28871) (xy 43.669458 -298.278296)
			(xy 43.669458 -298.27474) (xy 43.66998 -298.249485) (xy 43.678293 -298.199663) (xy 43.694694 -298.151889)
			(xy 43.718735 -298.107466) (xy 43.749759 -298.067606) (xy 43.786921 -298.033396) (xy 43.829207 -298.00577)
			(xy 43.875463 -297.98548) (xy 43.924428 -297.97308) (xy 43.974766 -297.968909) (xy 44.025104 -297.97308)
			(xy 44.074069 -297.98548) (xy 44.120325 -298.00577) (xy 44.162611 -298.033396) (xy 44.199773 -298.067606)
			(xy 44.230797 -298.107466) (xy 44.254838 -298.151889) (xy 44.271239 -298.199663) (xy 44.279552 -298.249485)
			(xy 44.280074 -298.27474) (xy 44.280074 -298.278296) (xy 44.27982 -298.28871) (xy 44.28744 -298.307252)
			(xy 44.345606 -298.36618) (xy 44.353004 -298.373028) (xy 44.371602 -298.380763) (xy 44.381674 -298.381166)
			(xy 44.518072 -298.381166) (xy 44.528136 -298.380729) (xy 44.546718 -298.372992) (xy 44.55414 -298.36618)
			(xy 44.612306 -298.307252) (xy 44.619926 -298.28871) (xy 44.619672 -298.278296) (xy 44.619672 -298.27474)
			(xy 44.620194 -298.249485) (xy 44.628507 -298.199663) (xy 44.644908 -298.151889) (xy 44.668949 -298.107466)
			(xy 44.699973 -298.067606) (xy 44.737135 -298.033396) (xy 44.779421 -298.00577) (xy 44.825677 -297.98548)
			(xy 44.874642 -297.97308) (xy 44.92498 -297.968909) (xy 44.975318 -297.97308) (xy 45.024283 -297.98548)
			(xy 45.070539 -298.00577) (xy 45.112825 -298.033396) (xy 45.149987 -298.067606) (xy 45.181011 -298.107466)
			(xy 45.205052 -298.151889) (xy 45.221453 -298.199663) (xy 45.229766 -298.249485) (xy 45.230288 -298.27474)
			(xy 45.230288 -298.278296) (xy 45.230034 -298.28871) (xy 45.237654 -298.307252) (xy 45.29582 -298.36618)
			(xy 45.303219 -298.373025) (xy 45.321817 -298.380756) (xy 45.331888 -298.381166) (xy 45.468032 -298.381166)
			(xy 45.478099 -298.380736) (xy 45.496692 -298.37301) (xy 45.5041 -298.36618) (xy 45.562266 -298.307252)
			(xy 45.569886 -298.28871) (xy 45.569632 -298.278296) (xy 45.569632 -298.27474) (xy 45.570154 -298.249485)
			(xy 45.578467 -298.199663) (xy 45.594868 -298.151889) (xy 45.618909 -298.107466) (xy 45.649933 -298.067606)
			(xy 45.687095 -298.033396) (xy 45.729381 -298.00577) (xy 45.775637 -297.98548) (xy 45.824602 -297.97308)
			(xy 45.87494 -297.968909) (xy 45.925278 -297.97308) (xy 45.974243 -297.98548) (xy 46.020499 -298.00577)
			(xy 46.062785 -298.033396) (xy 46.099947 -298.067606) (xy 46.130971 -298.107466) (xy 46.155012 -298.151889)
			(xy 46.171413 -298.199663) (xy 46.179726 -298.249485) (xy 46.180248 -298.27474) (xy 46.180248 -298.278296)
			(xy 46.179994 -298.28871) (xy 46.187614 -298.307252) (xy 46.24578 -298.36618) (xy 46.253182 -298.373016)
			(xy 46.27178 -298.380724) (xy 46.281848 -298.381166) (xy 46.417992 -298.381166) (xy 46.428062 -298.380744)
			(xy 46.446666 -298.373027) (xy 46.45406 -298.36618) (xy 46.512226 -298.307252) (xy 46.519846 -298.28871)
			(xy 46.519592 -298.278296) (xy 46.519592 -298.27474) (xy 46.520114 -298.249485) (xy 46.528427 -298.199663)
			(xy 46.544828 -298.151889) (xy 46.568869 -298.107466) (xy 46.599893 -298.067606) (xy 46.637055 -298.033396)
			(xy 46.679341 -298.00577) (xy 46.725597 -297.98548) (xy 46.774562 -297.97308) (xy 46.8249 -297.968909)
			(xy 46.875238 -297.97308) (xy 46.924203 -297.98548) (xy 46.970459 -298.00577) (xy 47.012745 -298.033396)
			(xy 47.049907 -298.067606) (xy 47.080931 -298.107466) (xy 47.104972 -298.151889) (xy 47.121373 -298.199663)
			(xy 47.129686 -298.249485) (xy 47.130208 -298.27474) (xy 47.469056 -298.27474) (xy 47.473016 -298.225686)
			(xy 47.484793 -298.177902) (xy 47.504084 -298.132626) (xy 47.530387 -298.09103) (xy 47.563022 -298.054193)
			(xy 47.601143 -298.023068) (xy 47.643764 -297.998461) (xy 47.68978 -297.981009) (xy 47.737999 -297.971165)
			(xy 47.787174 -297.969184) (xy 47.836029 -297.975116) (xy 47.8833 -297.988808) (xy 47.927762 -298.009906)
			(xy 47.968265 -298.037862) (xy 48.003758 -298.071954) (xy 48.033323 -298.111298) (xy 48.056194 -298.154875)
			(xy 48.071778 -298.201556) (xy 48.079673 -298.250133) (xy 48.080168 -298.27474) (xy 48.419016 -298.27474)
			(xy 48.422976 -298.225686) (xy 48.434753 -298.177902) (xy 48.454044 -298.132626) (xy 48.480347 -298.09103)
			(xy 48.512982 -298.054193) (xy 48.551103 -298.023068) (xy 48.593724 -297.998461) (xy 48.63974 -297.981009)
			(xy 48.687959 -297.971165) (xy 48.737134 -297.969184) (xy 48.785989 -297.975116) (xy 48.83326 -297.988808)
			(xy 48.877722 -298.009906) (xy 48.918225 -298.037862) (xy 48.953718 -298.071954) (xy 48.983283 -298.111298)
			(xy 49.006154 -298.154875) (xy 49.021738 -298.201556) (xy 49.029633 -298.250133) (xy 49.030128 -298.27474)
			(xy 49.029633 -298.299347) (xy 49.021738 -298.347924) (xy 49.006154 -298.394605) (xy 48.983283 -298.438182)
			(xy 48.953718 -298.477526) (xy 48.918225 -298.511618) (xy 48.877722 -298.539574) (xy 48.83326 -298.560672)
			(xy 48.785989 -298.574364) (xy 48.737134 -298.580296) (xy 48.687959 -298.578315) (xy 48.63974 -298.568471)
			(xy 48.593724 -298.551019) (xy 48.551103 -298.526412) (xy 48.512982 -298.495287) (xy 48.480347 -298.45845)
			(xy 48.454044 -298.416854) (xy 48.434753 -298.371578) (xy 48.422976 -298.323794) (xy 48.419016 -298.27474)
			(xy 48.080168 -298.27474) (xy 48.079673 -298.299347) (xy 48.071778 -298.347924) (xy 48.056194 -298.394605)
			(xy 48.033323 -298.438182) (xy 48.003758 -298.477526) (xy 47.968265 -298.511618) (xy 47.927762 -298.539574)
			(xy 47.8833 -298.560672) (xy 47.836029 -298.574364) (xy 47.787174 -298.580296) (xy 47.737999 -298.578315)
			(xy 47.68978 -298.568471) (xy 47.643764 -298.551019) (xy 47.601143 -298.526412) (xy 47.563022 -298.495287)
			(xy 47.530387 -298.45845) (xy 47.504084 -298.416854) (xy 47.484793 -298.371578) (xy 47.473016 -298.323794)
			(xy 47.469056 -298.27474) (xy 47.130208 -298.27474) (xy 47.129792 -298.29778) (xy 47.122874 -298.343337)
			(xy 47.109186 -298.387336) (xy 47.08904 -298.428778) (xy 47.062892 -298.46672) (xy 47.047404 -298.483782)
			(xy 47.033434 -298.498768) (xy 47.033942 -298.539662) (xy 47.242476 -298.748196) (xy 47.249326 -298.755593)
			(xy 47.257065 -298.774191) (xy 47.257462 -298.784264) (xy 47.257462 -298.965874) (xy 47.257996 -298.975862)
			(xy 47.26571 -298.994295) (xy 47.272448 -299.001688) (xy 47.27575 -299.005244) (xy 47.282559 -299.012589)
			(xy 47.290283 -299.031052) (xy 47.290736 -299.041058) (xy 47.290736 -299.224954) (xy 47.469056 -299.224954)
			(xy 47.473016 -299.1759) (xy 47.484793 -299.128116) (xy 47.504084 -299.08284) (xy 47.530387 -299.041244)
			(xy 47.563022 -299.004407) (xy 47.601143 -298.973282) (xy 47.643764 -298.948675) (xy 47.68978 -298.931223)
			(xy 47.737999 -298.921379) (xy 47.787174 -298.919398) (xy 47.836029 -298.92533) (xy 47.8833 -298.939022)
			(xy 47.927762 -298.96012) (xy 47.968265 -298.988076) (xy 48.003758 -299.022168) (xy 48.033323 -299.061512)
			(xy 48.056194 -299.105089) (xy 48.071778 -299.15177) (xy 48.079673 -299.200347) (xy 48.080168 -299.224954)
			(xy 48.419016 -299.224954) (xy 48.422976 -299.1759) (xy 48.434753 -299.128116) (xy 48.454044 -299.08284)
			(xy 48.480347 -299.041244) (xy 48.512982 -299.004407) (xy 48.551103 -298.973282) (xy 48.593724 -298.948675)
			(xy 48.63974 -298.931223) (xy 48.687959 -298.921379) (xy 48.737134 -298.919398) (xy 48.785989 -298.92533)
			(xy 48.83326 -298.939022) (xy 48.877722 -298.96012) (xy 48.918225 -298.988076) (xy 48.953718 -299.022168)
			(xy 48.983283 -299.061512) (xy 49.006154 -299.105089) (xy 49.021738 -299.15177) (xy 49.029633 -299.200347)
			(xy 49.030128 -299.224954) (xy 49.029633 -299.249561) (xy 49.021738 -299.298138) (xy 49.006154 -299.344819)
			(xy 48.983283 -299.388396) (xy 48.953718 -299.42774) (xy 48.918225 -299.461832) (xy 48.877722 -299.489788)
			(xy 48.83326 -299.510886) (xy 48.785989 -299.524578) (xy 48.737134 -299.53051) (xy 48.687959 -299.528529)
			(xy 48.63974 -299.518685) (xy 48.593724 -299.501233) (xy 48.551103 -299.476626) (xy 48.512982 -299.445501)
			(xy 48.480347 -299.408664) (xy 48.454044 -299.367068) (xy 48.434753 -299.321792) (xy 48.422976 -299.274008)
			(xy 48.419016 -299.224954) (xy 48.080168 -299.224954) (xy 48.079673 -299.249561) (xy 48.071778 -299.298138)
			(xy 48.056194 -299.344819) (xy 48.033323 -299.388396) (xy 48.003758 -299.42774) (xy 47.968265 -299.461832)
			(xy 47.927762 -299.489788) (xy 47.8833 -299.510886) (xy 47.836029 -299.524578) (xy 47.787174 -299.53051)
			(xy 47.737999 -299.528529) (xy 47.68978 -299.518685) (xy 47.643764 -299.501233) (xy 47.601143 -299.476626)
			(xy 47.563022 -299.445501) (xy 47.530387 -299.408664) (xy 47.504084 -299.367068) (xy 47.484793 -299.321792)
			(xy 47.473016 -299.274008) (xy 47.469056 -299.224954) (xy 47.290736 -299.224954) (xy 47.290736 -300.76648)
			(xy 47.291226 -300.77644) (xy 47.298821 -300.794858) (xy 47.305468 -300.802294) (xy 47.443644 -300.94047)
			(xy 47.451044 -300.947313) (xy 47.469642 -300.955036) (xy 47.479712 -300.955456) (xy 47.506636 -300.955456)
		)
		(stroke
			(width 0)
			(type solid)
		)
		(fill yes)
		(layer "In9.Cu")
		(net "PCEPLL0_VDDA18_PEX0")
	)
	(gr_poly
		(pts
			(xy 46.47819 -70.178676) (xy 46.488261 -70.178254) (xy 46.506865 -70.17054) (xy 46.514258 -70.16369)
			(xy 46.840394 -69.837554) (xy 46.840902 -69.837046) (xy 46.84749 -69.829667) (xy 46.854947 -69.811367)
			(xy 46.85538 -69.801486) (xy 46.85538 -67.91579) (xy 46.854984 -67.906267) (xy 46.848029 -67.888536)
			(xy 46.835082 -67.874566) (xy 46.826678 -67.87007) (xy 46.73092 -67.823842) (xy 46.702218 -67.827144)
			(xy 46.690534 -67.836288) (xy 46.670222 -67.851901) (xy 46.626208 -67.87812) (xy 46.579079 -67.898209)
			(xy 46.529684 -67.911806) (xy 46.478914 -67.918666) (xy 46.453298 -67.919092) (xy 46.426048 -67.918606)
			(xy 46.372103 -67.910849) (xy 46.319811 -67.895495) (xy 46.270236 -67.872854) (xy 46.224388 -67.843389)
			(xy 46.183199 -67.807699) (xy 46.14751 -67.766511) (xy 46.118045 -67.720662) (xy 46.095405 -67.671088)
			(xy 46.08005 -67.618795) (xy 46.072294 -67.56485) (xy 46.072294 -67.51035) (xy 46.08005 -67.456405)
			(xy 46.095405 -67.404112) (xy 46.118045 -67.354538) (xy 46.14751 -67.308689) (xy 46.183199 -67.267501)
			(xy 46.224388 -67.231811) (xy 46.270236 -67.202346) (xy 46.319811 -67.179705) (xy 46.372103 -67.164351)
			(xy 46.426048 -67.156594) (xy 46.453298 -67.156076) (xy 46.478914 -67.156491) (xy 46.529685 -67.163352)
			(xy 46.57908 -67.176952) (xy 46.626209 -67.197044) (xy 46.670221 -67.223267) (xy 46.690534 -67.23888)
			(xy 46.702218 -67.248024) (xy 46.73092 -67.251326) (xy 46.826678 -67.205098) (xy 46.835077 -67.200596)
			(xy 46.848017 -67.186624) (xy 46.854979 -67.168899) (xy 46.85538 -67.159378) (xy 46.85538 -65.506854)
			(xy 46.841664 -65.483486) (xy 46.830234 -65.476628) (xy 46.829726 -65.476628) (xy 46.756574 -65.433702)
			(xy 46.752181 -65.43132) (xy 46.742715 -65.428127) (xy 46.737778 -65.427352) (xy 46.727364 -65.426082)
			(xy 46.703742 -65.432432) (xy 46.698154 -65.43548) (xy 46.669869 -65.450258) (xy 46.609593 -65.471208)
			(xy 46.546672 -65.481837) (xy 46.514766 -65.48247) (xy 46.514512 -65.48247) (xy 46.487261 -65.482008)
			(xy 46.433314 -65.474253) (xy 46.38102 -65.458899) (xy 46.331444 -65.43626) (xy 46.285594 -65.406795)
			(xy 46.244404 -65.371105) (xy 46.208712 -65.329916) (xy 46.179246 -65.284067) (xy 46.156605 -65.234491)
			(xy 46.14125 -65.182197) (xy 46.133493 -65.128251) (xy 46.133493 -65.073749) (xy 46.14125 -65.019803)
			(xy 46.156605 -64.967509) (xy 46.179246 -64.917933) (xy 46.208712 -64.872084) (xy 46.244404 -64.830895)
			(xy 46.285594 -64.795205) (xy 46.331444 -64.76574) (xy 46.38102 -64.743101) (xy 46.433314 -64.727747)
			(xy 46.487261 -64.719992) (xy 46.514512 -64.719454) (xy 46.514766 -64.719454) (xy 46.546668 -64.720123)
			(xy 46.609581 -64.730767) (xy 46.669856 -64.751698) (xy 46.698154 -64.766444) (xy 46.703742 -64.769492)
			(xy 46.717458 -64.773302) (xy 46.722443 -64.774517) (xy 46.732682 -64.775166) (xy 46.737778 -64.774572)
			(xy 46.747684 -64.773302) (xy 46.82998 -64.725296) (xy 46.830742 -64.724788) (xy 46.83802 -64.719974)
			(xy 46.849067 -64.70648) (xy 46.854973 -64.690071) (xy 46.85538 -64.681354) (xy 46.85538 -52.63261)
			(xy 46.854872 -52.626006) (xy 46.853602 -52.615592) (xy 46.85284 -52.612798) (xy 46.847127 -52.589272)
			(xy 46.841015 -52.541247) (xy 46.840648 -52.51704) (xy 46.840648 -52.499514) (xy 46.840902 -52.49418)
			(xy 46.84268 -52.477162) (xy 46.84395 -52.46624) (xy 46.846236 -52.44973) (xy 46.847252 -52.444904)
			(xy 46.847252 -52.44465) (xy 46.851316 -52.427378) (xy 46.852586 -52.422552) (xy 46.852586 -52.421536)
			(xy 46.853602 -52.418234) (xy 46.85538 -52.41163) (xy 46.85538 -51.455828) (xy 46.855816 -51.445763)
			(xy 46.863546 -51.427176) (xy 46.870366 -51.41976) (xy 46.9773 -51.312826) (xy 46.984697 -51.305977)
			(xy 47.003296 -51.298238) (xy 47.013368 -51.29784) (xy 47.70374 -51.29784) (xy 47.712122 -51.297078)
			(xy 47.719725 -51.29556) (xy 47.733552 -51.288566) (xy 47.7393 -51.283362) (xy 47.804324 -51.218338)
			(xy 47.811012 -51.210929) (xy 47.818604 -51.192494) (xy 47.819056 -51.182524) (xy 47.819056 -49.18456)
			(xy 47.789592 -49.154842) (xy 47.784004 -49.154842) (xy 47.729648 -49.116742) (xy 47.723811 -49.112967)
			(xy 47.710665 -49.108463) (xy 47.70374 -49.107852) (xy 47.692818 -49.10709) (xy 47.681388 -49.111408)
			(xy 47.674784 -49.113694) (xy 47.6446 -49.123448) (xy 47.58204 -49.133917) (xy 47.550324 -49.134522)
			(xy 47.54626 -49.134522) (xy 47.519199 -49.133762) (xy 47.465693 -49.125541) (xy 47.413886 -49.109838)
			(xy 47.36482 -49.086968) (xy 47.31948 -49.057391) (xy 47.278778 -49.021701) (xy 47.24353 -48.980615)
			(xy 47.214445 -48.934957) (xy 47.192107 -48.885647) (xy 47.176965 -48.833673) (xy 47.169324 -48.780081)
			(xy 47.168816 -48.753014) (xy 47.169278 -48.725761) (xy 47.177034 -48.67181) (xy 47.192389 -48.619512)
			(xy 47.215031 -48.569931) (xy 47.244499 -48.524078) (xy 47.280193 -48.482886) (xy 47.321386 -48.447193)
			(xy 47.36724 -48.417726) (xy 47.416821 -48.395085) (xy 47.46912 -48.379732) (xy 47.523071 -48.371978)
			(xy 47.550324 -48.371506) (xy 47.551086 -48.371506) (xy 47.582605 -48.372219) (xy 47.644771 -48.382684)
			(xy 47.674784 -48.392334) (xy 47.682658 -48.395128) (xy 47.70501 -48.395128) (xy 47.712806 -48.394894)
			(xy 47.727684 -48.390241) (xy 47.73422 -48.385984) (xy 47.797212 -48.342042) (xy 47.803054 -48.337216)
			(xy 47.803308 -48.336962) (xy 47.810467 -48.329486) (xy 47.818596 -48.310473) (xy 47.819056 -48.300132)
			(xy 47.819056 -41.95445) (xy 47.818571 -41.944487) (xy 47.810983 -41.926063) (xy 47.804324 -41.918636)
			(xy 46.923706 -41.038018) (xy 46.916594 -41.030652) (xy 46.897798 -41.023032) (xy 45.116242 -41.023032)
			(xy 45.107544 -41.023391) (xy 45.091153 -41.029216) (xy 45.077646 -41.040179) (xy 45.072808 -41.047416)
			(xy 45.02785 -41.121584) (xy 45.023786 -41.13022) (xy 45.020462 -41.140527) (xy 45.021893 -41.162115)
			(xy 45.02658 -41.171876) (xy 45.027342 -41.1734) (xy 45.03166 -41.18229) (xy 45.043737 -41.208261)
			(xy 45.060849 -41.262919) (xy 45.069619 -41.319517) (xy 45.070268 -41.348152) (xy 45.070268 -41.34866)
			(xy 45.070268 -41.35501) (xy 45.069357 -41.383073) (xy 45.060312 -41.438488) (xy 45.043242 -41.491978)
			(xy 45.018517 -41.542388) (xy 44.98667 -41.58863) (xy 44.967906 -41.609518) (xy 44.967652 -41.609772)
			(xy 44.961175 -41.617125) (xy 44.95387 -41.635288) (xy 44.953428 -41.645078) (xy 44.953428 -41.724072)
			(xy 44.960286 -41.741852) (xy 44.967144 -41.748964) (xy 44.986415 -41.77029) (xy 45.018979 -41.817651)
			(xy 45.04407 -41.869362) (xy 45.061118 -41.924252) (xy 45.069739 -41.981078) (xy 45.069737 -42.038554)
			(xy 45.061111 -42.09538) (xy 45.044058 -42.150268) (xy 45.018963 -42.201977) (xy 44.986394 -42.249335)
			(xy 44.967144 -42.27068) (xy 44.960286 -42.277792) (xy 44.953428 -42.295572) (xy 44.953428 -42.384472)
			(xy 44.960286 -42.402252) (xy 44.967144 -42.409364) (xy 44.98641 -42.430693) (xy 45.018967 -42.478057)
			(xy 45.044051 -42.52977) (xy 45.061095 -42.584659) (xy 45.069713 -42.641485) (xy 45.070268 -42.670222)
			(xy 45.069795 -42.697591) (xy 45.061967 -42.751768) (xy 45.046477 -42.804269) (xy 45.023641 -42.854017)
			(xy 44.993929 -42.89999) (xy 44.976288 -42.92092) (xy 44.970192 -42.928032) (xy 44.963842 -42.944796)
			(xy 44.963842 -43.030648) (xy 44.970192 -43.047412) (xy 44.976288 -43.054524) (xy 44.993929 -43.075456)
			(xy 45.023653 -43.121422) (xy 45.046494 -43.171169) (xy 45.061981 -43.223673) (xy 45.069797 -43.277852)
			(xy 45.070268 -43.305222) (xy 45.069782 -43.332473) (xy 45.062026 -43.386421) (xy 45.046671 -43.438716)
			(xy 45.024029 -43.488293) (xy 44.994563 -43.534143) (xy 44.958872 -43.575334) (xy 44.917681 -43.611025)
			(xy 44.871831 -43.640491) (xy 44.822254 -43.663133) (xy 44.769959 -43.678488) (xy 44.716011 -43.686244)
			(xy 44.661509 -43.686244) (xy 44.607561 -43.678488) (xy 44.555266 -43.663133) (xy 44.505689 -43.640491)
			(xy 44.459839 -43.611025) (xy 44.418648 -43.575334) (xy 44.382957 -43.534143) (xy 44.353491 -43.488293)
			(xy 44.330849 -43.438716) (xy 44.315494 -43.386421) (xy 44.307738 -43.332473) (xy 44.307252 -43.305222)
			(xy 44.307729 -43.277854) (xy 44.315564 -43.223682) (xy 44.331061 -43.171186) (xy 44.353903 -43.121444)
			(xy 44.38362 -43.075478) (xy 44.401232 -43.054524) (xy 44.407328 -43.047412) (xy 44.413678 -43.030648)
			(xy 44.413678 -42.944796) (xy 44.407328 -42.928032) (xy 44.401232 -42.92092) (xy 44.383588 -42.89999)
			(xy 44.353857 -42.854024) (xy 44.331009 -42.804278) (xy 44.315515 -42.751774) (xy 44.307692 -42.697593)
			(xy 44.307252 -42.670222) (xy 44.307771 -42.641483) (xy 44.316392 -42.584654) (xy 44.333442 -42.529762)
			(xy 44.358534 -42.47805) (xy 44.391101 -42.430688) (xy 44.410376 -42.409364) (xy 44.417234 -42.402252)
			(xy 44.424092 -42.384472) (xy 44.424092 -42.295572) (xy 44.417234 -42.277792) (xy 44.410376 -42.27068)
			(xy 44.391106 -42.249352) (xy 44.358541 -42.201988) (xy 44.33345 -42.150275) (xy 44.316399 -42.095384)
			(xy 44.307775 -42.038555) (xy 44.307772 -41.981077) (xy 44.316392 -41.924248) (xy 44.333438 -41.869355)
			(xy 44.358525 -41.81764) (xy 44.391086 -41.770273) (xy 44.410376 -41.748964) (xy 44.417234 -41.741852)
			(xy 44.424092 -41.724072) (xy 44.424092 -41.635172) (xy 44.417234 -41.617646) (xy 44.410376 -41.61028)
			(xy 44.391574 -41.589487) (xy 44.359641 -41.543415) (xy 44.334784 -41.493171) (xy 44.317535 -41.439833)
			(xy 44.308266 -41.384548) (xy 44.307252 -41.356534) (xy 44.307252 -41.349422) (xy 44.307764 -41.320528)
			(xy 44.31645 -41.263399) (xy 44.333672 -41.208238) (xy 44.34586 -41.182036) (xy 44.353226 -41.166542)
			(xy 44.356286 -41.157735) (xy 44.356552 -41.139107) (xy 44.353734 -41.13022) (xy 44.34967 -41.121584)
			(xy 44.304712 -41.04767) (xy 44.297854 -41.035986) (xy 44.27474 -41.023032) (xy 43.354244 -41.023032)
			(xy 43.342621 -41.023601) (xy 43.321722 -41.033786) (xy 43.314112 -41.04259) (xy 43.25747 -41.11498)
			(xy 43.252644 -41.137586) (xy 43.255438 -41.14927) (xy 43.260759 -41.171949) (xy 43.266489 -41.21818)
			(xy 43.266868 -41.241472) (xy 43.266407 -41.268725) (xy 43.258653 -41.322677) (xy 43.243299 -41.374976)
			(xy 43.220657 -41.424557) (xy 43.191189 -41.470411) (xy 43.155495 -41.511603) (xy 43.114301 -41.547296)
			(xy 43.068446 -41.576763) (xy 43.018865 -41.599403) (xy 42.966565 -41.614755) (xy 42.912613 -41.622507)
			(xy 42.88536 -41.62298) (xy 42.856622 -41.622456) (xy 42.799798 -41.613828) (xy 42.744911 -41.596772)
			(xy 42.693204 -41.571676) (xy 42.645846 -41.539107) (xy 42.624502 -41.519856) (xy 42.61739 -41.512998)
			(xy 42.59961 -41.50614) (xy 42.51071 -41.50614) (xy 42.49293 -41.512998) (xy 42.485818 -41.519856)
			(xy 42.464491 -41.539127) (xy 42.417128 -41.571693) (xy 42.365416 -41.596787) (xy 42.310526 -41.613842)
			(xy 42.253699 -41.622471) (xy 42.22496 -41.62298) (xy 42.197711 -41.622491) (xy 42.14377 -41.61473)
			(xy 42.091481 -41.599371) (xy 42.041911 -41.576727) (xy 41.996068 -41.547259) (xy 41.954884 -41.511567)
			(xy 41.9192 -41.470378) (xy 41.88974 -41.424529) (xy 41.867105 -41.374955) (xy 41.851756 -41.322664)
			(xy 41.844004 -41.268721) (xy 41.843452 -41.241472) (xy 41.843831 -41.21818) (xy 41.849561 -41.171949)
			(xy 41.854882 -41.14927) (xy 41.857676 -41.137586) (xy 41.85285 -41.11498) (xy 41.796208 -41.04259)
			(xy 41.788617 -41.033764) (xy 41.767706 -41.023588) (xy 41.756076 -41.023032) (xy 37.908484 -41.023032)
			(xy 37.898416 -41.023459) (xy 37.879818 -41.031181) (xy 37.872416 -41.038018) (xy 37.705792 -41.204642)
			(xy 37.699115 -41.212054) (xy 37.69155 -41.23049) (xy 37.69106 -41.240456) (xy 37.69106 -43.73626)
			(xy 46.213012 -43.73626) (xy 46.217083 -43.680638) (xy 46.229209 -43.626201) (xy 46.249132 -43.57411)
			(xy 46.276428 -43.525475) (xy 46.310514 -43.481332) (xy 46.350663 -43.442623) (xy 46.396021 -43.410172)
			(xy 46.445621 -43.384671) (xy 46.498405 -43.366664) (xy 46.553248 -43.356534) (xy 46.608982 -43.354497)
			(xy 46.664419 -43.360597) (xy 46.718376 -43.374703) (xy 46.769705 -43.396515) (xy 46.817311 -43.425569)
			(xy 46.860179 -43.461244) (xy 46.897396 -43.502781) (xy 46.928169 -43.549294) (xy 46.951841 -43.599791)
			(xy 46.967909 -43.653198) (xy 46.976029 -43.708374) (xy 46.976538 -43.73626) (xy 46.976029 -43.764146)
			(xy 46.967909 -43.819322) (xy 46.951841 -43.872729) (xy 46.928169 -43.923226) (xy 46.897396 -43.969739)
			(xy 46.860179 -44.011276) (xy 46.817311 -44.046951) (xy 46.769705 -44.076005) (xy 46.718376 -44.097817)
			(xy 46.664419 -44.111923) (xy 46.608982 -44.118023) (xy 46.553248 -44.115986) (xy 46.498405 -44.105856)
			(xy 46.445621 -44.087849) (xy 46.396021 -44.062348) (xy 46.350663 -44.029897) (xy 46.310514 -43.991188)
			(xy 46.276428 -43.947045) (xy 46.249132 -43.89841) (xy 46.229209 -43.846319) (xy 46.217083 -43.791882)
			(xy 46.213012 -43.73626) (xy 37.69106 -43.73626) (xy 37.69106 -45.114464) (xy 46.065438 -45.114464)
			(xy 46.069509 -45.058842) (xy 46.081635 -45.004405) (xy 46.101558 -44.952314) (xy 46.128854 -44.903679)
			(xy 46.16294 -44.859536) (xy 46.203089 -44.820827) (xy 46.248447 -44.788376) (xy 46.298047 -44.762875)
			(xy 46.350831 -44.744868) (xy 46.405674 -44.734738) (xy 46.461408 -44.732701) (xy 46.516845 -44.738801)
			(xy 46.570802 -44.752907) (xy 46.622131 -44.774719) (xy 46.669737 -44.803773) (xy 46.712605 -44.839448)
			(xy 46.749822 -44.880985) (xy 46.780595 -44.927498) (xy 46.804267 -44.977995) (xy 46.820335 -45.031402)
			(xy 46.828455 -45.086578) (xy 46.828964 -45.114464) (xy 46.828455 -45.14235) (xy 46.820335 -45.197526)
			(xy 46.804267 -45.250933) (xy 46.780595 -45.30143) (xy 46.749822 -45.347943) (xy 46.712605 -45.38948)
			(xy 46.669737 -45.425155) (xy 46.622131 -45.454209) (xy 46.570802 -45.476021) (xy 46.516845 -45.490127)
			(xy 46.461408 -45.496227) (xy 46.405674 -45.49419) (xy 46.350831 -45.48406) (xy 46.298047 -45.466053)
			(xy 46.248447 -45.440552) (xy 46.203089 -45.408101) (xy 46.16294 -45.369392) (xy 46.128854 -45.325249)
			(xy 46.101558 -45.276614) (xy 46.081635 -45.224523) (xy 46.069509 -45.170086) (xy 46.065438 -45.114464)
			(xy 37.69106 -45.114464) (xy 37.69106 -46.893226) (xy 46.337218 -46.893226) (xy 46.341289 -46.837604)
			(xy 46.353415 -46.783167) (xy 46.373338 -46.731076) (xy 46.400634 -46.682441) (xy 46.43472 -46.638298)
			(xy 46.474869 -46.599589) (xy 46.520227 -46.567138) (xy 46.569827 -46.541637) (xy 46.622611 -46.52363)
			(xy 46.677454 -46.5135) (xy 46.733188 -46.511463) (xy 46.788625 -46.517563) (xy 46.842582 -46.531669)
			(xy 46.893911 -46.553481) (xy 46.941517 -46.582535) (xy 46.984385 -46.61821) (xy 47.021602 -46.659747)
			(xy 47.052375 -46.70626) (xy 47.076047 -46.756757) (xy 47.092115 -46.810164) (xy 47.100235 -46.86534)
			(xy 47.100744 -46.893226) (xy 47.100235 -46.921112) (xy 47.092115 -46.976288) (xy 47.076047 -47.029695)
			(xy 47.052375 -47.080192) (xy 47.021602 -47.126705) (xy 46.984385 -47.168242) (xy 46.941517 -47.203917)
			(xy 46.893911 -47.232971) (xy 46.842582 -47.254783) (xy 46.788625 -47.268889) (xy 46.733188 -47.274989)
			(xy 46.677454 -47.272952) (xy 46.622611 -47.262822) (xy 46.569827 -47.244815) (xy 46.520227 -47.219314)
			(xy 46.474869 -47.186863) (xy 46.43472 -47.148154) (xy 46.400634 -47.104011) (xy 46.373338 -47.055376)
			(xy 46.353415 -47.003285) (xy 46.341289 -46.948848) (xy 46.337218 -46.893226) (xy 37.69106 -46.893226)
			(xy 37.69106 -47.936658) (xy 44.652946 -47.936658) (xy 44.653432 -47.909407) (xy 44.661188 -47.855459)
			(xy 44.676543 -47.803164) (xy 44.699185 -47.753587) (xy 44.728651 -47.707737) (xy 44.764342 -47.666546)
			(xy 44.805533 -47.630855) (xy 44.851383 -47.601389) (xy 44.90096 -47.578747) (xy 44.953255 -47.563392)
			(xy 45.007203 -47.555636) (xy 45.061705 -47.555636) (xy 45.115653 -47.563392) (xy 45.167948 -47.578747)
			(xy 45.217525 -47.601389) (xy 45.263375 -47.630855) (xy 45.304566 -47.666546) (xy 45.340257 -47.707737)
			(xy 45.369723 -47.753587) (xy 45.392365 -47.803164) (xy 45.40772 -47.855459) (xy 45.415476 -47.909407)
			(xy 45.415962 -47.936658) (xy 45.415496 -47.962999) (xy 45.408246 -48.015179) (xy 45.393891 -48.065866)
			(xy 45.372705 -48.1141) (xy 45.345089 -48.158963) (xy 45.311569 -48.199603) (xy 45.272779 -48.23525)
			(xy 45.25137 -48.250602) (xy 45.239542 -48.259295) (xy 45.2211 -48.282119) (xy 45.209912 -48.309246)
			(xy 45.206903 -48.338435) (xy 45.212321 -48.367274) (xy 45.225719 -48.39338) (xy 45.245989 -48.414597)
			(xy 45.258482 -48.422306) (xy 45.28302 -48.436998) (xy 45.327778 -48.4726) (xy 45.366721 -48.514484)
			(xy 45.398977 -48.561711) (xy 45.423822 -48.613224) (xy 45.440701 -48.667868) (xy 45.449235 -48.724418)
			(xy 45.449744 -48.753014) (xy 45.449258 -48.780265) (xy 45.441502 -48.834213) (xy 45.426147 -48.886508)
			(xy 45.403505 -48.936085) (xy 45.374039 -48.981935) (xy 45.338348 -49.023126) (xy 45.297157 -49.058817)
			(xy 45.251307 -49.088283) (xy 45.20173 -49.110925) (xy 45.149435 -49.12628) (xy 45.095487 -49.134036)
			(xy 45.040985 -49.134036) (xy 44.987037 -49.12628) (xy 44.934742 -49.110925) (xy 44.885165 -49.088283)
			(xy 44.839315 -49.058817) (xy 44.798124 -49.023126) (xy 44.762433 -48.981935) (xy 44.732967 -48.936085)
			(xy 44.710325 -48.886508) (xy 44.69497 -48.834213) (xy 44.687214 -48.780265) (xy 44.686728 -48.753014)
			(xy 44.687177 -48.726673) (xy 44.694431 -48.674492) (xy 44.708789 -48.623804) (xy 44.729978 -48.575571)
			(xy 44.757596 -48.530708) (xy 44.791119 -48.490068) (xy 44.82991 -48.454422) (xy 44.85132 -48.43907)
			(xy 44.863164 -48.430402) (xy 44.881589 -48.407567) (xy 44.892764 -48.380437) (xy 44.895766 -48.35125)
			(xy 44.890347 -48.322413) (xy 44.876956 -48.296305) (xy 44.856695 -48.275082) (xy 44.844208 -48.267366)
			(xy 44.8197 -48.252627) (xy 44.774942 -48.217032) (xy 44.735998 -48.175156) (xy 44.703739 -48.127937)
			(xy 44.678889 -48.076432) (xy 44.662003 -48.021796) (xy 44.65346 -47.965251) (xy 44.652946 -47.936658)
			(xy 37.69106 -47.936658) (xy 37.69106 -58.731404) (xy 39.520622 -58.731404) (xy 39.521085 -58.704034)
			(xy 39.528903 -58.649854) (xy 39.544392 -58.597351) (xy 39.567235 -58.547604) (xy 39.59696 -58.501637)
			(xy 39.614602 -58.480706) (xy 39.620698 -58.473594) (xy 39.627048 -58.456576) (xy 39.627048 -58.371232)
			(xy 39.620698 -58.354214) (xy 39.614602 -58.347102) (xy 39.596966 -58.326166) (xy 39.567243 -58.280198)
			(xy 39.544399 -58.230452) (xy 39.528904 -58.177951) (xy 39.521075 -58.123773) (xy 39.521075 -58.069033)
			(xy 39.528902 -58.014855) (xy 39.544397 -57.962354) (xy 39.56724 -57.912607) (xy 39.596963 -57.866639)
			(xy 39.614602 -57.845706) (xy 39.620698 -57.838594) (xy 39.627048 -57.821576) (xy 39.627048 -57.736232)
			(xy 39.620698 -57.719214) (xy 39.614602 -57.712102) (xy 39.596966 -57.691166) (xy 39.567243 -57.645198)
			(xy 39.544399 -57.595452) (xy 39.528904 -57.542951) (xy 39.521075 -57.488773) (xy 39.521075 -57.434033)
			(xy 39.528902 -57.379855) (xy 39.544397 -57.327354) (xy 39.56724 -57.277607) (xy 39.596963 -57.231639)
			(xy 39.614602 -57.210706) (xy 39.620698 -57.203594) (xy 39.627048 -57.186576) (xy 39.627048 -57.101232)
			(xy 39.620698 -57.084214) (xy 39.614602 -57.077102) (xy 39.596951 -57.05618) (xy 39.567241 -57.010204)
			(xy 39.544407 -56.960454) (xy 39.528919 -56.907951) (xy 39.521094 -56.853774) (xy 39.520622 -56.826404)
			(xy 39.521108 -56.799153) (xy 39.528864 -56.745205) (xy 39.544219 -56.69291) (xy 39.566861 -56.643333)
			(xy 39.596327 -56.597483) (xy 39.632018 -56.556292) (xy 39.673209 -56.520601) (xy 39.719059 -56.491135)
			(xy 39.768636 -56.468493) (xy 39.820931 -56.453138) (xy 39.874879 -56.445382) (xy 39.929381 -56.445382)
			(xy 39.983329 -56.453138) (xy 40.035624 -56.468493) (xy 40.085201 -56.491135) (xy 40.131051 -56.520601)
			(xy 40.172242 -56.556292) (xy 40.207933 -56.597483) (xy 40.237399 -56.643333) (xy 40.260041 -56.69291)
			(xy 40.275396 -56.745205) (xy 40.283152 -56.799153) (xy 40.283638 -56.826404) (xy 40.283189 -56.853775)
			(xy 40.27537 -56.907955) (xy 40.259877 -56.960459) (xy 40.237031 -57.010206) (xy 40.207302 -57.056171)
			(xy 40.189658 -57.077102) (xy 40.183562 -57.084214) (xy 40.177212 -57.101232) (xy 40.177212 -57.186576)
			(xy 40.183562 -57.203594) (xy 40.189658 -57.210706) (xy 40.207303 -57.231635) (xy 40.237029 -57.277603)
			(xy 40.259875 -57.32735) (xy 40.275372 -57.379853) (xy 40.2832 -57.434032) (xy 40.2832 -57.488774)
			(xy 40.27537 -57.542953) (xy 40.259873 -57.595456) (xy 40.237026 -57.645202) (xy 40.2073 -57.69117)
			(xy 40.189658 -57.712102) (xy 40.183562 -57.719214) (xy 40.177212 -57.736232) (xy 40.177212 -57.821576)
			(xy 40.183562 -57.838594) (xy 40.189658 -57.845706) (xy 40.207303 -57.866635) (xy 40.237029 -57.912603)
			(xy 40.259875 -57.96235) (xy 40.275372 -58.014853) (xy 40.2832 -58.069032) (xy 40.2832 -58.123774)
			(xy 40.27537 -58.177953) (xy 40.259873 -58.230456) (xy 40.237026 -58.280202) (xy 40.2073 -58.32617)
			(xy 40.189658 -58.347102) (xy 40.183562 -58.354214) (xy 40.177212 -58.371232) (xy 40.177212 -58.456576)
			(xy 40.183562 -58.473594) (xy 40.189658 -58.480706) (xy 40.207307 -58.50163) (xy 40.237019 -58.547605)
			(xy 40.259853 -58.597354) (xy 40.275342 -58.649857) (xy 40.283166 -58.704034) (xy 40.283638 -58.731404)
			(xy 40.283152 -58.758655) (xy 40.278488 -58.791094) (xy 42.176446 -58.791094) (xy 42.176897 -58.763723)
			(xy 42.184717 -58.709543) (xy 42.200209 -58.657039) (xy 42.223054 -58.607293) (xy 42.252783 -58.561327)
			(xy 42.270426 -58.540396) (xy 42.276522 -58.533284) (xy 42.282872 -58.516266) (xy 42.282872 -58.430922)
			(xy 42.276522 -58.413904) (xy 42.270426 -58.406792) (xy 42.252779 -58.385864) (xy 42.223055 -58.339895)
			(xy 42.20021 -58.290148) (xy 42.184714 -58.237646) (xy 42.176886 -58.183466) (xy 42.176887 -58.128725)
			(xy 42.184716 -58.074546) (xy 42.200213 -58.022043) (xy 42.223059 -57.972297) (xy 42.252785 -57.926329)
			(xy 42.270426 -57.905396) (xy 42.276522 -57.898284) (xy 42.282872 -57.881266) (xy 42.282872 -57.795922)
			(xy 42.276522 -57.778904) (xy 42.270426 -57.771792) (xy 42.252774 -57.75087) (xy 42.223063 -57.704895)
			(xy 42.200229 -57.655145) (xy 42.184741 -57.602642) (xy 42.176917 -57.548464) (xy 42.176446 -57.521094)
			(xy 42.176901 -57.494778) (xy 42.184118 -57.442643) (xy 42.19843 -57.391995) (xy 42.219564 -57.343792)
			(xy 42.24712 -57.29895) (xy 42.280575 -57.258319) (xy 42.299636 -57.24017) (xy 42.307043 -57.232653)
			(xy 42.315567 -57.21337) (xy 42.316146 -57.202832) (xy 42.316146 -57.128156) (xy 42.315586 -57.11761)
			(xy 42.307071 -57.098315) (xy 42.299636 -57.090818) (xy 42.280572 -57.072667) (xy 42.247091 -57.032051)
			(xy 42.219518 -56.987214) (xy 42.198376 -56.93901) (xy 42.184069 -56.888355) (xy 42.176868 -56.836213)
			(xy 42.176446 -56.809894) (xy 42.176932 -56.782643) (xy 42.184688 -56.728695) (xy 42.200043 -56.6764)
			(xy 42.222685 -56.626823) (xy 42.252151 -56.580973) (xy 42.287842 -56.539782) (xy 42.329033 -56.504091)
			(xy 42.374883 -56.474625) (xy 42.42446 -56.451983) (xy 42.476755 -56.436628) (xy 42.530703 -56.428872)
			(xy 42.585205 -56.428872) (xy 42.639153 -56.436628) (xy 42.691448 -56.451983) (xy 42.741025 -56.474625)
			(xy 42.786875 -56.504091) (xy 42.828066 -56.539782) (xy 42.863757 -56.580973) (xy 42.893223 -56.626823)
			(xy 42.915865 -56.6764) (xy 42.93122 -56.728695) (xy 42.938976 -56.782643) (xy 42.939462 -56.809894)
			(xy 42.939064 -56.836212) (xy 42.931834 -56.888349) (xy 42.917511 -56.938999) (xy 42.896366 -56.987201)
			(xy 42.868801 -57.032041) (xy 42.835337 -57.07267) (xy 42.816272 -57.090818) (xy 42.808871 -57.098341)
			(xy 42.800344 -57.117619) (xy 42.799762 -57.128156) (xy 42.799762 -57.202832) (xy 42.800326 -57.213377)
			(xy 42.808838 -57.232672) (xy 42.816272 -57.24017) (xy 42.835331 -57.258325) (xy 42.868812 -57.29894)
			(xy 42.896386 -57.343776) (xy 42.917528 -57.39198) (xy 42.931837 -57.442634) (xy 42.93521 -57.467053)
			(xy 43.118469 -57.467053) (xy 43.118469 -57.412547) (xy 43.126227 -57.358595) (xy 43.141584 -57.306296)
			(xy 43.164228 -57.256716) (xy 43.193698 -57.210863) (xy 43.229394 -57.169671) (xy 43.270589 -57.133979)
			(xy 43.316444 -57.104513) (xy 43.366026 -57.081873) (xy 43.418326 -57.06652) (xy 43.472279 -57.058767)
			(xy 43.499532 -57.058306) (xy 43.525848 -57.058756) (xy 43.577982 -57.065977) (xy 43.628631 -57.08029)
			(xy 43.676833 -57.101425) (xy 43.721675 -57.128981) (xy 43.762306 -57.162435) (xy 43.780456 -57.181496)
			(xy 43.787993 -57.18888) (xy 43.807261 -57.197414) (xy 43.817794 -57.198006) (xy 43.89247 -57.198006)
			(xy 43.903019 -57.197472) (xy 43.922314 -57.18894) (xy 43.929808 -57.181496) (xy 43.947938 -57.162412)
			(xy 43.98856 -57.128935) (xy 44.033401 -57.101365) (xy 44.081609 -57.080227) (xy 44.132268 -57.065923)
			(xy 44.184412 -57.058726) (xy 44.210732 -57.058306) (xy 44.237983 -57.058766) (xy 44.291929 -57.066526)
			(xy 44.327072 -57.076848) (xy 45.138594 -57.076848) (xy 45.13909 -57.049479) (xy 45.146901 -56.995301)
			(xy 45.162383 -56.942798) (xy 45.185218 -56.893051) (xy 45.214936 -56.847083) (xy 45.232574 -56.82615)
			(xy 45.23867 -56.819038) (xy 45.24502 -56.80202) (xy 45.24502 -56.716676) (xy 45.23867 -56.699658)
			(xy 45.232574 -56.692546) (xy 45.214939 -56.671611) (xy 45.185227 -56.625638) (xy 45.162391 -56.575892)
			(xy 45.146899 -56.523392) (xy 45.139069 -56.469217) (xy 45.138594 -56.441848) (xy 45.13908 -56.414597)
			(xy 45.146836 -56.360649) (xy 45.162191 -56.308354) (xy 45.184833 -56.258777) (xy 45.214299 -56.212927)
			(xy 45.24999 -56.171736) (xy 45.291181 -56.136045) (xy 45.337031 -56.106579) (xy 45.386608 -56.083937)
			(xy 45.438903 -56.068582) (xy 45.492851 -56.060826) (xy 45.547353 -56.060826) (xy 45.601301 -56.068582)
			(xy 45.653596 -56.083937) (xy 45.703173 -56.106579) (xy 45.749023 -56.136045) (xy 45.790214 -56.171736)
			(xy 45.825905 -56.212927) (xy 45.855371 -56.258777) (xy 45.878013 -56.308354) (xy 45.893368 -56.360649)
			(xy 45.901124 -56.414597) (xy 45.90161 -56.441848) (xy 45.901111 -56.469217) (xy 45.893301 -56.523395)
			(xy 45.877819 -56.575897) (xy 45.854985 -56.625645) (xy 45.825268 -56.671613) (xy 45.80763 -56.692546)
			(xy 45.801534 -56.699658) (xy 45.795184 -56.716676) (xy 45.795184 -56.80202) (xy 45.801534 -56.819038)
			(xy 45.80763 -56.82615) (xy 45.825264 -56.847086) (xy 45.854975 -56.893058) (xy 45.877812 -56.942805)
			(xy 45.893304 -56.995304) (xy 45.901135 -57.049479) (xy 45.90161 -57.076848) (xy 45.901124 -57.104099)
			(xy 45.893368 -57.158047) (xy 45.878013 -57.210342) (xy 45.855371 -57.259919) (xy 45.825905 -57.305769)
			(xy 45.790214 -57.34696) (xy 45.749023 -57.382651) (xy 45.703173 -57.412117) (xy 45.653596 -57.434759)
			(xy 45.601301 -57.450114) (xy 45.547353 -57.45787) (xy 45.492851 -57.45787) (xy 45.438903 -57.450114)
			(xy 45.386608 -57.434759) (xy 45.337031 -57.412117) (xy 45.291181 -57.382651) (xy 45.24999 -57.34696)
			(xy 45.214299 -57.305769) (xy 45.184833 -57.259919) (xy 45.162191 -57.210342) (xy 45.146836 -57.158047)
			(xy 45.13908 -57.104099) (xy 45.138594 -57.076848) (xy 44.327072 -57.076848) (xy 44.344222 -57.081885)
			(xy 44.393797 -57.104529) (xy 44.439645 -57.133997) (xy 44.480833 -57.16969) (xy 44.516522 -57.210881)
			(xy 44.545987 -57.256731) (xy 44.568626 -57.306308) (xy 44.58398 -57.358602) (xy 44.591736 -57.412549)
			(xy 44.591736 -57.467051) (xy 44.58398 -57.520998) (xy 44.568626 -57.573292) (xy 44.545987 -57.622869)
			(xy 44.516522 -57.668719) (xy 44.480833 -57.70991) (xy 44.439645 -57.745603) (xy 44.393797 -57.775071)
			(xy 44.344222 -57.797715) (xy 44.291929 -57.813074) (xy 44.237983 -57.820834) (xy 44.210732 -57.821322)
			(xy 44.184416 -57.820887) (xy 44.132281 -57.813662) (xy 44.081633 -57.799345) (xy 44.033431 -57.778207)
			(xy 43.988589 -57.750649) (xy 43.947958 -57.717193) (xy 43.929808 -57.698132) (xy 43.922281 -57.690736)
			(xy 43.903005 -57.682207) (xy 43.89247 -57.681622) (xy 43.817794 -57.681622) (xy 43.807241 -57.682128)
			(xy 43.787946 -57.690679) (xy 43.780456 -57.698132) (xy 43.762329 -57.71722) (xy 43.721709 -57.7507)
			(xy 43.676867 -57.778271) (xy 43.628658 -57.799408) (xy 43.577998 -57.81371) (xy 43.525852 -57.820904)
			(xy 43.499532 -57.821322) (xy 43.472279 -57.820833) (xy 43.418326 -57.81308) (xy 43.366026 -57.797727)
			(xy 43.316444 -57.775087) (xy 43.270589 -57.745621) (xy 43.229394 -57.709929) (xy 43.193698 -57.668737)
			(xy 43.164228 -57.622884) (xy 43.141584 -57.573304) (xy 43.126227 -57.521005) (xy 43.118469 -57.467053)
			(xy 42.93521 -57.467053) (xy 42.939039 -57.494775) (xy 42.939462 -57.521094) (xy 42.939002 -57.548465)
			(xy 42.931184 -57.602644) (xy 42.915694 -57.655148) (xy 42.892851 -57.704895) (xy 42.863124 -57.750861)
			(xy 42.845482 -57.771792) (xy 42.839386 -57.778904) (xy 42.833036 -57.795922) (xy 42.833036 -57.881266)
			(xy 42.839386 -57.898284) (xy 42.845482 -57.905396) (xy 42.863116 -57.926334) (xy 42.892841 -57.972301)
			(xy 42.915686 -58.022046) (xy 42.931182 -58.074548) (xy 42.939011 -58.128725) (xy 42.939012 -58.183466)
			(xy 42.931184 -58.237644) (xy 42.915689 -58.290145) (xy 42.892845 -58.339891) (xy 42.863122 -58.385859)
			(xy 42.845482 -58.406792) (xy 42.839386 -58.413904) (xy 42.833036 -58.430922) (xy 42.833036 -58.516266)
			(xy 42.839386 -58.533284) (xy 42.845482 -58.540396) (xy 42.86313 -58.561321) (xy 42.892841 -58.607296)
			(xy 42.915676 -58.657045) (xy 42.931164 -58.709547) (xy 42.93899 -58.763724) (xy 42.939462 -58.791094)
			(xy 42.938976 -58.818345) (xy 42.93122 -58.872293) (xy 42.930823 -58.873644) (xy 44.200572 -58.873644)
			(xy 44.201046 -58.846274) (xy 44.208859 -58.792094) (xy 44.224346 -58.739591) (xy 44.247186 -58.689844)
			(xy 44.27691 -58.643877) (xy 44.294552 -58.622946) (xy 44.300648 -58.615834) (xy 44.306998 -58.598816)
			(xy 44.306998 -58.513472) (xy 44.300648 -58.496454) (xy 44.294552 -58.489342) (xy 44.276927 -58.468398)
			(xy 44.247211 -58.422429) (xy 44.224372 -58.372685) (xy 44.208878 -58.320187) (xy 44.201047 -58.266013)
			(xy 44.200572 -58.238644) (xy 44.201058 -58.211393) (xy 44.208814 -58.157445) (xy 44.224169 -58.10515)
			(xy 44.246811 -58.055573) (xy 44.276277 -58.009723) (xy 44.311968 -57.968532) (xy 44.353159 -57.932841)
			(xy 44.399009 -57.903375) (xy 44.448586 -57.880733) (xy 44.500881 -57.865378) (xy 44.554829 -57.857622)
			(xy 44.609331 -57.857622) (xy 44.663279 -57.865378) (xy 44.715574 -57.880733) (xy 44.765151 -57.903375)
			(xy 44.811001 -57.932841) (xy 44.852192 -57.968532) (xy 44.887883 -58.009723) (xy 44.917349 -58.055573)
			(xy 44.939991 -58.10515) (xy 44.955346 -58.157445) (xy 44.963102 -58.211393) (xy 44.963588 -58.238644)
			(xy 44.963092 -58.266013) (xy 44.955282 -58.320191) (xy 44.9398 -58.372694) (xy 44.916965 -58.422441)
			(xy 44.887246 -58.468409) (xy 44.869608 -58.489342) (xy 44.863512 -58.496454) (xy 44.857162 -58.513472)
			(xy 44.857162 -58.598816) (xy 44.863512 -58.615834) (xy 44.869608 -58.622946) (xy 44.887236 -58.643887)
			(xy 44.91695 -58.689857) (xy 44.939787 -58.739603) (xy 44.955281 -58.792101) (xy 44.963112 -58.846275)
			(xy 44.963588 -58.873644) (xy 44.963102 -58.900895) (xy 44.955346 -58.954843) (xy 44.939991 -59.007138)
			(xy 44.917349 -59.056715) (xy 44.887883 -59.102565) (xy 44.852192 -59.143756) (xy 44.811001 -59.179447)
			(xy 44.765151 -59.208913) (xy 44.715574 -59.231555) (xy 44.663279 -59.24691) (xy 44.609331 -59.254666)
			(xy 44.554829 -59.254666) (xy 44.500881 -59.24691) (xy 44.448586 -59.231555) (xy 44.399009 -59.208913)
			(xy 44.353159 -59.179447) (xy 44.311968 -59.143756) (xy 44.276277 -59.102565) (xy 44.246811 -59.056715)
			(xy 44.224169 -59.007138) (xy 44.208814 -58.954843) (xy 44.201058 -58.900895) (xy 44.200572 -58.873644)
			(xy 42.930823 -58.873644) (xy 42.915865 -58.924588) (xy 42.893223 -58.974165) (xy 42.863757 -59.020015)
			(xy 42.828066 -59.061206) (xy 42.786875 -59.096897) (xy 42.741025 -59.126363) (xy 42.691448 -59.149005)
			(xy 42.639153 -59.16436) (xy 42.585205 -59.172116) (xy 42.530703 -59.172116) (xy 42.476755 -59.16436)
			(xy 42.42446 -59.149005) (xy 42.374883 -59.126363) (xy 42.329033 -59.096897) (xy 42.287842 -59.061206)
			(xy 42.252151 -59.020015) (xy 42.222685 -58.974165) (xy 42.200043 -58.924588) (xy 42.184688 -58.872293)
			(xy 42.176932 -58.818345) (xy 42.176446 -58.791094) (xy 40.278488 -58.791094) (xy 40.275396 -58.812603)
			(xy 40.260041 -58.864898) (xy 40.237399 -58.914475) (xy 40.207933 -58.960325) (xy 40.172242 -59.001516)
			(xy 40.131051 -59.037207) (xy 40.085201 -59.066673) (xy 40.035624 -59.089315) (xy 39.983329 -59.10467)
			(xy 39.929381 -59.112426) (xy 39.874879 -59.112426) (xy 39.820931 -59.10467) (xy 39.768636 -59.089315)
			(xy 39.719059 -59.066673) (xy 39.673209 -59.037207) (xy 39.632018 -59.001516) (xy 39.596327 -58.960325)
			(xy 39.566861 -58.914475) (xy 39.544219 -58.864898) (xy 39.528864 -58.812603) (xy 39.521108 -58.758655)
			(xy 39.520622 -58.731404) (xy 37.69106 -58.731404) (xy 37.69106 -60.12645) (xy 43.180272 -60.12645)
			(xy 43.180272 -60.07195) (xy 43.188027 -60.018006) (xy 43.20338 -59.965714) (xy 43.226018 -59.916139)
			(xy 43.255481 -59.87029) (xy 43.291168 -59.8291) (xy 43.332353 -59.793408) (xy 43.378199 -59.76394)
			(xy 43.427771 -59.741296) (xy 43.480061 -59.725937) (xy 43.534004 -59.718175) (xy 43.561254 -59.717686)
			(xy 43.588623 -59.718182) (xy 43.642801 -59.725993) (xy 43.695303 -59.741476) (xy 43.745051 -59.76431)
			(xy 43.791019 -59.794028) (xy 43.811952 -59.811666) (xy 43.819064 -59.817762) (xy 43.836082 -59.824112)
			(xy 43.921426 -59.824112) (xy 43.938444 -59.817762) (xy 43.945556 -59.811666) (xy 43.966489 -59.794025)
			(xy 44.012457 -59.764301) (xy 44.062203 -59.741455) (xy 44.114705 -59.725959) (xy 44.168883 -59.71813)
			(xy 44.223625 -59.71813) (xy 44.277803 -59.725959) (xy 44.330305 -59.741455) (xy 44.380051 -59.764301)
			(xy 44.426019 -59.794025) (xy 44.446952 -59.811666) (xy 44.454064 -59.817762) (xy 44.471082 -59.824112)
			(xy 44.556426 -59.824112) (xy 44.573444 -59.817762) (xy 44.580556 -59.811666) (xy 44.601489 -59.794029)
			(xy 44.647462 -59.764318) (xy 44.69721 -59.741482) (xy 44.74971 -59.72599) (xy 44.803885 -59.718161)
			(xy 44.831254 -59.717686) (xy 44.858509 -59.718158) (xy 44.912464 -59.72591) (xy 44.964766 -59.741262)
			(xy 45.014351 -59.763901) (xy 45.060209 -59.793367) (xy 45.101407 -59.82906) (xy 45.137105 -59.870254)
			(xy 45.166577 -59.916108) (xy 45.189222 -59.965691) (xy 45.20458 -60.017991) (xy 45.212339 -60.071945)
			(xy 45.212339 -60.126455) (xy 45.20458 -60.180409) (xy 45.189222 -60.232709) (xy 45.166577 -60.282292)
			(xy 45.137105 -60.328146) (xy 45.101407 -60.36934) (xy 45.060209 -60.405033) (xy 45.014351 -60.434499)
			(xy 44.964766 -60.457138) (xy 44.912464 -60.47249) (xy 44.858509 -60.480242) (xy 44.831254 -60.480702)
			(xy 44.803885 -60.480204) (xy 44.749707 -60.472394) (xy 44.697205 -60.456912) (xy 44.647457 -60.434077)
			(xy 44.601489 -60.40436) (xy 44.580556 -60.386722) (xy 44.573444 -60.380626) (xy 44.556426 -60.374276)
			(xy 44.471082 -60.374276) (xy 44.454064 -60.380626) (xy 44.446952 -60.386722) (xy 44.426019 -60.404363)
			(xy 44.380051 -60.434087) (xy 44.330305 -60.456933) (xy 44.277803 -60.472429) (xy 44.223625 -60.480258)
			(xy 44.168883 -60.480258) (xy 44.114705 -60.472429) (xy 44.062203 -60.456933) (xy 44.012457 -60.434087)
			(xy 43.966489 -60.404363) (xy 43.945556 -60.386722) (xy 43.938444 -60.380626) (xy 43.921426 -60.374276)
			(xy 43.836082 -60.374276) (xy 43.819064 -60.380626) (xy 43.811952 -60.386722) (xy 43.791014 -60.404354)
			(xy 43.745042 -60.434066) (xy 43.695296 -60.456903) (xy 43.642797 -60.472396) (xy 43.588623 -60.480226)
			(xy 43.561254 -60.480702) (xy 43.534004 -60.480225) (xy 43.480061 -60.472463) (xy 43.427771 -60.457104)
			(xy 43.378199 -60.43446) (xy 43.332353 -60.404992) (xy 43.291168 -60.3693) (xy 43.255481 -60.32811)
			(xy 43.226018 -60.282261) (xy 43.20338 -60.232686) (xy 43.188027 -60.180394) (xy 43.180272 -60.12645)
			(xy 37.69106 -60.12645) (xy 37.69106 -60.999878) (xy 37.690525 -61.009866) (xy 37.682813 -61.0283)
			(xy 37.676074 -61.035692) (xy 37.045138 -61.666628) (xy 36.97351 -61.738256) (xy 36.97097 -61.740796)
			(xy 36.970716 -61.74105) (xy 36.900358 -61.811408) (xy 36.893005 -61.818065) (xy 36.874704 -61.825665)
			(xy 36.864798 -61.82614) (xy 32.86887 -61.82614) (xy 32.857186 -61.829188) (xy 32.85236 -61.831474)
			(xy 32.851852 -61.831728) (xy 32.836947 -61.838668) (xy 32.80617 -61.850245) (xy 32.790384 -61.854842)
			(xy 32.763091 -61.862061) (xy 32.707103 -61.8693) (xy 32.650659 -61.868199) (xy 32.622744 -61.863986)
			(xy 32.596166 -61.859024) (xy 32.544663 -61.842579) (xy 32.520128 -61.83122) (xy 32.515048 -61.82868)
			(xy 32.503872 -61.82614) (xy 31.06547 -61.82614) (xy 31.059628 -61.827156) (xy 31.04896 -61.829233)
			(xy 31.030673 -61.840942) (xy 31.024322 -61.849762) (xy 30.978094 -61.920374) (xy 30.970982 -61.931296)
			(xy 30.969966 -61.94425) (xy 30.96895 -61.956696) (xy 30.971998 -61.963808) (xy 30.971998 -61.964062)
			(xy 30.974284 -61.969142) (xy 30.984266 -61.993205) (xy 30.9983 -62.043373) (xy 31.005361 -62.094986)
			(xy 31.00578 -62.121034) (xy 31.00578 -62.12586) (xy 31.004968 -62.152886) (xy 30.996658 -62.206313)
			(xy 30.980889 -62.258031) (xy 30.957977 -62.307004) (xy 30.92838 -62.352253) (xy 30.892691 -62.39287)
			(xy 30.851626 -62.428042) (xy 30.806007 -62.457064) (xy 30.756747 -62.479355) (xy 30.704833 -62.494469)
			(xy 30.651306 -62.502102) (xy 30.597238 -62.502102) (xy 30.543711 -62.494469) (xy 30.491797 -62.479355)
			(xy 30.442537 -62.457064) (xy 30.396918 -62.428042) (xy 30.355853 -62.39287) (xy 30.320164 -62.352253)
			(xy 30.290567 -62.307004) (xy 30.267655 -62.258031) (xy 30.251886 -62.206313) (xy 30.243576 -62.152886)
			(xy 30.242764 -62.12586) (xy 30.242764 -62.12078) (xy 30.243212 -62.094683) (xy 30.250366 -62.042982)
			(xy 30.264498 -61.992737) (xy 30.274514 -61.968634) (xy 30.279594 -61.95695) (xy 30.278578 -61.94425)
			(xy 30.277562 -61.931296) (xy 30.223968 -61.849254) (xy 30.216776 -61.839568) (xy 30.195835 -61.827657)
			(xy 30.183836 -61.826394) (xy 30.180788 -61.82614) (xy 27.668982 -61.82614) (xy 27.666696 -61.82614)
			(xy 27.664918 -61.826394) (xy 27.655542 -61.827193) (xy 27.638332 -61.834771) (xy 27.63139 -61.841126)
			(xy 27.222704 -62.249812) (xy 27.215338 -62.256924) (xy 27.207718 -62.27572) (xy 27.207718 -62.839456)
			(xy 32.918823 -62.839456) (xy 32.918823 -62.784944) (xy 32.926581 -62.730988) (xy 32.941939 -62.678685)
			(xy 32.964584 -62.6291) (xy 32.994055 -62.583243) (xy 33.029752 -62.542047) (xy 33.070949 -62.50635)
			(xy 33.116807 -62.47688) (xy 33.166393 -62.454236) (xy 33.218696 -62.438879) (xy 33.272652 -62.431122)
			(xy 33.299908 -62.43066) (xy 33.328756 -62.431159) (xy 33.385794 -62.439842) (xy 33.440872 -62.457026)
			(xy 33.492729 -62.482316) (xy 33.540182 -62.515134) (xy 33.561528 -62.534546) (xy 33.56991 -62.54242)
			(xy 33.591754 -62.549278) (xy 33.693608 -62.535054) (xy 33.712658 -62.5221) (xy 33.7185 -62.512194)
			(xy 33.733304 -62.488067) (xy 33.768959 -62.444104) (xy 33.810715 -62.405887) (xy 33.857657 -62.374257)
			(xy 33.908756 -62.349905) (xy 33.96289 -62.333367) (xy 34.018874 -62.325004) (xy 34.047176 -62.324488)
			(xy 34.07443 -62.324958) (xy 34.128383 -62.332712) (xy 34.180683 -62.348066) (xy 34.230265 -62.370706)
			(xy 34.276121 -62.400174) (xy 34.317316 -62.435867) (xy 34.353012 -62.47706) (xy 34.382482 -62.522913)
			(xy 34.405126 -62.572495) (xy 34.420483 -62.624794) (xy 34.428241 -62.678746) (xy 34.428241 -62.733254)
			(xy 34.420483 -62.787206) (xy 34.405126 -62.839505) (xy 34.382482 -62.889087) (xy 34.353012 -62.93494)
			(xy 34.317316 -62.976133) (xy 34.276121 -63.011826) (xy 34.230265 -63.041294) (xy 34.180683 -63.063934)
			(xy 34.128383 -63.079288) (xy 34.07443 -63.087042) (xy 34.047176 -63.087504) (xy 34.018329 -63.086999)
			(xy 33.961291 -63.078314) (xy 33.906214 -63.061131) (xy 33.854357 -63.035844) (xy 33.806903 -63.003028)
			(xy 33.785556 -62.983618) (xy 33.777174 -62.975744) (xy 33.75533 -62.968886) (xy 33.653476 -62.98311)
			(xy 33.634426 -62.996064) (xy 33.628584 -63.00597) (xy 33.613778 -63.030096) (xy 33.578125 -63.074061)
			(xy 33.53637 -63.112279) (xy 33.489428 -63.14391) (xy 33.438329 -63.168262) (xy 33.384194 -63.1848)
			(xy 33.32821 -63.193161) (xy 33.299908 -63.193676) (xy 33.272652 -63.193278) (xy 33.218696 -63.185521)
			(xy 33.166393 -63.170164) (xy 33.116807 -63.14752) (xy 33.070949 -63.11805) (xy 33.029752 -63.082353)
			(xy 32.994055 -63.041157) (xy 32.964584 -62.9953) (xy 32.941939 -62.945715) (xy 32.926581 -62.893412)
			(xy 32.918823 -62.839456) (xy 27.207718 -62.839456) (xy 27.207718 -63.273432) (xy 29.576774 -63.273432)
			(xy 29.580845 -63.21781) (xy 29.592971 -63.163373) (xy 29.612894 -63.111282) (xy 29.64019 -63.062647)
			(xy 29.674276 -63.018504) (xy 29.714425 -62.979795) (xy 29.759783 -62.947344) (xy 29.809383 -62.921843)
			(xy 29.862167 -62.903836) (xy 29.91701 -62.893706) (xy 29.972744 -62.891669) (xy 30.028181 -62.897769)
			(xy 30.082138 -62.911875) (xy 30.133467 -62.933687) (xy 30.181073 -62.962741) (xy 30.223941 -62.998416)
			(xy 30.261158 -63.039953) (xy 30.291931 -63.086466) (xy 30.315603 -63.136963) (xy 30.331671 -63.19037)
			(xy 30.339791 -63.245546) (xy 30.339791 -63.245548) (xy 43.104592 -63.245548) (xy 43.104592 -63.191052)
			(xy 43.112347 -63.137109) (xy 43.1277 -63.084819) (xy 43.150337 -63.035247) (xy 43.179799 -62.9894)
			(xy 43.215485 -62.948212) (xy 43.256669 -62.912522) (xy 43.302513 -62.883056) (xy 43.352084 -62.860413)
			(xy 43.404372 -62.845055) (xy 43.458314 -62.837295) (xy 43.485562 -62.836806) (xy 43.512931 -62.837293)
			(xy 43.56711 -62.845105) (xy 43.619613 -62.86059) (xy 43.66936 -62.883427) (xy 43.715328 -62.913147)
			(xy 43.73626 -62.930786) (xy 43.743372 -62.936882) (xy 43.76039 -62.943232) (xy 43.845734 -62.943232)
			(xy 43.862752 -62.936882) (xy 43.869864 -62.930786) (xy 43.890797 -62.913145) (xy 43.936765 -62.883421)
			(xy 43.986511 -62.860575) (xy 44.039013 -62.845079) (xy 44.093191 -62.83725) (xy 44.147933 -62.83725)
			(xy 44.202111 -62.845079) (xy 44.254613 -62.860575) (xy 44.304359 -62.883421) (xy 44.350327 -62.913145)
			(xy 44.37126 -62.930786) (xy 44.378372 -62.936882) (xy 44.39539 -62.943232) (xy 44.480734 -62.943232)
			(xy 44.497752 -62.936882) (xy 44.504864 -62.930786) (xy 44.525797 -62.913148) (xy 44.57177 -62.883437)
			(xy 44.621517 -62.860601) (xy 44.674017 -62.845109) (xy 44.728193 -62.83728) (xy 44.755562 -62.836806)
			(xy 44.782818 -62.837238) (xy 44.836775 -62.844991) (xy 44.889079 -62.860344) (xy 44.938666 -62.882986)
			(xy 44.984526 -62.912454) (xy 45.025724 -62.948149) (xy 45.061423 -62.989344) (xy 45.090896 -63.035201)
			(xy 45.113542 -63.084785) (xy 45.128901 -63.137088) (xy 45.136659 -63.191044) (xy 45.136659 -63.245556)
			(xy 45.128901 -63.299512) (xy 45.113542 -63.351815) (xy 45.090896 -63.401399) (xy 45.061423 -63.447256)
			(xy 45.025724 -63.488451) (xy 44.984526 -63.524146) (xy 44.938666 -63.553614) (xy 44.889079 -63.576256)
			(xy 44.836775 -63.591609) (xy 44.782818 -63.599362) (xy 44.755562 -63.599822) (xy 44.728192 -63.599339)
			(xy 44.674013 -63.591528) (xy 44.621509 -63.576044) (xy 44.571762 -63.553206) (xy 44.525795 -63.523483)
			(xy 44.504864 -63.505842) (xy 44.497752 -63.499746) (xy 44.480734 -63.493396) (xy 44.39539 -63.493396)
			(xy 44.378372 -63.499746) (xy 44.37126 -63.505842) (xy 44.350327 -63.523483) (xy 44.304359 -63.553207)
			(xy 44.254613 -63.576053) (xy 44.202111 -63.591549) (xy 44.147933 -63.599378) (xy 44.093191 -63.599378)
			(xy 44.039013 -63.591549) (xy 43.986511 -63.576053) (xy 43.936765 -63.553207) (xy 43.890797 -63.523483)
			(xy 43.869864 -63.505842) (xy 43.862752 -63.499746) (xy 43.845734 -63.493396) (xy 43.76039 -63.493396)
			(xy 43.743372 -63.499746) (xy 43.73626 -63.505842) (xy 43.715322 -63.523473) (xy 43.66935 -63.553185)
			(xy 43.619604 -63.576022) (xy 43.567105 -63.591515) (xy 43.512931 -63.599346) (xy 43.485562 -63.599822)
			(xy 43.458314 -63.599305) (xy 43.404372 -63.591545) (xy 43.352084 -63.576187) (xy 43.302513 -63.553544)
			(xy 43.256669 -63.524078) (xy 43.215485 -63.488388) (xy 43.179799 -63.4472) (xy 43.150337 -63.401353)
			(xy 43.1277 -63.351781) (xy 43.112347 -63.299491) (xy 43.104592 -63.245548) (xy 30.339791 -63.245548)
			(xy 30.3403 -63.273432) (xy 30.339791 -63.301318) (xy 30.331671 -63.356494) (xy 30.315603 -63.409901)
			(xy 30.291931 -63.460398) (xy 30.261158 -63.506911) (xy 30.223941 -63.548448) (xy 30.181073 -63.584123)
			(xy 30.133467 -63.613177) (xy 30.082138 -63.634989) (xy 30.028181 -63.649095) (xy 29.972744 -63.655195)
			(xy 29.91701 -63.653158) (xy 29.862167 -63.643028) (xy 29.809383 -63.625021) (xy 29.759783 -63.59952)
			(xy 29.714425 -63.567069) (xy 29.674276 -63.52836) (xy 29.64019 -63.484217) (xy 29.612894 -63.435582)
			(xy 29.592971 -63.383491) (xy 29.580845 -63.329054) (xy 29.576774 -63.273432) (xy 27.207718 -63.273432)
			(xy 27.207718 -64.102234) (xy 27.387548 -64.102234) (xy 27.391619 -64.046612) (xy 27.403745 -63.992175)
			(xy 27.423668 -63.940084) (xy 27.450964 -63.891449) (xy 27.48505 -63.847306) (xy 27.525199 -63.808597)
			(xy 27.570557 -63.776146) (xy 27.620157 -63.750645) (xy 27.672941 -63.732638) (xy 27.727784 -63.722508)
			(xy 27.783518 -63.720471) (xy 27.838955 -63.726571) (xy 27.892912 -63.740677) (xy 27.944241 -63.762489)
			(xy 27.991847 -63.791543) (xy 28.034715 -63.827218) (xy 28.071932 -63.868755) (xy 28.102705 -63.915268)
			(xy 28.126377 -63.965765) (xy 28.142445 -64.019172) (xy 28.150565 -64.074348) (xy 28.151074 -64.102234)
			(xy 28.150565 -64.13012) (xy 28.142445 -64.185296) (xy 28.126377 -64.238703) (xy 28.102705 -64.2892)
			(xy 28.087427 -64.312292) (xy 31.065976 -64.312292) (xy 31.070047 -64.25667) (xy 31.082173 -64.202233)
			(xy 31.102096 -64.150142) (xy 31.129392 -64.101507) (xy 31.163478 -64.057364) (xy 31.203627 -64.018655)
			(xy 31.248985 -63.986204) (xy 31.298585 -63.960703) (xy 31.351369 -63.942696) (xy 31.406212 -63.932566)
			(xy 31.461946 -63.930529) (xy 31.517383 -63.936629) (xy 31.57134 -63.950735) (xy 31.622669 -63.972547)
			(xy 31.670275 -64.001601) (xy 31.713143 -64.037276) (xy 31.75036 -64.078813) (xy 31.781133 -64.125326)
			(xy 31.804805 -64.175823) (xy 31.820873 -64.22923) (xy 31.828993 -64.284406) (xy 31.829502 -64.312292)
			(xy 31.828993 -64.340178) (xy 31.820873 -64.395354) (xy 31.804805 -64.448761) (xy 31.781133 -64.499258)
			(xy 31.75036 -64.545771) (xy 31.713143 -64.587308) (xy 31.670275 -64.622983) (xy 31.622669 -64.652037)
			(xy 31.57134 -64.673849) (xy 31.517383 -64.687955) (xy 31.461946 -64.694055) (xy 31.406212 -64.692018)
			(xy 31.351369 -64.681888) (xy 31.298585 -64.663881) (xy 31.248985 -64.63838) (xy 31.203627 -64.605929)
			(xy 31.163478 -64.56722) (xy 31.129392 -64.523077) (xy 31.102096 -64.474442) (xy 31.082173 -64.422351)
			(xy 31.070047 -64.367914) (xy 31.065976 -64.312292) (xy 28.087427 -64.312292) (xy 28.071932 -64.335713)
			(xy 28.034715 -64.37725) (xy 27.991847 -64.412925) (xy 27.944241 -64.441979) (xy 27.892912 -64.463791)
			(xy 27.838955 -64.477897) (xy 27.783518 -64.483997) (xy 27.727784 -64.48196) (xy 27.672941 -64.47183)
			(xy 27.620157 -64.453823) (xy 27.570557 -64.428322) (xy 27.525199 -64.395871) (xy 27.48505 -64.357162)
			(xy 27.450964 -64.313019) (xy 27.423668 -64.264384) (xy 27.403745 -64.212293) (xy 27.391619 -64.157856)
			(xy 27.387548 -64.102234) (xy 27.207718 -64.102234) (xy 27.207718 -65.124076) (xy 32.107376 -65.124076)
			(xy 32.111447 -65.068454) (xy 32.123573 -65.014017) (xy 32.143496 -64.961926) (xy 32.170792 -64.913291)
			(xy 32.204878 -64.869148) (xy 32.245027 -64.830439) (xy 32.290385 -64.797988) (xy 32.339985 -64.772487)
			(xy 32.392769 -64.75448) (xy 32.447612 -64.74435) (xy 32.503346 -64.742313) (xy 32.558783 -64.748413)
			(xy 32.61274 -64.762519) (xy 32.664069 -64.784331) (xy 32.711675 -64.813385) (xy 32.754543 -64.84906)
			(xy 32.79176 -64.890597) (xy 32.822533 -64.93711) (xy 32.846205 -64.987607) (xy 32.862273 -65.041014)
			(xy 32.870393 -65.09619) (xy 32.870902 -65.124076) (xy 32.870393 -65.151962) (xy 32.869226 -65.15989)
			(xy 45.116494 -65.15989) (xy 45.120565 -65.104268) (xy 45.132691 -65.049831) (xy 45.152614 -64.99774)
			(xy 45.17991 -64.949105) (xy 45.213996 -64.904962) (xy 45.254145 -64.866253) (xy 45.299503 -64.833802)
			(xy 45.349103 -64.808301) (xy 45.401887 -64.790294) (xy 45.45673 -64.780164) (xy 45.512464 -64.778127)
			(xy 45.567901 -64.784227) (xy 45.621858 -64.798333) (xy 45.673187 -64.820145) (xy 45.720793 -64.849199)
			(xy 45.763661 -64.884874) (xy 45.800878 -64.926411) (xy 45.831651 -64.972924) (xy 45.855323 -65.023421)
			(xy 45.871391 -65.076828) (xy 45.879511 -65.132004) (xy 45.88002 -65.15989) (xy 45.879511 -65.187776)
			(xy 45.871391 -65.242952) (xy 45.855323 -65.296359) (xy 45.831651 -65.346856) (xy 45.800878 -65.393369)
			(xy 45.763661 -65.434906) (xy 45.720793 -65.470581) (xy 45.673187 -65.499635) (xy 45.621858 -65.521447)
			(xy 45.567901 -65.535553) (xy 45.512464 -65.541653) (xy 45.45673 -65.539616) (xy 45.401887 -65.529486)
			(xy 45.349103 -65.511479) (xy 45.299503 -65.485978) (xy 45.254145 -65.453527) (xy 45.213996 -65.414818)
			(xy 45.17991 -65.370675) (xy 45.152614 -65.32204) (xy 45.132691 -65.269949) (xy 45.120565 -65.215512)
			(xy 45.116494 -65.15989) (xy 32.869226 -65.15989) (xy 32.862273 -65.207138) (xy 32.846205 -65.260545)
			(xy 32.822533 -65.311042) (xy 32.79176 -65.357555) (xy 32.754543 -65.399092) (xy 32.711675 -65.434767)
			(xy 32.664069 -65.463821) (xy 32.61274 -65.485633) (xy 32.558783 -65.499739) (xy 32.503346 -65.505839)
			(xy 32.447612 -65.503802) (xy 32.392769 -65.493672) (xy 32.339985 -65.475665) (xy 32.290385 -65.450164)
			(xy 32.245027 -65.417713) (xy 32.204878 -65.379004) (xy 32.170792 -65.334861) (xy 32.143496 -65.286226)
			(xy 32.123573 -65.234135) (xy 32.111447 -65.179698) (xy 32.107376 -65.124076) (xy 27.207718 -65.124076)
			(xy 27.207718 -65.75552) (xy 40.346628 -65.75552) (xy 40.350699 -65.699898) (xy 40.362825 -65.645461)
			(xy 40.382748 -65.59337) (xy 40.410044 -65.544735) (xy 40.44413 -65.500592) (xy 40.484279 -65.461883)
			(xy 40.529637 -65.429432) (xy 40.579237 -65.403931) (xy 40.632021 -65.385924) (xy 40.686864 -65.375794)
			(xy 40.742598 -65.373757) (xy 40.798035 -65.379857) (xy 40.851992 -65.393963) (xy 40.903321 -65.415775)
			(xy 40.950927 -65.444829) (xy 40.993795 -65.480504) (xy 41.031012 -65.522041) (xy 41.061785 -65.568554)
			(xy 41.085457 -65.619051) (xy 41.101525 -65.672458) (xy 41.109645 -65.727634) (xy 41.110154 -65.75552)
			(xy 41.109645 -65.783406) (xy 41.101525 -65.838582) (xy 41.085457 -65.891989) (xy 41.061785 -65.942486)
			(xy 41.031012 -65.988999) (xy 40.993795 -66.030536) (xy 40.950927 -66.066211) (xy 40.903321 -66.095265)
			(xy 40.851992 -66.117077) (xy 40.798035 -66.131183) (xy 40.742598 -66.137283) (xy 40.686864 -66.135246)
			(xy 40.632021 -66.125116) (xy 40.579237 -66.107109) (xy 40.529637 -66.081608) (xy 40.484279 -66.049157)
			(xy 40.44413 -66.010448) (xy 40.410044 -65.966305) (xy 40.382748 -65.91767) (xy 40.362825 -65.865579)
			(xy 40.350699 -65.811142) (xy 40.346628 -65.75552) (xy 27.207718 -65.75552) (xy 27.207718 -67.488054)
			(xy 44.779182 -67.488054) (xy 44.783253 -67.432432) (xy 44.795379 -67.377995) (xy 44.815302 -67.325904)
			(xy 44.842598 -67.277269) (xy 44.876684 -67.233126) (xy 44.916833 -67.194417) (xy 44.962191 -67.161966)
			(xy 45.011791 -67.136465) (xy 45.064575 -67.118458) (xy 45.119418 -67.108328) (xy 45.175152 -67.106291)
			(xy 45.230589 -67.112391) (xy 45.284546 -67.126497) (xy 45.335875 -67.148309) (xy 45.383481 -67.177363)
			(xy 45.426349 -67.213038) (xy 45.463566 -67.254575) (xy 45.494339 -67.301088) (xy 45.518011 -67.351585)
			(xy 45.534079 -67.404992) (xy 45.542199 -67.460168) (xy 45.542708 -67.488054) (xy 45.542199 -67.51594)
			(xy 45.534079 -67.571116) (xy 45.518011 -67.624523) (xy 45.494339 -67.67502) (xy 45.463566 -67.721533)
			(xy 45.426349 -67.76307) (xy 45.383481 -67.798745) (xy 45.335875 -67.827799) (xy 45.284546 -67.849611)
			(xy 45.230589 -67.863717) (xy 45.175152 -67.869817) (xy 45.119418 -67.86778) (xy 45.064575 -67.85765)
			(xy 45.011791 -67.839643) (xy 44.962191 -67.814142) (xy 44.916833 -67.781691) (xy 44.876684 -67.742982)
			(xy 44.842598 -67.698839) (xy 44.815302 -67.650204) (xy 44.795379 -67.598113) (xy 44.783253 -67.543676)
			(xy 44.779182 -67.488054) (xy 27.207718 -67.488054) (xy 27.207718 -69.9516) (xy 27.208175 -69.961478)
			(xy 27.215616 -69.97978) (xy 27.222196 -69.98716) (xy 27.22245 -69.987414) (xy 27.398726 -70.16369)
			(xy 27.399234 -70.164198) (xy 27.406612 -70.170789) (xy 27.424911 -70.178255) (xy 27.434794 -70.178676)
		)
		(stroke
			(width 0)
			(type solid)
		)
		(fill yes)
		(layer "In9.Cu")
		(net "P12V_SSD1_R")
	)
	(gr_poly
		(pts
			(xy 72.478138 -70.178676) (xy 72.488205 -70.178245) (xy 72.506797 -70.170519) (xy 72.514206 -70.16369)
			(xy 72.840342 -69.837554) (xy 72.84085 -69.837046) (xy 72.847433 -69.829665) (xy 72.854883 -69.811366)
			(xy 72.855328 -69.801486) (xy 72.855328 -67.91579) (xy 72.854931 -67.906269) (xy 72.847972 -67.888544)
			(xy 72.835019 -67.874585) (xy 72.826626 -67.87007) (xy 72.730868 -67.823842) (xy 72.702166 -67.827144)
			(xy 72.690482 -67.836288) (xy 72.670171 -67.851904) (xy 72.626158 -67.878128) (xy 72.579029 -67.898223)
			(xy 72.529634 -67.911826) (xy 72.478863 -67.918693) (xy 72.453246 -67.919092) (xy 72.425992 -67.918632)
			(xy 72.372039 -67.910881) (xy 72.319737 -67.895529) (xy 72.270153 -67.87289) (xy 72.224297 -67.843425)
			(xy 72.1831 -67.807732) (xy 72.147403 -67.76654) (xy 72.117932 -67.720687) (xy 72.095287 -67.671106)
			(xy 72.079929 -67.618807) (xy 72.072171 -67.564854) (xy 72.072171 -67.510346) (xy 72.079929 -67.456393)
			(xy 72.095287 -67.404094) (xy 72.117932 -67.354513) (xy 72.147403 -67.30866) (xy 72.1831 -67.267468)
			(xy 72.224297 -67.231775) (xy 72.270153 -67.20231) (xy 72.319737 -67.179671) (xy 72.372039 -67.164319)
			(xy 72.425992 -67.156568) (xy 72.453246 -67.156076) (xy 72.478863 -67.156488) (xy 72.529638 -67.163343)
			(xy 72.579036 -67.176936) (xy 72.626169 -67.197024) (xy 72.670187 -67.223243) (xy 72.690482 -67.23888)
			(xy 72.702166 -67.248024) (xy 72.730868 -67.251326) (xy 72.826626 -67.205098) (xy 72.835032 -67.200601)
			(xy 72.847985 -67.186632) (xy 72.854955 -67.168903) (xy 72.855328 -67.159378) (xy 72.855328 -65.506854)
			(xy 72.841612 -65.483486) (xy 72.830182 -65.476628) (xy 72.829674 -65.476628) (xy 72.756522 -65.433702)
			(xy 72.752131 -65.431316) (xy 72.742665 -65.428114) (xy 72.737726 -65.427352) (xy 72.727312 -65.426082)
			(xy 72.70369 -65.432432) (xy 72.698102 -65.43548) (xy 72.669816 -65.450254) (xy 72.60954 -65.471196)
			(xy 72.546619 -65.481816) (xy 72.514714 -65.48247) (xy 72.51446 -65.48247) (xy 72.487213 -65.481981)
			(xy 72.433275 -65.474221) (xy 72.380991 -65.458864) (xy 72.331424 -65.436223) (xy 72.285583 -65.406758)
			(xy 72.244401 -65.37107) (xy 72.208718 -65.329885) (xy 72.179258 -65.284041) (xy 72.156622 -65.234472)
			(xy 72.141271 -65.182185) (xy 72.133516 -65.128247) (xy 72.133516 -65.073753) (xy 72.141271 -65.019815)
			(xy 72.156622 -64.967528) (xy 72.179258 -64.917959) (xy 72.208718 -64.872115) (xy 72.244401 -64.83093)
			(xy 72.285583 -64.795242) (xy 72.331424 -64.765777) (xy 72.380991 -64.743136) (xy 72.433275 -64.727779)
			(xy 72.487213 -64.720019) (xy 72.51446 -64.719454) (xy 72.514714 -64.719454) (xy 72.546618 -64.720119)
			(xy 72.609533 -64.730755) (xy 72.669813 -64.751679) (xy 72.698102 -64.766444) (xy 72.70369 -64.769492)
			(xy 72.717406 -64.773302) (xy 72.722391 -64.774512) (xy 72.732629 -64.775152) (xy 72.737726 -64.774572)
			(xy 72.747632 -64.773302) (xy 72.829928 -64.725296) (xy 72.83069 -64.724788) (xy 72.837974 -64.719977)
			(xy 72.849032 -64.706486) (xy 72.854944 -64.690074) (xy 72.855328 -64.681354) (xy 72.855328 -52.63261)
			(xy 72.85482 -52.626006) (xy 72.85355 -52.615592) (xy 72.852788 -52.612798) (xy 72.847076 -52.589272)
			(xy 72.840965 -52.541247) (xy 72.840596 -52.51704) (xy 72.840596 -52.499514) (xy 72.84085 -52.49418)
			(xy 72.842628 -52.477162) (xy 72.843898 -52.46624) (xy 72.846184 -52.44973) (xy 72.8472 -52.444904)
			(xy 72.8472 -52.44465) (xy 72.851264 -52.427378) (xy 72.852534 -52.422552) (xy 72.852534 -52.421536)
			(xy 72.85355 -52.418234) (xy 72.855328 -52.41163) (xy 72.855328 -51.455828) (xy 72.855765 -51.445764)
			(xy 72.863501 -51.427181) (xy 72.870314 -51.41976) (xy 72.977248 -51.312826) (xy 72.984648 -51.305985)
			(xy 73.003246 -51.298263) (xy 73.013316 -51.29784) (xy 73.703688 -51.29784) (xy 73.71207 -51.297078)
			(xy 73.719676 -51.295567) (xy 73.733514 -51.288583) (xy 73.739248 -51.283362) (xy 73.819258 -51.203352)
			(xy 73.819004 -51.198526) (xy 73.819004 -49.20615) (xy 73.818408 -49.193826) (xy 73.806954 -49.172001)
			(xy 73.79716 -49.164494) (xy 73.73366 -49.120044) (xy 73.727159 -49.115866) (xy 73.712426 -49.111225)
			(xy 73.704704 -49.1109) (xy 73.682606 -49.1109) (xy 73.674732 -49.113694) (xy 73.644548 -49.123452)
			(xy 73.581988 -49.133929) (xy 73.550272 -49.134522) (xy 73.546208 -49.134522) (xy 73.51915 -49.133759)
			(xy 73.465649 -49.125532) (xy 73.413849 -49.109824) (xy 73.364789 -49.086952) (xy 73.319456 -49.057373)
			(xy 73.278759 -49.021683) (xy 73.243517 -48.980598) (xy 73.214436 -48.934943) (xy 73.192102 -48.885636)
			(xy 73.176963 -48.833667) (xy 73.169323 -48.780079) (xy 73.168764 -48.753014) (xy 73.169249 -48.725761)
			(xy 73.177004 -48.671811) (xy 73.192357 -48.619513) (xy 73.214997 -48.569932) (xy 73.244463 -48.524078)
			(xy 73.280154 -48.482883) (xy 73.321344 -48.447188) (xy 73.367195 -48.417717) (xy 73.416773 -48.395072)
			(xy 73.46907 -48.379712) (xy 73.523019 -48.371952) (xy 73.550272 -48.371506) (xy 73.551034 -48.371506)
			(xy 73.58465 -48.37226) (xy 73.650826 -48.384143) (xy 73.682606 -48.395128) (xy 73.69429 -48.399446)
			(xy 73.718928 -48.396398) (xy 73.79716 -48.341534) (xy 73.806829 -48.333922) (xy 73.818235 -48.31216)
			(xy 73.819004 -48.299878) (xy 73.819004 -41.95445) (xy 73.818572 -41.944384) (xy 73.810845 -41.925792)
			(xy 73.804018 -41.918382) (xy 72.923654 -41.038018) (xy 72.916542 -41.030652) (xy 72.897746 -41.023032)
			(xy 71.11619 -41.023032) (xy 71.107488 -41.023383) (xy 71.091085 -41.029198) (xy 71.077565 -41.040157)
			(xy 71.072756 -41.047416) (xy 71.027798 -41.121584) (xy 71.023734 -41.13022) (xy 71.020409 -41.140526)
			(xy 71.02184 -41.162115) (xy 71.026528 -41.171876) (xy 71.02729 -41.1734) (xy 71.031608 -41.18229)
			(xy 71.043687 -41.20826) (xy 71.060801 -41.262918) (xy 71.069572 -41.319517) (xy 71.070216 -41.348152)
			(xy 71.070216 -41.34866) (xy 71.070216 -41.35501) (xy 71.069305 -41.383073) (xy 71.060259 -41.438486)
			(xy 71.043187 -41.491975) (xy 71.01846 -41.542383) (xy 70.98661 -41.588623) (xy 70.967854 -41.609518)
			(xy 70.9676 -41.609772) (xy 70.961128 -41.617127) (xy 70.953831 -41.63529) (xy 70.953376 -41.645078)
			(xy 70.953376 -41.724072) (xy 70.960234 -41.741852) (xy 70.967092 -41.748964) (xy 70.98636 -41.770291)
			(xy 71.018921 -41.817653) (xy 71.044008 -41.869364) (xy 71.061055 -41.924253) (xy 71.069674 -41.981078)
			(xy 71.069672 -42.038554) (xy 71.061048 -42.095378) (xy 71.043997 -42.150266) (xy 71.018905 -42.201974)
			(xy 70.98634 -42.249334) (xy 70.967092 -42.27068) (xy 70.960234 -42.277792) (xy 70.953376 -42.295572)
			(xy 70.953376 -42.384472) (xy 70.960234 -42.402252) (xy 70.967092 -42.409364) (xy 70.986361 -42.430692)
			(xy 71.018922 -42.478055) (xy 71.04401 -42.529767) (xy 71.061056 -42.584657) (xy 71.069675 -42.641484)
			(xy 71.070216 -42.670222) (xy 71.069743 -42.697592) (xy 71.061916 -42.751769) (xy 71.046427 -42.804271)
			(xy 71.023594 -42.85402) (xy 70.993885 -42.899996) (xy 70.976236 -42.92092) (xy 70.97014 -42.928032)
			(xy 70.96379 -42.944796) (xy 70.96379 -43.030648) (xy 70.97014 -43.047412) (xy 70.976236 -43.054524)
			(xy 70.993879 -43.075455) (xy 71.023607 -43.12142) (xy 71.046451 -43.171167) (xy 71.061941 -43.223671)
			(xy 71.069758 -43.277851) (xy 71.070216 -43.305222) (xy 71.06973 -43.332473) (xy 71.061974 -43.386421)
			(xy 71.046619 -43.438716) (xy 71.023977 -43.488293) (xy 70.994511 -43.534143) (xy 70.95882 -43.575334)
			(xy 70.917629 -43.611025) (xy 70.871779 -43.640491) (xy 70.822202 -43.663133) (xy 70.769907 -43.678488)
			(xy 70.715959 -43.686244) (xy 70.661457 -43.686244) (xy 70.607509 -43.678488) (xy 70.555214 -43.663133)
			(xy 70.505637 -43.640491) (xy 70.459787 -43.611025) (xy 70.418596 -43.575334) (xy 70.382905 -43.534143)
			(xy 70.353439 -43.488293) (xy 70.330797 -43.438716) (xy 70.315442 -43.386421) (xy 70.307686 -43.332473)
			(xy 70.3072 -43.305222) (xy 70.307677 -43.277854) (xy 70.315511 -43.223681) (xy 70.331007 -43.171184)
			(xy 70.353846 -43.12144) (xy 70.38356 -43.075471) (xy 70.40118 -43.054524) (xy 70.407276 -43.047412)
			(xy 70.413626 -43.030648) (xy 70.413626 -42.944796) (xy 70.407276 -42.928032) (xy 70.40118 -42.92092)
			(xy 70.383538 -42.899989) (xy 70.353811 -42.854022) (xy 70.330966 -42.804276) (xy 70.315474 -42.751772)
			(xy 70.307653 -42.697593) (xy 70.3072 -42.670222) (xy 70.307719 -42.641482) (xy 70.316339 -42.584653)
			(xy 70.333387 -42.52976) (xy 70.358477 -42.478045) (xy 70.391041 -42.43068) (xy 70.410324 -42.409364)
			(xy 70.417182 -42.402252) (xy 70.42404 -42.384472) (xy 70.42404 -42.295572) (xy 70.417182 -42.277792)
			(xy 70.410324 -42.27068) (xy 70.391052 -42.249353) (xy 70.358483 -42.20199) (xy 70.333388 -42.150277)
			(xy 70.316335 -42.095385) (xy 70.30771 -42.038556) (xy 70.307708 -41.981076) (xy 70.316328 -41.924246)
			(xy 70.333376 -41.869352) (xy 70.358467 -41.817638) (xy 70.391031 -41.770272) (xy 70.410324 -41.748964)
			(xy 70.417182 -41.741852) (xy 70.42404 -41.724072) (xy 70.42404 -41.635172) (xy 70.417182 -41.617646)
			(xy 70.410324 -41.61028) (xy 70.391524 -41.589486) (xy 70.359596 -41.543413) (xy 70.334742 -41.493168)
			(xy 70.317496 -41.439831) (xy 70.308228 -41.384547) (xy 70.3072 -41.356534) (xy 70.3072 -41.349422)
			(xy 70.307712 -41.320529) (xy 70.316399 -41.263399) (xy 70.333623 -41.20824) (xy 70.345808 -41.182036)
			(xy 70.353174 -41.166542) (xy 70.356236 -41.157735) (xy 70.356502 -41.139107) (xy 70.353682 -41.13022)
			(xy 70.349618 -41.121584) (xy 70.30466 -41.04767) (xy 70.297802 -41.035986) (xy 70.274688 -41.023032)
			(xy 69.354192 -41.023032) (xy 69.342574 -41.023612) (xy 69.321693 -41.033809) (xy 69.31406 -41.04259)
			(xy 69.257418 -41.11498) (xy 69.252592 -41.137586) (xy 69.255386 -41.14927) (xy 69.260708 -41.171949)
			(xy 69.266438 -41.21818) (xy 69.266816 -41.241472) (xy 69.266355 -41.268726) (xy 69.258601 -41.322681)
			(xy 69.243247 -41.374982) (xy 69.220607 -41.424567) (xy 69.191139 -41.470424) (xy 69.155446 -41.51162)
			(xy 69.114253 -41.547318) (xy 69.068398 -41.576789) (xy 69.018816 -41.599435) (xy 68.966516 -41.614793)
			(xy 68.912562 -41.622552) (xy 68.885308 -41.62298) (xy 68.856569 -41.62246) (xy 68.799741 -41.613838)
			(xy 68.744849 -41.596788) (xy 68.693137 -41.571696) (xy 68.645775 -41.53913) (xy 68.62445 -41.519856)
			(xy 68.617338 -41.512998) (xy 68.599558 -41.50614) (xy 68.510658 -41.50614) (xy 68.492878 -41.512998)
			(xy 68.485766 -41.519856) (xy 68.464438 -41.539124) (xy 68.417073 -41.571683) (xy 68.365361 -41.596771)
			(xy 68.310472 -41.613818) (xy 68.253646 -41.62244) (xy 68.224908 -41.62298) (xy 68.197656 -41.622517)
			(xy 68.143705 -41.614761) (xy 68.091408 -41.599405) (xy 68.041829 -41.576763) (xy 67.995977 -41.547295)
			(xy 67.954785 -41.511601) (xy 67.919093 -41.470407) (xy 67.889627 -41.424554) (xy 67.866988 -41.374973)
			(xy 67.851635 -41.322675) (xy 67.843881 -41.268725) (xy 67.8434 -41.241472) (xy 67.843779 -41.21818)
			(xy 67.84951 -41.171949) (xy 67.85483 -41.14927) (xy 67.857624 -41.137586) (xy 67.852798 -41.11498)
			(xy 67.796156 -41.04259) (xy 67.788568 -41.033756) (xy 67.767658 -41.02356) (xy 67.756024 -41.023032)
			(xy 63.908432 -41.023032) (xy 63.898368 -41.023468) (xy 63.879784 -41.031204) (xy 63.872364 -41.038018)
			(xy 63.70574 -41.204642) (xy 63.699 -41.212013) (xy 63.691417 -41.230475) (xy 63.691008 -41.240456)
			(xy 63.691008 -43.73626) (xy 72.21296 -43.73626) (xy 72.217031 -43.680638) (xy 72.229157 -43.626201)
			(xy 72.24908 -43.57411) (xy 72.276376 -43.525475) (xy 72.310462 -43.481332) (xy 72.350611 -43.442623)
			(xy 72.395969 -43.410172) (xy 72.445569 -43.384671) (xy 72.498353 -43.366664) (xy 72.553196 -43.356534)
			(xy 72.60893 -43.354497) (xy 72.664367 -43.360597) (xy 72.718324 -43.374703) (xy 72.769653 -43.396515)
			(xy 72.817259 -43.425569) (xy 72.860127 -43.461244) (xy 72.897344 -43.502781) (xy 72.928117 -43.549294)
			(xy 72.951789 -43.599791) (xy 72.967857 -43.653198) (xy 72.975977 -43.708374) (xy 72.976486 -43.73626)
			(xy 72.975977 -43.764146) (xy 72.967857 -43.819322) (xy 72.951789 -43.872729) (xy 72.928117 -43.923226)
			(xy 72.897344 -43.969739) (xy 72.860127 -44.011276) (xy 72.817259 -44.046951) (xy 72.769653 -44.076005)
			(xy 72.718324 -44.097817) (xy 72.664367 -44.111923) (xy 72.60893 -44.118023) (xy 72.553196 -44.115986)
			(xy 72.498353 -44.105856) (xy 72.445569 -44.087849) (xy 72.395969 -44.062348) (xy 72.350611 -44.029897)
			(xy 72.310462 -43.991188) (xy 72.276376 -43.947045) (xy 72.24908 -43.89841) (xy 72.229157 -43.846319)
			(xy 72.217031 -43.791882) (xy 72.21296 -43.73626) (xy 63.691008 -43.73626) (xy 63.691008 -45.114464)
			(xy 72.065386 -45.114464) (xy 72.069457 -45.058842) (xy 72.081583 -45.004405) (xy 72.101506 -44.952314)
			(xy 72.128802 -44.903679) (xy 72.162888 -44.859536) (xy 72.203037 -44.820827) (xy 72.248395 -44.788376)
			(xy 72.297995 -44.762875) (xy 72.350779 -44.744868) (xy 72.405622 -44.734738) (xy 72.461356 -44.732701)
			(xy 72.516793 -44.738801) (xy 72.57075 -44.752907) (xy 72.622079 -44.774719) (xy 72.669685 -44.803773)
			(xy 72.712553 -44.839448) (xy 72.74977 -44.880985) (xy 72.780543 -44.927498) (xy 72.804215 -44.977995)
			(xy 72.820283 -45.031402) (xy 72.828403 -45.086578) (xy 72.828912 -45.114464) (xy 72.828403 -45.14235)
			(xy 72.820283 -45.197526) (xy 72.804215 -45.250933) (xy 72.780543 -45.30143) (xy 72.74977 -45.347943)
			(xy 72.712553 -45.38948) (xy 72.669685 -45.425155) (xy 72.622079 -45.454209) (xy 72.57075 -45.476021)
			(xy 72.516793 -45.490127) (xy 72.461356 -45.496227) (xy 72.405622 -45.49419) (xy 72.350779 -45.48406)
			(xy 72.297995 -45.466053) (xy 72.248395 -45.440552) (xy 72.203037 -45.408101) (xy 72.162888 -45.369392)
			(xy 72.128802 -45.325249) (xy 72.101506 -45.276614) (xy 72.081583 -45.224523) (xy 72.069457 -45.170086)
			(xy 72.065386 -45.114464) (xy 63.691008 -45.114464) (xy 63.691008 -46.893226) (xy 72.337166 -46.893226)
			(xy 72.341237 -46.837604) (xy 72.353363 -46.783167) (xy 72.373286 -46.731076) (xy 72.400582 -46.682441)
			(xy 72.434668 -46.638298) (xy 72.474817 -46.599589) (xy 72.520175 -46.567138) (xy 72.569775 -46.541637)
			(xy 72.622559 -46.52363) (xy 72.677402 -46.5135) (xy 72.733136 -46.511463) (xy 72.788573 -46.517563)
			(xy 72.84253 -46.531669) (xy 72.893859 -46.553481) (xy 72.941465 -46.582535) (xy 72.984333 -46.61821)
			(xy 73.02155 -46.659747) (xy 73.052323 -46.70626) (xy 73.075995 -46.756757) (xy 73.092063 -46.810164)
			(xy 73.100183 -46.86534) (xy 73.100692 -46.893226) (xy 73.100183 -46.921112) (xy 73.092063 -46.976288)
			(xy 73.075995 -47.029695) (xy 73.052323 -47.080192) (xy 73.02155 -47.126705) (xy 72.984333 -47.168242)
			(xy 72.941465 -47.203917) (xy 72.893859 -47.232971) (xy 72.84253 -47.254783) (xy 72.788573 -47.268889)
			(xy 72.733136 -47.274989) (xy 72.677402 -47.272952) (xy 72.622559 -47.262822) (xy 72.569775 -47.244815)
			(xy 72.520175 -47.219314) (xy 72.474817 -47.186863) (xy 72.434668 -47.148154) (xy 72.400582 -47.104011)
			(xy 72.373286 -47.055376) (xy 72.353363 -47.003285) (xy 72.341237 -46.948848) (xy 72.337166 -46.893226)
			(xy 63.691008 -46.893226) (xy 63.691008 -47.936658) (xy 70.652894 -47.936658) (xy 70.65338 -47.909407)
			(xy 70.661136 -47.855459) (xy 70.676491 -47.803164) (xy 70.699133 -47.753587) (xy 70.728599 -47.707737)
			(xy 70.76429 -47.666546) (xy 70.805481 -47.630855) (xy 70.851331 -47.601389) (xy 70.900908 -47.578747)
			(xy 70.953203 -47.563392) (xy 71.007151 -47.555636) (xy 71.061653 -47.555636) (xy 71.115601 -47.563392)
			(xy 71.167896 -47.578747) (xy 71.217473 -47.601389) (xy 71.263323 -47.630855) (xy 71.304514 -47.666546)
			(xy 71.340205 -47.707737) (xy 71.369671 -47.753587) (xy 71.392313 -47.803164) (xy 71.407668 -47.855459)
			(xy 71.415424 -47.909407) (xy 71.41591 -47.936658) (xy 71.415466 -47.963) (xy 71.408215 -48.015181)
			(xy 71.393858 -48.065871) (xy 71.372669 -48.114105) (xy 71.345049 -48.158968) (xy 71.311524 -48.199608)
			(xy 71.272729 -48.235252) (xy 71.251318 -48.250602) (xy 71.239497 -48.259301) (xy 71.221065 -48.282126)
			(xy 71.209884 -48.30925) (xy 71.206877 -48.338435) (xy 71.212292 -48.367269) (xy 71.225682 -48.393373)
			(xy 71.245943 -48.414593) (xy 71.25843 -48.422306) (xy 71.282979 -48.43698) (xy 71.327735 -48.472587)
			(xy 71.366675 -48.514475) (xy 71.398929 -48.561705) (xy 71.423772 -48.61322) (xy 71.44065 -48.667866)
			(xy 71.449183 -48.724418) (xy 71.449692 -48.753014) (xy 71.449206 -48.780265) (xy 71.44145 -48.834213)
			(xy 71.426095 -48.886508) (xy 71.403453 -48.936085) (xy 71.373987 -48.981935) (xy 71.338296 -49.023126)
			(xy 71.297105 -49.058817) (xy 71.251255 -49.088283) (xy 71.201678 -49.110925) (xy 71.149383 -49.12628)
			(xy 71.095435 -49.134036) (xy 71.040933 -49.134036) (xy 70.986985 -49.12628) (xy 70.93469 -49.110925)
			(xy 70.885113 -49.088283) (xy 70.839263 -49.058817) (xy 70.798072 -49.023126) (xy 70.762381 -48.981935)
			(xy 70.732915 -48.936085) (xy 70.710273 -48.886508) (xy 70.694918 -48.834213) (xy 70.687162 -48.780265)
			(xy 70.686676 -48.753014) (xy 70.687105 -48.726672) (xy 70.69436 -48.67449) (xy 70.708719 -48.6238)
			(xy 70.729911 -48.575566) (xy 70.757533 -48.530704) (xy 70.79106 -48.490064) (xy 70.829856 -48.45442)
			(xy 70.851268 -48.43907) (xy 70.863119 -48.430408) (xy 70.881555 -48.407575) (xy 70.892736 -48.380442)
			(xy 70.89574 -48.351249) (xy 70.890319 -48.322408) (xy 70.876919 -48.296299) (xy 70.856649 -48.275078)
			(xy 70.844156 -48.267366) (xy 70.819636 -48.252647) (xy 70.774881 -48.217046) (xy 70.735939 -48.175166)
			(xy 70.703683 -48.127943) (xy 70.678835 -48.076436) (xy 70.66195 -48.021798) (xy 70.653408 -47.965252)
			(xy 70.652894 -47.936658) (xy 63.691008 -47.936658) (xy 63.691008 -58.731404) (xy 65.52057 -58.731404)
			(xy 65.521021 -58.704033) (xy 65.52884 -58.649853) (xy 65.544332 -58.597349) (xy 65.567177 -58.547602)
			(xy 65.596906 -58.501636) (xy 65.61455 -58.480706) (xy 65.620646 -58.473594) (xy 65.626996 -58.456576)
			(xy 65.626996 -58.371232) (xy 65.620646 -58.354214) (xy 65.61455 -58.347102) (xy 65.596912 -58.326167)
			(xy 65.567186 -58.2802) (xy 65.544339 -58.230454) (xy 65.528841 -58.177952) (xy 65.521012 -58.123774)
			(xy 65.521011 -58.069032) (xy 65.52884 -58.014854) (xy 65.544336 -57.962352) (xy 65.567183 -57.912605)
			(xy 65.596909 -57.866638) (xy 65.61455 -57.845706) (xy 65.620646 -57.838594) (xy 65.626996 -57.821576)
			(xy 65.626996 -57.736232) (xy 65.620646 -57.719214) (xy 65.61455 -57.712102) (xy 65.596912 -57.691167)
			(xy 65.567186 -57.6452) (xy 65.544339 -57.595454) (xy 65.528841 -57.542952) (xy 65.521012 -57.488774)
			(xy 65.521011 -57.434032) (xy 65.52884 -57.379854) (xy 65.544336 -57.327352) (xy 65.567183 -57.277605)
			(xy 65.596909 -57.231638) (xy 65.61455 -57.210706) (xy 65.620646 -57.203594) (xy 65.626996 -57.186576)
			(xy 65.626996 -57.101232) (xy 65.620646 -57.084214) (xy 65.61455 -57.077102) (xy 65.596906 -57.056174)
			(xy 65.567193 -57.010201) (xy 65.544357 -56.960452) (xy 65.528868 -56.90795) (xy 65.521042 -56.853774)
			(xy 65.52057 -56.826404) (xy 65.521056 -56.799153) (xy 65.528812 -56.745205) (xy 65.544167 -56.69291)
			(xy 65.566809 -56.643333) (xy 65.596275 -56.597483) (xy 65.631966 -56.556292) (xy 65.673157 -56.520601)
			(xy 65.719007 -56.491135) (xy 65.768584 -56.468493) (xy 65.820879 -56.453138) (xy 65.874827 -56.445382)
			(xy 65.929329 -56.445382) (xy 65.983277 -56.453138) (xy 66.035572 -56.468493) (xy 66.085149 -56.491135)
			(xy 66.130999 -56.520601) (xy 66.17219 -56.556292) (xy 66.207881 -56.597483) (xy 66.237347 -56.643333)
			(xy 66.259989 -56.69291) (xy 66.275344 -56.745205) (xy 66.2831 -56.799153) (xy 66.283586 -56.826404)
			(xy 66.283126 -56.853774) (xy 66.275307 -56.907954) (xy 66.259817 -56.960457) (xy 66.236974 -57.010204)
			(xy 66.207248 -57.056171) (xy 66.189606 -57.077102) (xy 66.18351 -57.084214) (xy 66.17716 -57.101232)
			(xy 66.17716 -57.186576) (xy 66.18351 -57.203594) (xy 66.189606 -57.210706) (xy 66.207249 -57.231636)
			(xy 66.236971 -57.277605) (xy 66.259814 -57.327352) (xy 66.275309 -57.379854) (xy 66.283137 -57.434033)
			(xy 66.283136 -57.488773) (xy 66.275308 -57.542952) (xy 66.259812 -57.595454) (xy 66.236968 -57.6452)
			(xy 66.207246 -57.691169) (xy 66.189606 -57.712102) (xy 66.18351 -57.719214) (xy 66.17716 -57.736232)
			(xy 66.17716 -57.821576) (xy 66.18351 -57.838594) (xy 66.189606 -57.845706) (xy 66.207249 -57.866636)
			(xy 66.236971 -57.912605) (xy 66.259814 -57.962352) (xy 66.275309 -58.014854) (xy 66.283137 -58.069033)
			(xy 66.283136 -58.123773) (xy 66.275308 -58.177952) (xy 66.259812 -58.230454) (xy 66.236968 -58.2802)
			(xy 66.207246 -58.326169) (xy 66.189606 -58.347102) (xy 66.18351 -58.354214) (xy 66.17716 -58.371232)
			(xy 66.17716 -58.456576) (xy 66.18351 -58.473594) (xy 66.189606 -58.480706) (xy 66.207262 -58.501624)
			(xy 66.236971 -58.547601) (xy 66.259804 -58.597352) (xy 66.275291 -58.649856) (xy 66.283114 -58.704034)
			(xy 66.283586 -58.731404) (xy 66.2831 -58.758655) (xy 66.278436 -58.791094) (xy 68.176394 -58.791094)
			(xy 68.176858 -58.763724) (xy 68.184677 -58.709545) (xy 68.200166 -58.657042) (xy 68.223008 -58.607295)
			(xy 68.252733 -58.561328) (xy 68.270374 -58.540396) (xy 68.27647 -58.533284) (xy 68.28282 -58.516266)
			(xy 68.28282 -58.430922) (xy 68.27647 -58.413904) (xy 68.270374 -58.406792) (xy 68.252725 -58.385865)
			(xy 68.222997 -58.339897) (xy 68.200149 -58.29015) (xy 68.184652 -58.237647) (xy 68.176823 -58.183467)
			(xy 68.176823 -58.128724) (xy 68.184654 -58.074544) (xy 68.200153 -58.022041) (xy 68.223002 -57.972295)
			(xy 68.252731 -57.926328) (xy 68.270374 -57.905396) (xy 68.27647 -57.898284) (xy 68.28282 -57.881266)
			(xy 68.28282 -57.795922) (xy 68.27647 -57.778904) (xy 68.270374 -57.771792) (xy 68.252714 -57.750877)
			(xy 68.223006 -57.704899) (xy 68.200174 -57.655147) (xy 68.184688 -57.602643) (xy 68.176865 -57.548464)
			(xy 68.176394 -57.521094) (xy 68.176865 -57.494779) (xy 68.184082 -57.442645) (xy 68.198391 -57.391998)
			(xy 68.219523 -57.343796) (xy 68.247075 -57.298953) (xy 68.280525 -57.258321) (xy 68.299584 -57.24017)
			(xy 68.306998 -57.232659) (xy 68.315516 -57.213371) (xy 68.316094 -57.202832) (xy 68.316094 -57.128156)
			(xy 68.31555 -57.117608) (xy 68.307025 -57.098313) (xy 68.299584 -57.090818) (xy 68.28051 -57.072678)
			(xy 68.247032 -57.032058) (xy 68.219462 -56.987219) (xy 68.198322 -56.939012) (xy 68.184016 -56.888356)
			(xy 68.176816 -56.836213) (xy 68.176394 -56.809894) (xy 68.17688 -56.782643) (xy 68.184636 -56.728695)
			(xy 68.199991 -56.6764) (xy 68.222633 -56.626823) (xy 68.252099 -56.580973) (xy 68.28779 -56.539782)
			(xy 68.328981 -56.504091) (xy 68.374831 -56.474625) (xy 68.424408 -56.451983) (xy 68.476703 -56.436628)
			(xy 68.530651 -56.428872) (xy 68.585153 -56.428872) (xy 68.639101 -56.436628) (xy 68.691396 -56.451983)
			(xy 68.740973 -56.474625) (xy 68.786823 -56.504091) (xy 68.828014 -56.539782) (xy 68.863705 -56.580973)
			(xy 68.893171 -56.626823) (xy 68.915813 -56.6764) (xy 68.931168 -56.728695) (xy 68.938924 -56.782643)
			(xy 68.93941 -56.809894) (xy 68.938996 -56.836211) (xy 68.931768 -56.888347) (xy 68.917447 -56.938996)
			(xy 68.896305 -56.987197) (xy 68.868743 -57.032038) (xy 68.835283 -57.072669) (xy 68.81622 -57.090818)
			(xy 68.808811 -57.098334) (xy 68.80029 -57.117618) (xy 68.79971 -57.128156) (xy 68.79971 -57.202832)
			(xy 68.80026 -57.213379) (xy 68.80878 -57.232675) (xy 68.81622 -57.24017) (xy 68.83527 -57.258335)
			(xy 68.868753 -57.298947) (xy 68.89633 -57.343781) (xy 68.917474 -57.391983) (xy 68.931784 -57.442636)
			(xy 68.935157 -57.467049) (xy 69.118492 -57.467049) (xy 69.118492 -57.412551) (xy 69.126248 -57.358607)
			(xy 69.141601 -57.306316) (xy 69.16424 -57.256742) (xy 69.193704 -57.210894) (xy 69.229392 -57.169706)
			(xy 69.270578 -57.134016) (xy 69.316424 -57.10455) (xy 69.365997 -57.081908) (xy 69.418287 -57.066552)
			(xy 69.472231 -57.058794) (xy 69.49948 -57.058306) (xy 69.525797 -57.058724) (xy 69.577933 -57.065951)
			(xy 69.628582 -57.080271) (xy 69.676784 -57.101412) (xy 69.721625 -57.128973) (xy 69.762255 -57.162433)
			(xy 69.780404 -57.181496) (xy 69.787923 -57.188901) (xy 69.807205 -57.197423) (xy 69.817742 -57.198006)
			(xy 69.892418 -57.198006) (xy 69.902964 -57.197444) (xy 69.922259 -57.188932) (xy 69.929756 -57.181496)
			(xy 69.947911 -57.162437) (xy 69.988527 -57.128958) (xy 70.033364 -57.101384) (xy 70.081567 -57.080242)
			(xy 70.132221 -57.065933) (xy 70.184362 -57.05873) (xy 70.21068 -57.058306) (xy 70.237935 -57.05874)
			(xy 70.29189 -57.066494) (xy 70.327158 -57.076848) (xy 71.138542 -57.076848) (xy 71.139026 -57.049478)
			(xy 71.146838 -56.9953) (xy 71.162322 -56.942796) (xy 71.18516 -56.893049) (xy 71.214882 -56.847082)
			(xy 71.232522 -56.82615) (xy 71.238618 -56.819038) (xy 71.244968 -56.80202) (xy 71.244968 -56.716676)
			(xy 71.238618 -56.699658) (xy 71.232522 -56.692546) (xy 71.214894 -56.671605) (xy 71.18518 -56.625635)
			(xy 71.162342 -56.57589) (xy 71.146848 -56.523391) (xy 71.139017 -56.469217) (xy 71.138542 -56.441848)
			(xy 71.139028 -56.414597) (xy 71.146784 -56.360649) (xy 71.162139 -56.308354) (xy 71.184781 -56.258777)
			(xy 71.214247 -56.212927) (xy 71.249938 -56.171736) (xy 71.291129 -56.136045) (xy 71.336979 -56.106579)
			(xy 71.386556 -56.083937) (xy 71.438851 -56.068582) (xy 71.492799 -56.060826) (xy 71.547301 -56.060826)
			(xy 71.601249 -56.068582) (xy 71.653544 -56.083937) (xy 71.703121 -56.106579) (xy 71.748971 -56.136045)
			(xy 71.790162 -56.171736) (xy 71.825853 -56.212927) (xy 71.855319 -56.258777) (xy 71.877961 -56.308354)
			(xy 71.893316 -56.360649) (xy 71.901072 -56.414597) (xy 71.901558 -56.441848) (xy 71.901072 -56.469218)
			(xy 71.89326 -56.523396) (xy 71.877777 -56.5759) (xy 71.854939 -56.625647) (xy 71.825218 -56.671614)
			(xy 71.807578 -56.692546) (xy 71.801482 -56.699658) (xy 71.795132 -56.716676) (xy 71.795132 -56.80202)
			(xy 71.801482 -56.819038) (xy 71.807578 -56.82615) (xy 71.825204 -56.847093) (xy 71.854918 -56.893062)
			(xy 71.877757 -56.942807) (xy 71.893251 -56.995306) (xy 71.901083 -57.04948) (xy 71.901558 -57.076848)
			(xy 71.901072 -57.104099) (xy 71.893316 -57.158047) (xy 71.877961 -57.210342) (xy 71.855319 -57.259919)
			(xy 71.825853 -57.305769) (xy 71.790162 -57.34696) (xy 71.748971 -57.382651) (xy 71.703121 -57.412117)
			(xy 71.653544 -57.434759) (xy 71.601249 -57.450114) (xy 71.547301 -57.45787) (xy 71.492799 -57.45787)
			(xy 71.438851 -57.450114) (xy 71.386556 -57.434759) (xy 71.336979 -57.412117) (xy 71.291129 -57.382651)
			(xy 71.249938 -57.34696) (xy 71.214247 -57.305769) (xy 71.184781 -57.259919) (xy 71.162139 -57.210342)
			(xy 71.146784 -57.158047) (xy 71.139028 -57.104099) (xy 71.138542 -57.076848) (xy 70.327158 -57.076848)
			(xy 70.344192 -57.081849) (xy 70.393777 -57.104492) (xy 70.439634 -57.13396) (xy 70.480831 -57.169655)
			(xy 70.516528 -57.21085) (xy 70.545999 -57.256706) (xy 70.568644 -57.306289) (xy 70.584001 -57.35859)
			(xy 70.591759 -57.412545) (xy 70.591759 -57.467055) (xy 70.584001 -57.52101) (xy 70.568644 -57.573311)
			(xy 70.545999 -57.622894) (xy 70.516528 -57.66875) (xy 70.480831 -57.709945) (xy 70.439634 -57.74564)
			(xy 70.393777 -57.775108) (xy 70.344192 -57.797751) (xy 70.29189 -57.813106) (xy 70.237935 -57.82086)
			(xy 70.21068 -57.821322) (xy 70.184365 -57.820855) (xy 70.132231 -57.813637) (xy 70.081584 -57.799326)
			(xy 70.033382 -57.778194) (xy 69.98854 -57.750642) (xy 69.947907 -57.717191) (xy 69.929756 -57.698132)
			(xy 69.922249 -57.690714) (xy 69.902958 -57.682198) (xy 69.892418 -57.681622) (xy 69.817742 -57.681622)
			(xy 69.807193 -57.682154) (xy 69.787897 -57.690687) (xy 69.780404 -57.698132) (xy 69.762254 -57.717196)
			(xy 69.721638 -57.750678) (xy 69.676802 -57.778253) (xy 69.628597 -57.799394) (xy 69.577941 -57.813701)
			(xy 69.525799 -57.820901) (xy 69.49948 -57.821322) (xy 69.472231 -57.820806) (xy 69.418287 -57.813048)
			(xy 69.365997 -57.797692) (xy 69.316424 -57.77505) (xy 69.270578 -57.745584) (xy 69.229392 -57.709894)
			(xy 69.193704 -57.668706) (xy 69.16424 -57.622858) (xy 69.141601 -57.573284) (xy 69.126248 -57.520993)
			(xy 69.118492 -57.467049) (xy 68.935157 -57.467049) (xy 68.938987 -57.494776) (xy 68.93941 -57.521094)
			(xy 68.938938 -57.548464) (xy 68.931121 -57.602643) (xy 68.915633 -57.655146) (xy 68.892793 -57.704893)
			(xy 68.86307 -57.75086) (xy 68.84543 -57.771792) (xy 68.839334 -57.778904) (xy 68.832984 -57.795922)
			(xy 68.832984 -57.881266) (xy 68.839334 -57.898284) (xy 68.84543 -57.905396) (xy 68.863067 -57.926333)
			(xy 68.892795 -57.972299) (xy 68.915643 -58.022044) (xy 68.931142 -58.074546) (xy 68.938972 -58.128725)
			(xy 68.938973 -58.183466) (xy 68.931144 -58.237645) (xy 68.915646 -58.290147) (xy 68.892799 -58.339893)
			(xy 68.863072 -58.38586) (xy 68.84543 -58.406792) (xy 68.839334 -58.413904) (xy 68.832984 -58.430922)
			(xy 68.832984 -58.516266) (xy 68.839334 -58.533284) (xy 68.84543 -58.540396) (xy 68.863085 -58.561315)
			(xy 68.892794 -58.607292) (xy 68.915626 -58.657043) (xy 68.931113 -58.709546) (xy 68.938938 -58.763724)
			(xy 68.93941 -58.791094) (xy 68.938924 -58.818345) (xy 68.931168 -58.872293) (xy 68.930771 -58.873644)
			(xy 70.20052 -58.873644) (xy 70.201007 -58.846274) (xy 70.208819 -58.792096) (xy 70.224303 -58.739593)
			(xy 70.24714 -58.689846) (xy 70.276861 -58.643878) (xy 70.2945 -58.622946) (xy 70.300596 -58.615834)
			(xy 70.306946 -58.598816) (xy 70.306946 -58.513472) (xy 70.300596 -58.496454) (xy 70.2945 -58.489342)
			(xy 70.276867 -58.468405) (xy 70.247154 -58.422433) (xy 70.224317 -58.372687) (xy 70.208825 -58.320188)
			(xy 70.200995 -58.266013) (xy 70.20052 -58.238644) (xy 70.201006 -58.211393) (xy 70.208762 -58.157445)
			(xy 70.224117 -58.10515) (xy 70.246759 -58.055573) (xy 70.276225 -58.009723) (xy 70.311916 -57.968532)
			(xy 70.353107 -57.932841) (xy 70.398957 -57.903375) (xy 70.448534 -57.880733) (xy 70.500829 -57.865378)
			(xy 70.554777 -57.857622) (xy 70.609279 -57.857622) (xy 70.663227 -57.865378) (xy 70.715522 -57.880733)
			(xy 70.765099 -57.903375) (xy 70.810949 -57.932841) (xy 70.85214 -57.968532) (xy 70.887831 -58.009723)
			(xy 70.917297 -58.055573) (xy 70.939939 -58.10515) (xy 70.955294 -58.157445) (xy 70.96305 -58.211393)
			(xy 70.963536 -58.238644) (xy 70.963053 -58.266014) (xy 70.955241 -58.320193) (xy 70.939757 -58.372696)
			(xy 70.916919 -58.422444) (xy 70.887197 -58.46841) (xy 70.869556 -58.489342) (xy 70.86346 -58.496454)
			(xy 70.85711 -58.513472) (xy 70.85711 -58.598816) (xy 70.86346 -58.615834) (xy 70.869556 -58.622946)
			(xy 70.887176 -58.643893) (xy 70.916893 -58.689861) (xy 70.939733 -58.739605) (xy 70.955228 -58.792102)
			(xy 70.96306 -58.846276) (xy 70.963536 -58.873644) (xy 70.96305 -58.900895) (xy 70.955294 -58.954843)
			(xy 70.939939 -59.007138) (xy 70.917297 -59.056715) (xy 70.887831 -59.102565) (xy 70.85214 -59.143756)
			(xy 70.810949 -59.179447) (xy 70.765099 -59.208913) (xy 70.715522 -59.231555) (xy 70.663227 -59.24691)
			(xy 70.609279 -59.254666) (xy 70.554777 -59.254666) (xy 70.500829 -59.24691) (xy 70.448534 -59.231555)
			(xy 70.398957 -59.208913) (xy 70.353107 -59.179447) (xy 70.311916 -59.143756) (xy 70.276225 -59.102565)
			(xy 70.246759 -59.056715) (xy 70.224117 -59.007138) (xy 70.208762 -58.954843) (xy 70.201006 -58.900895)
			(xy 70.20052 -58.873644) (xy 68.930771 -58.873644) (xy 68.915813 -58.924588) (xy 68.893171 -58.974165)
			(xy 68.863705 -59.020015) (xy 68.828014 -59.061206) (xy 68.786823 -59.096897) (xy 68.740973 -59.126363)
			(xy 68.691396 -59.149005) (xy 68.639101 -59.16436) (xy 68.585153 -59.172116) (xy 68.530651 -59.172116)
			(xy 68.476703 -59.16436) (xy 68.424408 -59.149005) (xy 68.374831 -59.126363) (xy 68.328981 -59.096897)
			(xy 68.28779 -59.061206) (xy 68.252099 -59.020015) (xy 68.222633 -58.974165) (xy 68.199991 -58.924588)
			(xy 68.184636 -58.872293) (xy 68.17688 -58.818345) (xy 68.176394 -58.791094) (xy 66.278436 -58.791094)
			(xy 66.275344 -58.812603) (xy 66.259989 -58.864898) (xy 66.237347 -58.914475) (xy 66.207881 -58.960325)
			(xy 66.17219 -59.001516) (xy 66.130999 -59.037207) (xy 66.085149 -59.066673) (xy 66.035572 -59.089315)
			(xy 65.983277 -59.10467) (xy 65.929329 -59.112426) (xy 65.874827 -59.112426) (xy 65.820879 -59.10467)
			(xy 65.768584 -59.089315) (xy 65.719007 -59.066673) (xy 65.673157 -59.037207) (xy 65.631966 -59.001516)
			(xy 65.596275 -58.960325) (xy 65.566809 -58.914475) (xy 65.544167 -58.864898) (xy 65.528812 -58.812603)
			(xy 65.521056 -58.758655) (xy 65.52057 -58.731404) (xy 63.691008 -58.731404) (xy 63.691008 -60.126453)
			(xy 69.180149 -60.126453) (xy 69.180149 -60.071947) (xy 69.187907 -60.017995) (xy 69.203263 -59.965696)
			(xy 69.225906 -59.916115) (xy 69.255375 -59.870261) (xy 69.291069 -59.829068) (xy 69.332262 -59.793373)
			(xy 69.378117 -59.763905) (xy 69.427698 -59.741262) (xy 69.479997 -59.725906) (xy 69.533949 -59.718149)
			(xy 69.561202 -59.717686) (xy 69.588572 -59.718154) (xy 69.642751 -59.725972) (xy 69.695254 -59.741461)
			(xy 69.745001 -59.764302) (xy 69.790968 -59.794025) (xy 69.8119 -59.811666) (xy 69.819012 -59.817762)
			(xy 69.83603 -59.824112) (xy 69.921374 -59.824112) (xy 69.938392 -59.817762) (xy 69.945504 -59.811666)
			(xy 69.966437 -59.794025) (xy 70.012405 -59.764301) (xy 70.062151 -59.741455) (xy 70.114653 -59.725959)
			(xy 70.168831 -59.71813) (xy 70.223573 -59.71813) (xy 70.277751 -59.725959) (xy 70.330253 -59.741455)
			(xy 70.379999 -59.764301) (xy 70.425967 -59.794025) (xy 70.4469 -59.811666) (xy 70.454012 -59.817762)
			(xy 70.47103 -59.824112) (xy 70.556374 -59.824112) (xy 70.573392 -59.817762) (xy 70.580504 -59.811666)
			(xy 70.601419 -59.794006) (xy 70.647397 -59.764299) (xy 70.697149 -59.741467) (xy 70.749653 -59.725981)
			(xy 70.803832 -59.718158) (xy 70.831202 -59.717686) (xy 70.858453 -59.718184) (xy 70.912399 -59.725941)
			(xy 70.964693 -59.741296) (xy 71.014269 -59.763936) (xy 71.060119 -59.793402) (xy 71.101308 -59.829093)
			(xy 71.136999 -59.870283) (xy 71.166464 -59.916132) (xy 71.189105 -59.965709) (xy 71.20446 -60.018003)
			(xy 71.212216 -60.071949) (xy 71.212216 -60.126451) (xy 71.20446 -60.180397) (xy 71.189105 -60.232691)
			(xy 71.166464 -60.282268) (xy 71.136999 -60.328117) (xy 71.101308 -60.369307) (xy 71.060119 -60.404998)
			(xy 71.014269 -60.434464) (xy 70.964693 -60.457104) (xy 70.912399 -60.472459) (xy 70.858453 -60.480216)
			(xy 70.831202 -60.480702) (xy 70.803832 -60.480234) (xy 70.749653 -60.472417) (xy 70.69715 -60.456928)
			(xy 70.647403 -60.434087) (xy 70.601436 -60.404363) (xy 70.580504 -60.386722) (xy 70.573392 -60.380626)
			(xy 70.556374 -60.374276) (xy 70.47103 -60.374276) (xy 70.454012 -60.380626) (xy 70.4469 -60.386722)
			(xy 70.425967 -60.404363) (xy 70.379999 -60.434087) (xy 70.330253 -60.456933) (xy 70.277751 -60.472429)
			(xy 70.223573 -60.480258) (xy 70.168831 -60.480258) (xy 70.114653 -60.472429) (xy 70.062151 -60.456933)
			(xy 70.012405 -60.434087) (xy 69.966437 -60.404363) (xy 69.945504 -60.386722) (xy 69.938392 -60.380626)
			(xy 69.921374 -60.374276) (xy 69.83603 -60.374276) (xy 69.819012 -60.380626) (xy 69.8119 -60.386722)
			(xy 69.790982 -60.404378) (xy 69.745005 -60.434087) (xy 69.695254 -60.456919) (xy 69.64275 -60.472406)
			(xy 69.588572 -60.48023) (xy 69.561202 -60.480702) (xy 69.533949 -60.480251) (xy 69.479997 -60.472494)
			(xy 69.427698 -60.457138) (xy 69.378117 -60.434495) (xy 69.332262 -60.405027) (xy 69.291069 -60.369332)
			(xy 69.255375 -60.328139) (xy 69.225906 -60.282285) (xy 69.203263 -60.232704) (xy 69.187907 -60.180405)
			(xy 69.180149 -60.126453) (xy 63.691008 -60.126453) (xy 63.691008 -60.999878) (xy 63.690475 -61.009867)
			(xy 63.682768 -61.028306) (xy 63.676022 -61.035692) (xy 62.900306 -61.811408) (xy 62.89295 -61.818057)
			(xy 62.874649 -61.825638) (xy 62.864746 -61.82614) (xy 61.077856 -61.82614) (xy 61.066184 -61.8267)
			(xy 61.045245 -61.837012) (xy 61.037724 -61.845952) (xy 60.988956 -61.909706) (xy 60.983278 -61.917895)
			(xy 60.978057 -61.937106) (xy 60.978796 -61.947044) (xy 60.979812 -61.953648) (xy 60.980574 -61.956696)
			(xy 60.986122 -61.979795) (xy 60.992108 -62.026923) (xy 60.992512 -62.050676) (xy 60.992512 -62.054486)
			(xy 60.991827 -62.081763) (xy 60.983622 -62.135705) (xy 60.96782 -62.187929) (xy 60.944743 -62.237371)
			(xy 60.914862 -62.283024) (xy 60.878785 -62.323957) (xy 60.837248 -62.359337) (xy 60.791096 -62.388442)
			(xy 60.74127 -62.410679) (xy 60.688786 -62.425595) (xy 60.661804 -62.429644) (xy 60.649163 -62.43121)
			(xy 60.623742 -62.432864) (xy 60.611004 -62.432946) (xy 60.587449 -62.432567) (xy 60.540704 -62.426712)
			(xy 60.517786 -62.421262) (xy 60.503562 -62.417706) (xy 60.476384 -62.426342) (xy 60.398152 -62.517274)
			(xy 60.39358 -62.545468) (xy 60.399168 -62.55893) (xy 60.408494 -62.582314) (xy 60.421615 -62.630918)
			(xy 60.428233 -62.680824) (xy 60.428632 -62.705996) (xy 60.428147 -62.733248) (xy 60.420391 -62.787198)
			(xy 60.405036 -62.839494) (xy 60.382395 -62.889073) (xy 60.35293 -62.934926) (xy 60.317238 -62.976119)
			(xy 60.276048 -63.011813) (xy 60.230198 -63.041282) (xy 60.18062 -63.063926) (xy 60.128325 -63.079285)
			(xy 60.074376 -63.087045) (xy 60.047124 -63.087504) (xy 60.018314 -63.086978) (xy 59.961349 -63.078312)
			(xy 59.906337 -63.061174) (xy 59.854529 -63.035954) (xy 59.807107 -63.003225) (xy 59.785758 -62.983872)
			(xy 59.777122 -62.975744) (xy 59.755278 -62.968886) (xy 59.665362 -62.981332) (xy 59.66333 -62.981586)
			(xy 59.652593 -62.984094) (xy 59.634553 -62.996733) (xy 59.628532 -63.00597) (xy 59.613714 -63.03009)
			(xy 59.578076 -63.074069) (xy 59.536328 -63.112298) (xy 59.489387 -63.143935) (xy 59.438286 -63.168286)
			(xy 59.384147 -63.184816) (xy 59.328159 -63.193163) (xy 59.299856 -63.193676) (xy 59.272609 -63.193187)
			(xy 59.218671 -63.185426) (xy 59.166386 -63.170068) (xy 59.116818 -63.147427) (xy 59.070977 -63.117962)
			(xy 59.029796 -63.082273) (xy 58.994112 -63.041087) (xy 58.964652 -62.995243) (xy 58.942016 -62.945673)
			(xy 58.926665 -62.893386) (xy 58.91891 -62.839447) (xy 58.91891 -62.784953) (xy 58.926665 -62.731014)
			(xy 58.942016 -62.678727) (xy 58.964652 -62.629157) (xy 58.994112 -62.583313) (xy 59.029796 -62.542127)
			(xy 59.070977 -62.506438) (xy 59.116818 -62.476973) (xy 59.166386 -62.454332) (xy 59.218671 -62.438974)
			(xy 59.272609 -62.431213) (xy 59.299856 -62.43066) (xy 59.328667 -62.431184) (xy 59.385634 -62.439847)
			(xy 59.440649 -62.456981) (xy 59.49246 -62.482198) (xy 59.539887 -62.514923) (xy 59.561222 -62.534292)
			(xy 59.569858 -62.54242) (xy 59.591702 -62.549278) (xy 59.681618 -62.536832) (xy 59.68365 -62.536578)
			(xy 59.694388 -62.534072) (xy 59.712426 -62.521431) (xy 59.718448 -62.512194) (xy 59.733267 -62.488075)
			(xy 59.768907 -62.444097) (xy 59.810655 -62.405871) (xy 59.857595 -62.374234) (xy 59.908696 -62.349883)
			(xy 59.962834 -62.333351) (xy 60.018821 -62.325003) (xy 60.047124 -62.324488) (xy 60.070678 -62.324869)
			(xy 60.117422 -62.330728) (xy 60.140342 -62.336172) (xy 60.154566 -62.339728) (xy 60.181744 -62.331092)
			(xy 60.259976 -62.24016) (xy 60.264548 -62.211966) (xy 60.25896 -62.198504) (xy 60.249815 -62.175595)
			(xy 60.236829 -62.128008) (xy 60.230074 -62.079146) (xy 60.229496 -62.054486) (xy 60.229496 -62.050676)
			(xy 60.229907 -62.026924) (xy 60.235896 -61.979797) (xy 60.241434 -61.956696) (xy 60.242196 -61.953648)
			(xy 60.243212 -61.947044) (xy 60.243981 -61.937105) (xy 60.238746 -61.91789) (xy 60.233052 -61.909706)
			(xy 60.184284 -61.845952) (xy 60.176705 -61.837076) (xy 60.155806 -61.826738) (xy 60.144152 -61.82614)
			(xy 58.868818 -61.82614) (xy 58.857134 -61.829188) (xy 58.852308 -61.831474) (xy 58.8518 -61.831728)
			(xy 58.836894 -61.838666) (xy 58.806116 -61.850239) (xy 58.790332 -61.854842) (xy 58.763039 -61.862057)
			(xy 58.707051 -61.869289) (xy 58.65061 -61.86818) (xy 58.622692 -61.863986) (xy 58.596113 -61.859027)
			(xy 58.544607 -61.842588) (xy 58.520076 -61.83122) (xy 58.514996 -61.82868) (xy 58.50382 -61.82614)
			(xy 57.067196 -61.82614) (xy 57.054467 -61.826849) (xy 57.032088 -61.83899) (xy 57.024524 -61.849254)
			(xy 56.97093 -61.931296) (xy 56.969914 -61.94425) (xy 56.968898 -61.956696) (xy 56.971946 -61.963808)
			(xy 56.971946 -61.964062) (xy 56.974232 -61.969142) (xy 56.984215 -61.993204) (xy 56.998251 -62.043372)
			(xy 57.005313 -62.094986) (xy 57.005728 -62.121034) (xy 57.005728 -62.12586) (xy 57.004916 -62.152886)
			(xy 56.996606 -62.206313) (xy 56.980837 -62.258031) (xy 56.957925 -62.307004) (xy 56.928328 -62.352253)
			(xy 56.892639 -62.39287) (xy 56.851574 -62.428042) (xy 56.805955 -62.457064) (xy 56.756695 -62.479355)
			(xy 56.704781 -62.494469) (xy 56.651254 -62.502102) (xy 56.597186 -62.502102) (xy 56.543659 -62.494469)
			(xy 56.491745 -62.479355) (xy 56.442485 -62.457064) (xy 56.396866 -62.428042) (xy 56.355801 -62.39287)
			(xy 56.320112 -62.352253) (xy 56.290515 -62.307004) (xy 56.267603 -62.258031) (xy 56.251834 -62.206313)
			(xy 56.243524 -62.152886) (xy 56.242712 -62.12586) (xy 56.242712 -62.12078) (xy 56.24316 -62.094683)
			(xy 56.250313 -62.042981) (xy 56.264443 -61.992736) (xy 56.274462 -61.968634) (xy 56.279542 -61.95695)
			(xy 56.278526 -61.94425) (xy 56.27751 -61.931296) (xy 56.223916 -61.849254) (xy 56.216804 -61.838332)
			(xy 56.194452 -61.82614) (xy 53.657246 -61.82614) (xy 53.63845 -61.83376) (xy 53.631338 -61.841126)
			(xy 53.222652 -62.249812) (xy 53.215286 -62.256924) (xy 53.207666 -62.27572) (xy 53.207666 -63.273432)
			(xy 55.576722 -63.273432) (xy 55.580793 -63.21781) (xy 55.592919 -63.163373) (xy 55.612842 -63.111282)
			(xy 55.640138 -63.062647) (xy 55.674224 -63.018504) (xy 55.714373 -62.979795) (xy 55.759731 -62.947344)
			(xy 55.809331 -62.921843) (xy 55.862115 -62.903836) (xy 55.916958 -62.893706) (xy 55.972692 -62.891669)
			(xy 56.028129 -62.897769) (xy 56.082086 -62.911875) (xy 56.133415 -62.933687) (xy 56.181021 -62.962741)
			(xy 56.223889 -62.998416) (xy 56.261106 -63.039953) (xy 56.291879 -63.086466) (xy 56.315551 -63.136963)
			(xy 56.331619 -63.19037) (xy 56.339739 -63.245546) (xy 56.339739 -63.245552) (xy 69.104469 -63.245552)
			(xy 69.104469 -63.191048) (xy 69.112226 -63.137098) (xy 69.127582 -63.084801) (xy 69.150225 -63.035222)
			(xy 69.179692 -62.98937) (xy 69.215386 -62.948179) (xy 69.256578 -62.912486) (xy 69.302431 -62.88302)
			(xy 69.352011 -62.860379) (xy 69.404308 -62.845024) (xy 69.458258 -62.837269) (xy 69.48551 -62.836806)
			(xy 69.512881 -62.837265) (xy 69.56706 -62.845084) (xy 69.619563 -62.860575) (xy 69.66931 -62.883418)
			(xy 69.715276 -62.913144) (xy 69.736208 -62.930786) (xy 69.74332 -62.936882) (xy 69.760338 -62.943232)
			(xy 69.845682 -62.943232) (xy 69.8627 -62.936882) (xy 69.869812 -62.930786) (xy 69.890745 -62.913145)
			(xy 69.936713 -62.883421) (xy 69.986459 -62.860575) (xy 70.038961 -62.845079) (xy 70.093139 -62.83725)
			(xy 70.147881 -62.83725) (xy 70.202059 -62.845079) (xy 70.254561 -62.860575) (xy 70.304307 -62.883421)
			(xy 70.350275 -62.913145) (xy 70.371208 -62.930786) (xy 70.37832 -62.936882) (xy 70.395338 -62.943232)
			(xy 70.480682 -62.943232) (xy 70.4977 -62.936882) (xy 70.504812 -62.930786) (xy 70.525765 -62.913173)
			(xy 70.571732 -62.883457) (xy 70.621474 -62.860617) (xy 70.67397 -62.84512) (xy 70.728142 -62.837284)
			(xy 70.75551 -62.836806) (xy 70.782762 -62.837264) (xy 70.83671 -62.845022) (xy 70.889006 -62.860379)
			(xy 70.938584 -62.883022) (xy 70.984434 -62.912489) (xy 71.025625 -62.948182) (xy 71.061317 -62.989374)
			(xy 71.090783 -63.035225) (xy 71.113424 -63.084803) (xy 71.12878 -63.137099) (xy 71.136536 -63.191048)
			(xy 71.136536 -63.245552) (xy 71.12878 -63.299501) (xy 71.113424 -63.351797) (xy 71.090783 -63.401375)
			(xy 71.061317 -63.447226) (xy 71.025625 -63.488418) (xy 70.984434 -63.524111) (xy 70.938584 -63.553578)
			(xy 70.889006 -63.576221) (xy 70.83671 -63.591578) (xy 70.782762 -63.599336) (xy 70.75551 -63.599822)
			(xy 70.728139 -63.599369) (xy 70.673959 -63.591551) (xy 70.621455 -63.57606) (xy 70.571708 -63.553215)
			(xy 70.525742 -63.523486) (xy 70.504812 -63.505842) (xy 70.4977 -63.499746) (xy 70.480682 -63.493396)
			(xy 70.395338 -63.493396) (xy 70.37832 -63.499746) (xy 70.371208 -63.505842) (xy 70.350275 -63.523483)
			(xy 70.304307 -63.553207) (xy 70.254561 -63.576053) (xy 70.202059 -63.591549) (xy 70.147881 -63.599378)
			(xy 70.093139 -63.599378) (xy 70.038961 -63.591549) (xy 69.986459 -63.576053) (xy 69.936713 -63.553207)
			(xy 69.890745 -63.523483) (xy 69.869812 -63.505842) (xy 69.8627 -63.499746) (xy 69.845682 -63.493396)
			(xy 69.760338 -63.493396) (xy 69.74332 -63.499746) (xy 69.736208 -63.505842) (xy 69.715289 -63.523498)
			(xy 69.669312 -63.553206) (xy 69.619561 -63.576038) (xy 69.567058 -63.591525) (xy 69.51288 -63.59935)
			(xy 69.48551 -63.599822) (xy 69.458258 -63.599331) (xy 69.404308 -63.591576) (xy 69.352011 -63.576221)
			(xy 69.302431 -63.55358) (xy 69.256578 -63.524114) (xy 69.215386 -63.488421) (xy 69.179692 -63.44723)
			(xy 69.150225 -63.401378) (xy 69.127582 -63.351799) (xy 69.112226 -63.299502) (xy 69.104469 -63.245552)
			(xy 56.339739 -63.245552) (xy 56.340248 -63.273432) (xy 56.339739 -63.301318) (xy 56.331619 -63.356494)
			(xy 56.315551 -63.409901) (xy 56.291879 -63.460398) (xy 56.261106 -63.506911) (xy 56.223889 -63.548448)
			(xy 56.181021 -63.584123) (xy 56.133415 -63.613177) (xy 56.082086 -63.634989) (xy 56.028129 -63.649095)
			(xy 55.972692 -63.655195) (xy 55.916958 -63.653158) (xy 55.862115 -63.643028) (xy 55.809331 -63.625021)
			(xy 55.759731 -63.59952) (xy 55.714373 -63.567069) (xy 55.674224 -63.52836) (xy 55.640138 -63.484217)
			(xy 55.612842 -63.435582) (xy 55.592919 -63.383491) (xy 55.580793 -63.329054) (xy 55.576722 -63.273432)
			(xy 53.207666 -63.273432) (xy 53.207666 -64.102234) (xy 53.387496 -64.102234) (xy 53.391567 -64.046612)
			(xy 53.403693 -63.992175) (xy 53.423616 -63.940084) (xy 53.450912 -63.891449) (xy 53.484998 -63.847306)
			(xy 53.525147 -63.808597) (xy 53.570505 -63.776146) (xy 53.620105 -63.750645) (xy 53.672889 -63.732638)
			(xy 53.727732 -63.722508) (xy 53.783466 -63.720471) (xy 53.838903 -63.726571) (xy 53.89286 -63.740677)
			(xy 53.944189 -63.762489) (xy 53.991795 -63.791543) (xy 54.034663 -63.827218) (xy 54.07188 -63.868755)
			(xy 54.102653 -63.915268) (xy 54.126325 -63.965765) (xy 54.142393 -64.019172) (xy 54.150513 -64.074348)
			(xy 54.151022 -64.102234) (xy 54.150513 -64.13012) (xy 54.142393 -64.185296) (xy 54.126325 -64.238703)
			(xy 54.102653 -64.2892) (xy 54.087375 -64.312292) (xy 57.065924 -64.312292) (xy 57.069995 -64.25667)
			(xy 57.082121 -64.202233) (xy 57.102044 -64.150142) (xy 57.12934 -64.101507) (xy 57.163426 -64.057364)
			(xy 57.203575 -64.018655) (xy 57.248933 -63.986204) (xy 57.298533 -63.960703) (xy 57.351317 -63.942696)
			(xy 57.40616 -63.932566) (xy 57.461894 -63.930529) (xy 57.517331 -63.936629) (xy 57.571288 -63.950735)
			(xy 57.622617 -63.972547) (xy 57.670223 -64.001601) (xy 57.713091 -64.037276) (xy 57.750308 -64.078813)
			(xy 57.781081 -64.125326) (xy 57.804753 -64.175823) (xy 57.820821 -64.22923) (xy 57.828941 -64.284406)
			(xy 57.82945 -64.312292) (xy 58.9059 -64.312292) (xy 58.909971 -64.25667) (xy 58.922097 -64.202233)
			(xy 58.94202 -64.150142) (xy 58.969316 -64.101507) (xy 59.003402 -64.057364) (xy 59.043551 -64.018655)
			(xy 59.088909 -63.986204) (xy 59.138509 -63.960703) (xy 59.191293 -63.942696) (xy 59.246136 -63.932566)
			(xy 59.30187 -63.930529) (xy 59.357307 -63.936629) (xy 59.411264 -63.950735) (xy 59.462593 -63.972547)
			(xy 59.510199 -64.001601) (xy 59.553067 -64.037276) (xy 59.590284 -64.078813) (xy 59.621057 -64.125326)
			(xy 59.644729 -64.175823) (xy 59.660797 -64.22923) (xy 59.668917 -64.284406) (xy 59.669426 -64.312292)
			(xy 59.668917 -64.340178) (xy 59.660797 -64.395354) (xy 59.644729 -64.448761) (xy 59.621057 -64.499258)
			(xy 59.590284 -64.545771) (xy 59.553067 -64.587308) (xy 59.510199 -64.622983) (xy 59.462593 -64.652037)
			(xy 59.411264 -64.673849) (xy 59.357307 -64.687955) (xy 59.30187 -64.694055) (xy 59.246136 -64.692018)
			(xy 59.191293 -64.681888) (xy 59.138509 -64.663881) (xy 59.088909 -64.63838) (xy 59.043551 -64.605929)
			(xy 59.003402 -64.56722) (xy 58.969316 -64.523077) (xy 58.94202 -64.474442) (xy 58.922097 -64.422351)
			(xy 58.909971 -64.367914) (xy 58.9059 -64.312292) (xy 57.82945 -64.312292) (xy 57.828941 -64.340178)
			(xy 57.820821 -64.395354) (xy 57.804753 -64.448761) (xy 57.781081 -64.499258) (xy 57.750308 -64.545771)
			(xy 57.713091 -64.587308) (xy 57.670223 -64.622983) (xy 57.622617 -64.652037) (xy 57.571288 -64.673849)
			(xy 57.517331 -64.687955) (xy 57.461894 -64.694055) (xy 57.40616 -64.692018) (xy 57.351317 -64.681888)
			(xy 57.298533 -64.663881) (xy 57.248933 -64.63838) (xy 57.203575 -64.605929) (xy 57.163426 -64.56722)
			(xy 57.12934 -64.523077) (xy 57.102044 -64.474442) (xy 57.082121 -64.422351) (xy 57.069995 -64.367914)
			(xy 57.065924 -64.312292) (xy 54.087375 -64.312292) (xy 54.07188 -64.335713) (xy 54.034663 -64.37725)
			(xy 53.991795 -64.412925) (xy 53.944189 -64.441979) (xy 53.89286 -64.463791) (xy 53.838903 -64.477897)
			(xy 53.783466 -64.483997) (xy 53.727732 -64.48196) (xy 53.672889 -64.47183) (xy 53.620105 -64.453823)
			(xy 53.570505 -64.428322) (xy 53.525147 -64.395871) (xy 53.484998 -64.357162) (xy 53.450912 -64.313019)
			(xy 53.423616 -64.264384) (xy 53.403693 -64.212293) (xy 53.391567 -64.157856) (xy 53.387496 -64.102234)
			(xy 53.207666 -64.102234) (xy 53.207666 -65.15989) (xy 71.116442 -65.15989) (xy 71.120513 -65.104268)
			(xy 71.132639 -65.049831) (xy 71.152562 -64.99774) (xy 71.179858 -64.949105) (xy 71.213944 -64.904962)
			(xy 71.254093 -64.866253) (xy 71.299451 -64.833802) (xy 71.349051 -64.808301) (xy 71.401835 -64.790294)
			(xy 71.456678 -64.780164) (xy 71.512412 -64.778127) (xy 71.567849 -64.784227) (xy 71.621806 -64.798333)
			(xy 71.673135 -64.820145) (xy 71.720741 -64.849199) (xy 71.763609 -64.884874) (xy 71.800826 -64.926411)
			(xy 71.831599 -64.972924) (xy 71.855271 -65.023421) (xy 71.871339 -65.076828) (xy 71.879459 -65.132004)
			(xy 71.879968 -65.15989) (xy 71.879459 -65.187776) (xy 71.871339 -65.242952) (xy 71.855271 -65.296359)
			(xy 71.831599 -65.346856) (xy 71.800826 -65.393369) (xy 71.763609 -65.434906) (xy 71.720741 -65.470581)
			(xy 71.673135 -65.499635) (xy 71.621806 -65.521447) (xy 71.567849 -65.535553) (xy 71.512412 -65.541653)
			(xy 71.456678 -65.539616) (xy 71.401835 -65.529486) (xy 71.349051 -65.511479) (xy 71.299451 -65.485978)
			(xy 71.254093 -65.453527) (xy 71.213944 -65.414818) (xy 71.179858 -65.370675) (xy 71.152562 -65.32204)
			(xy 71.132639 -65.269949) (xy 71.120513 -65.215512) (xy 71.116442 -65.15989) (xy 53.207666 -65.15989)
			(xy 53.207666 -65.75552) (xy 66.346576 -65.75552) (xy 66.350647 -65.699898) (xy 66.362773 -65.645461)
			(xy 66.382696 -65.59337) (xy 66.409992 -65.544735) (xy 66.444078 -65.500592) (xy 66.484227 -65.461883)
			(xy 66.529585 -65.429432) (xy 66.579185 -65.403931) (xy 66.631969 -65.385924) (xy 66.686812 -65.375794)
			(xy 66.742546 -65.373757) (xy 66.797983 -65.379857) (xy 66.85194 -65.393963) (xy 66.903269 -65.415775)
			(xy 66.950875 -65.444829) (xy 66.993743 -65.480504) (xy 67.03096 -65.522041) (xy 67.061733 -65.568554)
			(xy 67.085405 -65.619051) (xy 67.101473 -65.672458) (xy 67.109593 -65.727634) (xy 67.110102 -65.75552)
			(xy 67.109593 -65.783406) (xy 67.101473 -65.838582) (xy 67.085405 -65.891989) (xy 67.061733 -65.942486)
			(xy 67.03096 -65.988999) (xy 66.993743 -66.030536) (xy 66.950875 -66.066211) (xy 66.903269 -66.095265)
			(xy 66.85194 -66.117077) (xy 66.797983 -66.131183) (xy 66.742546 -66.137283) (xy 66.686812 -66.135246)
			(xy 66.631969 -66.125116) (xy 66.579185 -66.107109) (xy 66.529585 -66.081608) (xy 66.484227 -66.049157)
			(xy 66.444078 -66.010448) (xy 66.409992 -65.966305) (xy 66.382696 -65.91767) (xy 66.362773 -65.865579)
			(xy 66.350647 -65.811142) (xy 66.346576 -65.75552) (xy 53.207666 -65.75552) (xy 53.207666 -67.488054)
			(xy 70.77913 -67.488054) (xy 70.783201 -67.432432) (xy 70.795327 -67.377995) (xy 70.81525 -67.325904)
			(xy 70.842546 -67.277269) (xy 70.876632 -67.233126) (xy 70.916781 -67.194417) (xy 70.962139 -67.161966)
			(xy 71.011739 -67.136465) (xy 71.064523 -67.118458) (xy 71.119366 -67.108328) (xy 71.1751 -67.106291)
			(xy 71.230537 -67.112391) (xy 71.284494 -67.126497) (xy 71.335823 -67.148309) (xy 71.383429 -67.177363)
			(xy 71.426297 -67.213038) (xy 71.463514 -67.254575) (xy 71.494287 -67.301088) (xy 71.517959 -67.351585)
			(xy 71.534027 -67.404992) (xy 71.542147 -67.460168) (xy 71.542656 -67.488054) (xy 71.542147 -67.51594)
			(xy 71.534027 -67.571116) (xy 71.517959 -67.624523) (xy 71.494287 -67.67502) (xy 71.463514 -67.721533)
			(xy 71.426297 -67.76307) (xy 71.383429 -67.798745) (xy 71.335823 -67.827799) (xy 71.284494 -67.849611)
			(xy 71.230537 -67.863717) (xy 71.1751 -67.869817) (xy 71.119366 -67.86778) (xy 71.064523 -67.85765)
			(xy 71.011739 -67.839643) (xy 70.962139 -67.814142) (xy 70.916781 -67.781691) (xy 70.876632 -67.742982)
			(xy 70.842546 -67.698839) (xy 70.81525 -67.650204) (xy 70.795327 -67.598113) (xy 70.783201 -67.543676)
			(xy 70.77913 -67.488054) (xy 53.207666 -67.488054) (xy 53.207666 -69.9516) (xy 53.208122 -69.961479)
			(xy 53.215557 -69.979785) (xy 53.222144 -69.98716) (xy 53.222398 -69.987414) (xy 53.398674 -70.16369)
			(xy 53.399182 -70.164198) (xy 53.406562 -70.170782) (xy 53.424862 -70.17823) (xy 53.434742 -70.178676)
		)
		(stroke
			(width 0)
			(type solid)
		)
		(fill yes)
		(layer "In9.Cu")
		(net "P12V_SSD2_R")
	)
	(gr_poly
		(pts
			(xy 98.478086 -70.178676) (xy 98.488149 -70.178237) (xy 98.506728 -70.170498) (xy 98.514154 -70.16369)
			(xy 98.84029 -69.837554) (xy 98.840798 -69.837046) (xy 98.847386 -69.829667) (xy 98.854844 -69.811368)
			(xy 98.855276 -69.801486) (xy 98.855276 -67.91579) (xy 98.85488 -67.906267) (xy 98.847924 -67.888536)
			(xy 98.834977 -67.874568) (xy 98.826574 -67.87007) (xy 98.730816 -67.823842) (xy 98.702114 -67.827144)
			(xy 98.69043 -67.836288) (xy 98.670118 -67.851901) (xy 98.626104 -67.87812) (xy 98.578975 -67.898208)
			(xy 98.52958 -67.911804) (xy 98.47881 -67.918664) (xy 98.453194 -67.919092) (xy 98.425944 -67.918605)
			(xy 98.371999 -67.910848) (xy 98.319708 -67.895493) (xy 98.270133 -67.872853) (xy 98.224286 -67.843388)
			(xy 98.183098 -67.807698) (xy 98.147409 -67.76651) (xy 98.117944 -67.720661) (xy 98.095304 -67.671087)
			(xy 98.07995 -67.618795) (xy 98.072194 -67.56485) (xy 98.072194 -67.51035) (xy 98.07995 -67.456405)
			(xy 98.095304 -67.404113) (xy 98.117944 -67.354539) (xy 98.147409 -67.30869) (xy 98.183098 -67.267502)
			(xy 98.224286 -67.231812) (xy 98.270133 -67.202347) (xy 98.319708 -67.179707) (xy 98.371999 -67.164352)
			(xy 98.425944 -67.156595) (xy 98.453194 -67.156076) (xy 98.47881 -67.156491) (xy 98.529582 -67.163352)
			(xy 98.578977 -67.17695) (xy 98.626105 -67.197042) (xy 98.670119 -67.223265) (xy 98.69043 -67.23888)
			(xy 98.702114 -67.248024) (xy 98.730816 -67.251326) (xy 98.826574 -67.205098) (xy 98.834974 -67.200596)
			(xy 98.847914 -67.186625) (xy 98.854877 -67.168899) (xy 98.855276 -67.159378) (xy 98.855276 -65.506854)
			(xy 98.84156 -65.483486) (xy 98.83013 -65.476628) (xy 98.829622 -65.476628) (xy 98.75647 -65.433702)
			(xy 98.752077 -65.43132) (xy 98.74261 -65.428128) (xy 98.737674 -65.427352) (xy 98.72726 -65.426082)
			(xy 98.703638 -65.432432) (xy 98.69805 -65.43548) (xy 98.669765 -65.450258) (xy 98.609489 -65.471207)
			(xy 98.546568 -65.481835) (xy 98.514662 -65.48247) (xy 98.514408 -65.48247) (xy 98.487157 -65.482007)
			(xy 98.433211 -65.474252) (xy 98.380917 -65.458898) (xy 98.331341 -65.436258) (xy 98.285492 -65.406794)
			(xy 98.244302 -65.371103) (xy 98.208611 -65.329915) (xy 98.179145 -65.284066) (xy 98.156505 -65.23449)
			(xy 98.14115 -65.182197) (xy 98.133393 -65.128251) (xy 98.133393 -65.073749) (xy 98.14115 -65.019803)
			(xy 98.156505 -64.96751) (xy 98.179145 -64.917934) (xy 98.208611 -64.872085) (xy 98.244302 -64.830897)
			(xy 98.285492 -64.795206) (xy 98.331341 -64.765742) (xy 98.380917 -64.743102) (xy 98.433211 -64.727748)
			(xy 98.487157 -64.719993) (xy 98.514408 -64.719454) (xy 98.514662 -64.719454) (xy 98.546565 -64.720123)
			(xy 98.609477 -64.730766) (xy 98.669752 -64.751697) (xy 98.69805 -64.766444) (xy 98.703638 -64.769492)
			(xy 98.717354 -64.773302) (xy 98.722339 -64.774517) (xy 98.732578 -64.775167) (xy 98.737674 -64.774572)
			(xy 98.74758 -64.773302) (xy 98.829876 -64.725296) (xy 98.830638 -64.724788) (xy 98.837917 -64.719974)
			(xy 98.848964 -64.70648) (xy 98.854871 -64.690072) (xy 98.855276 -64.681354) (xy 98.855276 -52.63261)
			(xy 98.854768 -52.626006) (xy 98.853498 -52.615592) (xy 98.852736 -52.612798) (xy 98.847024 -52.589272)
			(xy 98.840911 -52.541247) (xy 98.840544 -52.51704) (xy 98.840544 -52.499514) (xy 98.840798 -52.49418)
			(xy 98.842576 -52.477162) (xy 98.843846 -52.46624) (xy 98.846132 -52.44973) (xy 98.847148 -52.444904)
			(xy 98.847148 -52.44465) (xy 98.851212 -52.427378) (xy 98.852482 -52.422552) (xy 98.852482 -52.421536)
			(xy 98.853498 -52.418234) (xy 98.855276 -52.41163) (xy 98.855276 -51.455828) (xy 98.855712 -51.445763)
			(xy 98.863442 -51.427175) (xy 98.870262 -51.41976) (xy 98.977196 -51.312826) (xy 98.984593 -51.305976)
			(xy 99.003191 -51.298236) (xy 99.013264 -51.29784) (xy 99.703636 -51.29784) (xy 99.712018 -51.297078)
			(xy 99.719621 -51.29556) (xy 99.733449 -51.288568) (xy 99.739196 -51.283362) (xy 99.80422 -51.218338)
			(xy 99.811065 -51.21094) (xy 99.81879 -51.192341) (xy 99.819206 -51.18227) (xy 99.819206 -49.20615)
			(xy 99.818723 -49.195814) (xy 99.810602 -49.176804) (xy 99.803458 -49.16932) (xy 99.800156 -49.166272)
			(xy 99.729544 -49.116742) (xy 99.723706 -49.112968) (xy 99.710561 -49.108464) (xy 99.703636 -49.107852)
			(xy 99.692714 -49.10709) (xy 99.681284 -49.111408) (xy 99.67468 -49.113694) (xy 99.644495 -49.123448)
			(xy 99.581936 -49.133917) (xy 99.55022 -49.134522) (xy 99.546156 -49.134522) (xy 99.519096 -49.133762)
			(xy 99.46559 -49.125541) (xy 99.413784 -49.109837) (xy 99.364718 -49.086967) (xy 99.319379 -49.05739)
			(xy 99.278676 -49.0217) (xy 99.243429 -48.980613) (xy 99.214344 -48.934956) (xy 99.192007 -48.885646)
			(xy 99.176865 -48.833673) (xy 99.169224 -48.780081) (xy 99.168712 -48.753014) (xy 99.169174 -48.725761)
			(xy 99.17693 -48.67181) (xy 99.192285 -48.619511) (xy 99.214927 -48.569931) (xy 99.244395 -48.524077)
			(xy 99.280089 -48.482884) (xy 99.321282 -48.447191) (xy 99.367136 -48.417724) (xy 99.416717 -48.395083)
			(xy 99.469016 -48.379729) (xy 99.522967 -48.371974) (xy 99.55022 -48.371506) (xy 99.550982 -48.371506)
			(xy 99.582501 -48.372219) (xy 99.644667 -48.382683) (xy 99.67468 -48.392334) (xy 99.682554 -48.395128)
			(xy 99.704906 -48.395128) (xy 99.712703 -48.394894) (xy 99.727581 -48.390242) (xy 99.734116 -48.385984)
			(xy 99.797108 -48.342042) (xy 99.80295 -48.337216) (xy 99.803458 -48.336708) (xy 99.810619 -48.329232)
			(xy 99.818757 -48.31022) (xy 99.819206 -48.299878) (xy 99.819206 -41.954704) (xy 99.818784 -41.944633)
			(xy 99.811071 -41.926027) (xy 99.80422 -41.918636) (xy 98.923602 -41.038018) (xy 98.91649 -41.030652)
			(xy 98.897694 -41.023032) (xy 97.116138 -41.023032) (xy 97.107441 -41.023391) (xy 97.09105 -41.029218)
			(xy 97.077545 -41.040181) (xy 97.072704 -41.047416) (xy 97.027746 -41.121584) (xy 97.023682 -41.13022)
			(xy 97.020355 -41.140526) (xy 97.021788 -41.162115) (xy 97.026476 -41.171876) (xy 97.027238 -41.1734)
			(xy 97.031556 -41.18229) (xy 97.043633 -41.208261) (xy 97.060745 -41.262919) (xy 97.069515 -41.319517)
			(xy 97.070164 -41.348152) (xy 97.070164 -41.34866) (xy 97.070164 -41.35501) (xy 97.069253 -41.383073)
			(xy 97.060208 -41.438488) (xy 97.043138 -41.491977) (xy 97.018413 -41.542388) (xy 96.986566 -41.58863)
			(xy 96.967802 -41.609518) (xy 96.967548 -41.609772) (xy 96.961071 -41.617125) (xy 96.953767 -41.635288)
			(xy 96.953324 -41.645078) (xy 96.953324 -41.724072) (xy 96.960182 -41.741852) (xy 96.96704 -41.748964)
			(xy 96.986311 -41.77029) (xy 97.018876 -41.817651) (xy 97.043967 -41.869362) (xy 97.061015 -41.924251)
			(xy 97.069636 -41.981078) (xy 97.069634 -42.038554) (xy 97.061008 -42.09538) (xy 97.043955 -42.150268)
			(xy 97.01886 -42.201977) (xy 96.986291 -42.249335) (xy 96.96704 -42.27068) (xy 96.960182 -42.277792)
			(xy 96.953324 -42.295572) (xy 96.953324 -42.384472) (xy 96.960182 -42.402252) (xy 96.96704 -42.409364)
			(xy 96.986307 -42.430693) (xy 97.018864 -42.478057) (xy 97.043948 -42.529769) (xy 97.060992 -42.584659)
			(xy 97.06961 -42.641484) (xy 97.070164 -42.670222) (xy 97.069691 -42.697591) (xy 97.061863 -42.751767)
			(xy 97.046373 -42.804268) (xy 97.023537 -42.854016) (xy 96.993825 -42.899989) (xy 96.976184 -42.92092)
			(xy 96.970088 -42.928032) (xy 96.963738 -42.944796) (xy 96.963738 -43.030648) (xy 96.970088 -43.047412)
			(xy 96.976184 -43.054524) (xy 96.993825 -43.075455) (xy 97.02355 -43.121422) (xy 97.046391 -43.171169)
			(xy 97.061878 -43.223673) (xy 97.069694 -43.277852) (xy 97.070164 -43.305222) (xy 97.069678 -43.332473)
			(xy 97.061922 -43.386421) (xy 97.046567 -43.438716) (xy 97.023925 -43.488293) (xy 96.994459 -43.534143)
			(xy 96.958768 -43.575334) (xy 96.917577 -43.611025) (xy 96.871727 -43.640491) (xy 96.82215 -43.663133)
			(xy 96.769855 -43.678488) (xy 96.715907 -43.686244) (xy 96.661405 -43.686244) (xy 96.607457 -43.678488)
			(xy 96.555162 -43.663133) (xy 96.505585 -43.640491) (xy 96.459735 -43.611025) (xy 96.418544 -43.575334)
			(xy 96.382853 -43.534143) (xy 96.353387 -43.488293) (xy 96.330745 -43.438716) (xy 96.31539 -43.386421)
			(xy 96.307634 -43.332473) (xy 96.307148 -43.305222) (xy 96.307625 -43.277854) (xy 96.31546 -43.223682)
			(xy 96.330957 -43.171186) (xy 96.353799 -43.121444) (xy 96.383515 -43.075478) (xy 96.401128 -43.054524)
			(xy 96.407224 -43.047412) (xy 96.413574 -43.030648) (xy 96.413574 -42.944796) (xy 96.407224 -42.928032)
			(xy 96.401128 -42.92092) (xy 96.383484 -42.89999) (xy 96.353753 -42.854024) (xy 96.330906 -42.804278)
			(xy 96.315411 -42.751774) (xy 96.307589 -42.697593) (xy 96.307148 -42.670222) (xy 96.307667 -42.641483)
			(xy 96.316288 -42.584654) (xy 96.333337 -42.529762) (xy 96.35843 -42.47805) (xy 96.390996 -42.430687)
			(xy 96.410272 -42.409364) (xy 96.41713 -42.402252) (xy 96.423988 -42.384472) (xy 96.423988 -42.295572)
			(xy 96.41713 -42.277792) (xy 96.410272 -42.27068) (xy 96.391002 -42.249352) (xy 96.358438 -42.201988)
			(xy 96.333346 -42.150275) (xy 96.316296 -42.095383) (xy 96.307672 -42.038555) (xy 96.307669 -41.981077)
			(xy 96.316289 -41.924248) (xy 96.333335 -41.869355) (xy 96.358422 -41.81764) (xy 96.390982 -41.770273)
			(xy 96.410272 -41.748964) (xy 96.41713 -41.741852) (xy 96.423988 -41.724072) (xy 96.423988 -41.635172)
			(xy 96.41713 -41.617646) (xy 96.410272 -41.61028) (xy 96.39147 -41.589487) (xy 96.359538 -41.543415)
			(xy 96.33468 -41.493171) (xy 96.317432 -41.439833) (xy 96.308163 -41.384548) (xy 96.307148 -41.356534)
			(xy 96.307148 -41.349422) (xy 96.30766 -41.320528) (xy 96.316346 -41.263399) (xy 96.333568 -41.208238)
			(xy 96.345756 -41.182036) (xy 96.353122 -41.166542) (xy 96.356182 -41.157735) (xy 96.356448 -41.139107)
			(xy 96.35363 -41.13022) (xy 96.349566 -41.121584) (xy 96.304608 -41.04767) (xy 96.29775 -41.035986)
			(xy 96.274636 -41.023032) (xy 95.35414 -41.023032) (xy 95.342517 -41.023602) (xy 95.32162 -41.033788)
			(xy 95.314008 -41.04259) (xy 95.257366 -41.11498) (xy 95.25254 -41.137586) (xy 95.255334 -41.14927)
			(xy 95.260655 -41.171949) (xy 95.266385 -41.21818) (xy 95.266764 -41.241472) (xy 95.266303 -41.268725)
			(xy 95.258549 -41.322677) (xy 95.243195 -41.374975) (xy 95.220553 -41.424556) (xy 95.191085 -41.47041)
			(xy 95.155391 -41.511602) (xy 95.114197 -41.547295) (xy 95.068342 -41.576761) (xy 95.01876 -41.5994)
			(xy 94.966461 -41.614752) (xy 94.912509 -41.622504) (xy 94.885256 -41.62298) (xy 94.856515 -41.622463)
			(xy 94.799684 -41.613848) (xy 94.744788 -41.596803) (xy 94.693071 -41.571715) (xy 94.645703 -41.539152)
			(xy 94.624398 -41.519856) (xy 94.617286 -41.512998) (xy 94.599506 -41.50614) (xy 94.510606 -41.50614)
			(xy 94.492826 -41.512998) (xy 94.485714 -41.519856) (xy 94.464386 -41.539126) (xy 94.417024 -41.571692)
			(xy 94.365312 -41.596786) (xy 94.310422 -41.61384) (xy 94.253595 -41.622469) (xy 94.224856 -41.62298)
			(xy 94.197608 -41.622491) (xy 94.143666 -41.614729) (xy 94.091378 -41.59937) (xy 94.041809 -41.576726)
			(xy 93.995966 -41.547258) (xy 93.954783 -41.511566) (xy 93.919099 -41.470377) (xy 93.88964 -41.424528)
			(xy 93.867005 -41.374954) (xy 93.851656 -41.322663) (xy 93.843904 -41.268721) (xy 93.843348 -41.241472)
			(xy 93.843727 -41.21818) (xy 93.849457 -41.171949) (xy 93.854778 -41.14927) (xy 93.857572 -41.137586)
			(xy 93.852746 -41.11498) (xy 93.796104 -41.04259) (xy 93.788512 -41.033765) (xy 93.767602 -41.023591)
			(xy 93.755972 -41.023032) (xy 89.90838 -41.023032) (xy 89.898312 -41.023459) (xy 89.879716 -41.031183)
			(xy 89.872312 -41.038018) (xy 89.705688 -41.204642) (xy 89.699012 -41.212054) (xy 89.691447 -41.230491)
			(xy 89.690956 -41.240456) (xy 89.690956 -43.73626) (xy 98.212908 -43.73626) (xy 98.216979 -43.680638)
			(xy 98.229105 -43.626201) (xy 98.249028 -43.57411) (xy 98.276324 -43.525475) (xy 98.31041 -43.481332)
			(xy 98.350559 -43.442623) (xy 98.395917 -43.410172) (xy 98.445517 -43.384671) (xy 98.498301 -43.366664)
			(xy 98.553144 -43.356534) (xy 98.608878 -43.354497) (xy 98.664315 -43.360597) (xy 98.718272 -43.374703)
			(xy 98.769601 -43.396515) (xy 98.817207 -43.425569) (xy 98.860075 -43.461244) (xy 98.897292 -43.502781)
			(xy 98.928065 -43.549294) (xy 98.951737 -43.599791) (xy 98.967805 -43.653198) (xy 98.975925 -43.708374)
			(xy 98.976434 -43.73626) (xy 98.975925 -43.764146) (xy 98.967805 -43.819322) (xy 98.951737 -43.872729)
			(xy 98.928065 -43.923226) (xy 98.897292 -43.969739) (xy 98.860075 -44.011276) (xy 98.817207 -44.046951)
			(xy 98.769601 -44.076005) (xy 98.718272 -44.097817) (xy 98.664315 -44.111923) (xy 98.608878 -44.118023)
			(xy 98.553144 -44.115986) (xy 98.498301 -44.105856) (xy 98.445517 -44.087849) (xy 98.395917 -44.062348)
			(xy 98.350559 -44.029897) (xy 98.31041 -43.991188) (xy 98.276324 -43.947045) (xy 98.249028 -43.89841)
			(xy 98.229105 -43.846319) (xy 98.216979 -43.791882) (xy 98.212908 -43.73626) (xy 89.690956 -43.73626)
			(xy 89.690956 -45.114464) (xy 98.065334 -45.114464) (xy 98.069405 -45.058842) (xy 98.081531 -45.004405)
			(xy 98.101454 -44.952314) (xy 98.12875 -44.903679) (xy 98.162836 -44.859536) (xy 98.202985 -44.820827)
			(xy 98.248343 -44.788376) (xy 98.297943 -44.762875) (xy 98.350727 -44.744868) (xy 98.40557 -44.734738)
			(xy 98.461304 -44.732701) (xy 98.516741 -44.738801) (xy 98.570698 -44.752907) (xy 98.622027 -44.774719)
			(xy 98.669633 -44.803773) (xy 98.712501 -44.839448) (xy 98.749718 -44.880985) (xy 98.780491 -44.927498)
			(xy 98.804163 -44.977995) (xy 98.820231 -45.031402) (xy 98.828351 -45.086578) (xy 98.82886 -45.114464)
			(xy 98.828351 -45.14235) (xy 98.820231 -45.197526) (xy 98.804163 -45.250933) (xy 98.780491 -45.30143)
			(xy 98.749718 -45.347943) (xy 98.712501 -45.38948) (xy 98.669633 -45.425155) (xy 98.622027 -45.454209)
			(xy 98.570698 -45.476021) (xy 98.516741 -45.490127) (xy 98.461304 -45.496227) (xy 98.40557 -45.49419)
			(xy 98.350727 -45.48406) (xy 98.297943 -45.466053) (xy 98.248343 -45.440552) (xy 98.202985 -45.408101)
			(xy 98.162836 -45.369392) (xy 98.12875 -45.325249) (xy 98.101454 -45.276614) (xy 98.081531 -45.224523)
			(xy 98.069405 -45.170086) (xy 98.065334 -45.114464) (xy 89.690956 -45.114464) (xy 89.690956 -46.893226)
			(xy 98.337114 -46.893226) (xy 98.341185 -46.837604) (xy 98.353311 -46.783167) (xy 98.373234 -46.731076)
			(xy 98.40053 -46.682441) (xy 98.434616 -46.638298) (xy 98.474765 -46.599589) (xy 98.520123 -46.567138)
			(xy 98.569723 -46.541637) (xy 98.622507 -46.52363) (xy 98.67735 -46.5135) (xy 98.733084 -46.511463)
			(xy 98.788521 -46.517563) (xy 98.842478 -46.531669) (xy 98.893807 -46.553481) (xy 98.941413 -46.582535)
			(xy 98.984281 -46.61821) (xy 99.021498 -46.659747) (xy 99.052271 -46.70626) (xy 99.075943 -46.756757)
			(xy 99.092011 -46.810164) (xy 99.100131 -46.86534) (xy 99.10064 -46.893226) (xy 99.100131 -46.921112)
			(xy 99.092011 -46.976288) (xy 99.075943 -47.029695) (xy 99.052271 -47.080192) (xy 99.021498 -47.126705)
			(xy 98.984281 -47.168242) (xy 98.941413 -47.203917) (xy 98.893807 -47.232971) (xy 98.842478 -47.254783)
			(xy 98.788521 -47.268889) (xy 98.733084 -47.274989) (xy 98.67735 -47.272952) (xy 98.622507 -47.262822)
			(xy 98.569723 -47.244815) (xy 98.520123 -47.219314) (xy 98.474765 -47.186863) (xy 98.434616 -47.148154)
			(xy 98.40053 -47.104011) (xy 98.373234 -47.055376) (xy 98.353311 -47.003285) (xy 98.341185 -46.948848)
			(xy 98.337114 -46.893226) (xy 89.690956 -46.893226) (xy 89.690956 -47.936658) (xy 96.652842 -47.936658)
			(xy 96.653328 -47.909407) (xy 96.661084 -47.855459) (xy 96.676439 -47.803164) (xy 96.699081 -47.753587)
			(xy 96.728547 -47.707737) (xy 96.764238 -47.666546) (xy 96.805429 -47.630855) (xy 96.851279 -47.601389)
			(xy 96.900856 -47.578747) (xy 96.953151 -47.563392) (xy 97.007099 -47.555636) (xy 97.061601 -47.555636)
			(xy 97.115549 -47.563392) (xy 97.167844 -47.578747) (xy 97.217421 -47.601389) (xy 97.263271 -47.630855)
			(xy 97.304462 -47.666546) (xy 97.340153 -47.707737) (xy 97.369619 -47.753587) (xy 97.392261 -47.803164)
			(xy 97.407616 -47.855459) (xy 97.415372 -47.909407) (xy 97.415858 -47.936658) (xy 97.415393 -47.962999)
			(xy 97.408143 -48.015179) (xy 97.393789 -48.065867) (xy 97.372602 -48.1141) (xy 97.344986 -48.158963)
			(xy 97.311465 -48.199604) (xy 97.272675 -48.23525) (xy 97.251266 -48.250602) (xy 97.239438 -48.259295)
			(xy 97.220997 -48.282119) (xy 97.20981 -48.309246) (xy 97.206801 -48.338435) (xy 97.212219 -48.367273)
			(xy 97.225616 -48.39338) (xy 97.245886 -48.414597) (xy 97.258378 -48.422306) (xy 97.282915 -48.437)
			(xy 97.327673 -48.472602) (xy 97.366617 -48.514485) (xy 97.398872 -48.561712) (xy 97.423718 -48.613224)
			(xy 97.440597 -48.667868) (xy 97.449131 -48.724418) (xy 97.44964 -48.753014) (xy 97.449154 -48.780265)
			(xy 97.441398 -48.834213) (xy 97.426043 -48.886508) (xy 97.403401 -48.936085) (xy 97.373935 -48.981935)
			(xy 97.338244 -49.023126) (xy 97.297053 -49.058817) (xy 97.251203 -49.088283) (xy 97.201626 -49.110925)
			(xy 97.149331 -49.12628) (xy 97.095383 -49.134036) (xy 97.040881 -49.134036) (xy 96.986933 -49.12628)
			(xy 96.934638 -49.110925) (xy 96.885061 -49.088283) (xy 96.839211 -49.058817) (xy 96.79802 -49.023126)
			(xy 96.762329 -48.981935) (xy 96.732863 -48.936085) (xy 96.710221 -48.886508) (xy 96.694866 -48.834213)
			(xy 96.68711 -48.780265) (xy 96.686624 -48.753014) (xy 96.687075 -48.726673) (xy 96.694329 -48.674493)
			(xy 96.708686 -48.623805) (xy 96.729875 -48.575571) (xy 96.757493 -48.530709) (xy 96.791016 -48.490068)
			(xy 96.829806 -48.454422) (xy 96.851216 -48.43907) (xy 96.86306 -48.430403) (xy 96.881486 -48.407568)
			(xy 96.892662 -48.380437) (xy 96.895664 -48.35125) (xy 96.890245 -48.322412) (xy 96.876853 -48.296305)
			(xy 96.856592 -48.275081) (xy 96.844104 -48.267366) (xy 96.819595 -48.252629) (xy 96.774838 -48.217033)
			(xy 96.735894 -48.175157) (xy 96.703635 -48.127937) (xy 96.678785 -48.076432) (xy 96.661899 -48.021796)
			(xy 96.653356 -47.965251) (xy 96.652842 -47.936658) (xy 89.690956 -47.936658) (xy 89.690956 -58.731404)
			(xy 91.520518 -58.731404) (xy 91.520982 -58.704034) (xy 91.5288 -58.649854) (xy 91.544289 -58.597351)
			(xy 91.567131 -58.547604) (xy 91.596856 -58.501638) (xy 91.614498 -58.480706) (xy 91.620594 -58.473594)
			(xy 91.626944 -58.456576) (xy 91.626944 -58.371232) (xy 91.620594 -58.354214) (xy 91.614498 -58.347102)
			(xy 91.596862 -58.326166) (xy 91.56714 -58.280198) (xy 91.544296 -58.230452) (xy 91.528801 -58.177951)
			(xy 91.520972 -58.123773) (xy 91.520972 -58.069033) (xy 91.528799 -58.014855) (xy 91.544294 -57.962354)
			(xy 91.567137 -57.912608) (xy 91.596859 -57.866639) (xy 91.614498 -57.845706) (xy 91.620594 -57.838594)
			(xy 91.626944 -57.821576) (xy 91.626944 -57.736232) (xy 91.620594 -57.719214) (xy 91.614498 -57.712102)
			(xy 91.596862 -57.691166) (xy 91.56714 -57.645198) (xy 91.544296 -57.595452) (xy 91.528801 -57.542951)
			(xy 91.520972 -57.488773) (xy 91.520972 -57.434033) (xy 91.528799 -57.379855) (xy 91.544294 -57.327354)
			(xy 91.567137 -57.277608) (xy 91.596859 -57.231639) (xy 91.614498 -57.210706) (xy 91.620594 -57.203594)
			(xy 91.626944 -57.186576) (xy 91.626944 -57.101232) (xy 91.620594 -57.084214) (xy 91.614498 -57.077102)
			(xy 91.596846 -57.05618) (xy 91.567136 -57.010205) (xy 91.544303 -56.960454) (xy 91.528815 -56.907951)
			(xy 91.52099 -56.853774) (xy 91.520518 -56.826404) (xy 91.521004 -56.799153) (xy 91.52876 -56.745205)
			(xy 91.544115 -56.69291) (xy 91.566757 -56.643333) (xy 91.596223 -56.597483) (xy 91.631914 -56.556292)
			(xy 91.673105 -56.520601) (xy 91.718955 -56.491135) (xy 91.768532 -56.468493) (xy 91.820827 -56.453138)
			(xy 91.874775 -56.445382) (xy 91.929277 -56.445382) (xy 91.983225 -56.453138) (xy 92.03552 -56.468493)
			(xy 92.085097 -56.491135) (xy 92.130947 -56.520601) (xy 92.172138 -56.556292) (xy 92.207829 -56.597483)
			(xy 92.237295 -56.643333) (xy 92.259937 -56.69291) (xy 92.275292 -56.745205) (xy 92.283048 -56.799153)
			(xy 92.283534 -56.826404) (xy 92.283086 -56.853775) (xy 92.275267 -56.907956) (xy 92.259774 -56.96046)
			(xy 92.236928 -57.010206) (xy 92.207198 -57.056172) (xy 92.189554 -57.077102) (xy 92.183458 -57.084214)
			(xy 92.177108 -57.101232) (xy 92.177108 -57.186576) (xy 92.183458 -57.203594) (xy 92.189554 -57.210706)
			(xy 92.207199 -57.231635) (xy 92.236925 -57.277603) (xy 92.259772 -57.32735) (xy 92.275269 -57.379853)
			(xy 92.283097 -57.434032) (xy 92.283097 -57.488774) (xy 92.275267 -57.542953) (xy 92.25977 -57.595456)
			(xy 92.236923 -57.645202) (xy 92.207196 -57.69117) (xy 92.189554 -57.712102) (xy 92.183458 -57.719214)
			(xy 92.177108 -57.736232) (xy 92.177108 -57.821576) (xy 92.183458 -57.838594) (xy 92.189554 -57.845706)
			(xy 92.207199 -57.866635) (xy 92.236925 -57.912603) (xy 92.259772 -57.96235) (xy 92.275269 -58.014853)
			(xy 92.283097 -58.069032) (xy 92.283097 -58.123774) (xy 92.275267 -58.177953) (xy 92.25977 -58.230456)
			(xy 92.236923 -58.280202) (xy 92.207196 -58.32617) (xy 92.189554 -58.347102) (xy 92.183458 -58.354214)
			(xy 92.177108 -58.371232) (xy 92.177108 -58.456576) (xy 92.183458 -58.473594) (xy 92.189554 -58.480706)
			(xy 92.207202 -58.501631) (xy 92.236914 -58.547605) (xy 92.259749 -58.597354) (xy 92.275238 -58.649857)
			(xy 92.283062 -58.704034) (xy 92.283534 -58.731404) (xy 92.283048 -58.758655) (xy 92.278384 -58.791094)
			(xy 94.176342 -58.791094) (xy 94.176794 -58.763723) (xy 94.184614 -58.709543) (xy 94.200106 -58.657039)
			(xy 94.222951 -58.607293) (xy 94.252679 -58.561327) (xy 94.270322 -58.540396) (xy 94.276418 -58.533284)
			(xy 94.282768 -58.516266) (xy 94.282768 -58.430922) (xy 94.276418 -58.413904) (xy 94.270322 -58.406792)
			(xy 94.252676 -58.385864) (xy 94.222951 -58.339895) (xy 94.200107 -58.290148) (xy 94.184611 -58.237645)
			(xy 94.176783 -58.183466) (xy 94.176784 -58.128725) (xy 94.184613 -58.074546) (xy 94.20011 -58.022043)
			(xy 94.222956 -57.972297) (xy 94.252681 -57.926329) (xy 94.270322 -57.905396) (xy 94.276418 -57.898284)
			(xy 94.282768 -57.881266) (xy 94.282768 -57.795922) (xy 94.276418 -57.778904) (xy 94.270322 -57.771792)
			(xy 94.252669 -57.750871) (xy 94.222959 -57.704895) (xy 94.200125 -57.655145) (xy 94.184637 -57.602642)
			(xy 94.176813 -57.548464) (xy 94.176342 -57.521094) (xy 94.176798 -57.494778) (xy 94.184016 -57.442643)
			(xy 94.198327 -57.391995) (xy 94.219461 -57.343793) (xy 94.247016 -57.298951) (xy 94.280471 -57.258319)
			(xy 94.299532 -57.24017) (xy 94.306939 -57.232652) (xy 94.315463 -57.21337) (xy 94.316042 -57.202832)
			(xy 94.316042 -57.128156) (xy 94.315484 -57.11761) (xy 94.306968 -57.098315) (xy 94.299532 -57.090818)
			(xy 94.280467 -57.072668) (xy 94.246987 -57.032052) (xy 94.219414 -56.987215) (xy 94.198272 -56.93901)
			(xy 94.183965 -56.888355) (xy 94.176764 -56.836213) (xy 94.176342 -56.809894) (xy 94.176828 -56.782643)
			(xy 94.184584 -56.728695) (xy 94.199939 -56.6764) (xy 94.222581 -56.626823) (xy 94.252047 -56.580973)
			(xy 94.287738 -56.539782) (xy 94.328929 -56.504091) (xy 94.374779 -56.474625) (xy 94.424356 -56.451983)
			(xy 94.476651 -56.436628) (xy 94.530599 -56.428872) (xy 94.585101 -56.428872) (xy 94.639049 -56.436628)
			(xy 94.691344 -56.451983) (xy 94.740921 -56.474625) (xy 94.786771 -56.504091) (xy 94.827962 -56.539782)
			(xy 94.863653 -56.580973) (xy 94.893119 -56.626823) (xy 94.915761 -56.6764) (xy 94.931116 -56.728695)
			(xy 94.938872 -56.782643) (xy 94.939358 -56.809894) (xy 94.938961 -56.836212) (xy 94.931731 -56.888349)
			(xy 94.917408 -56.938999) (xy 94.896263 -56.987201) (xy 94.868697 -57.032041) (xy 94.835233 -57.07267)
			(xy 94.816168 -57.090818) (xy 94.808766 -57.09834) (xy 94.80024 -57.117619) (xy 94.799658 -57.128156)
			(xy 94.799658 -57.202832) (xy 94.800223 -57.213377) (xy 94.808734 -57.232672) (xy 94.816168 -57.24017)
			(xy 94.835227 -57.258326) (xy 94.868708 -57.298941) (xy 94.896282 -57.343777) (xy 94.917424 -57.39198)
			(xy 94.931733 -57.442634) (xy 94.935106 -57.467053) (xy 95.118369 -57.467053) (xy 95.118369 -57.412547)
			(xy 95.126127 -57.358595) (xy 95.141484 -57.306297) (xy 95.164127 -57.256717) (xy 95.193597 -57.210864)
			(xy 95.229292 -57.169672) (xy 95.270487 -57.13398) (xy 95.316342 -57.104514) (xy 95.365924 -57.081874)
			(xy 95.418223 -57.066521) (xy 95.472175 -57.058767) (xy 95.499428 -57.058306) (xy 95.525744 -57.058759)
			(xy 95.577878 -57.065979) (xy 95.628526 -57.080292) (xy 95.676728 -57.101426) (xy 95.72157 -57.128982)
			(xy 95.762202 -57.162436) (xy 95.780352 -57.181496) (xy 95.787853 -57.188922) (xy 95.807149 -57.197432)
			(xy 95.81769 -57.198006) (xy 95.892366 -57.198006) (xy 95.902915 -57.19747) (xy 95.92221 -57.188939)
			(xy 95.929704 -57.181496) (xy 95.947836 -57.162414) (xy 95.988457 -57.128936) (xy 96.033298 -57.101366)
			(xy 96.081506 -57.080228) (xy 96.132164 -57.065924) (xy 96.184308 -57.058726) (xy 96.210628 -57.058306)
			(xy 96.237879 -57.058766) (xy 96.291826 -57.066526) (xy 96.326972 -57.076848) (xy 97.13849 -57.076848)
			(xy 97.138987 -57.049479) (xy 97.146797 -56.995301) (xy 97.16228 -56.942799) (xy 97.185114 -56.893051)
			(xy 97.214832 -56.847083) (xy 97.23247 -56.82615) (xy 97.238566 -56.819038) (xy 97.244916 -56.80202)
			(xy 97.244916 -56.716676) (xy 97.238566 -56.699658) (xy 97.23247 -56.692546) (xy 97.214834 -56.671611)
			(xy 97.185123 -56.625639) (xy 97.162287 -56.575892) (xy 97.146795 -56.523392) (xy 97.138965 -56.469217)
			(xy 97.13849 -56.441848) (xy 97.138976 -56.414597) (xy 97.146732 -56.360649) (xy 97.162087 -56.308354)
			(xy 97.184729 -56.258777) (xy 97.214195 -56.212927) (xy 97.249886 -56.171736) (xy 97.291077 -56.136045)
			(xy 97.336927 -56.106579) (xy 97.386504 -56.083937) (xy 97.438799 -56.068582) (xy 97.492747 -56.060826)
			(xy 97.547249 -56.060826) (xy 97.601197 -56.068582) (xy 97.653492 -56.083937) (xy 97.703069 -56.106579)
			(xy 97.748919 -56.136045) (xy 97.79011 -56.171736) (xy 97.825801 -56.212927) (xy 97.855267 -56.258777)
			(xy 97.877909 -56.308354) (xy 97.893264 -56.360649) (xy 97.90102 -56.414597) (xy 97.901506 -56.441848)
			(xy 97.901008 -56.469217) (xy 97.893198 -56.523395) (xy 97.877716 -56.575897) (xy 97.854881 -56.625645)
			(xy 97.825164 -56.671613) (xy 97.807526 -56.692546) (xy 97.80143 -56.699658) (xy 97.79508 -56.716676)
			(xy 97.79508 -56.80202) (xy 97.80143 -56.819038) (xy 97.807526 -56.82615) (xy 97.825159 -56.847087)
			(xy 97.854871 -56.893059) (xy 97.877708 -56.942805) (xy 97.8932 -56.995305) (xy 97.901031 -57.049479)
			(xy 97.901506 -57.076848) (xy 97.90102 -57.104099) (xy 97.893264 -57.158047) (xy 97.877909 -57.210342)
			(xy 97.855267 -57.259919) (xy 97.825801 -57.305769) (xy 97.79011 -57.34696) (xy 97.748919 -57.382651)
			(xy 97.703069 -57.412117) (xy 97.653492 -57.434759) (xy 97.601197 -57.450114) (xy 97.547249 -57.45787)
			(xy 97.492747 -57.45787) (xy 97.438799 -57.450114) (xy 97.386504 -57.434759) (xy 97.336927 -57.412117)
			(xy 97.291077 -57.382651) (xy 97.249886 -57.34696) (xy 97.214195 -57.305769) (xy 97.184729 -57.259919)
			(xy 97.162087 -57.210342) (xy 97.146732 -57.158047) (xy 97.138976 -57.104099) (xy 97.13849 -57.076848)
			(xy 96.326972 -57.076848) (xy 96.344119 -57.081884) (xy 96.393694 -57.104527) (xy 96.439543 -57.133996)
			(xy 96.480731 -57.169688) (xy 96.516421 -57.210879) (xy 96.545886 -57.25673) (xy 96.568526 -57.306307)
			(xy 96.58388 -57.358602) (xy 96.591636 -57.412549) (xy 96.591636 -57.467051) (xy 96.58388 -57.520998)
			(xy 96.568526 -57.573293) (xy 96.545886 -57.62287) (xy 96.516421 -57.668721) (xy 96.480731 -57.709912)
			(xy 96.439543 -57.745604) (xy 96.393694 -57.775073) (xy 96.344119 -57.797716) (xy 96.291826 -57.813074)
			(xy 96.237879 -57.820834) (xy 96.210628 -57.821322) (xy 96.184311 -57.82089) (xy 96.132177 -57.813664)
			(xy 96.081528 -57.799347) (xy 96.033327 -57.778208) (xy 95.988485 -57.75065) (xy 95.947854 -57.717193)
			(xy 95.929704 -57.698132) (xy 95.922179 -57.690735) (xy 95.902902 -57.682207) (xy 95.892366 -57.681622)
			(xy 95.81769 -57.681622) (xy 95.807137 -57.682126) (xy 95.787842 -57.690678) (xy 95.780352 -57.698132)
			(xy 95.762227 -57.717222) (xy 95.721606 -57.750701) (xy 95.676764 -57.778272) (xy 95.628554 -57.799409)
			(xy 95.577894 -57.813711) (xy 95.525748 -57.820904) (xy 95.499428 -57.821322) (xy 95.472175 -57.820833)
			(xy 95.418223 -57.813079) (xy 95.365924 -57.797726) (xy 95.316342 -57.775086) (xy 95.270487 -57.74562)
			(xy 95.229292 -57.709928) (xy 95.193597 -57.668736) (xy 95.164127 -57.622883) (xy 95.141484 -57.573303)
			(xy 95.126127 -57.521005) (xy 95.118369 -57.467053) (xy 94.935106 -57.467053) (xy 94.938935 -57.494776)
			(xy 94.939358 -57.521094) (xy 94.938899 -57.548465) (xy 94.931081 -57.602644) (xy 94.915591 -57.655148)
			(xy 94.892747 -57.704895) (xy 94.86302 -57.750861) (xy 94.845378 -57.771792) (xy 94.839282 -57.778904)
			(xy 94.832932 -57.795922) (xy 94.832932 -57.881266) (xy 94.839282 -57.898284) (xy 94.845378 -57.905396)
			(xy 94.863013 -57.926334) (xy 94.892737 -57.972301) (xy 94.915583 -58.022046) (xy 94.931079 -58.074547)
			(xy 94.938908 -58.128725) (xy 94.938909 -58.183466) (xy 94.931081 -58.237644) (xy 94.915586 -58.290145)
			(xy 94.892742 -58.339891) (xy 94.863018 -58.385859) (xy 94.845378 -58.406792) (xy 94.839282 -58.413904)
			(xy 94.832932 -58.430922) (xy 94.832932 -58.516266) (xy 94.839282 -58.533284) (xy 94.845378 -58.540396)
			(xy 94.863025 -58.561322) (xy 94.892737 -58.607296) (xy 94.915571 -58.657045) (xy 94.93106 -58.709547)
			(xy 94.938886 -58.763724) (xy 94.939358 -58.791094) (xy 94.938872 -58.818345) (xy 94.931116 -58.872293)
			(xy 94.930719 -58.873644) (xy 96.200468 -58.873644) (xy 96.200943 -58.846274) (xy 96.208756 -58.792095)
			(xy 96.224242 -58.739591) (xy 96.247082 -58.689844) (xy 96.276807 -58.643877) (xy 96.294448 -58.622946)
			(xy 96.300544 -58.615834) (xy 96.306894 -58.598816) (xy 96.306894 -58.513472) (xy 96.300544 -58.496454)
			(xy 96.294448 -58.489342) (xy 96.276823 -58.468399) (xy 96.247107 -58.42243) (xy 96.224268 -58.372685)
			(xy 96.208774 -58.320187) (xy 96.200943 -58.266013) (xy 96.200468 -58.238644) (xy 96.200954 -58.211393)
			(xy 96.20871 -58.157445) (xy 96.224065 -58.10515) (xy 96.246707 -58.055573) (xy 96.276173 -58.009723)
			(xy 96.311864 -57.968532) (xy 96.353055 -57.932841) (xy 96.398905 -57.903375) (xy 96.448482 -57.880733)
			(xy 96.500777 -57.865378) (xy 96.554725 -57.857622) (xy 96.609227 -57.857622) (xy 96.663175 -57.865378)
			(xy 96.71547 -57.880733) (xy 96.765047 -57.903375) (xy 96.810897 -57.932841) (xy 96.852088 -57.968532)
			(xy 96.887779 -58.009723) (xy 96.917245 -58.055573) (xy 96.939887 -58.10515) (xy 96.955242 -58.157445)
			(xy 96.962998 -58.211393) (xy 96.963484 -58.238644) (xy 96.962989 -58.266013) (xy 96.955179 -58.320191)
			(xy 96.939697 -58.372694) (xy 96.916861 -58.422442) (xy 96.887143 -58.46841) (xy 96.869504 -58.489342)
			(xy 96.863408 -58.496454) (xy 96.857058 -58.513472) (xy 96.857058 -58.598816) (xy 96.863408 -58.615834)
			(xy 96.869504 -58.622946) (xy 96.887132 -58.643887) (xy 96.916845 -58.689857) (xy 96.939683 -58.739603)
			(xy 96.955177 -58.792101) (xy 96.963008 -58.846275) (xy 96.963484 -58.873644) (xy 96.962998 -58.900895)
			(xy 96.955242 -58.954843) (xy 96.939887 -59.007138) (xy 96.917245 -59.056715) (xy 96.887779 -59.102565)
			(xy 96.852088 -59.143756) (xy 96.810897 -59.179447) (xy 96.765047 -59.208913) (xy 96.71547 -59.231555)
			(xy 96.663175 -59.24691) (xy 96.609227 -59.254666) (xy 96.554725 -59.254666) (xy 96.500777 -59.24691)
			(xy 96.448482 -59.231555) (xy 96.398905 -59.208913) (xy 96.353055 -59.179447) (xy 96.311864 -59.143756)
			(xy 96.276173 -59.102565) (xy 96.246707 -59.056715) (xy 96.224065 -59.007138) (xy 96.20871 -58.954843)
			(xy 96.200954 -58.900895) (xy 96.200468 -58.873644) (xy 94.930719 -58.873644) (xy 94.915761 -58.924588)
			(xy 94.893119 -58.974165) (xy 94.863653 -59.020015) (xy 94.827962 -59.061206) (xy 94.786771 -59.096897)
			(xy 94.740921 -59.126363) (xy 94.691344 -59.149005) (xy 94.639049 -59.16436) (xy 94.585101 -59.172116)
			(xy 94.530599 -59.172116) (xy 94.476651 -59.16436) (xy 94.424356 -59.149005) (xy 94.374779 -59.126363)
			(xy 94.328929 -59.096897) (xy 94.287738 -59.061206) (xy 94.252047 -59.020015) (xy 94.222581 -58.974165)
			(xy 94.199939 -58.924588) (xy 94.184584 -58.872293) (xy 94.176828 -58.818345) (xy 94.176342 -58.791094)
			(xy 92.278384 -58.791094) (xy 92.275292 -58.812603) (xy 92.259937 -58.864898) (xy 92.237295 -58.914475)
			(xy 92.207829 -58.960325) (xy 92.172138 -59.001516) (xy 92.130947 -59.037207) (xy 92.085097 -59.066673)
			(xy 92.03552 -59.089315) (xy 91.983225 -59.10467) (xy 91.929277 -59.112426) (xy 91.874775 -59.112426)
			(xy 91.820827 -59.10467) (xy 91.768532 -59.089315) (xy 91.718955 -59.066673) (xy 91.673105 -59.037207)
			(xy 91.631914 -59.001516) (xy 91.596223 -58.960325) (xy 91.566757 -58.914475) (xy 91.544115 -58.864898)
			(xy 91.52876 -58.812603) (xy 91.521004 -58.758655) (xy 91.520518 -58.731404) (xy 89.690956 -58.731404)
			(xy 89.690956 -60.126449) (xy 95.180172 -60.126449) (xy 95.180172 -60.071951) (xy 95.187927 -60.018006)
			(xy 95.20328 -59.965715) (xy 95.225918 -59.91614) (xy 95.25538 -59.870291) (xy 95.291066 -59.829102)
			(xy 95.332251 -59.79341) (xy 95.378096 -59.763942) (xy 95.427668 -59.741297) (xy 95.479957 -59.725938)
			(xy 95.533901 -59.718175) (xy 95.56115 -59.717686) (xy 95.588519 -59.718185) (xy 95.642697 -59.725995)
			(xy 95.695199 -59.741477) (xy 95.744947 -59.764311) (xy 95.790915 -59.794028) (xy 95.811848 -59.811666)
			(xy 95.81896 -59.817762) (xy 95.835978 -59.824112) (xy 95.921322 -59.824112) (xy 95.93834 -59.817762)
			(xy 95.945452 -59.811666) (xy 95.966385 -59.794025) (xy 96.012353 -59.764301) (xy 96.062099 -59.741455)
			(xy 96.114601 -59.725959) (xy 96.168779 -59.71813) (xy 96.223521 -59.71813) (xy 96.277699 -59.725959)
			(xy 96.330201 -59.741455) (xy 96.379947 -59.764301) (xy 96.425915 -59.794025) (xy 96.446848 -59.811666)
			(xy 96.45396 -59.817762) (xy 96.470978 -59.824112) (xy 96.556322 -59.824112) (xy 96.57334 -59.817762)
			(xy 96.580452 -59.811666) (xy 96.601387 -59.794031) (xy 96.64736 -59.764319) (xy 96.697106 -59.741483)
			(xy 96.749606 -59.725991) (xy 96.803781 -59.718161) (xy 96.83115 -59.717686) (xy 96.858405 -59.718158)
			(xy 96.91236 -59.725909) (xy 96.964663 -59.74126) (xy 97.014249 -59.7639) (xy 97.060108 -59.793366)
			(xy 97.101306 -59.829059) (xy 97.137004 -59.870252) (xy 97.166476 -59.916107) (xy 97.189122 -59.96569)
			(xy 97.20448 -60.017991) (xy 97.212239 -60.071945) (xy 97.212239 -60.126455) (xy 97.20448 -60.180409)
			(xy 97.189122 -60.23271) (xy 97.166476 -60.282293) (xy 97.137004 -60.328148) (xy 97.101306 -60.369341)
			(xy 97.060108 -60.405034) (xy 97.014249 -60.4345) (xy 96.964663 -60.45714) (xy 96.91236 -60.472491)
			(xy 96.858405 -60.480242) (xy 96.83115 -60.480702) (xy 96.803781 -60.480206) (xy 96.749603 -60.472395)
			(xy 96.6971 -60.456913) (xy 96.647353 -60.434078) (xy 96.601385 -60.40436) (xy 96.580452 -60.386722)
			(xy 96.57334 -60.380626) (xy 96.556322 -60.374276) (xy 96.470978 -60.374276) (xy 96.45396 -60.380626)
			(xy 96.446848 -60.386722) (xy 96.425915 -60.404363) (xy 96.379947 -60.434087) (xy 96.330201 -60.456933)
			(xy 96.277699 -60.472429) (xy 96.223521 -60.480258) (xy 96.168779 -60.480258) (xy 96.114601 -60.472429)
			(xy 96.062099 -60.456933) (xy 96.012353 -60.434087) (xy 95.966385 -60.404363) (xy 95.945452 -60.386722)
			(xy 95.93834 -60.380626) (xy 95.921322 -60.374276) (xy 95.835978 -60.374276) (xy 95.81896 -60.380626)
			(xy 95.811848 -60.386722) (xy 95.790911 -60.404355) (xy 95.74494 -60.434067) (xy 95.695193 -60.456904)
			(xy 95.642694 -60.472397) (xy 95.588519 -60.480227) (xy 95.56115 -60.480702) (xy 95.533901 -60.480225)
			(xy 95.479957 -60.472462) (xy 95.427668 -60.457103) (xy 95.378096 -60.434458) (xy 95.332251 -60.40499)
			(xy 95.291066 -60.369298) (xy 95.25538 -60.328109) (xy 95.225918 -60.28226) (xy 95.20328 -60.232685)
			(xy 95.187927 -60.180394) (xy 95.180172 -60.126449) (xy 89.690956 -60.126449) (xy 89.690956 -60.999878)
			(xy 89.690421 -61.009866) (xy 89.682708 -61.0283) (xy 89.67597 -61.035692) (xy 88.900254 -61.811408)
			(xy 88.8929 -61.818064) (xy 88.8746 -61.825663) (xy 88.864694 -61.82614) (xy 87.077804 -61.82614)
			(xy 87.066138 -61.826711) (xy 87.045217 -61.837036) (xy 87.037672 -61.845952) (xy 86.988904 -61.909706)
			(xy 86.983222 -61.917894) (xy 86.977995 -61.937106) (xy 86.978744 -61.947044) (xy 86.97976 -61.953648)
			(xy 86.980522 -61.956696) (xy 86.986071 -61.979795) (xy 86.992058 -62.026923) (xy 86.99246 -62.050676)
			(xy 86.99246 -62.054486) (xy 86.991764 -62.081592) (xy 86.983653 -62.135203) (xy 86.968032 -62.187126)
			(xy 86.945216 -62.236313) (xy 86.915665 -62.281775) (xy 86.879974 -62.322593) (xy 86.838864 -62.357947)
			(xy 86.793161 -62.387124) (xy 86.743788 -62.409535) (xy 86.691739 -62.424729) (xy 86.638063 -62.4324)
			(xy 86.610952 -62.432946) (xy 86.587398 -62.432563) (xy 86.540654 -62.426703) (xy 86.517734 -62.421262)
			(xy 86.50351 -62.417706) (xy 86.476332 -62.426342) (xy 86.3981 -62.517274) (xy 86.393528 -62.545468)
			(xy 86.399116 -62.55893) (xy 86.408441 -62.582314) (xy 86.42156 -62.630918) (xy 86.428177 -62.680824)
			(xy 86.42858 -62.705996) (xy 86.428117 -62.733248) (xy 86.42036 -62.787198) (xy 86.405004 -62.839495)
			(xy 86.382362 -62.889074) (xy 86.352893 -62.934925) (xy 86.317199 -62.976116) (xy 86.276006 -63.011808)
			(xy 86.230153 -63.041273) (xy 86.180572 -63.063913) (xy 86.128275 -63.079265) (xy 86.074324 -63.087019)
			(xy 86.047072 -63.087504) (xy 86.018261 -63.086982) (xy 85.961292 -63.078322) (xy 85.906275 -63.061189)
			(xy 85.854463 -63.035973) (xy 85.807035 -63.003248) (xy 85.785706 -62.983872) (xy 85.77707 -62.975744)
			(xy 85.755226 -62.968886) (xy 85.66531 -62.981332) (xy 85.663278 -62.981586) (xy 85.652547 -62.984103)
			(xy 85.634524 -62.996751) (xy 85.62848 -63.00597) (xy 85.613663 -63.030092) (xy 85.578026 -63.074076)
			(xy 85.536279 -63.11231) (xy 85.489339 -63.143953) (xy 85.438238 -63.16831) (xy 85.384098 -63.184847)
			(xy 85.328109 -63.1932) (xy 85.299804 -63.193676) (xy 85.272553 -63.193213) (xy 85.218606 -63.185457)
			(xy 85.166312 -63.170103) (xy 85.116736 -63.147462) (xy 85.070886 -63.117997) (xy 85.029697 -63.082306)
			(xy 84.994005 -63.041117) (xy 84.96454 -62.995268) (xy 84.941899 -62.945691) (xy 84.926544 -62.893397)
			(xy 84.918787 -62.839451) (xy 84.918787 -62.784949) (xy 84.926544 -62.731003) (xy 84.941899 -62.678709)
			(xy 84.96454 -62.629132) (xy 84.994005 -62.583283) (xy 85.029697 -62.542094) (xy 85.070886 -62.506403)
			(xy 85.116736 -62.476938) (xy 85.166312 -62.454297) (xy 85.218606 -62.438943) (xy 85.272553 -62.431187)
			(xy 85.299804 -62.43066) (xy 85.328614 -62.431188) (xy 85.385577 -62.439857) (xy 85.440587 -62.456997)
			(xy 85.492393 -62.482218) (xy 85.539815 -62.514946) (xy 85.56117 -62.534292) (xy 85.569806 -62.54242)
			(xy 85.59165 -62.549278) (xy 85.681566 -62.536832) (xy 85.683598 -62.536578) (xy 85.69433 -62.534063)
			(xy 85.712353 -62.521415) (xy 85.718396 -62.512194) (xy 85.733215 -62.488077) (xy 85.768857 -62.444104)
			(xy 85.810607 -62.405883) (xy 85.857547 -62.374252) (xy 85.908648 -62.349907) (xy 85.962785 -62.333382)
			(xy 86.01877 -62.325041) (xy 86.047072 -62.324488) (xy 86.070626 -62.324872) (xy 86.117368 -62.330736)
			(xy 86.14029 -62.336172) (xy 86.154514 -62.339728) (xy 86.181692 -62.331092) (xy 86.259924 -62.24016)
			(xy 86.264496 -62.211966) (xy 86.258908 -62.198504) (xy 86.249762 -62.175595) (xy 86.236774 -62.128008)
			(xy 86.230018 -62.079146) (xy 86.229444 -62.054486) (xy 86.229444 -62.050676) (xy 86.229855 -62.026924)
			(xy 86.235843 -61.979797) (xy 86.241382 -61.956696) (xy 86.242144 -61.953648) (xy 86.24316 -61.947044)
			(xy 86.243928 -61.937105) (xy 86.238689 -61.917893) (xy 86.233 -61.909706) (xy 86.184232 -61.845952)
			(xy 86.17665 -61.837085) (xy 86.15575 -61.826767) (xy 86.1441 -61.82614) (xy 84.868766 -61.82614)
			(xy 84.857082 -61.829188) (xy 84.852256 -61.831474) (xy 84.851748 -61.831728) (xy 84.836843 -61.838668)
			(xy 84.806066 -61.850245) (xy 84.79028 -61.854842) (xy 84.762987 -61.86206) (xy 84.706999 -61.869299)
			(xy 84.650556 -61.868198) (xy 84.62264 -61.863986) (xy 84.596063 -61.859024) (xy 84.544559 -61.842578)
			(xy 84.520024 -61.83122) (xy 84.514944 -61.82868) (xy 84.503768 -61.82614) (xy 83.067144 -61.82614)
			(xy 83.054409 -61.826838) (xy 83.032012 -61.838968) (xy 83.024472 -61.849254) (xy 82.970878 -61.931296)
			(xy 82.969862 -61.94425) (xy 82.968846 -61.956696) (xy 82.971894 -61.963808) (xy 82.971894 -61.964062)
			(xy 82.97418 -61.969142) (xy 82.984162 -61.993204) (xy 82.998196 -62.043373) (xy 83.005257 -62.094986)
			(xy 83.005676 -62.121034) (xy 83.005676 -62.12586) (xy 83.004864 -62.152886) (xy 82.996554 -62.206313)
			(xy 82.980785 -62.258031) (xy 82.957873 -62.307004) (xy 82.928276 -62.352253) (xy 82.892587 -62.39287)
			(xy 82.851522 -62.428042) (xy 82.805903 -62.457064) (xy 82.756643 -62.479355) (xy 82.704729 -62.494469)
			(xy 82.651202 -62.502102) (xy 82.597134 -62.502102) (xy 82.543607 -62.494469) (xy 82.491693 -62.479355)
			(xy 82.442433 -62.457064) (xy 82.396814 -62.428042) (xy 82.355749 -62.39287) (xy 82.32006 -62.352253)
			(xy 82.290463 -62.307004) (xy 82.267551 -62.258031) (xy 82.251782 -62.206313) (xy 82.243472 -62.152886)
			(xy 82.24266 -62.12586) (xy 82.24266 -62.12078) (xy 82.243108 -62.094683) (xy 82.250262 -62.042982)
			(xy 82.264394 -61.992737) (xy 82.27441 -61.968634) (xy 82.27949 -61.95695) (xy 82.278474 -61.94425)
			(xy 82.277458 -61.931296) (xy 82.223864 -61.849254) (xy 82.216752 -61.838332) (xy 82.1944 -61.82614)
			(xy 79.657194 -61.82614) (xy 79.638398 -61.83376) (xy 79.631286 -61.841126) (xy 79.2226 -62.249812)
			(xy 79.215234 -62.256924) (xy 79.207614 -62.27572) (xy 79.207614 -63.273432) (xy 81.57667 -63.273432)
			(xy 81.580741 -63.21781) (xy 81.592867 -63.163373) (xy 81.61279 -63.111282) (xy 81.640086 -63.062647)
			(xy 81.674172 -63.018504) (xy 81.714321 -62.979795) (xy 81.759679 -62.947344) (xy 81.809279 -62.921843)
			(xy 81.862063 -62.903836) (xy 81.916906 -62.893706) (xy 81.97264 -62.891669) (xy 82.028077 -62.897769)
			(xy 82.082034 -62.911875) (xy 82.133363 -62.933687) (xy 82.180969 -62.962741) (xy 82.223837 -62.998416)
			(xy 82.261054 -63.039953) (xy 82.291827 -63.086466) (xy 82.315499 -63.136963) (xy 82.331567 -63.19037)
			(xy 82.339687 -63.245546) (xy 82.339687 -63.245548) (xy 95.104492 -63.245548) (xy 95.104492 -63.191052)
			(xy 95.112247 -63.13711) (xy 95.1276 -63.08482) (xy 95.150237 -63.035248) (xy 95.179698 -62.989401)
			(xy 95.215384 -62.948214) (xy 95.256567 -62.912523) (xy 95.302411 -62.883057) (xy 95.351981 -62.860414)
			(xy 95.404269 -62.845056) (xy 95.45821 -62.837295) (xy 95.485458 -62.836806) (xy 95.512827 -62.837295)
			(xy 95.567006 -62.845107) (xy 95.619508 -62.860591) (xy 95.669256 -62.883427) (xy 95.715224 -62.913147)
			(xy 95.736156 -62.930786) (xy 95.743268 -62.936882) (xy 95.760286 -62.943232) (xy 95.84563 -62.943232)
			(xy 95.862648 -62.936882) (xy 95.86976 -62.930786) (xy 95.890693 -62.913145) (xy 95.936661 -62.883421)
			(xy 95.986407 -62.860575) (xy 96.038909 -62.845079) (xy 96.093087 -62.83725) (xy 96.147829 -62.83725)
			(xy 96.202007 -62.845079) (xy 96.254509 -62.860575) (xy 96.304255 -62.883421) (xy 96.350223 -62.913145)
			(xy 96.371156 -62.930786) (xy 96.378268 -62.936882) (xy 96.395286 -62.943232) (xy 96.48063 -62.943232)
			(xy 96.497648 -62.936882) (xy 96.50476 -62.930786) (xy 96.525695 -62.91315) (xy 96.571667 -62.883438)
			(xy 96.621414 -62.860602) (xy 96.673914 -62.84511) (xy 96.728089 -62.837281) (xy 96.755458 -62.836806)
			(xy 96.782714 -62.837238) (xy 96.836671 -62.84499) (xy 96.888976 -62.860343) (xy 96.938564 -62.882984)
			(xy 96.984424 -62.912452) (xy 97.025623 -62.948147) (xy 97.061322 -62.989343) (xy 97.090795 -63.0352)
			(xy 97.113442 -63.084784) (xy 97.128801 -63.137088) (xy 97.136559 -63.191044) (xy 97.136559 -63.245556)
			(xy 97.128801 -63.299512) (xy 97.113442 -63.351816) (xy 97.090795 -63.4014) (xy 97.061322 -63.447257)
			(xy 97.025623 -63.488453) (xy 96.984424 -63.524148) (xy 96.938564 -63.553616) (xy 96.888976 -63.576257)
			(xy 96.836671 -63.59161) (xy 96.782714 -63.599362) (xy 96.755458 -63.599822) (xy 96.728088 -63.599341)
			(xy 96.673909 -63.59153) (xy 96.621405 -63.576045) (xy 96.571658 -63.553206) (xy 96.525691 -63.523483)
			(xy 96.50476 -63.505842) (xy 96.497648 -63.499746) (xy 96.48063 -63.493396) (xy 96.395286 -63.493396)
			(xy 96.378268 -63.499746) (xy 96.371156 -63.505842) (xy 96.350223 -63.523483) (xy 96.304255 -63.553207)
			(xy 96.254509 -63.576053) (xy 96.202007 -63.591549) (xy 96.147829 -63.599378) (xy 96.093087 -63.599378)
			(xy 96.038909 -63.591549) (xy 95.986407 -63.576053) (xy 95.936661 -63.553207) (xy 95.890693 -63.523483)
			(xy 95.86976 -63.505842) (xy 95.862648 -63.499746) (xy 95.84563 -63.493396) (xy 95.760286 -63.493396)
			(xy 95.743268 -63.499746) (xy 95.736156 -63.505842) (xy 95.715219 -63.523475) (xy 95.669247 -63.553187)
			(xy 95.619501 -63.576023) (xy 95.567001 -63.591516) (xy 95.512827 -63.599347) (xy 95.485458 -63.599822)
			(xy 95.45821 -63.599305) (xy 95.404269 -63.591544) (xy 95.351981 -63.576186) (xy 95.302411 -63.553543)
			(xy 95.256567 -63.524077) (xy 95.215384 -63.488386) (xy 95.179698 -63.447199) (xy 95.150237 -63.401352)
			(xy 95.1276 -63.35178) (xy 95.112247 -63.29949) (xy 95.104492 -63.245548) (xy 82.339687 -63.245548)
			(xy 82.340196 -63.273432) (xy 82.339687 -63.301318) (xy 82.331567 -63.356494) (xy 82.315499 -63.409901)
			(xy 82.291827 -63.460398) (xy 82.261054 -63.506911) (xy 82.223837 -63.548448) (xy 82.180969 -63.584123)
			(xy 82.133363 -63.613177) (xy 82.082034 -63.634989) (xy 82.028077 -63.649095) (xy 81.97264 -63.655195)
			(xy 81.916906 -63.653158) (xy 81.862063 -63.643028) (xy 81.809279 -63.625021) (xy 81.759679 -63.59952)
			(xy 81.714321 -63.567069) (xy 81.674172 -63.52836) (xy 81.640086 -63.484217) (xy 81.61279 -63.435582)
			(xy 81.592867 -63.383491) (xy 81.580741 -63.329054) (xy 81.57667 -63.273432) (xy 79.207614 -63.273432)
			(xy 79.207614 -64.102234) (xy 79.387444 -64.102234) (xy 79.391515 -64.046612) (xy 79.403641 -63.992175)
			(xy 79.423564 -63.940084) (xy 79.45086 -63.891449) (xy 79.484946 -63.847306) (xy 79.525095 -63.808597)
			(xy 79.570453 -63.776146) (xy 79.620053 -63.750645) (xy 79.672837 -63.732638) (xy 79.72768 -63.722508)
			(xy 79.783414 -63.720471) (xy 79.838851 -63.726571) (xy 79.892808 -63.740677) (xy 79.944137 -63.762489)
			(xy 79.991743 -63.791543) (xy 80.034611 -63.827218) (xy 80.071828 -63.868755) (xy 80.102601 -63.915268)
			(xy 80.126273 -63.965765) (xy 80.142341 -64.019172) (xy 80.150461 -64.074348) (xy 80.15097 -64.102234)
			(xy 80.150461 -64.13012) (xy 80.142341 -64.185296) (xy 80.126273 -64.238703) (xy 80.102601 -64.2892)
			(xy 80.087323 -64.312292) (xy 83.065872 -64.312292) (xy 83.069943 -64.25667) (xy 83.082069 -64.202233)
			(xy 83.101992 -64.150142) (xy 83.129288 -64.101507) (xy 83.163374 -64.057364) (xy 83.203523 -64.018655)
			(xy 83.248881 -63.986204) (xy 83.298481 -63.960703) (xy 83.351265 -63.942696) (xy 83.406108 -63.932566)
			(xy 83.461842 -63.930529) (xy 83.517279 -63.936629) (xy 83.571236 -63.950735) (xy 83.622565 -63.972547)
			(xy 83.670171 -64.001601) (xy 83.713039 -64.037276) (xy 83.750256 -64.078813) (xy 83.781029 -64.125326)
			(xy 83.804701 -64.175823) (xy 83.820769 -64.22923) (xy 83.828889 -64.284406) (xy 83.829398 -64.312292)
			(xy 83.828889 -64.340178) (xy 83.820769 -64.395354) (xy 83.804701 -64.448761) (xy 83.781029 -64.499258)
			(xy 83.750256 -64.545771) (xy 83.713039 -64.587308) (xy 83.670171 -64.622983) (xy 83.622565 -64.652037)
			(xy 83.571236 -64.673849) (xy 83.517279 -64.687955) (xy 83.461842 -64.694055) (xy 83.406108 -64.692018)
			(xy 83.351265 -64.681888) (xy 83.298481 -64.663881) (xy 83.248881 -64.63838) (xy 83.203523 -64.605929)
			(xy 83.163374 -64.56722) (xy 83.129288 -64.523077) (xy 83.101992 -64.474442) (xy 83.082069 -64.422351)
			(xy 83.069943 -64.367914) (xy 83.065872 -64.312292) (xy 80.087323 -64.312292) (xy 80.071828 -64.335713)
			(xy 80.034611 -64.37725) (xy 79.991743 -64.412925) (xy 79.944137 -64.441979) (xy 79.892808 -64.463791)
			(xy 79.838851 -64.477897) (xy 79.783414 -64.483997) (xy 79.72768 -64.48196) (xy 79.672837 -64.47183)
			(xy 79.620053 -64.453823) (xy 79.570453 -64.428322) (xy 79.525095 -64.395871) (xy 79.484946 -64.357162)
			(xy 79.45086 -64.313019) (xy 79.423564 -64.264384) (xy 79.403641 -64.212293) (xy 79.391515 -64.157856)
			(xy 79.387444 -64.102234) (xy 79.207614 -64.102234) (xy 79.207614 -65.124076) (xy 84.107272 -65.124076)
			(xy 84.111343 -65.068454) (xy 84.123469 -65.014017) (xy 84.143392 -64.961926) (xy 84.170688 -64.913291)
			(xy 84.204774 -64.869148) (xy 84.244923 -64.830439) (xy 84.290281 -64.797988) (xy 84.339881 -64.772487)
			(xy 84.392665 -64.75448) (xy 84.447508 -64.74435) (xy 84.503242 -64.742313) (xy 84.558679 -64.748413)
			(xy 84.612636 -64.762519) (xy 84.663965 -64.784331) (xy 84.711571 -64.813385) (xy 84.754439 -64.84906)
			(xy 84.791656 -64.890597) (xy 84.822429 -64.93711) (xy 84.846101 -64.987607) (xy 84.862169 -65.041014)
			(xy 84.870289 -65.09619) (xy 84.870798 -65.124076) (xy 84.870289 -65.151962) (xy 84.869122 -65.15989)
			(xy 97.11639 -65.15989) (xy 97.120461 -65.104268) (xy 97.132587 -65.049831) (xy 97.15251 -64.99774)
			(xy 97.179806 -64.949105) (xy 97.213892 -64.904962) (xy 97.254041 -64.866253) (xy 97.299399 -64.833802)
			(xy 97.348999 -64.808301) (xy 97.401783 -64.790294) (xy 97.456626 -64.780164) (xy 97.51236 -64.778127)
			(xy 97.567797 -64.784227) (xy 97.621754 -64.798333) (xy 97.673083 -64.820145) (xy 97.720689 -64.849199)
			(xy 97.763557 -64.884874) (xy 97.800774 -64.926411) (xy 97.831547 -64.972924) (xy 97.855219 -65.023421)
			(xy 97.871287 -65.076828) (xy 97.879407 -65.132004) (xy 97.879916 -65.15989) (xy 97.879407 -65.187776)
			(xy 97.871287 -65.242952) (xy 97.855219 -65.296359) (xy 97.831547 -65.346856) (xy 97.800774 -65.393369)
			(xy 97.763557 -65.434906) (xy 97.720689 -65.470581) (xy 97.673083 -65.499635) (xy 97.621754 -65.521447)
			(xy 97.567797 -65.535553) (xy 97.51236 -65.541653) (xy 97.456626 -65.539616) (xy 97.401783 -65.529486)
			(xy 97.348999 -65.511479) (xy 97.299399 -65.485978) (xy 97.254041 -65.453527) (xy 97.213892 -65.414818)
			(xy 97.179806 -65.370675) (xy 97.15251 -65.32204) (xy 97.132587 -65.269949) (xy 97.120461 -65.215512)
			(xy 97.11639 -65.15989) (xy 84.869122 -65.15989) (xy 84.862169 -65.207138) (xy 84.846101 -65.260545)
			(xy 84.822429 -65.311042) (xy 84.791656 -65.357555) (xy 84.754439 -65.399092) (xy 84.711571 -65.434767)
			(xy 84.663965 -65.463821) (xy 84.612636 -65.485633) (xy 84.558679 -65.499739) (xy 84.503242 -65.505839)
			(xy 84.447508 -65.503802) (xy 84.392665 -65.493672) (xy 84.339881 -65.475665) (xy 84.290281 -65.450164)
			(xy 84.244923 -65.417713) (xy 84.204774 -65.379004) (xy 84.170688 -65.334861) (xy 84.143392 -65.286226)
			(xy 84.123469 -65.234135) (xy 84.111343 -65.179698) (xy 84.107272 -65.124076) (xy 79.207614 -65.124076)
			(xy 79.207614 -65.75552) (xy 92.346524 -65.75552) (xy 92.350595 -65.699898) (xy 92.362721 -65.645461)
			(xy 92.382644 -65.59337) (xy 92.40994 -65.544735) (xy 92.444026 -65.500592) (xy 92.484175 -65.461883)
			(xy 92.529533 -65.429432) (xy 92.579133 -65.403931) (xy 92.631917 -65.385924) (xy 92.68676 -65.375794)
			(xy 92.742494 -65.373757) (xy 92.797931 -65.379857) (xy 92.851888 -65.393963) (xy 92.903217 -65.415775)
			(xy 92.950823 -65.444829) (xy 92.993691 -65.480504) (xy 93.030908 -65.522041) (xy 93.061681 -65.568554)
			(xy 93.085353 -65.619051) (xy 93.101421 -65.672458) (xy 93.109541 -65.727634) (xy 93.11005 -65.75552)
			(xy 93.109541 -65.783406) (xy 93.101421 -65.838582) (xy 93.085353 -65.891989) (xy 93.061681 -65.942486)
			(xy 93.030908 -65.988999) (xy 92.993691 -66.030536) (xy 92.950823 -66.066211) (xy 92.903217 -66.095265)
			(xy 92.851888 -66.117077) (xy 92.797931 -66.131183) (xy 92.742494 -66.137283) (xy 92.68676 -66.135246)
			(xy 92.631917 -66.125116) (xy 92.579133 -66.107109) (xy 92.529533 -66.081608) (xy 92.484175 -66.049157)
			(xy 92.444026 -66.010448) (xy 92.40994 -65.966305) (xy 92.382644 -65.91767) (xy 92.362721 -65.865579)
			(xy 92.350595 -65.811142) (xy 92.346524 -65.75552) (xy 79.207614 -65.75552) (xy 79.207614 -67.488054)
			(xy 96.779078 -67.488054) (xy 96.783149 -67.432432) (xy 96.795275 -67.377995) (xy 96.815198 -67.325904)
			(xy 96.842494 -67.277269) (xy 96.87658 -67.233126) (xy 96.916729 -67.194417) (xy 96.962087 -67.161966)
			(xy 97.011687 -67.136465) (xy 97.064471 -67.118458) (xy 97.119314 -67.108328) (xy 97.175048 -67.106291)
			(xy 97.230485 -67.112391) (xy 97.284442 -67.126497) (xy 97.335771 -67.148309) (xy 97.383377 -67.177363)
			(xy 97.426245 -67.213038) (xy 97.463462 -67.254575) (xy 97.494235 -67.301088) (xy 97.517907 -67.351585)
			(xy 97.533975 -67.404992) (xy 97.542095 -67.460168) (xy 97.542604 -67.488054) (xy 97.542095 -67.51594)
			(xy 97.533975 -67.571116) (xy 97.517907 -67.624523) (xy 97.494235 -67.67502) (xy 97.463462 -67.721533)
			(xy 97.426245 -67.76307) (xy 97.383377 -67.798745) (xy 97.335771 -67.827799) (xy 97.284442 -67.849611)
			(xy 97.230485 -67.863717) (xy 97.175048 -67.869817) (xy 97.119314 -67.86778) (xy 97.064471 -67.85765)
			(xy 97.011687 -67.839643) (xy 96.962087 -67.814142) (xy 96.916729 -67.781691) (xy 96.87658 -67.742982)
			(xy 96.842494 -67.698839) (xy 96.815198 -67.650204) (xy 96.795275 -67.598113) (xy 96.783149 -67.543676)
			(xy 96.779078 -67.488054) (xy 79.207614 -67.488054) (xy 79.207614 -69.9516) (xy 79.208071 -69.961478)
			(xy 79.215511 -69.97978) (xy 79.222092 -69.98716) (xy 79.222346 -69.987414) (xy 79.398622 -70.16369)
			(xy 79.39913 -70.164198) (xy 79.406508 -70.17079) (xy 79.424807 -70.178257) (xy 79.43469 -70.178676)
		)
		(stroke
			(width 0)
			(type solid)
		)
		(fill yes)
		(layer "In9.Cu")
		(net "P12V_SSD3_R")
	)
	(gr_poly
		(pts
			(xy 278.678132 -70.178676) (xy 278.688199 -70.178246) (xy 278.706793 -70.170521) (xy 278.7142 -70.16369)
			(xy 279.040336 -69.837554) (xy 279.040844 -69.837046) (xy 279.047427 -69.829665) (xy 279.054879 -69.811366)
			(xy 279.055322 -69.801486) (xy 279.055322 -67.91579) (xy 279.054924 -67.906269) (xy 279.047965 -67.888545)
			(xy 279.035012 -67.874587) (xy 279.02662 -67.87007) (xy 278.930862 -67.823842) (xy 278.90216 -67.827144)
			(xy 278.890476 -67.836288) (xy 278.870165 -67.851904) (xy 278.826151 -67.878127) (xy 278.779023 -67.898221)
			(xy 278.729628 -67.911824) (xy 278.678857 -67.918689) (xy 278.65324 -67.919092) (xy 278.625986 -67.918631)
			(xy 278.572033 -67.910879) (xy 278.519733 -67.895527) (xy 278.47015 -67.872888) (xy 278.424294 -67.843423)
			(xy 278.383098 -67.80773) (xy 278.347401 -67.766538) (xy 278.317931 -67.720685) (xy 278.295287 -67.671105)
			(xy 278.279929 -67.618806) (xy 278.272171 -67.564854) (xy 278.272171 -67.510346) (xy 278.279929 -67.456394)
			(xy 278.295287 -67.404095) (xy 278.317931 -67.354515) (xy 278.347401 -67.308662) (xy 278.383098 -67.26747)
			(xy 278.424294 -67.231777) (xy 278.47015 -67.202312) (xy 278.519733 -67.179673) (xy 278.572033 -67.164321)
			(xy 278.625986 -67.156569) (xy 278.65324 -67.156076) (xy 278.678855 -67.156494) (xy 278.729624 -67.16336)
			(xy 278.779016 -67.176964) (xy 278.82614 -67.19706) (xy 278.870149 -67.223286) (xy 278.890476 -67.23888)
			(xy 278.90216 -67.248024) (xy 278.930862 -67.251326) (xy 279.02662 -67.205098) (xy 279.035026 -67.200601)
			(xy 279.047981 -67.186633) (xy 279.054952 -67.168903) (xy 279.055322 -67.159378) (xy 279.055322 -65.506854)
			(xy 279.041606 -65.483486) (xy 279.030176 -65.476628) (xy 279.029668 -65.476628) (xy 278.956516 -65.433702)
			(xy 278.952124 -65.431317) (xy 278.942659 -65.428116) (xy 278.93772 -65.427352) (xy 278.927306 -65.426082)
			(xy 278.903684 -65.432432) (xy 278.898096 -65.43548) (xy 278.86981 -65.450254) (xy 278.809534 -65.471195)
			(xy 278.746613 -65.481814) (xy 278.714708 -65.48247) (xy 278.714454 -65.48247) (xy 278.687208 -65.481981)
			(xy 278.63327 -65.47422) (xy 278.580986 -65.458862) (xy 278.53142 -65.436221) (xy 278.48558 -65.406756)
			(xy 278.444399 -65.371068) (xy 278.408716 -65.329883) (xy 278.379257 -65.28404) (xy 278.356622 -65.23447)
			(xy 278.341271 -65.182185) (xy 278.333516 -65.128246) (xy 278.333516 -65.073754) (xy 278.341271 -65.019815)
			(xy 278.356622 -64.96753) (xy 278.379257 -64.91796) (xy 278.408716 -64.872117) (xy 278.444399 -64.830932)
			(xy 278.48558 -64.795244) (xy 278.53142 -64.765779) (xy 278.580986 -64.743138) (xy 278.63327 -64.72778)
			(xy 278.687208 -64.720019) (xy 278.714454 -64.719454) (xy 278.714708 -64.719454) (xy 278.746612 -64.720118)
			(xy 278.809528 -64.730753) (xy 278.869808 -64.751677) (xy 278.898096 -64.766444) (xy 278.903684 -64.769492)
			(xy 278.9174 -64.773302) (xy 278.922385 -64.774512) (xy 278.932623 -64.775154) (xy 278.93772 -64.774572)
			(xy 278.947626 -64.773302) (xy 279.029922 -64.725296) (xy 279.030684 -64.724788) (xy 279.037957 -64.71997)
			(xy 279.048995 -64.706475) (xy 279.054895 -64.690069) (xy 279.055322 -64.681354) (xy 279.055322 -52.622958)
			(xy 279.053544 -52.616608) (xy 279.047484 -52.592357) (xy 279.040986 -52.542795) (xy 279.04059 -52.517802)
			(xy 279.04059 -52.51577) (xy 279.041055 -52.491159) (xy 279.047553 -52.442364) (xy 279.053544 -52.418488)
			(xy 279.055322 -52.411884) (xy 279.055322 -51.455828) (xy 279.055759 -51.445764) (xy 279.063494 -51.427181)
			(xy 279.070308 -51.41976) (xy 279.177242 -51.312826) (xy 279.184641 -51.305983) (xy 279.20324 -51.29826)
			(xy 279.21331 -51.29784) (xy 279.903682 -51.29784) (xy 279.912064 -51.297078) (xy 279.919671 -51.295567)
			(xy 279.93351 -51.288585) (xy 279.939242 -51.283362) (xy 280.019252 -51.203352) (xy 280.019252 -49.20615)
			(xy 280.018654 -49.193828) (xy 280.007192 -49.172012) (xy 279.997408 -49.164494) (xy 279.933654 -49.120044)
			(xy 279.927153 -49.115867) (xy 279.912419 -49.111227) (xy 279.904698 -49.1109) (xy 279.8826 -49.1109)
			(xy 279.874726 -49.113694) (xy 279.844542 -49.123451) (xy 279.781982 -49.133928) (xy 279.750266 -49.134522)
			(xy 279.746202 -49.134522) (xy 279.719139 -49.133765) (xy 279.665629 -49.125549) (xy 279.613817 -49.109849)
			(xy 279.564746 -49.086982) (xy 279.519401 -49.057406) (xy 279.478693 -49.021716) (xy 279.44344 -48.980628)
			(xy 279.414352 -48.934969) (xy 279.392011 -48.885656) (xy 279.376867 -48.833679) (xy 279.369224 -48.780083)
			(xy 279.368758 -48.753014) (xy 279.369243 -48.725761) (xy 279.376998 -48.67181) (xy 279.392351 -48.619512)
			(xy 279.414991 -48.569931) (xy 279.444456 -48.524076) (xy 279.480147 -48.482881) (xy 279.521338 -48.447185)
			(xy 279.567188 -48.417714) (xy 279.616767 -48.395068) (xy 279.669063 -48.379708) (xy 279.723013 -48.371946)
			(xy 279.750266 -48.371506) (xy 279.751028 -48.371506) (xy 279.784644 -48.372259) (xy 279.850821 -48.384141)
			(xy 279.8826 -48.395128) (xy 279.894284 -48.399446) (xy 279.918922 -48.396398) (xy 279.997408 -48.341534)
			(xy 280.007069 -48.333918) (xy 280.018464 -48.312157) (xy 280.019252 -48.299878) (xy 280.019252 -41.95445)
			(xy 280.018722 -41.94446) (xy 280.011016 -41.926019) (xy 280.004266 -41.918636) (xy 279.123648 -41.038018)
			(xy 279.116536 -41.030652) (xy 279.09774 -41.023032) (xy 277.316184 -41.023032) (xy 277.307483 -41.023384)
			(xy 277.291081 -41.029201) (xy 277.277563 -41.04016) (xy 277.27275 -41.047416) (xy 277.227792 -41.121584)
			(xy 277.223728 -41.13022) (xy 277.220402 -41.140526) (xy 277.221834 -41.162115) (xy 277.226522 -41.171876)
			(xy 277.227284 -41.1734) (xy 277.231602 -41.18229) (xy 277.243681 -41.20826) (xy 277.260795 -41.262918)
			(xy 277.269566 -41.319517) (xy 277.27021 -41.348152) (xy 277.27021 -41.34866) (xy 277.27021 -41.35501)
			(xy 277.269299 -41.383073) (xy 277.260253 -41.438486) (xy 277.243181 -41.491975) (xy 277.218453 -41.542383)
			(xy 277.186603 -41.588622) (xy 277.167848 -41.609518) (xy 277.167594 -41.609772) (xy 277.161123 -41.617128)
			(xy 277.153826 -41.63529) (xy 277.15337 -41.645078) (xy 277.15337 -41.724072) (xy 277.160228 -41.741852)
			(xy 277.167086 -41.748964) (xy 277.186355 -41.770291) (xy 277.218916 -41.817653) (xy 277.244004 -41.869364)
			(xy 277.26105 -41.924253) (xy 277.26967 -41.981078) (xy 277.269667 -42.038554) (xy 277.261043 -42.095378)
			(xy 277.243992 -42.150266) (xy 277.2189 -42.201975) (xy 277.186335 -42.249334) (xy 277.167086 -42.27068)
			(xy 277.160228 -42.277792) (xy 277.15337 -42.295572) (xy 277.15337 -42.384472) (xy 277.160228 -42.402252)
			(xy 277.167086 -42.409364) (xy 277.186355 -42.430691) (xy 277.218917 -42.478055) (xy 277.244005 -42.529767)
			(xy 277.261051 -42.584657) (xy 277.26967 -42.641484) (xy 277.27021 -42.670222) (xy 277.269737 -42.697592)
			(xy 277.26191 -42.751768) (xy 277.246421 -42.80427) (xy 277.223587 -42.85402) (xy 277.193878 -42.899995)
			(xy 277.17623 -42.92092) (xy 277.170134 -42.928032) (xy 277.163784 -42.944796) (xy 277.163784 -43.030648)
			(xy 277.170134 -43.047412) (xy 277.17623 -43.054524) (xy 277.193869 -43.075456) (xy 277.22359 -43.121424)
			(xy 277.246428 -43.171171) (xy 277.261914 -43.223674) (xy 277.269729 -43.277852) (xy 277.27021 -43.305222)
			(xy 277.269724 -43.332473) (xy 277.261968 -43.386421) (xy 277.246613 -43.438716) (xy 277.223971 -43.488293)
			(xy 277.194505 -43.534143) (xy 277.158814 -43.575334) (xy 277.117623 -43.611025) (xy 277.071773 -43.640491)
			(xy 277.022196 -43.663133) (xy 276.969901 -43.678488) (xy 276.915953 -43.686244) (xy 276.861451 -43.686244)
			(xy 276.807503 -43.678488) (xy 276.755208 -43.663133) (xy 276.705631 -43.640491) (xy 276.659781 -43.611025)
			(xy 276.61859 -43.575334) (xy 276.582899 -43.534143) (xy 276.553433 -43.488293) (xy 276.530791 -43.438716)
			(xy 276.515436 -43.386421) (xy 276.50768 -43.332473) (xy 276.507194 -43.305222) (xy 276.507671 -43.277854)
			(xy 276.515505 -43.223681) (xy 276.531 -43.171184) (xy 276.553839 -43.12144) (xy 276.583553 -43.075471)
			(xy 276.601174 -43.054524) (xy 276.60727 -43.047412) (xy 276.61362 -43.030648) (xy 276.61362 -42.944796)
			(xy 276.60727 -42.928032) (xy 276.601174 -42.92092) (xy 276.583532 -42.899988) (xy 276.553805 -42.854022)
			(xy 276.530961 -42.804275) (xy 276.515469 -42.751772) (xy 276.507649 -42.697593) (xy 276.507194 -42.670222)
			(xy 276.507713 -42.641482) (xy 276.516333 -42.584653) (xy 276.53338 -42.529759) (xy 276.55847 -42.478045)
			(xy 276.591034 -42.430679) (xy 276.610318 -42.409364) (xy 276.617176 -42.402252) (xy 276.624034 -42.384472)
			(xy 276.624034 -42.295572) (xy 276.617176 -42.277792) (xy 276.610318 -42.27068) (xy 276.591046 -42.249353)
			(xy 276.558478 -42.20199) (xy 276.533383 -42.150277) (xy 276.516331 -42.095385) (xy 276.507706 -42.038556)
			(xy 276.507703 -41.981076) (xy 276.516324 -41.924246) (xy 276.533372 -41.869353) (xy 276.558462 -41.817638)
			(xy 276.591026 -41.770272) (xy 276.610318 -41.748964) (xy 276.617176 -41.741852) (xy 276.624034 -41.724072)
			(xy 276.624034 -41.635172) (xy 276.617176 -41.617646) (xy 276.610318 -41.61028) (xy 276.591519 -41.589486)
			(xy 276.559591 -41.543412) (xy 276.534737 -41.493168) (xy 276.517491 -41.439831) (xy 276.508223 -41.384547)
			(xy 276.507194 -41.356534) (xy 276.507194 -41.349422) (xy 276.507706 -41.320529) (xy 276.516393 -41.263399)
			(xy 276.533616 -41.20824) (xy 276.545802 -41.182036) (xy 276.553168 -41.166542) (xy 276.556231 -41.157735)
			(xy 276.556496 -41.139107) (xy 276.553676 -41.13022) (xy 276.549612 -41.121584) (xy 276.504654 -41.04767)
			(xy 276.497796 -41.035986) (xy 276.474682 -41.023032) (xy 275.554186 -41.023032) (xy 275.542569 -41.023613)
			(xy 275.521689 -41.033812) (xy 275.514054 -41.04259) (xy 275.457412 -41.11498) (xy 275.452586 -41.137586)
			(xy 275.45538 -41.14927) (xy 275.460702 -41.171949) (xy 275.466432 -41.21818) (xy 275.46681 -41.241472)
			(xy 275.466349 -41.268726) (xy 275.458595 -41.32268) (xy 275.443241 -41.374982) (xy 275.4206 -41.424565)
			(xy 275.391133 -41.470422) (xy 275.35544 -41.511618) (xy 275.314246 -41.547315) (xy 275.268392 -41.576786)
			(xy 275.21881 -41.599431) (xy 275.16651 -41.614788) (xy 275.112556 -41.622546) (xy 275.085302 -41.62298)
			(xy 275.056563 -41.622459) (xy 274.999735 -41.613836) (xy 274.944845 -41.596786) (xy 274.893133 -41.571693)
			(xy 274.845771 -41.539127) (xy 274.824444 -41.519856) (xy 274.817332 -41.512998) (xy 274.799552 -41.50614)
			(xy 274.710652 -41.50614) (xy 274.692872 -41.512998) (xy 274.68576 -41.519856) (xy 274.664431 -41.539123)
			(xy 274.617067 -41.571682) (xy 274.565355 -41.596769) (xy 274.510465 -41.613815) (xy 274.45364 -41.622436)
			(xy 274.424902 -41.62298) (xy 274.39765 -41.622517) (xy 274.3437 -41.61476) (xy 274.291404 -41.599404)
			(xy 274.241825 -41.576761) (xy 274.195974 -41.547293) (xy 274.154783 -41.511599) (xy 274.119092 -41.470405)
			(xy 274.089627 -41.424552) (xy 274.066987 -41.374972) (xy 274.051635 -41.322674) (xy 274.043881 -41.268724)
			(xy 274.043394 -41.241472) (xy 274.043773 -41.21818) (xy 274.049504 -41.171949) (xy 274.054824 -41.14927)
			(xy 274.057618 -41.137586) (xy 274.052792 -41.11498) (xy 273.99615 -41.04259) (xy 273.988561 -41.033757)
			(xy 273.967651 -41.023564) (xy 273.956018 -41.023032) (xy 270.108426 -41.023032) (xy 270.098362 -41.023469)
			(xy 270.07978 -41.031206) (xy 270.072358 -41.038018) (xy 269.905734 -41.204642) (xy 269.898995 -41.212014)
			(xy 269.891412 -41.230476) (xy 269.891002 -41.240456) (xy 269.891002 -43.73626) (xy 278.412954 -43.73626)
			(xy 278.417025 -43.680638) (xy 278.429151 -43.626201) (xy 278.449074 -43.57411) (xy 278.47637 -43.525475)
			(xy 278.510456 -43.481332) (xy 278.550605 -43.442623) (xy 278.595963 -43.410172) (xy 278.645563 -43.384671)
			(xy 278.698347 -43.366664) (xy 278.75319 -43.356534) (xy 278.808924 -43.354497) (xy 278.864361 -43.360597)
			(xy 278.918318 -43.374703) (xy 278.969647 -43.396515) (xy 279.017253 -43.425569) (xy 279.060121 -43.461244)
			(xy 279.097338 -43.502781) (xy 279.128111 -43.549294) (xy 279.151783 -43.599791) (xy 279.167851 -43.653198)
			(xy 279.175971 -43.708374) (xy 279.17648 -43.73626) (xy 279.175971 -43.764146) (xy 279.167851 -43.819322)
			(xy 279.151783 -43.872729) (xy 279.128111 -43.923226) (xy 279.097338 -43.969739) (xy 279.060121 -44.011276)
			(xy 279.017253 -44.046951) (xy 278.969647 -44.076005) (xy 278.918318 -44.097817) (xy 278.864361 -44.111923)
			(xy 278.808924 -44.118023) (xy 278.75319 -44.115986) (xy 278.698347 -44.105856) (xy 278.645563 -44.087849)
			(xy 278.595963 -44.062348) (xy 278.550605 -44.029897) (xy 278.510456 -43.991188) (xy 278.47637 -43.947045)
			(xy 278.449074 -43.89841) (xy 278.429151 -43.846319) (xy 278.417025 -43.791882) (xy 278.412954 -43.73626)
			(xy 269.891002 -43.73626) (xy 269.891002 -45.114464) (xy 278.26538 -45.114464) (xy 278.269451 -45.058842)
			(xy 278.281577 -45.004405) (xy 278.3015 -44.952314) (xy 278.328796 -44.903679) (xy 278.362882 -44.859536)
			(xy 278.403031 -44.820827) (xy 278.448389 -44.788376) (xy 278.497989 -44.762875) (xy 278.550773 -44.744868)
			(xy 278.605616 -44.734738) (xy 278.66135 -44.732701) (xy 278.716787 -44.738801) (xy 278.770744 -44.752907)
			(xy 278.822073 -44.774719) (xy 278.869679 -44.803773) (xy 278.912547 -44.839448) (xy 278.949764 -44.880985)
			(xy 278.980537 -44.927498) (xy 279.004209 -44.977995) (xy 279.020277 -45.031402) (xy 279.028397 -45.086578)
			(xy 279.028906 -45.114464) (xy 279.028397 -45.14235) (xy 279.020277 -45.197526) (xy 279.004209 -45.250933)
			(xy 278.980537 -45.30143) (xy 278.949764 -45.347943) (xy 278.912547 -45.38948) (xy 278.869679 -45.425155)
			(xy 278.822073 -45.454209) (xy 278.770744 -45.476021) (xy 278.716787 -45.490127) (xy 278.66135 -45.496227)
			(xy 278.605616 -45.49419) (xy 278.550773 -45.48406) (xy 278.497989 -45.466053) (xy 278.448389 -45.440552)
			(xy 278.403031 -45.408101) (xy 278.362882 -45.369392) (xy 278.328796 -45.325249) (xy 278.3015 -45.276614)
			(xy 278.281577 -45.224523) (xy 278.269451 -45.170086) (xy 278.26538 -45.114464) (xy 269.891002 -45.114464)
			(xy 269.891002 -46.893226) (xy 278.53716 -46.893226) (xy 278.541231 -46.837604) (xy 278.553357 -46.783167)
			(xy 278.57328 -46.731076) (xy 278.600576 -46.682441) (xy 278.634662 -46.638298) (xy 278.674811 -46.599589)
			(xy 278.720169 -46.567138) (xy 278.769769 -46.541637) (xy 278.822553 -46.52363) (xy 278.877396 -46.5135)
			(xy 278.93313 -46.511463) (xy 278.988567 -46.517563) (xy 279.042524 -46.531669) (xy 279.093853 -46.553481)
			(xy 279.141459 -46.582535) (xy 279.184327 -46.61821) (xy 279.221544 -46.659747) (xy 279.252317 -46.70626)
			(xy 279.275989 -46.756757) (xy 279.292057 -46.810164) (xy 279.300177 -46.86534) (xy 279.300686 -46.893226)
			(xy 279.300177 -46.921112) (xy 279.292057 -46.976288) (xy 279.275989 -47.029695) (xy 279.252317 -47.080192)
			(xy 279.221544 -47.126705) (xy 279.184327 -47.168242) (xy 279.141459 -47.203917) (xy 279.093853 -47.232971)
			(xy 279.042524 -47.254783) (xy 278.988567 -47.268889) (xy 278.93313 -47.274989) (xy 278.877396 -47.272952)
			(xy 278.822553 -47.262822) (xy 278.769769 -47.244815) (xy 278.720169 -47.219314) (xy 278.674811 -47.186863)
			(xy 278.634662 -47.148154) (xy 278.600576 -47.104011) (xy 278.57328 -47.055376) (xy 278.553357 -47.003285)
			(xy 278.541231 -46.948848) (xy 278.53716 -46.893226) (xy 269.891002 -46.893226) (xy 269.891002 -47.936658)
			(xy 276.852888 -47.936658) (xy 276.853374 -47.909407) (xy 276.86113 -47.855459) (xy 276.876485 -47.803164)
			(xy 276.899127 -47.753587) (xy 276.928593 -47.707737) (xy 276.964284 -47.666546) (xy 277.005475 -47.630855)
			(xy 277.051325 -47.601389) (xy 277.100902 -47.578747) (xy 277.153197 -47.563392) (xy 277.207145 -47.555636)
			(xy 277.261647 -47.555636) (xy 277.315595 -47.563392) (xy 277.36789 -47.578747) (xy 277.417467 -47.601389)
			(xy 277.463317 -47.630855) (xy 277.504508 -47.666546) (xy 277.540199 -47.707737) (xy 277.569665 -47.753587)
			(xy 277.592307 -47.803164) (xy 277.607662 -47.855459) (xy 277.615418 -47.909407) (xy 277.615904 -47.936658)
			(xy 277.615463 -47.963) (xy 277.608211 -48.015182) (xy 277.593854 -48.065871) (xy 277.572665 -48.114106)
			(xy 277.545045 -48.158969) (xy 277.511519 -48.199608) (xy 277.472724 -48.235252) (xy 277.451312 -48.250602)
			(xy 277.439492 -48.259301) (xy 277.421061 -48.282127) (xy 277.409881 -48.309251) (xy 277.406874 -48.338435)
			(xy 277.412289 -48.367268) (xy 277.425678 -48.393373) (xy 277.445937 -48.414593) (xy 277.458424 -48.422306)
			(xy 277.482971 -48.436982) (xy 277.527727 -48.472589) (xy 277.566669 -48.514476) (xy 277.598922 -48.561706)
			(xy 277.623766 -48.613221) (xy 277.640644 -48.667866) (xy 277.649177 -48.724418) (xy 277.649686 -48.753014)
			(xy 277.6492 -48.780265) (xy 277.641444 -48.834213) (xy 277.626089 -48.886508) (xy 277.603447 -48.936085)
			(xy 277.573981 -48.981935) (xy 277.53829 -49.023126) (xy 277.497099 -49.058817) (xy 277.451249 -49.088283)
			(xy 277.401672 -49.110925) (xy 277.349377 -49.12628) (xy 277.295429 -49.134036) (xy 277.240927 -49.134036)
			(xy 277.186979 -49.12628) (xy 277.134684 -49.110925) (xy 277.085107 -49.088283) (xy 277.039257 -49.058817)
			(xy 276.998066 -49.023126) (xy 276.962375 -48.981935) (xy 276.932909 -48.936085) (xy 276.910267 -48.886508)
			(xy 276.894912 -48.834213) (xy 276.887156 -48.780265) (xy 276.88667 -48.753014) (xy 276.887101 -48.726672)
			(xy 276.894356 -48.67449) (xy 276.908715 -48.623801) (xy 276.929907 -48.575567) (xy 276.957528 -48.530704)
			(xy 276.991055 -48.490065) (xy 277.02985 -48.45442) (xy 277.051262 -48.43907) (xy 277.063114 -48.430409)
			(xy 277.081551 -48.407576) (xy 277.092733 -48.380442) (xy 277.095737 -48.351249) (xy 277.090315 -48.322407)
			(xy 277.076915 -48.296298) (xy 277.056643 -48.275078) (xy 277.04415 -48.267366) (xy 277.019629 -48.252649)
			(xy 276.974874 -48.217048) (xy 276.935933 -48.175167) (xy 276.903677 -48.127944) (xy 276.878828 -48.076437)
			(xy 276.861944 -48.021798) (xy 276.853402 -47.965252) (xy 276.852888 -47.936658) (xy 269.891002 -47.936658)
			(xy 269.891002 -58.731404) (xy 271.720564 -58.731404) (xy 271.721017 -58.704033) (xy 271.728835 -58.649853)
			(xy 271.744327 -58.597349) (xy 271.767172 -58.547602) (xy 271.796901 -58.501637) (xy 271.814544 -58.480706)
			(xy 271.82064 -58.473594) (xy 271.82699 -58.456576) (xy 271.82699 -58.371232) (xy 271.82064 -58.354214)
			(xy 271.814544 -58.347102) (xy 271.796907 -58.326166) (xy 271.76718 -58.2802) (xy 271.744334 -58.230454)
			(xy 271.728836 -58.177952) (xy 271.721007 -58.123774) (xy 271.721007 -58.069032) (xy 271.728835 -58.014854)
			(xy 271.744332 -57.962352) (xy 271.767177 -57.912606) (xy 271.796903 -57.866638) (xy 271.814544 -57.845706)
			(xy 271.82064 -57.838594) (xy 271.82699 -57.821576) (xy 271.82699 -57.736232) (xy 271.82064 -57.719214)
			(xy 271.814544 -57.712102) (xy 271.796907 -57.691166) (xy 271.76718 -57.6452) (xy 271.744334 -57.595454)
			(xy 271.728836 -57.542952) (xy 271.721007 -57.488774) (xy 271.721007 -57.434032) (xy 271.728835 -57.379854)
			(xy 271.744332 -57.327352) (xy 271.767177 -57.277606) (xy 271.796903 -57.231638) (xy 271.814544 -57.210706)
			(xy 271.82064 -57.203594) (xy 271.82699 -57.186576) (xy 271.82699 -57.101232) (xy 271.82064 -57.084214)
			(xy 271.814544 -57.077102) (xy 271.796899 -57.056174) (xy 271.767187 -57.010201) (xy 271.744351 -56.960452)
			(xy 271.728862 -56.907951) (xy 271.721036 -56.853774) (xy 271.720564 -56.826404) (xy 271.72105 -56.799153)
			(xy 271.728806 -56.745205) (xy 271.744161 -56.69291) (xy 271.766803 -56.643333) (xy 271.796269 -56.597483)
			(xy 271.83196 -56.556292) (xy 271.873151 -56.520601) (xy 271.919001 -56.491135) (xy 271.968578 -56.468493)
			(xy 272.020873 -56.453138) (xy 272.074821 -56.445382) (xy 272.129323 -56.445382) (xy 272.183271 -56.453138)
			(xy 272.235566 -56.468493) (xy 272.285143 -56.491135) (xy 272.330993 -56.520601) (xy 272.372184 -56.556292)
			(xy 272.407875 -56.597483) (xy 272.437341 -56.643333) (xy 272.459983 -56.69291) (xy 272.475338 -56.745205)
			(xy 272.483094 -56.799153) (xy 272.48358 -56.826404) (xy 272.483121 -56.853775) (xy 272.475302 -56.907954)
			(xy 272.459812 -56.960458) (xy 272.436968 -57.010204) (xy 272.407242 -57.056171) (xy 272.3896 -57.077102)
			(xy 272.383504 -57.084214) (xy 272.377154 -57.101232) (xy 272.377154 -57.186576) (xy 272.383504 -57.203594)
			(xy 272.3896 -57.210706) (xy 272.407243 -57.231636) (xy 272.436966 -57.277605) (xy 272.45981 -57.327352)
			(xy 272.475304 -57.379854) (xy 272.483132 -57.434033) (xy 272.483132 -57.488773) (xy 272.475303 -57.542952)
			(xy 272.459807 -57.595454) (xy 272.436963 -57.6452) (xy 272.40724 -57.691169) (xy 272.3896 -57.712102)
			(xy 272.383504 -57.719214) (xy 272.377154 -57.736232) (xy 272.377154 -57.821576) (xy 272.383504 -57.838594)
			(xy 272.3896 -57.845706) (xy 272.407243 -57.866636) (xy 272.436966 -57.912605) (xy 272.45981 -57.962352)
			(xy 272.475304 -58.014854) (xy 272.483132 -58.069033) (xy 272.483132 -58.123773) (xy 272.475303 -58.177952)
			(xy 272.459807 -58.230454) (xy 272.436963 -58.2802) (xy 272.40724 -58.326169) (xy 272.3896 -58.347102)
			(xy 272.383504 -58.354214) (xy 272.377154 -58.371232) (xy 272.377154 -58.456576) (xy 272.383504 -58.473594)
			(xy 272.3896 -58.480706) (xy 272.407255 -58.501625) (xy 272.436965 -58.547601) (xy 272.459798 -58.597352)
			(xy 272.475285 -58.649856) (xy 272.483108 -58.704034) (xy 272.48358 -58.731404) (xy 272.483094 -58.758655)
			(xy 272.47843 -58.791094) (xy 274.376388 -58.791094) (xy 274.376853 -58.763724) (xy 274.384672 -58.709545)
			(xy 274.400161 -58.657042) (xy 274.423003 -58.607295) (xy 274.452727 -58.561328) (xy 274.470368 -58.540396)
			(xy 274.476464 -58.533284) (xy 274.482814 -58.516266) (xy 274.482814 -58.430922) (xy 274.476464 -58.413904)
			(xy 274.470368 -58.406792) (xy 274.45272 -58.385865) (xy 274.422992 -58.339897) (xy 274.400145 -58.29015)
			(xy 274.384647 -58.237647) (xy 274.376818 -58.183467) (xy 274.376819 -58.128724) (xy 274.384649 -58.074544)
			(xy 274.400148 -58.022041) (xy 274.422996 -57.972295) (xy 274.452725 -57.926328) (xy 274.470368 -57.905396)
			(xy 274.476464 -57.898284) (xy 274.482814 -57.881266) (xy 274.482814 -57.795922) (xy 274.476464 -57.778904)
			(xy 274.470368 -57.771792) (xy 274.452707 -57.750878) (xy 274.422999 -57.7049) (xy 274.400168 -57.655148)
			(xy 274.384682 -57.602643) (xy 274.376859 -57.548464) (xy 274.376388 -57.521094) (xy 274.376861 -57.494779)
			(xy 274.384078 -57.442646) (xy 274.398387 -57.391998) (xy 274.419518 -57.343796) (xy 274.447069 -57.298954)
			(xy 274.480519 -57.258321) (xy 274.499578 -57.24017) (xy 274.506992 -57.232659) (xy 274.51551 -57.213371)
			(xy 274.516088 -57.202832) (xy 274.516088 -57.128156) (xy 274.515545 -57.117608) (xy 274.50702 -57.098312)
			(xy 274.499578 -57.090818) (xy 274.480522 -57.072659) (xy 274.447039 -57.032046) (xy 274.419464 -56.987211)
			(xy 274.39832 -56.939008) (xy 274.384012 -56.888354) (xy 274.37681 -56.836212) (xy 274.376388 -56.809894)
			(xy 274.376874 -56.782643) (xy 274.38463 -56.728695) (xy 274.399985 -56.6764) (xy 274.422627 -56.626823)
			(xy 274.452093 -56.580973) (xy 274.487784 -56.539782) (xy 274.528975 -56.504091) (xy 274.574825 -56.474625)
			(xy 274.624402 -56.451983) (xy 274.676697 -56.436628) (xy 274.730645 -56.428872) (xy 274.785147 -56.428872)
			(xy 274.839095 -56.436628) (xy 274.89139 -56.451983) (xy 274.940967 -56.474625) (xy 274.986817 -56.504091)
			(xy 275.028008 -56.539782) (xy 275.063699 -56.580973) (xy 275.093165 -56.626823) (xy 275.115807 -56.6764)
			(xy 275.131162 -56.728695) (xy 275.138918 -56.782643) (xy 275.139404 -56.809894) (xy 275.138992 -56.836211)
			(xy 275.131763 -56.888347) (xy 275.117442 -56.938996) (xy 275.0963 -56.987198) (xy 275.068738 -57.032039)
			(xy 275.035277 -57.072669) (xy 275.016214 -57.090818) (xy 275.008805 -57.098333) (xy 275.000284 -57.117618)
			(xy 274.999704 -57.128156) (xy 274.999704 -57.202832) (xy 275.000255 -57.213379) (xy 275.008775 -57.232675)
			(xy 275.016214 -57.24017) (xy 275.035281 -57.258317) (xy 275.06876 -57.298935) (xy 275.096332 -57.343773)
			(xy 275.117472 -57.391978) (xy 275.13178 -57.442633) (xy 275.135152 -57.467049) (xy 275.318492 -57.467049)
			(xy 275.318492 -57.412551) (xy 275.326248 -57.358608) (xy 275.341601 -57.306317) (xy 275.364239 -57.256743)
			(xy 275.393702 -57.210896) (xy 275.429389 -57.169708) (xy 275.470575 -57.134018) (xy 275.51642 -57.104552)
			(xy 275.565992 -57.08191) (xy 275.618282 -57.066553) (xy 275.672225 -57.058794) (xy 275.699474 -57.058306)
			(xy 275.725791 -57.058728) (xy 275.777927 -57.065954) (xy 275.828575 -57.080273) (xy 275.876777 -57.101413)
			(xy 275.921618 -57.128974) (xy 275.962249 -57.162433) (xy 275.980398 -57.181496) (xy 275.987919 -57.188898)
			(xy 276.0072 -57.197422) (xy 276.017736 -57.198006) (xy 276.092412 -57.198006) (xy 276.102964 -57.197495)
			(xy 276.122259 -57.188947) (xy 276.12975 -57.181496) (xy 276.147859 -57.162392) (xy 276.188485 -57.128916)
			(xy 276.233331 -57.101349) (xy 276.281544 -57.080215) (xy 276.332206 -57.065916) (xy 276.384353 -57.058723)
			(xy 276.410674 -57.058306) (xy 276.437929 -57.058739) (xy 276.491885 -57.066493) (xy 276.527157 -57.076848)
			(xy 277.338536 -57.076848) (xy 277.339021 -57.049478) (xy 277.346833 -56.9953) (xy 277.362317 -56.942797)
			(xy 277.385155 -56.893049) (xy 277.414876 -56.847082) (xy 277.432516 -56.82615) (xy 277.438612 -56.819038)
			(xy 277.444962 -56.80202) (xy 277.444962 -56.716676) (xy 277.438612 -56.699658) (xy 277.432516 -56.692546)
			(xy 277.414887 -56.671605) (xy 277.385174 -56.625635) (xy 277.362335 -56.57589) (xy 277.346842 -56.523391)
			(xy 277.339011 -56.469217) (xy 277.338536 -56.441848) (xy 277.339022 -56.414597) (xy 277.346778 -56.360649)
			(xy 277.362133 -56.308354) (xy 277.384775 -56.258777) (xy 277.414241 -56.212927) (xy 277.449932 -56.171736)
			(xy 277.491123 -56.136045) (xy 277.536973 -56.106579) (xy 277.58655 -56.083937) (xy 277.638845 -56.068582)
			(xy 277.692793 -56.060826) (xy 277.747295 -56.060826) (xy 277.801243 -56.068582) (xy 277.853538 -56.083937)
			(xy 277.903115 -56.106579) (xy 277.948965 -56.136045) (xy 277.990156 -56.171736) (xy 278.025847 -56.212927)
			(xy 278.055313 -56.258777) (xy 278.077955 -56.308354) (xy 278.09331 -56.360649) (xy 278.101066 -56.414597)
			(xy 278.101552 -56.441848) (xy 278.101067 -56.469218) (xy 278.093256 -56.523396) (xy 278.077772 -56.5759)
			(xy 278.054934 -56.625647) (xy 278.025212 -56.671614) (xy 278.007572 -56.692546) (xy 278.001476 -56.699658)
			(xy 277.995126 -56.716676) (xy 277.995126 -56.80202) (xy 278.001476 -56.819038) (xy 278.007572 -56.82615)
			(xy 278.025197 -56.847094) (xy 278.054912 -56.893063) (xy 278.077751 -56.942807) (xy 278.093245 -56.995306)
			(xy 278.101076 -57.04948) (xy 278.101552 -57.076848) (xy 278.101066 -57.104099) (xy 278.09331 -57.158047)
			(xy 278.077955 -57.210342) (xy 278.055313 -57.259919) (xy 278.025847 -57.305769) (xy 277.990156 -57.34696)
			(xy 277.948965 -57.382651) (xy 277.903115 -57.412117) (xy 277.853538 -57.434759) (xy 277.801243 -57.450114)
			(xy 277.747295 -57.45787) (xy 277.692793 -57.45787) (xy 277.638845 -57.450114) (xy 277.58655 -57.434759)
			(xy 277.536973 -57.412117) (xy 277.491123 -57.382651) (xy 277.449932 -57.34696) (xy 277.414241 -57.305769)
			(xy 277.384775 -57.259919) (xy 277.362133 -57.210342) (xy 277.346778 -57.158047) (xy 277.339022 -57.104099)
			(xy 277.338536 -57.076848) (xy 276.527157 -57.076848) (xy 276.544188 -57.081848) (xy 276.593773 -57.10449)
			(xy 276.639631 -57.133958) (xy 276.680829 -57.169653) (xy 276.716526 -57.210848) (xy 276.745998 -57.256704)
			(xy 276.768643 -57.306288) (xy 276.784001 -57.35859) (xy 276.791759 -57.412545) (xy 276.791759 -57.467055)
			(xy 276.784001 -57.52101) (xy 276.768643 -57.573312) (xy 276.745998 -57.622896) (xy 276.716526 -57.668752)
			(xy 276.680829 -57.709947) (xy 276.639631 -57.745642) (xy 276.593773 -57.77511) (xy 276.544188 -57.797752)
			(xy 276.491885 -57.813107) (xy 276.437929 -57.820861) (xy 276.410674 -57.821322) (xy 276.384358 -57.820859)
			(xy 276.332225 -57.81364) (xy 276.281577 -57.799328) (xy 276.233376 -57.778196) (xy 276.188533 -57.750643)
			(xy 276.147901 -57.717191) (xy 276.12975 -57.698132) (xy 276.122245 -57.690711) (xy 276.102952 -57.682196)
			(xy 276.092412 -57.681622) (xy 276.017736 -57.681622) (xy 276.007186 -57.68215) (xy 275.98789 -57.690685)
			(xy 275.980398 -57.698132) (xy 275.962251 -57.717199) (xy 275.921635 -57.750681) (xy 275.876797 -57.778255)
			(xy 275.828592 -57.799396) (xy 275.777936 -57.813702) (xy 275.725793 -57.820901) (xy 275.699474 -57.821322)
			(xy 275.672225 -57.820806) (xy 275.618282 -57.813047) (xy 275.565992 -57.79769) (xy 275.51642 -57.775048)
			(xy 275.470575 -57.745582) (xy 275.429389 -57.709892) (xy 275.393702 -57.668704) (xy 275.364239 -57.622857)
			(xy 275.341601 -57.573283) (xy 275.326248 -57.520992) (xy 275.318492 -57.467049) (xy 275.135152 -57.467049)
			(xy 275.138981 -57.494775) (xy 275.139404 -57.521094) (xy 275.138933 -57.548464) (xy 275.131117 -57.602643)
			(xy 275.115628 -57.655146) (xy 275.092788 -57.704893) (xy 275.063065 -57.75086) (xy 275.045424 -57.771792)
			(xy 275.039328 -57.778904) (xy 275.032978 -57.795922) (xy 275.032978 -57.881266) (xy 275.039328 -57.898284)
			(xy 275.045424 -57.905396) (xy 275.063061 -57.926333) (xy 275.09279 -57.972298) (xy 275.115638 -58.022044)
			(xy 275.131137 -58.074546) (xy 275.138967 -58.128725) (xy 275.138968 -58.183466) (xy 275.131139 -58.237645)
			(xy 275.115642 -58.290148) (xy 275.092794 -58.339894) (xy 275.063066 -58.38586) (xy 275.045424 -58.406792)
			(xy 275.039328 -58.413904) (xy 275.032978 -58.430922) (xy 275.032978 -58.516266) (xy 275.039328 -58.533284)
			(xy 275.045424 -58.540396) (xy 275.063078 -58.561316) (xy 275.092787 -58.607292) (xy 275.11562 -58.657043)
			(xy 275.131107 -58.709546) (xy 275.138932 -58.763724) (xy 275.139404 -58.791094) (xy 275.138918 -58.818345)
			(xy 275.131162 -58.872293) (xy 275.130765 -58.873644) (xy 276.400514 -58.873644) (xy 276.401002 -58.846275)
			(xy 276.408814 -58.792096) (xy 276.424298 -58.739593) (xy 276.447135 -58.689846) (xy 276.476855 -58.643878)
			(xy 276.494494 -58.622946) (xy 276.50059 -58.615834) (xy 276.50694 -58.598816) (xy 276.50694 -58.513472)
			(xy 276.50059 -58.496454) (xy 276.494494 -58.489342) (xy 276.47686 -58.468406) (xy 276.447148 -58.422434)
			(xy 276.424311 -58.372688) (xy 276.408819 -58.320188) (xy 276.400989 -58.266013) (xy 276.400514 -58.238644)
			(xy 276.401 -58.211393) (xy 276.408756 -58.157445) (xy 276.424111 -58.10515) (xy 276.446753 -58.055573)
			(xy 276.476219 -58.009723) (xy 276.51191 -57.968532) (xy 276.553101 -57.932841) (xy 276.598951 -57.903375)
			(xy 276.648528 -57.880733) (xy 276.700823 -57.865378) (xy 276.754771 -57.857622) (xy 276.809273 -57.857622)
			(xy 276.863221 -57.865378) (xy 276.915516 -57.880733) (xy 276.965093 -57.903375) (xy 277.010943 -57.932841)
			(xy 277.052134 -57.968532) (xy 277.087825 -58.009723) (xy 277.117291 -58.055573) (xy 277.139933 -58.10515)
			(xy 277.155288 -58.157445) (xy 277.163044 -58.211393) (xy 277.16353 -58.238644) (xy 277.163048 -58.266014)
			(xy 277.155237 -58.320193) (xy 277.139752 -58.372697) (xy 277.116914 -58.422444) (xy 277.087191 -58.468411)
			(xy 277.06955 -58.489342) (xy 277.063454 -58.496454) (xy 277.057104 -58.513472) (xy 277.057104 -58.598816)
			(xy 277.063454 -58.615834) (xy 277.06955 -58.622946) (xy 277.087169 -58.643894) (xy 277.116886 -58.689862)
			(xy 277.139726 -58.739605) (xy 277.155222 -58.792102) (xy 277.163054 -58.846276) (xy 277.16353 -58.873644)
			(xy 277.163044 -58.900895) (xy 277.155288 -58.954843) (xy 277.139933 -59.007138) (xy 277.117291 -59.056715)
			(xy 277.087825 -59.102565) (xy 277.052134 -59.143756) (xy 277.010943 -59.179447) (xy 276.965093 -59.208913)
			(xy 276.915516 -59.231555) (xy 276.863221 -59.24691) (xy 276.809273 -59.254666) (xy 276.754771 -59.254666)
			(xy 276.700823 -59.24691) (xy 276.648528 -59.231555) (xy 276.598951 -59.208913) (xy 276.553101 -59.179447)
			(xy 276.51191 -59.143756) (xy 276.476219 -59.102565) (xy 276.446753 -59.056715) (xy 276.424111 -59.007138)
			(xy 276.408756 -58.954843) (xy 276.401 -58.900895) (xy 276.400514 -58.873644) (xy 275.130765 -58.873644)
			(xy 275.115807 -58.924588) (xy 275.093165 -58.974165) (xy 275.063699 -59.020015) (xy 275.028008 -59.061206)
			(xy 274.986817 -59.096897) (xy 274.940967 -59.126363) (xy 274.89139 -59.149005) (xy 274.839095 -59.16436)
			(xy 274.785147 -59.172116) (xy 274.730645 -59.172116) (xy 274.676697 -59.16436) (xy 274.624402 -59.149005)
			(xy 274.574825 -59.126363) (xy 274.528975 -59.096897) (xy 274.487784 -59.061206) (xy 274.452093 -59.020015)
			(xy 274.422627 -58.974165) (xy 274.399985 -58.924588) (xy 274.38463 -58.872293) (xy 274.376874 -58.818345)
			(xy 274.376388 -58.791094) (xy 272.47843 -58.791094) (xy 272.475338 -58.812603) (xy 272.459983 -58.864898)
			(xy 272.437341 -58.914475) (xy 272.407875 -58.960325) (xy 272.372184 -59.001516) (xy 272.330993 -59.037207)
			(xy 272.285143 -59.066673) (xy 272.235566 -59.089315) (xy 272.183271 -59.10467) (xy 272.129323 -59.112426)
			(xy 272.074821 -59.112426) (xy 272.020873 -59.10467) (xy 271.968578 -59.089315) (xy 271.919001 -59.066673)
			(xy 271.873151 -59.037207) (xy 271.83196 -59.001516) (xy 271.796269 -58.960325) (xy 271.766803 -58.914475)
			(xy 271.744161 -58.864898) (xy 271.728806 -58.812603) (xy 271.72105 -58.758655) (xy 271.720564 -58.731404)
			(xy 269.891002 -58.731404) (xy 269.891002 -60.126451) (xy 275.380172 -60.126451) (xy 275.380172 -60.071949)
			(xy 275.387928 -60.018) (xy 275.403283 -59.965705) (xy 275.425925 -59.916127) (xy 275.455391 -59.870276)
			(xy 275.491083 -59.829086) (xy 275.532273 -59.793393) (xy 275.578124 -59.763927) (xy 275.627701 -59.741285)
			(xy 275.679996 -59.725929) (xy 275.733945 -59.718172) (xy 275.761196 -59.717686) (xy 275.788566 -59.718158)
			(xy 275.842745 -59.725975) (xy 275.895248 -59.741463) (xy 275.944995 -59.764303) (xy 275.990962 -59.794026)
			(xy 276.011894 -59.811666) (xy 276.019006 -59.817762) (xy 276.036024 -59.824112) (xy 276.121368 -59.824112)
			(xy 276.138386 -59.817762) (xy 276.145498 -59.811666) (xy 276.166431 -59.794025) (xy 276.212399 -59.764301)
			(xy 276.262145 -59.741455) (xy 276.314647 -59.725959) (xy 276.368825 -59.71813) (xy 276.423567 -59.71813)
			(xy 276.477745 -59.725959) (xy 276.530247 -59.741455) (xy 276.579993 -59.764301) (xy 276.625961 -59.794025)
			(xy 276.646894 -59.811666) (xy 276.654006 -59.817762) (xy 276.671024 -59.824112) (xy 276.756368 -59.824112)
			(xy 276.773386 -59.817762) (xy 276.780498 -59.811666) (xy 276.801416 -59.794009) (xy 276.847393 -59.764301)
			(xy 276.897144 -59.741469) (xy 276.949648 -59.725982) (xy 277.003826 -59.718158) (xy 277.031196 -59.717686)
			(xy 277.058449 -59.718161) (xy 277.112399 -59.725917) (xy 277.164697 -59.741273) (xy 277.214276 -59.763915)
			(xy 277.260129 -59.793382) (xy 277.301322 -59.829075) (xy 277.337015 -59.870267) (xy 277.366483 -59.91612)
			(xy 277.389126 -59.9657) (xy 277.404482 -60.017997) (xy 277.412239 -60.071947) (xy 277.412239 -60.126453)
			(xy 277.404482 -60.180403) (xy 277.389126 -60.2327) (xy 277.366483 -60.28228) (xy 277.337015 -60.328133)
			(xy 277.301322 -60.369325) (xy 277.260129 -60.405018) (xy 277.214276 -60.434485) (xy 277.164697 -60.457127)
			(xy 277.112399 -60.472483) (xy 277.058449 -60.480239) (xy 277.031196 -60.480702) (xy 277.003826 -60.480238)
			(xy 276.949647 -60.472419) (xy 276.897143 -60.45693) (xy 276.847397 -60.434088) (xy 276.80143 -60.404363)
			(xy 276.780498 -60.386722) (xy 276.773386 -60.380626) (xy 276.756368 -60.374276) (xy 276.671024 -60.374276)
			(xy 276.654006 -60.380626) (xy 276.646894 -60.386722) (xy 276.625961 -60.404363) (xy 276.579993 -60.434087)
			(xy 276.530247 -60.456933) (xy 276.477745 -60.472429) (xy 276.423567 -60.480258) (xy 276.368825 -60.480258)
			(xy 276.314647 -60.472429) (xy 276.262145 -60.456933) (xy 276.212399 -60.434087) (xy 276.166431 -60.404363)
			(xy 276.145498 -60.386722) (xy 276.138386 -60.380626) (xy 276.121368 -60.374276) (xy 276.036024 -60.374276)
			(xy 276.019006 -60.380626) (xy 276.011894 -60.386722) (xy 275.990978 -60.404381) (xy 275.945 -60.434089)
			(xy 275.895249 -60.456921) (xy 275.842745 -60.472407) (xy 275.788566 -60.480231) (xy 275.761196 -60.480702)
			(xy 275.733945 -60.480228) (xy 275.679996 -60.472471) (xy 275.627701 -60.457115) (xy 275.578124 -60.434473)
			(xy 275.532273 -60.405007) (xy 275.491083 -60.369314) (xy 275.455391 -60.328124) (xy 275.425925 -60.282273)
			(xy 275.403283 -60.232695) (xy 275.387928 -60.1804) (xy 275.380172 -60.126451) (xy 269.891002 -60.126451)
			(xy 269.891002 -60.999878) (xy 269.890468 -61.009867) (xy 269.882761 -61.028305) (xy 269.876016 -61.035692)
			(xy 269.1003 -61.811408) (xy 269.092943 -61.818056) (xy 269.074643 -61.825635) (xy 269.06474 -61.82614)
			(xy 269.00886 -61.82614) (xy 269.004796 -61.826902) (xy 268.989606 -61.829207) (xy 268.95894 -61.831115)
			(xy 268.943582 -61.830712) (xy 267.279374 -61.830712) (xy 267.274762 -61.830814) (xy 267.265689 -61.832477)
			(xy 267.26134 -61.834014) (xy 267.251942 -61.83757) (xy 267.24483 -61.844174) (xy 267.238988 -61.850524)
			(xy 267.1826 -61.923168) (xy 267.177774 -61.946028) (xy 267.180822 -61.957458) (xy 267.186182 -61.980005)
			(xy 267.192034 -62.025981) (xy 267.192506 -62.049152) (xy 267.192506 -62.054232) (xy 267.191828 -62.081351)
			(xy 267.183746 -62.134992) (xy 267.168147 -62.186948) (xy 267.145346 -62.23617) (xy 267.115802 -62.281666)
			(xy 267.080113 -62.322519) (xy 267.038996 -62.357904) (xy 266.993281 -62.387109) (xy 266.943891 -62.409544)
			(xy 266.891821 -62.424756) (xy 266.838121 -62.43244) (xy 266.810998 -62.432946) (xy 266.787443 -62.432566)
			(xy 266.740699 -62.426711) (xy 266.71778 -62.421262) (xy 266.703556 -62.417706) (xy 266.676378 -62.426342)
			(xy 266.598146 -62.517274) (xy 266.593574 -62.545468) (xy 266.599162 -62.55893) (xy 266.608488 -62.582314)
			(xy 266.621609 -62.630918) (xy 266.628227 -62.680824) (xy 266.628626 -62.705996) (xy 266.628141 -62.733248)
			(xy 266.620385 -62.787197) (xy 266.60503 -62.839493) (xy 266.582389 -62.889072) (xy 266.552923 -62.934924)
			(xy 266.517232 -62.976117) (xy 266.476042 -63.01181) (xy 266.430191 -63.041279) (xy 266.380614 -63.063922)
			(xy 266.328319 -63.07928) (xy 266.27437 -63.087039) (xy 266.247118 -63.087504) (xy 266.218308 -63.086978)
			(xy 266.161344 -63.078311) (xy 266.106332 -63.061172) (xy 266.054525 -63.035951) (xy 266.007103 -63.003222)
			(xy 265.985752 -62.983872) (xy 265.977116 -62.975744) (xy 265.955272 -62.968886) (xy 265.865356 -62.981332)
			(xy 265.863324 -62.981586) (xy 265.852587 -62.984095) (xy 265.83455 -62.996735) (xy 265.828526 -63.00597)
			(xy 265.813708 -63.03009) (xy 265.778069 -63.074069) (xy 265.736321 -63.112296) (xy 265.689381 -63.143933)
			(xy 265.63828 -63.168283) (xy 265.584141 -63.184813) (xy 265.528153 -63.193158) (xy 265.49985 -63.193676)
			(xy 265.472603 -63.193186) (xy 265.418666 -63.185425) (xy 265.366381 -63.170067) (xy 265.316815 -63.147425)
			(xy 265.270974 -63.117959) (xy 265.229794 -63.082271) (xy 265.194111 -63.041085) (xy 265.164651 -62.995241)
			(xy 265.142016 -62.945672) (xy 265.126665 -62.893385) (xy 265.11891 -62.839447) (xy 265.11891 -62.784953)
			(xy 265.126665 -62.731015) (xy 265.142016 -62.678728) (xy 265.164651 -62.629159) (xy 265.194111 -62.583314)
			(xy 265.229794 -62.542129) (xy 265.270974 -62.506441) (xy 265.316815 -62.476975) (xy 265.366381 -62.454333)
			(xy 265.418666 -62.438975) (xy 265.472603 -62.431214) (xy 265.49985 -62.43066) (xy 265.528661 -62.431184)
			(xy 265.585628 -62.439845) (xy 265.640644 -62.45698) (xy 265.692456 -62.482196) (xy 265.739883 -62.51492)
			(xy 265.761216 -62.534292) (xy 265.769852 -62.54242) (xy 265.791696 -62.549278) (xy 265.893296 -62.535054)
			(xy 265.912346 -62.522354) (xy 265.918442 -62.512194) (xy 265.93326 -62.488075) (xy 265.9689 -62.444097)
			(xy 266.010649 -62.405869) (xy 266.057589 -62.374232) (xy 266.108689 -62.34988) (xy 266.162827 -62.333347)
			(xy 266.218815 -62.324998) (xy 266.247118 -62.324488) (xy 266.267184 -62.324996) (xy 266.267438 -62.324996)
			(xy 266.283186 -62.326012) (xy 266.291822 -62.327028) (xy 266.31265 -62.330076) (xy 266.312904 -62.330076)
			(xy 266.340336 -62.336172) (xy 266.35456 -62.339728) (xy 266.381738 -62.331092) (xy 266.45997 -62.24016)
			(xy 266.464542 -62.211966) (xy 266.458954 -62.198504) (xy 266.449799 -62.175554) (xy 266.436811 -62.127882)
			(xy 266.430077 -62.078933) (xy 266.42949 -62.054232) (xy 266.42949 -62.051184) (xy 266.429838 -62.027702)
			(xy 266.435574 -61.981089) (xy 266.44092 -61.95822) (xy 266.441174 -61.957966) (xy 266.443603 -61.946435)
			(xy 266.43884 -61.923386) (xy 266.43203 -61.91377) (xy 266.383008 -61.850524) (xy 266.377166 -61.844174)
			(xy 266.370054 -61.83757) (xy 266.360656 -61.834014) (xy 266.356308 -61.832475) (xy 266.347234 -61.83082)
			(xy 266.342622 -61.830712) (xy 265.36396 -61.830712) (xy 265.351588 -61.830642) (xy 265.326919 -61.828737)
			(xy 265.314684 -61.826902) (xy 265.31062 -61.82614) (xy 265.068812 -61.82614) (xy 265.057128 -61.829188)
			(xy 265.052302 -61.831474) (xy 265.051794 -61.831728) (xy 265.036888 -61.838666) (xy 265.00611 -61.850238)
			(xy 264.990326 -61.854842) (xy 264.963033 -61.862056) (xy 264.907045 -61.869287) (xy 264.850604 -61.868178)
			(xy 264.822686 -61.863986) (xy 264.796107 -61.859027) (xy 264.744601 -61.842587) (xy 264.72007 -61.83122)
			(xy 264.71499 -61.82868) (xy 264.703814 -61.82614) (xy 264.4521 -61.82614) (xy 264.448036 -61.826902)
			(xy 264.4358 -61.828727) (xy 264.411131 -61.830637) (xy 264.39876 -61.830712) (xy 263.264142 -61.830712)
			(xy 263.255717 -61.831057) (xy 263.239767 -61.836489) (xy 263.2329 -61.84138) (xy 263.226042 -61.846714)
			(xy 263.178036 -61.920374) (xy 263.170924 -61.931296) (xy 263.169908 -61.94425) (xy 263.168892 -61.956696)
			(xy 263.174734 -61.970158) (xy 263.184551 -61.994086) (xy 263.198369 -62.043925) (xy 263.205325 -62.095174)
			(xy 263.205722 -62.121034) (xy 263.205722 -62.12586) (xy 263.20491 -62.152886) (xy 263.1966 -62.206313)
			(xy 263.180831 -62.258031) (xy 263.157919 -62.307004) (xy 263.128322 -62.352253) (xy 263.092633 -62.39287)
			(xy 263.051568 -62.428042) (xy 263.005949 -62.457064) (xy 262.956689 -62.479355) (xy 262.904775 -62.494469)
			(xy 262.851248 -62.502102) (xy 262.79718 -62.502102) (xy 262.743653 -62.494469) (xy 262.691739 -62.479355)
			(xy 262.642479 -62.457064) (xy 262.59686 -62.428042) (xy 262.555795 -62.39287) (xy 262.520106 -62.352253)
			(xy 262.490509 -62.307004) (xy 262.467597 -62.258031) (xy 262.451828 -62.206313) (xy 262.443518 -62.152886)
			(xy 262.442706 -62.12586) (xy 262.442706 -62.12078) (xy 262.443154 -62.094683) (xy 262.450307 -62.042981)
			(xy 262.464437 -61.992735) (xy 262.474456 -61.968634) (xy 262.47852 -61.959236) (xy 262.479028 -61.93917)
			(xy 262.475218 -61.929772) (xy 262.470392 -61.920374) (xy 262.426958 -61.85408) (xy 262.419446 -61.843883)
			(xy 262.397187 -61.831868) (xy 262.38454 -61.83122) (xy 259.86232 -61.83122) (xy 259.852359 -61.831709)
			(xy 259.83394 -61.839303) (xy 259.826506 -61.845952) (xy 259.422646 -62.249812) (xy 259.41528 -62.256924)
			(xy 259.40766 -62.27572) (xy 259.40766 -63.273432) (xy 261.776716 -63.273432) (xy 261.780787 -63.21781)
			(xy 261.792913 -63.163373) (xy 261.812836 -63.111282) (xy 261.840132 -63.062647) (xy 261.874218 -63.018504)
			(xy 261.914367 -62.979795) (xy 261.959725 -62.947344) (xy 262.009325 -62.921843) (xy 262.062109 -62.903836)
			(xy 262.116952 -62.893706) (xy 262.172686 -62.891669) (xy 262.228123 -62.897769) (xy 262.28208 -62.911875)
			(xy 262.333409 -62.933687) (xy 262.381015 -62.962741) (xy 262.423883 -62.998416) (xy 262.4611 -63.039953)
			(xy 262.491873 -63.086466) (xy 262.515545 -63.136963) (xy 262.531613 -63.19037) (xy 262.539733 -63.245546)
			(xy 262.539733 -63.245552) (xy 275.304469 -63.245552) (xy 275.304469 -63.191048) (xy 275.312226 -63.137099)
			(xy 275.327582 -63.084802) (xy 275.350224 -63.035224) (xy 275.379691 -62.989372) (xy 275.415384 -62.948181)
			(xy 275.456575 -62.912489) (xy 275.502427 -62.883022) (xy 275.552006 -62.86038) (xy 275.604303 -62.845025)
			(xy 275.658252 -62.837269) (xy 275.685504 -62.836806) (xy 275.712874 -62.837268) (xy 275.767054 -62.845087)
			(xy 275.819557 -62.860577) (xy 275.869304 -62.883419) (xy 275.91527 -62.913144) (xy 275.936202 -62.930786)
			(xy 275.943314 -62.936882) (xy 275.960332 -62.943232) (xy 276.045676 -62.943232) (xy 276.062694 -62.936882)
			(xy 276.069806 -62.930786) (xy 276.090739 -62.913145) (xy 276.136707 -62.883421) (xy 276.186453 -62.860575)
			(xy 276.238955 -62.845079) (xy 276.293133 -62.83725) (xy 276.347875 -62.83725) (xy 276.402053 -62.845079)
			(xy 276.454555 -62.860575) (xy 276.504301 -62.883421) (xy 276.550269 -62.913145) (xy 276.571202 -62.930786)
			(xy 276.578314 -62.936882) (xy 276.595332 -62.943232) (xy 276.680676 -62.943232) (xy 276.697694 -62.936882)
			(xy 276.704806 -62.930786) (xy 276.725723 -62.913128) (xy 276.7717 -62.88342) (xy 276.821452 -62.860588)
			(xy 276.873956 -62.845101) (xy 276.928134 -62.837277) (xy 276.955504 -62.836806) (xy 276.982756 -62.837264)
			(xy 277.036705 -62.845021) (xy 277.089002 -62.860377) (xy 277.13858 -62.88302) (xy 277.184432 -62.912487)
			(xy 277.225623 -62.94818) (xy 277.261315 -62.989372) (xy 277.290782 -63.035223) (xy 277.313424 -63.084802)
			(xy 277.32878 -63.137099) (xy 277.336536 -63.191048) (xy 277.336536 -63.245552) (xy 277.32878 -63.299501)
			(xy 277.313424 -63.351798) (xy 277.290782 -63.401377) (xy 277.261315 -63.447228) (xy 277.225623 -63.48842)
			(xy 277.184432 -63.524113) (xy 277.13858 -63.55358) (xy 277.089002 -63.576223) (xy 277.036705 -63.591579)
			(xy 276.982756 -63.599336) (xy 276.955504 -63.599822) (xy 276.928133 -63.599373) (xy 276.873952 -63.591554)
			(xy 276.821448 -63.576062) (xy 276.771702 -63.553216) (xy 276.725736 -63.523486) (xy 276.704806 -63.505842)
			(xy 276.697694 -63.499746) (xy 276.680676 -63.493396) (xy 276.595332 -63.493396) (xy 276.578314 -63.499746)
			(xy 276.571202 -63.505842) (xy 276.550269 -63.523483) (xy 276.504301 -63.553207) (xy 276.454555 -63.576053)
			(xy 276.402053 -63.591549) (xy 276.347875 -63.599378) (xy 276.293133 -63.599378) (xy 276.238955 -63.591549)
			(xy 276.186453 -63.576053) (xy 276.136707 -63.553207) (xy 276.090739 -63.523483) (xy 276.069806 -63.505842)
			(xy 276.062694 -63.499746) (xy 276.045676 -63.493396) (xy 275.960332 -63.493396) (xy 275.943314 -63.499746)
			(xy 275.936202 -63.505842) (xy 275.915286 -63.523501) (xy 275.869308 -63.553208) (xy 275.819556 -63.57604)
			(xy 275.767052 -63.591527) (xy 275.712874 -63.599351) (xy 275.685504 -63.599822) (xy 275.658252 -63.599331)
			(xy 275.604303 -63.591575) (xy 275.552006 -63.57622) (xy 275.502427 -63.553578) (xy 275.456575 -63.524111)
			(xy 275.415384 -63.488419) (xy 275.379691 -63.447228) (xy 275.350224 -63.401376) (xy 275.327582 -63.351798)
			(xy 275.312226 -63.299501) (xy 275.304469 -63.245552) (xy 262.539733 -63.245552) (xy 262.540242 -63.273432)
			(xy 262.539733 -63.301318) (xy 262.531613 -63.356494) (xy 262.515545 -63.409901) (xy 262.491873 -63.460398)
			(xy 262.4611 -63.506911) (xy 262.423883 -63.548448) (xy 262.381015 -63.584123) (xy 262.333409 -63.613177)
			(xy 262.28208 -63.634989) (xy 262.228123 -63.649095) (xy 262.172686 -63.655195) (xy 262.116952 -63.653158)
			(xy 262.062109 -63.643028) (xy 262.009325 -63.625021) (xy 261.959725 -63.59952) (xy 261.914367 -63.567069)
			(xy 261.874218 -63.52836) (xy 261.840132 -63.484217) (xy 261.812836 -63.435582) (xy 261.792913 -63.383491)
			(xy 261.780787 -63.329054) (xy 261.776716 -63.273432) (xy 259.40766 -63.273432) (xy 259.40766 -64.102234)
			(xy 259.58749 -64.102234) (xy 259.591561 -64.046612) (xy 259.603687 -63.992175) (xy 259.62361 -63.940084)
			(xy 259.650906 -63.891449) (xy 259.684992 -63.847306) (xy 259.725141 -63.808597) (xy 259.770499 -63.776146)
			(xy 259.820099 -63.750645) (xy 259.872883 -63.732638) (xy 259.927726 -63.722508) (xy 259.98346 -63.720471)
			(xy 260.038897 -63.726571) (xy 260.092854 -63.740677) (xy 260.144183 -63.762489) (xy 260.191789 -63.791543)
			(xy 260.234657 -63.827218) (xy 260.271874 -63.868755) (xy 260.302647 -63.915268) (xy 260.326319 -63.965765)
			(xy 260.342387 -64.019172) (xy 260.350507 -64.074348) (xy 260.351016 -64.102234) (xy 260.350507 -64.13012)
			(xy 260.342387 -64.185296) (xy 260.326319 -64.238703) (xy 260.302647 -64.2892) (xy 260.287369 -64.312292)
			(xy 263.265918 -64.312292) (xy 263.269989 -64.25667) (xy 263.282115 -64.202233) (xy 263.302038 -64.150142)
			(xy 263.329334 -64.101507) (xy 263.36342 -64.057364) (xy 263.403569 -64.018655) (xy 263.448927 -63.986204)
			(xy 263.498527 -63.960703) (xy 263.551311 -63.942696) (xy 263.606154 -63.932566) (xy 263.661888 -63.930529)
			(xy 263.717325 -63.936629) (xy 263.771282 -63.950735) (xy 263.822611 -63.972547) (xy 263.870217 -64.001601)
			(xy 263.913085 -64.037276) (xy 263.950302 -64.078813) (xy 263.981075 -64.125326) (xy 264.004747 -64.175823)
			(xy 264.020815 -64.22923) (xy 264.028935 -64.284406) (xy 264.029444 -64.312292) (xy 264.028935 -64.340178)
			(xy 264.020815 -64.395354) (xy 264.004747 -64.448761) (xy 263.981075 -64.499258) (xy 263.950302 -64.545771)
			(xy 263.913085 -64.587308) (xy 263.870217 -64.622983) (xy 263.822611 -64.652037) (xy 263.771282 -64.673849)
			(xy 263.717325 -64.687955) (xy 263.661888 -64.694055) (xy 263.606154 -64.692018) (xy 263.551311 -64.681888)
			(xy 263.498527 -64.663881) (xy 263.448927 -64.63838) (xy 263.403569 -64.605929) (xy 263.36342 -64.56722)
			(xy 263.329334 -64.523077) (xy 263.302038 -64.474442) (xy 263.282115 -64.422351) (xy 263.269989 -64.367914)
			(xy 263.265918 -64.312292) (xy 260.287369 -64.312292) (xy 260.271874 -64.335713) (xy 260.234657 -64.37725)
			(xy 260.191789 -64.412925) (xy 260.144183 -64.441979) (xy 260.092854 -64.463791) (xy 260.038897 -64.477897)
			(xy 259.98346 -64.483997) (xy 259.927726 -64.48196) (xy 259.872883 -64.47183) (xy 259.820099 -64.453823)
			(xy 259.770499 -64.428322) (xy 259.725141 -64.395871) (xy 259.684992 -64.357162) (xy 259.650906 -64.313019)
			(xy 259.62361 -64.264384) (xy 259.603687 -64.212293) (xy 259.591561 -64.157856) (xy 259.58749 -64.102234)
			(xy 259.40766 -64.102234) (xy 259.40766 -65.124076) (xy 264.307318 -65.124076) (xy 264.311389 -65.068454)
			(xy 264.323515 -65.014017) (xy 264.343438 -64.961926) (xy 264.370734 -64.913291) (xy 264.40482 -64.869148)
			(xy 264.444969 -64.830439) (xy 264.490327 -64.797988) (xy 264.539927 -64.772487) (xy 264.592711 -64.75448)
			(xy 264.647554 -64.74435) (xy 264.703288 -64.742313) (xy 264.758725 -64.748413) (xy 264.812682 -64.762519)
			(xy 264.864011 -64.784331) (xy 264.911617 -64.813385) (xy 264.954485 -64.84906) (xy 264.991702 -64.890597)
			(xy 265.022475 -64.93711) (xy 265.046147 -64.987607) (xy 265.062215 -65.041014) (xy 265.070335 -65.09619)
			(xy 265.070844 -65.124076) (xy 265.070335 -65.151962) (xy 265.069168 -65.15989) (xy 277.316436 -65.15989)
			(xy 277.320507 -65.104268) (xy 277.332633 -65.049831) (xy 277.352556 -64.99774) (xy 277.379852 -64.949105)
			(xy 277.413938 -64.904962) (xy 277.454087 -64.866253) (xy 277.499445 -64.833802) (xy 277.549045 -64.808301)
			(xy 277.601829 -64.790294) (xy 277.656672 -64.780164) (xy 277.712406 -64.778127) (xy 277.767843 -64.784227)
			(xy 277.8218 -64.798333) (xy 277.873129 -64.820145) (xy 277.920735 -64.849199) (xy 277.963603 -64.884874)
			(xy 278.00082 -64.926411) (xy 278.031593 -64.972924) (xy 278.055265 -65.023421) (xy 278.071333 -65.076828)
			(xy 278.079453 -65.132004) (xy 278.079962 -65.15989) (xy 278.079453 -65.187776) (xy 278.071333 -65.242952)
			(xy 278.055265 -65.296359) (xy 278.031593 -65.346856) (xy 278.00082 -65.393369) (xy 277.963603 -65.434906)
			(xy 277.920735 -65.470581) (xy 277.873129 -65.499635) (xy 277.8218 -65.521447) (xy 277.767843 -65.535553)
			(xy 277.712406 -65.541653) (xy 277.656672 -65.539616) (xy 277.601829 -65.529486) (xy 277.549045 -65.511479)
			(xy 277.499445 -65.485978) (xy 277.454087 -65.453527) (xy 277.413938 -65.414818) (xy 277.379852 -65.370675)
			(xy 277.352556 -65.32204) (xy 277.332633 -65.269949) (xy 277.320507 -65.215512) (xy 277.316436 -65.15989)
			(xy 265.069168 -65.15989) (xy 265.062215 -65.207138) (xy 265.046147 -65.260545) (xy 265.022475 -65.311042)
			(xy 264.991702 -65.357555) (xy 264.954485 -65.399092) (xy 264.911617 -65.434767) (xy 264.864011 -65.463821)
			(xy 264.812682 -65.485633) (xy 264.758725 -65.499739) (xy 264.703288 -65.505839) (xy 264.647554 -65.503802)
			(xy 264.592711 -65.493672) (xy 264.539927 -65.475665) (xy 264.490327 -65.450164) (xy 264.444969 -65.417713)
			(xy 264.40482 -65.379004) (xy 264.370734 -65.334861) (xy 264.343438 -65.286226) (xy 264.323515 -65.234135)
			(xy 264.311389 -65.179698) (xy 264.307318 -65.124076) (xy 259.40766 -65.124076) (xy 259.40766 -65.75552)
			(xy 272.54657 -65.75552) (xy 272.550641 -65.699898) (xy 272.562767 -65.645461) (xy 272.58269 -65.59337)
			(xy 272.609986 -65.544735) (xy 272.644072 -65.500592) (xy 272.684221 -65.461883) (xy 272.729579 -65.429432)
			(xy 272.779179 -65.403931) (xy 272.831963 -65.385924) (xy 272.886806 -65.375794) (xy 272.94254 -65.373757)
			(xy 272.997977 -65.379857) (xy 273.051934 -65.393963) (xy 273.103263 -65.415775) (xy 273.150869 -65.444829)
			(xy 273.193737 -65.480504) (xy 273.230954 -65.522041) (xy 273.261727 -65.568554) (xy 273.285399 -65.619051)
			(xy 273.301467 -65.672458) (xy 273.309587 -65.727634) (xy 273.310096 -65.75552) (xy 273.309587 -65.783406)
			(xy 273.301467 -65.838582) (xy 273.285399 -65.891989) (xy 273.261727 -65.942486) (xy 273.230954 -65.988999)
			(xy 273.193737 -66.030536) (xy 273.150869 -66.066211) (xy 273.103263 -66.095265) (xy 273.051934 -66.117077)
			(xy 272.997977 -66.131183) (xy 272.94254 -66.137283) (xy 272.886806 -66.135246) (xy 272.831963 -66.125116)
			(xy 272.779179 -66.107109) (xy 272.729579 -66.081608) (xy 272.684221 -66.049157) (xy 272.644072 -66.010448)
			(xy 272.609986 -65.966305) (xy 272.58269 -65.91767) (xy 272.562767 -65.865579) (xy 272.550641 -65.811142)
			(xy 272.54657 -65.75552) (xy 259.40766 -65.75552) (xy 259.40766 -67.488054) (xy 276.979124 -67.488054)
			(xy 276.983195 -67.432432) (xy 276.995321 -67.377995) (xy 277.015244 -67.325904) (xy 277.04254 -67.277269)
			(xy 277.076626 -67.233126) (xy 277.116775 -67.194417) (xy 277.162133 -67.161966) (xy 277.211733 -67.136465)
			(xy 277.264517 -67.118458) (xy 277.31936 -67.108328) (xy 277.375094 -67.106291) (xy 277.430531 -67.112391)
			(xy 277.484488 -67.126497) (xy 277.535817 -67.148309) (xy 277.583423 -67.177363) (xy 277.626291 -67.213038)
			(xy 277.663508 -67.254575) (xy 277.694281 -67.301088) (xy 277.717953 -67.351585) (xy 277.734021 -67.404992)
			(xy 277.742141 -67.460168) (xy 277.74265 -67.488054) (xy 277.742141 -67.51594) (xy 277.734021 -67.571116)
			(xy 277.717953 -67.624523) (xy 277.694281 -67.67502) (xy 277.663508 -67.721533) (xy 277.626291 -67.76307)
			(xy 277.583423 -67.798745) (xy 277.535817 -67.827799) (xy 277.484488 -67.849611) (xy 277.430531 -67.863717)
			(xy 277.375094 -67.869817) (xy 277.31936 -67.86778) (xy 277.264517 -67.85765) (xy 277.211733 -67.839643)
			(xy 277.162133 -67.814142) (xy 277.116775 -67.781691) (xy 277.076626 -67.742982) (xy 277.04254 -67.698839)
			(xy 277.015244 -67.650204) (xy 276.995321 -67.598113) (xy 276.983195 -67.543676) (xy 276.979124 -67.488054)
			(xy 259.40766 -67.488054) (xy 259.40766 -69.9516) (xy 259.408116 -69.961479) (xy 259.41555 -69.979786)
			(xy 259.422138 -69.98716) (xy 259.422392 -69.987414) (xy 259.598668 -70.16369) (xy 259.599176 -70.164198)
			(xy 259.606556 -70.170783) (xy 259.624856 -70.178233) (xy 259.634736 -70.178676)
		)
		(stroke
			(width 0)
			(type solid)
		)
		(fill yes)
		(layer "In9.Cu")
		(net "P12V_SSD9_R")
	)
	(gr_poly
		(pts
			(xy 420.778178 -70.178676) (xy 420.788241 -70.178238) (xy 420.806823 -70.170501) (xy 420.814246 -70.16369)
			(xy 421.140382 -69.837554) (xy 421.14089 -69.837046) (xy 421.147468 -69.829663) (xy 421.154912 -69.811364)
			(xy 421.155368 -69.801486) (xy 421.155368 -67.91579) (xy 421.154971 -67.906267) (xy 421.148016 -67.888538)
			(xy 421.135068 -67.874571) (xy 421.126666 -67.87007) (xy 421.030908 -67.823842) (xy 421.002206 -67.827144)
			(xy 420.990522 -67.836288) (xy 420.97021 -67.851901) (xy 420.926195 -67.878118) (xy 420.879066 -67.898205)
			(xy 420.829672 -67.911801) (xy 420.778902 -67.918659) (xy 420.753286 -67.919092) (xy 420.726037 -67.918605)
			(xy 420.672093 -67.910847) (xy 420.619802 -67.895491) (xy 420.570229 -67.87285) (xy 420.524382 -67.843385)
			(xy 420.483195 -67.807695) (xy 420.447507 -67.766507) (xy 420.418043 -67.720659) (xy 420.395404 -67.671085)
			(xy 420.38005 -67.618794) (xy 420.372294 -67.564849) (xy 420.372294 -67.510351) (xy 420.38005 -67.456406)
			(xy 420.395404 -67.404115) (xy 420.418043 -67.354541) (xy 420.447507 -67.308693) (xy 420.483195 -67.267505)
			(xy 420.524382 -67.231815) (xy 420.570229 -67.20235) (xy 420.619802 -67.179709) (xy 420.672093 -67.164353)
			(xy 420.726037 -67.156595) (xy 420.753286 -67.156076) (xy 420.778903 -67.15649) (xy 420.829674 -67.16335)
			(xy 420.87907 -67.176948) (xy 420.926199 -67.197039) (xy 420.970213 -67.223261) (xy 420.990522 -67.23888)
			(xy 421.002206 -67.248024) (xy 421.030908 -67.251326) (xy 421.126666 -67.205098) (xy 421.135067 -67.200597)
			(xy 421.148009 -67.186626) (xy 421.154974 -67.1689) (xy 421.155368 -67.159378) (xy 421.155368 -65.506854)
			(xy 421.141652 -65.483486) (xy 421.130222 -65.476628) (xy 421.129714 -65.476628) (xy 421.056562 -65.433702)
			(xy 421.04755 -65.428958) (xy 421.027371 -65.426338) (xy 421.017446 -65.428622) (xy 421.00373 -65.432432)
			(xy 420.998142 -65.43548) (xy 420.969857 -65.450257) (xy 420.909581 -65.471205) (xy 420.84666 -65.481832)
			(xy 420.814754 -65.48247) (xy 420.8145 -65.48247) (xy 420.787251 -65.481984) (xy 420.733309 -65.474228)
			(xy 420.68102 -65.458875) (xy 420.631447 -65.436236) (xy 420.585602 -65.406772) (xy 420.544416 -65.371084)
			(xy 420.508728 -65.329898) (xy 420.479264 -65.284053) (xy 420.456625 -65.23448) (xy 420.441272 -65.182191)
			(xy 420.433516 -65.128249) (xy 420.433516 -65.073751) (xy 420.441272 -65.019809) (xy 420.456625 -64.96752)
			(xy 420.479264 -64.917947) (xy 420.508728 -64.872102) (xy 420.544416 -64.830916) (xy 420.585602 -64.795228)
			(xy 420.631447 -64.765764) (xy 420.68102 -64.743125) (xy 420.733309 -64.727772) (xy 420.787251 -64.720016)
			(xy 420.8145 -64.719454) (xy 420.814754 -64.719454) (xy 420.846657 -64.720122) (xy 420.90957 -64.730764)
			(xy 420.969846 -64.751694) (xy 420.998142 -64.766444) (xy 421.00373 -64.769492) (xy 421.017446 -64.773302)
			(xy 421.027371 -64.775555) (xy 421.047535 -64.772925) (xy 421.056562 -64.768222) (xy 421.129968 -64.725296)
			(xy 421.13073 -64.724788) (xy 421.13801 -64.719975) (xy 421.149059 -64.706481) (xy 421.154966 -64.690072)
			(xy 421.155368 -64.681354) (xy 421.155368 -52.622958) (xy 421.15359 -52.616608) (xy 421.147531 -52.592357)
			(xy 421.141034 -52.542795) (xy 421.140636 -52.517802) (xy 421.140636 -52.51577) (xy 421.141101 -52.491159)
			(xy 421.147598 -52.442363) (xy 421.15359 -52.418488) (xy 421.155368 -52.411884) (xy 421.155368 -51.455828)
			(xy 421.155872 -51.445777) (xy 421.163591 -51.427213) (xy 421.170354 -51.41976) (xy 421.277288 -51.312826)
			(xy 421.284685 -51.305975) (xy 421.303283 -51.298232) (xy 421.313356 -51.29784) (xy 422.003728 -51.29784)
			(xy 422.01211 -51.297078) (xy 422.019714 -51.295561) (xy 422.033543 -51.28857) (xy 422.039288 -51.283362)
			(xy 422.104058 -51.218592) (xy 422.104566 -51.218084) (xy 422.111153 -51.210704) (xy 422.118615 -51.192405)
			(xy 422.119044 -51.182524) (xy 422.119044 -49.20615) (xy 422.118449 -49.193824) (xy 422.107001 -49.171993)
			(xy 422.0972 -49.164494) (xy 422.0337 -49.120044) (xy 422.0272 -49.115861) (xy 422.012467 -49.111208)
			(xy 422.004744 -49.1109) (xy 421.982646 -49.1109) (xy 421.974772 -49.113694) (xy 421.944587 -49.123447)
			(xy 421.882027 -49.133915) (xy 421.850312 -49.134522) (xy 421.846248 -49.134522) (xy 421.819188 -49.133761)
			(xy 421.765683 -49.125539) (xy 421.713878 -49.109835) (xy 421.664813 -49.086965) (xy 421.619475 -49.057387)
			(xy 421.578773 -49.021697) (xy 421.543527 -48.980611) (xy 421.514443 -48.934954) (xy 421.492106 -48.885644)
			(xy 421.476965 -48.833672) (xy 421.469324 -48.780081) (xy 421.468804 -48.753014) (xy 421.469266 -48.725761)
			(xy 421.477022 -48.671809) (xy 421.492377 -48.61951) (xy 421.515019 -48.569929) (xy 421.544486 -48.524075)
			(xy 421.58018 -48.482882) (xy 421.621373 -48.447188) (xy 421.667227 -48.41772) (xy 421.716808 -48.395077)
			(xy 421.769107 -48.379722) (xy 421.823059 -48.371967) (xy 421.850312 -48.371506) (xy 421.851074 -48.371506)
			(xy 421.88469 -48.372263) (xy 421.950863 -48.384153) (xy 421.982646 -48.395128) (xy 421.99433 -48.399446)
			(xy 422.018968 -48.396398) (xy 422.0972 -48.341534) (xy 422.106863 -48.333918) (xy 422.118259 -48.312158)
			(xy 422.119044 -48.299878) (xy 422.119044 -41.95445) (xy 422.11861 -41.944385) (xy 422.110877 -41.925799)
			(xy 422.104058 -41.918382) (xy 421.223694 -41.038018) (xy 421.216582 -41.030652) (xy 421.197786 -41.023032)
			(xy 419.41623 -41.023032) (xy 419.407533 -41.023393) (xy 419.391145 -41.029221) (xy 419.377641 -41.040185)
			(xy 419.372796 -41.047416) (xy 419.327838 -41.121584) (xy 419.323774 -41.13022) (xy 419.320447 -41.140526)
			(xy 419.321879 -41.162115) (xy 419.326568 -41.171876) (xy 419.32733 -41.1734) (xy 419.331648 -41.18229)
			(xy 419.343726 -41.208261) (xy 419.360838 -41.262919) (xy 419.369608 -41.319517) (xy 419.370256 -41.348152)
			(xy 419.370256 -41.34866) (xy 419.370256 -41.35501) (xy 419.369345 -41.383073) (xy 419.3603 -41.438487)
			(xy 419.34323 -41.491977) (xy 419.318504 -41.542387) (xy 419.286656 -41.588628) (xy 419.267894 -41.609518)
			(xy 419.26764 -41.609772) (xy 419.261164 -41.617126) (xy 419.253861 -41.635288) (xy 419.253416 -41.645078)
			(xy 419.253416 -41.724072) (xy 419.260274 -41.741852) (xy 419.267132 -41.748964) (xy 419.286399 -41.770292)
			(xy 419.318956 -41.817655) (xy 419.344041 -41.869366) (xy 419.361085 -41.924255) (xy 419.369704 -41.981079)
			(xy 419.369701 -42.038553) (xy 419.361078 -42.095376) (xy 419.344029 -42.150264) (xy 419.31894 -42.201972)
			(xy 419.286378 -42.249333) (xy 419.267132 -42.27068) (xy 419.260274 -42.277792) (xy 419.253416 -42.295572)
			(xy 419.253416 -42.384472) (xy 419.260274 -42.402252) (xy 419.267132 -42.409364) (xy 419.286399 -42.430692)
			(xy 419.318957 -42.478057) (xy 419.344042 -42.529769) (xy 419.361086 -42.584659) (xy 419.369704 -42.641484)
			(xy 419.370256 -42.670222) (xy 419.369783 -42.697591) (xy 419.361955 -42.751767) (xy 419.346464 -42.804268)
			(xy 419.323628 -42.854016) (xy 419.293915 -42.899988) (xy 419.276276 -42.92092) (xy 419.27018 -42.928032)
			(xy 419.26383 -42.944796) (xy 419.26383 -43.030648) (xy 419.27018 -43.047412) (xy 419.276276 -43.054524)
			(xy 419.293918 -43.075455) (xy 419.323643 -43.121422) (xy 419.346484 -43.171169) (xy 419.361972 -43.223672)
			(xy 419.369788 -43.277852) (xy 419.370256 -43.305222) (xy 419.36977 -43.332473) (xy 419.362014 -43.386421)
			(xy 419.346659 -43.438716) (xy 419.324017 -43.488293) (xy 419.294551 -43.534143) (xy 419.25886 -43.575334)
			(xy 419.217669 -43.611025) (xy 419.171819 -43.640491) (xy 419.122242 -43.663133) (xy 419.069947 -43.678488)
			(xy 419.015999 -43.686244) (xy 418.961497 -43.686244) (xy 418.907549 -43.678488) (xy 418.855254 -43.663133)
			(xy 418.805677 -43.640491) (xy 418.759827 -43.611025) (xy 418.718636 -43.575334) (xy 418.682945 -43.534143)
			(xy 418.653479 -43.488293) (xy 418.630837 -43.438716) (xy 418.615482 -43.386421) (xy 418.607726 -43.332473)
			(xy 418.60724 -43.305222) (xy 418.607717 -43.277854) (xy 418.615552 -43.223682) (xy 418.631049 -43.171186)
			(xy 418.65389 -43.121443) (xy 418.683606 -43.075476) (xy 418.70122 -43.054524) (xy 418.707316 -43.047412)
			(xy 418.713666 -43.030648) (xy 418.713666 -42.944796) (xy 418.707316 -42.928032) (xy 418.70122 -42.92092)
			(xy 418.683576 -42.899989) (xy 418.653846 -42.854024) (xy 418.630999 -42.804277) (xy 418.615505 -42.751774)
			(xy 418.607683 -42.697593) (xy 418.60724 -42.670222) (xy 418.607759 -42.641483) (xy 418.61638 -42.584654)
			(xy 418.633429 -42.529762) (xy 418.658521 -42.478049) (xy 418.691087 -42.430686) (xy 418.710364 -42.409364)
			(xy 418.717222 -42.402252) (xy 418.72408 -42.384472) (xy 418.72408 -42.295572) (xy 418.717222 -42.277792)
			(xy 418.710364 -42.27068) (xy 418.69109 -42.249354) (xy 418.658518 -42.201992) (xy 418.63342 -42.150279)
			(xy 418.616366 -42.095387) (xy 418.607739 -42.038557) (xy 418.607737 -41.981075) (xy 418.616358 -41.924245)
			(xy 418.633409 -41.86935) (xy 418.658502 -41.817636) (xy 418.69107 -41.770271) (xy 418.710364 -41.748964)
			(xy 418.717222 -41.741852) (xy 418.72408 -41.724072) (xy 418.72408 -41.635172) (xy 418.717222 -41.617646)
			(xy 418.710364 -41.61028) (xy 418.691563 -41.589487) (xy 418.659631 -41.543414) (xy 418.634774 -41.49317)
			(xy 418.617526 -41.439833) (xy 418.608257 -41.384548) (xy 418.60724 -41.356534) (xy 418.60724 -41.349422)
			(xy 418.607752 -41.320528) (xy 418.616438 -41.263399) (xy 418.633659 -41.208238) (xy 418.645848 -41.182036)
			(xy 418.653214 -41.166542) (xy 418.656275 -41.157735) (xy 418.65654 -41.139107) (xy 418.653722 -41.13022)
			(xy 418.649658 -41.121584) (xy 418.6047 -41.04767) (xy 418.597842 -41.035986) (xy 418.574728 -41.023032)
			(xy 417.654232 -41.023032) (xy 417.64261 -41.023603) (xy 417.621715 -41.033791) (xy 417.6141 -41.04259)
			(xy 417.557458 -41.11498) (xy 417.552632 -41.137586) (xy 417.555426 -41.14927) (xy 417.560747 -41.171949)
			(xy 417.566477 -41.21818) (xy 417.566856 -41.241472) (xy 417.566372 -41.268726) (xy 417.558619 -41.322679)
			(xy 417.543267 -41.37498) (xy 417.520628 -41.424564) (xy 417.491163 -41.470421) (xy 417.455472 -41.511619)
			(xy 417.414282 -41.547318) (xy 417.368431 -41.576792) (xy 417.318851 -41.59944) (xy 417.266553 -41.614803)
			(xy 417.212602 -41.622567) (xy 417.185348 -41.62298) (xy 417.156608 -41.622463) (xy 417.099777 -41.613846)
			(xy 417.044882 -41.5968) (xy 416.993165 -41.571712) (xy 416.945798 -41.539149) (xy 416.92449 -41.519856)
			(xy 416.917378 -41.512998) (xy 416.899598 -41.50614) (xy 416.810698 -41.50614) (xy 416.792918 -41.512998)
			(xy 416.785806 -41.519856) (xy 416.764478 -41.539126) (xy 416.717115 -41.571691) (xy 416.665404 -41.596783)
			(xy 416.610514 -41.613836) (xy 416.553687 -41.622464) (xy 416.524948 -41.62298) (xy 416.497694 -41.62252)
			(xy 416.443739 -41.614768) (xy 416.391437 -41.599416) (xy 416.341853 -41.576776) (xy 416.295995 -41.547309)
			(xy 416.254799 -41.511615) (xy 416.219103 -41.470421) (xy 416.189634 -41.424565) (xy 416.166991 -41.374982)
			(xy 416.151636 -41.322681) (xy 416.143882 -41.268726) (xy 416.14344 -41.241472) (xy 416.143819 -41.21818)
			(xy 416.149549 -41.171949) (xy 416.15487 -41.14927) (xy 416.157664 -41.137586) (xy 416.152838 -41.11498)
			(xy 416.096196 -41.04259) (xy 416.08861 -41.033749) (xy 416.0677 -41.023537) (xy 416.056064 -41.023032)
			(xy 412.208472 -41.023032) (xy 412.198405 -41.023461) (xy 412.179811 -41.031186) (xy 412.172404 -41.038018)
			(xy 412.00578 -41.204642) (xy 411.999104 -41.212055) (xy 411.991541 -41.230491) (xy 411.991048 -41.240456)
			(xy 411.991048 -43.73626) (xy 420.513 -43.73626) (xy 420.517071 -43.680638) (xy 420.529197 -43.626201)
			(xy 420.54912 -43.57411) (xy 420.576416 -43.525475) (xy 420.610502 -43.481332) (xy 420.650651 -43.442623)
			(xy 420.696009 -43.410172) (xy 420.745609 -43.384671) (xy 420.798393 -43.366664) (xy 420.853236 -43.356534)
			(xy 420.90897 -43.354497) (xy 420.964407 -43.360597) (xy 421.018364 -43.374703) (xy 421.069693 -43.396515)
			(xy 421.117299 -43.425569) (xy 421.160167 -43.461244) (xy 421.197384 -43.502781) (xy 421.228157 -43.549294)
			(xy 421.251829 -43.599791) (xy 421.267897 -43.653198) (xy 421.276017 -43.708374) (xy 421.276526 -43.73626)
			(xy 421.276017 -43.764146) (xy 421.267897 -43.819322) (xy 421.251829 -43.872729) (xy 421.228157 -43.923226)
			(xy 421.197384 -43.969739) (xy 421.160167 -44.011276) (xy 421.117299 -44.046951) (xy 421.069693 -44.076005)
			(xy 421.018364 -44.097817) (xy 420.964407 -44.111923) (xy 420.90897 -44.118023) (xy 420.853236 -44.115986)
			(xy 420.798393 -44.105856) (xy 420.745609 -44.087849) (xy 420.696009 -44.062348) (xy 420.650651 -44.029897)
			(xy 420.610502 -43.991188) (xy 420.576416 -43.947045) (xy 420.54912 -43.89841) (xy 420.529197 -43.846319)
			(xy 420.517071 -43.791882) (xy 420.513 -43.73626) (xy 411.991048 -43.73626) (xy 411.991048 -45.114464)
			(xy 420.365426 -45.114464) (xy 420.369497 -45.058842) (xy 420.381623 -45.004405) (xy 420.401546 -44.952314)
			(xy 420.428842 -44.903679) (xy 420.462928 -44.859536) (xy 420.503077 -44.820827) (xy 420.548435 -44.788376)
			(xy 420.598035 -44.762875) (xy 420.650819 -44.744868) (xy 420.705662 -44.734738) (xy 420.761396 -44.732701)
			(xy 420.816833 -44.738801) (xy 420.87079 -44.752907) (xy 420.922119 -44.774719) (xy 420.969725 -44.803773)
			(xy 421.012593 -44.839448) (xy 421.04981 -44.880985) (xy 421.080583 -44.927498) (xy 421.104255 -44.977995)
			(xy 421.120323 -45.031402) (xy 421.128443 -45.086578) (xy 421.128952 -45.114464) (xy 421.128443 -45.14235)
			(xy 421.120323 -45.197526) (xy 421.104255 -45.250933) (xy 421.080583 -45.30143) (xy 421.04981 -45.347943)
			(xy 421.012593 -45.38948) (xy 420.969725 -45.425155) (xy 420.922119 -45.454209) (xy 420.87079 -45.476021)
			(xy 420.816833 -45.490127) (xy 420.761396 -45.496227) (xy 420.705662 -45.49419) (xy 420.650819 -45.48406)
			(xy 420.598035 -45.466053) (xy 420.548435 -45.440552) (xy 420.503077 -45.408101) (xy 420.462928 -45.369392)
			(xy 420.428842 -45.325249) (xy 420.401546 -45.276614) (xy 420.381623 -45.224523) (xy 420.369497 -45.170086)
			(xy 420.365426 -45.114464) (xy 411.991048 -45.114464) (xy 411.991048 -46.893226) (xy 420.637206 -46.893226)
			(xy 420.641277 -46.837604) (xy 420.653403 -46.783167) (xy 420.673326 -46.731076) (xy 420.700622 -46.682441)
			(xy 420.734708 -46.638298) (xy 420.774857 -46.599589) (xy 420.820215 -46.567138) (xy 420.869815 -46.541637)
			(xy 420.922599 -46.52363) (xy 420.977442 -46.5135) (xy 421.033176 -46.511463) (xy 421.088613 -46.517563)
			(xy 421.14257 -46.531669) (xy 421.193899 -46.553481) (xy 421.241505 -46.582535) (xy 421.284373 -46.61821)
			(xy 421.32159 -46.659747) (xy 421.352363 -46.70626) (xy 421.376035 -46.756757) (xy 421.392103 -46.810164)
			(xy 421.400223 -46.86534) (xy 421.400732 -46.893226) (xy 421.400223 -46.921112) (xy 421.392103 -46.976288)
			(xy 421.376035 -47.029695) (xy 421.352363 -47.080192) (xy 421.32159 -47.126705) (xy 421.284373 -47.168242)
			(xy 421.241505 -47.203917) (xy 421.193899 -47.232971) (xy 421.14257 -47.254783) (xy 421.088613 -47.268889)
			(xy 421.033176 -47.274989) (xy 420.977442 -47.272952) (xy 420.922599 -47.262822) (xy 420.869815 -47.244815)
			(xy 420.820215 -47.219314) (xy 420.774857 -47.186863) (xy 420.734708 -47.148154) (xy 420.700622 -47.104011)
			(xy 420.673326 -47.055376) (xy 420.653403 -47.003285) (xy 420.641277 -46.948848) (xy 420.637206 -46.893226)
			(xy 411.991048 -46.893226) (xy 411.991048 -47.936658) (xy 418.952934 -47.936658) (xy 418.95342 -47.909407)
			(xy 418.961176 -47.855459) (xy 418.976531 -47.803164) (xy 418.999173 -47.753587) (xy 419.028639 -47.707737)
			(xy 419.06433 -47.666546) (xy 419.105521 -47.630855) (xy 419.151371 -47.601389) (xy 419.200948 -47.578747)
			(xy 419.253243 -47.563392) (xy 419.307191 -47.555636) (xy 419.361693 -47.555636) (xy 419.415641 -47.563392)
			(xy 419.467936 -47.578747) (xy 419.517513 -47.601389) (xy 419.563363 -47.630855) (xy 419.604554 -47.666546)
			(xy 419.640245 -47.707737) (xy 419.669711 -47.753587) (xy 419.692353 -47.803164) (xy 419.707708 -47.855459)
			(xy 419.715464 -47.909407) (xy 419.71595 -47.936658) (xy 419.715489 -47.962999) (xy 419.708239 -48.015179)
			(xy 419.693884 -48.065867) (xy 419.672697 -48.114101) (xy 419.64508 -48.158964) (xy 419.611558 -48.199604)
			(xy 419.572768 -48.235251) (xy 419.551358 -48.250602) (xy 419.539531 -48.259296) (xy 419.521092 -48.28212)
			(xy 419.509905 -48.309247) (xy 419.506897 -48.338435) (xy 419.512314 -48.367273) (xy 419.52571 -48.393379)
			(xy 419.545979 -48.414596) (xy 419.55847 -48.422306) (xy 419.583005 -48.437003) (xy 419.627764 -48.472604)
			(xy 419.666708 -48.514487) (xy 419.698964 -48.561713) (xy 419.72381 -48.613225) (xy 419.740689 -48.667868)
			(xy 419.749223 -48.724419) (xy 419.749732 -48.753014) (xy 419.749246 -48.780265) (xy 419.74149 -48.834213)
			(xy 419.726135 -48.886508) (xy 419.703493 -48.936085) (xy 419.674027 -48.981935) (xy 419.638336 -49.023126)
			(xy 419.597145 -49.058817) (xy 419.551295 -49.088283) (xy 419.501718 -49.110925) (xy 419.449423 -49.12628)
			(xy 419.395475 -49.134036) (xy 419.340973 -49.134036) (xy 419.287025 -49.12628) (xy 419.23473 -49.110925)
			(xy 419.185153 -49.088283) (xy 419.139303 -49.058817) (xy 419.098112 -49.023126) (xy 419.062421 -48.981935)
			(xy 419.032955 -48.936085) (xy 419.010313 -48.886508) (xy 418.994958 -48.834213) (xy 418.987202 -48.780265)
			(xy 418.986716 -48.753014) (xy 418.98717 -48.726673) (xy 418.994423 -48.674493) (xy 419.008781 -48.623805)
			(xy 419.029969 -48.575572) (xy 419.057586 -48.530709) (xy 419.091108 -48.490069) (xy 419.129898 -48.454422)
			(xy 419.151308 -48.43907) (xy 419.163153 -48.430403) (xy 419.181581 -48.407569) (xy 419.192757 -48.380438)
			(xy 419.19576 -48.35125) (xy 419.190341 -48.322412) (xy 419.176947 -48.296304) (xy 419.156685 -48.275081)
			(xy 419.144196 -48.267366) (xy 419.119685 -48.252632) (xy 419.074928 -48.217035) (xy 419.035985 -48.175158)
			(xy 419.003726 -48.127938) (xy 418.978876 -48.076433) (xy 418.961991 -48.021796) (xy 418.953448 -47.965251)
			(xy 418.952934 -47.936658) (xy 411.991048 -47.936658) (xy 411.991048 -58.731404) (xy 413.82061 -58.731404)
			(xy 413.821076 -58.704034) (xy 413.828893 -58.649855) (xy 413.844382 -58.597351) (xy 413.867224 -58.547604)
			(xy 413.896949 -58.501638) (xy 413.91459 -58.480706) (xy 413.920686 -58.473594) (xy 413.927036 -58.456576)
			(xy 413.927036 -58.371232) (xy 413.920686 -58.354214) (xy 413.91459 -58.347102) (xy 413.896955 -58.326165)
			(xy 413.867233 -58.280197) (xy 413.844389 -58.230451) (xy 413.828894 -58.17795) (xy 413.821066 -58.123773)
			(xy 413.821066 -58.069033) (xy 413.828893 -58.014856) (xy 413.844387 -57.962354) (xy 413.86723 -57.912608)
			(xy 413.896951 -57.866639) (xy 413.91459 -57.845706) (xy 413.920686 -57.838594) (xy 413.927036 -57.821576)
			(xy 413.927036 -57.736232) (xy 413.920686 -57.719214) (xy 413.91459 -57.712102) (xy 413.896955 -57.691165)
			(xy 413.867233 -57.645197) (xy 413.844389 -57.595451) (xy 413.828894 -57.54295) (xy 413.821066 -57.488773)
			(xy 413.821066 -57.434033) (xy 413.828893 -57.379856) (xy 413.844387 -57.327354) (xy 413.86723 -57.277608)
			(xy 413.896951 -57.231639) (xy 413.91459 -57.210706) (xy 413.920686 -57.203594) (xy 413.927036 -57.186576)
			(xy 413.927036 -57.101232) (xy 413.920686 -57.084214) (xy 413.91459 -57.077102) (xy 413.896937 -57.056181)
			(xy 413.867227 -57.010205) (xy 413.844394 -56.960455) (xy 413.828907 -56.907952) (xy 413.821082 -56.853774)
			(xy 413.82061 -56.826404) (xy 413.821096 -56.799153) (xy 413.828852 -56.745205) (xy 413.844207 -56.69291)
			(xy 413.866849 -56.643333) (xy 413.896315 -56.597483) (xy 413.932006 -56.556292) (xy 413.973197 -56.520601)
			(xy 414.019047 -56.491135) (xy 414.068624 -56.468493) (xy 414.120919 -56.453138) (xy 414.174867 -56.445382)
			(xy 414.229369 -56.445382) (xy 414.283317 -56.453138) (xy 414.335612 -56.468493) (xy 414.385189 -56.491135)
			(xy 414.431039 -56.520601) (xy 414.47223 -56.556292) (xy 414.507921 -56.597483) (xy 414.537387 -56.643333)
			(xy 414.560029 -56.69291) (xy 414.575384 -56.745205) (xy 414.58314 -56.799153) (xy 414.583626 -56.826404)
			(xy 414.58318 -56.853775) (xy 414.57536 -56.907956) (xy 414.559867 -56.96046) (xy 414.537021 -57.010206)
			(xy 414.50729 -57.056172) (xy 414.489646 -57.077102) (xy 414.48355 -57.084214) (xy 414.4772 -57.101232)
			(xy 414.4772 -57.186576) (xy 414.48355 -57.203594) (xy 414.489646 -57.210706) (xy 414.507292 -57.231635)
			(xy 414.537018 -57.277603) (xy 414.559865 -57.32735) (xy 414.575362 -57.379852) (xy 414.583191 -57.434032)
			(xy 414.583191 -57.488774) (xy 414.575361 -57.542954) (xy 414.559863 -57.595456) (xy 414.537016 -57.645203)
			(xy 414.507288 -57.69117) (xy 414.489646 -57.712102) (xy 414.48355 -57.719214) (xy 414.4772 -57.736232)
			(xy 414.4772 -57.821576) (xy 414.48355 -57.838594) (xy 414.489646 -57.845706) (xy 414.507292 -57.866635)
			(xy 414.537018 -57.912603) (xy 414.559865 -57.96235) (xy 414.575362 -58.014852) (xy 414.583191 -58.069032)
			(xy 414.583191 -58.123774) (xy 414.575361 -58.177954) (xy 414.559863 -58.230456) (xy 414.537016 -58.280203)
			(xy 414.507288 -58.32617) (xy 414.489646 -58.347102) (xy 414.48355 -58.354214) (xy 414.4772 -58.371232)
			(xy 414.4772 -58.456576) (xy 414.48355 -58.473594) (xy 414.489646 -58.480706) (xy 414.507293 -58.501632)
			(xy 414.537005 -58.547606) (xy 414.559841 -58.597355) (xy 414.57533 -58.649857) (xy 414.583154 -58.704034)
			(xy 414.583626 -58.731404) (xy 414.58314 -58.758655) (xy 414.578476 -58.791094) (xy 416.476434 -58.791094)
			(xy 416.476888 -58.763723) (xy 416.484708 -58.709543) (xy 416.500199 -58.65704) (xy 416.523044 -58.607293)
			(xy 416.552771 -58.561327) (xy 416.570414 -58.540396) (xy 416.57651 -58.533284) (xy 416.58286 -58.516266)
			(xy 416.58286 -58.430922) (xy 416.57651 -58.413904) (xy 416.570414 -58.406792) (xy 416.552768 -58.385864)
			(xy 416.523044 -58.339895) (xy 416.5002 -58.290148) (xy 416.484705 -58.237645) (xy 416.476877 -58.183466)
			(xy 416.476878 -58.128725) (xy 416.484707 -58.074546) (xy 416.500203 -58.022044) (xy 416.523049 -57.972297)
			(xy 416.552773 -57.926329) (xy 416.570414 -57.905396) (xy 416.57651 -57.898284) (xy 416.58286 -57.881266)
			(xy 416.58286 -57.795922) (xy 416.57651 -57.778904) (xy 416.570414 -57.771792) (xy 416.55276 -57.750872)
			(xy 416.52305 -57.704896) (xy 416.500217 -57.655146) (xy 416.484729 -57.602642) (xy 416.476905 -57.548464)
			(xy 416.476434 -57.521094) (xy 416.476892 -57.494778) (xy 416.48411 -57.442644) (xy 416.498421 -57.391995)
			(xy 416.519555 -57.343793) (xy 416.547109 -57.298951) (xy 416.580563 -57.25832) (xy 416.599624 -57.24017)
			(xy 416.60703 -57.232651) (xy 416.615554 -57.21337) (xy 416.616134 -57.202832) (xy 416.616134 -57.128156)
			(xy 416.615578 -57.11761) (xy 416.607061 -57.098315) (xy 416.599624 -57.090818) (xy 416.580558 -57.07267)
			(xy 416.547078 -57.032053) (xy 416.519505 -56.987215) (xy 416.498364 -56.93901) (xy 416.484057 -56.888355)
			(xy 416.476856 -56.836213) (xy 416.476434 -56.809894) (xy 416.47692 -56.782643) (xy 416.484676 -56.728695)
			(xy 416.500031 -56.6764) (xy 416.522673 -56.626823) (xy 416.552139 -56.580973) (xy 416.58783 -56.539782)
			(xy 416.629021 -56.504091) (xy 416.674871 -56.474625) (xy 416.724448 -56.451983) (xy 416.776743 -56.436628)
			(xy 416.830691 -56.428872) (xy 416.885193 -56.428872) (xy 416.939141 -56.436628) (xy 416.991436 -56.451983)
			(xy 417.041013 -56.474625) (xy 417.086863 -56.504091) (xy 417.128054 -56.539782) (xy 417.163745 -56.580973)
			(xy 417.193211 -56.626823) (xy 417.215853 -56.6764) (xy 417.231208 -56.728695) (xy 417.238964 -56.782643)
			(xy 417.23945 -56.809894) (xy 417.239055 -56.836212) (xy 417.231826 -56.888349) (xy 417.217502 -56.938999)
			(xy 417.196357 -56.987201) (xy 417.16879 -57.032042) (xy 417.135326 -57.07267) (xy 417.11626 -57.090818)
			(xy 417.108857 -57.098339) (xy 417.100331 -57.117619) (xy 417.09975 -57.128156) (xy 417.09975 -57.202832)
			(xy 417.100317 -57.213377) (xy 417.108827 -57.232672) (xy 417.11626 -57.24017) (xy 417.135317 -57.258327)
			(xy 417.168799 -57.298942) (xy 417.196373 -57.343777) (xy 417.217516 -57.391981) (xy 417.231825 -57.442635)
			(xy 417.235198 -57.467053) (xy 417.418469 -57.467053) (xy 417.418469 -57.412547) (xy 417.426227 -57.358597)
			(xy 417.441583 -57.306299) (xy 417.464226 -57.256719) (xy 417.493695 -57.210867) (xy 417.529389 -57.169675)
			(xy 417.570583 -57.133983) (xy 417.616437 -57.104517) (xy 417.666018 -57.081876) (xy 417.718316 -57.066522)
			(xy 417.772267 -57.058768) (xy 417.79952 -57.058306) (xy 417.825836 -57.058764) (xy 417.87797 -57.065983)
			(xy 417.928618 -57.080295) (xy 417.97682 -57.101428) (xy 418.021662 -57.128983) (xy 418.062294 -57.162436)
			(xy 418.080444 -57.181496) (xy 418.087948 -57.188918) (xy 418.107241 -57.197431) (xy 418.117782 -57.198006)
			(xy 418.192458 -57.198006) (xy 418.203006 -57.197466) (xy 418.222302 -57.188938) (xy 418.229796 -57.181496)
			(xy 418.247932 -57.162418) (xy 418.288552 -57.12894) (xy 418.333392 -57.101369) (xy 418.3816 -57.080231)
			(xy 418.432257 -57.065926) (xy 418.484401 -57.058727) (xy 418.51072 -57.058306) (xy 418.537971 -57.058765)
			(xy 418.591919 -57.066524) (xy 418.627072 -57.076848) (xy 419.438582 -57.076848) (xy 419.439056 -57.049478)
			(xy 419.446869 -56.995298) (xy 419.462355 -56.942795) (xy 419.485196 -56.893047) (xy 419.51492 -56.847081)
			(xy 419.532562 -56.82615) (xy 419.538658 -56.819038) (xy 419.545008 -56.80202) (xy 419.545008 -56.716676)
			(xy 419.538658 -56.699658) (xy 419.532562 -56.692546) (xy 419.514925 -56.671613) (xy 419.485214 -56.62564)
			(xy 419.462378 -56.575892) (xy 419.446886 -56.523392) (xy 419.439057 -56.469217) (xy 419.438582 -56.441848)
			(xy 419.439068 -56.414597) (xy 419.446824 -56.360649) (xy 419.462179 -56.308354) (xy 419.484821 -56.258777)
			(xy 419.514287 -56.212927) (xy 419.549978 -56.171736) (xy 419.591169 -56.136045) (xy 419.637019 -56.106579)
			(xy 419.686596 -56.083937) (xy 419.738891 -56.068582) (xy 419.792839 -56.060826) (xy 419.847341 -56.060826)
			(xy 419.901289 -56.068582) (xy 419.953584 -56.083937) (xy 420.003161 -56.106579) (xy 420.049011 -56.136045)
			(xy 420.090202 -56.171736) (xy 420.125893 -56.212927) (xy 420.155359 -56.258777) (xy 420.178001 -56.308354)
			(xy 420.193356 -56.360649) (xy 420.201112 -56.414597) (xy 420.201598 -56.441848) (xy 420.201102 -56.469217)
			(xy 420.193291 -56.523395) (xy 420.177809 -56.575898) (xy 420.154974 -56.625645) (xy 420.125256 -56.671613)
			(xy 420.107618 -56.692546) (xy 420.101522 -56.699658) (xy 420.095172 -56.716676) (xy 420.095172 -56.80202)
			(xy 420.101522 -56.819038) (xy 420.107618 -56.82615) (xy 420.12525 -56.847088) (xy 420.154962 -56.893059)
			(xy 420.177799 -56.942805) (xy 420.193292 -56.995305) (xy 420.201123 -57.049479) (xy 420.201598 -57.076848)
			(xy 420.201112 -57.104099) (xy 420.193356 -57.158047) (xy 420.178001 -57.210342) (xy 420.155359 -57.259919)
			(xy 420.125893 -57.305769) (xy 420.090202 -57.34696) (xy 420.049011 -57.382651) (xy 420.003161 -57.412117)
			(xy 419.953584 -57.434759) (xy 419.901289 -57.450114) (xy 419.847341 -57.45787) (xy 419.792839 -57.45787)
			(xy 419.738891 -57.450114) (xy 419.686596 -57.434759) (xy 419.637019 -57.412117) (xy 419.591169 -57.382651)
			(xy 419.549978 -57.34696) (xy 419.514287 -57.305769) (xy 419.484821 -57.259919) (xy 419.462179 -57.210342)
			(xy 419.446824 -57.158047) (xy 419.439068 -57.104099) (xy 419.438582 -57.076848) (xy 418.627072 -57.076848)
			(xy 418.644213 -57.081882) (xy 418.69379 -57.104525) (xy 418.739639 -57.133993) (xy 418.780829 -57.169686)
			(xy 418.816519 -57.210877) (xy 418.845985 -57.256728) (xy 418.868625 -57.306306) (xy 418.88398 -57.358601)
			(xy 418.891736 -57.412549) (xy 418.891736 -57.467051) (xy 418.88398 -57.520999) (xy 418.868625 -57.573294)
			(xy 418.845985 -57.622872) (xy 418.816519 -57.668723) (xy 418.780829 -57.709914) (xy 418.739639 -57.745607)
			(xy 418.69379 -57.775075) (xy 418.644213 -57.797718) (xy 418.591919 -57.813076) (xy 418.537971 -57.820835)
			(xy 418.51072 -57.821322) (xy 418.484403 -57.820895) (xy 418.432268 -57.813669) (xy 418.38162 -57.79935)
			(xy 418.333418 -57.778211) (xy 418.288577 -57.750651) (xy 418.247946 -57.717194) (xy 418.229796 -57.698132)
			(xy 418.222274 -57.690731) (xy 418.202994 -57.682205) (xy 418.192458 -57.681622) (xy 418.117782 -57.681622)
			(xy 418.107235 -57.682175) (xy 418.087939 -57.690693) (xy 418.080444 -57.698132) (xy 418.062274 -57.717177)
			(xy 418.021663 -57.750661) (xy 417.97683 -57.778237) (xy 417.928629 -57.799383) (xy 417.877977 -57.813694)
			(xy 417.825838 -57.820898) (xy 417.79952 -57.821322) (xy 417.772267 -57.820832) (xy 417.718316 -57.813078)
			(xy 417.666018 -57.797724) (xy 417.616437 -57.775083) (xy 417.570583 -57.745617) (xy 417.529389 -57.709925)
			(xy 417.493695 -57.668733) (xy 417.464226 -57.622881) (xy 417.441583 -57.573301) (xy 417.426227 -57.521003)
			(xy 417.418469 -57.467053) (xy 417.235198 -57.467053) (xy 417.239027 -57.494776) (xy 417.23945 -57.521094)
			(xy 417.238993 -57.548465) (xy 417.231175 -57.602645) (xy 417.215684 -57.655148) (xy 417.19284 -57.704895)
			(xy 417.163113 -57.750861) (xy 417.14547 -57.771792) (xy 417.139374 -57.778904) (xy 417.133024 -57.795922)
			(xy 417.133024 -57.881266) (xy 417.139374 -57.898284) (xy 417.14547 -57.905396) (xy 417.163105 -57.926333)
			(xy 417.19283 -57.9723) (xy 417.215676 -58.022046) (xy 417.231173 -58.074547) (xy 417.239002 -58.128725)
			(xy 417.239003 -58.183466) (xy 417.231175 -58.237644) (xy 417.215679 -58.290146) (xy 417.192835 -58.339892)
			(xy 417.16311 -58.385859) (xy 417.14547 -58.406792) (xy 417.139374 -58.413904) (xy 417.133024 -58.430922)
			(xy 417.133024 -58.516266) (xy 417.139374 -58.533284) (xy 417.14547 -58.540396) (xy 417.163116 -58.561323)
			(xy 417.192828 -58.607296) (xy 417.215663 -58.657045) (xy 417.231152 -58.709547) (xy 417.238978 -58.763724)
			(xy 417.23945 -58.791094) (xy 417.238964 -58.818345) (xy 417.231208 -58.872293) (xy 417.230811 -58.873644)
			(xy 418.50056 -58.873644) (xy 418.501037 -58.846274) (xy 418.50885 -58.792095) (xy 418.524336 -58.739591)
			(xy 418.547175 -58.689844) (xy 418.576899 -58.643877) (xy 418.59454 -58.622946) (xy 418.600636 -58.615834)
			(xy 418.606986 -58.598816) (xy 418.606986 -58.513472) (xy 418.600636 -58.496454) (xy 418.59454 -58.489342)
			(xy 418.576913 -58.4684) (xy 418.547198 -58.42243) (xy 418.524359 -58.372686) (xy 418.508865 -58.320187)
			(xy 418.501035 -58.266013) (xy 418.50056 -58.238644) (xy 418.501046 -58.211393) (xy 418.508802 -58.157445)
			(xy 418.524157 -58.10515) (xy 418.546799 -58.055573) (xy 418.576265 -58.009723) (xy 418.611956 -57.968532)
			(xy 418.653147 -57.932841) (xy 418.698997 -57.903375) (xy 418.748574 -57.880733) (xy 418.800869 -57.865378)
			(xy 418.854817 -57.857622) (xy 418.909319 -57.857622) (xy 418.963267 -57.865378) (xy 419.015562 -57.880733)
			(xy 419.065139 -57.903375) (xy 419.110989 -57.932841) (xy 419.15218 -57.968532) (xy 419.187871 -58.009723)
			(xy 419.217337 -58.055573) (xy 419.239979 -58.10515) (xy 419.255334 -58.157445) (xy 419.26309 -58.211393)
			(xy 419.263576 -58.238644) (xy 419.263083 -58.266013) (xy 419.255273 -58.320191) (xy 419.23979 -58.372695)
			(xy 419.216954 -58.422442) (xy 419.187235 -58.46841) (xy 419.169596 -58.489342) (xy 419.1635 -58.496454)
			(xy 419.15715 -58.513472) (xy 419.15715 -58.598816) (xy 419.1635 -58.615834) (xy 419.169596 -58.622946)
			(xy 419.187223 -58.643888) (xy 419.216936 -58.689858) (xy 419.239775 -58.739603) (xy 419.255269 -58.792102)
			(xy 419.2631 -58.846276) (xy 419.263576 -58.873644) (xy 419.26309 -58.900895) (xy 419.255334 -58.954843)
			(xy 419.239979 -59.007138) (xy 419.217337 -59.056715) (xy 419.187871 -59.102565) (xy 419.15218 -59.143756)
			(xy 419.110989 -59.179447) (xy 419.065139 -59.208913) (xy 419.015562 -59.231555) (xy 418.963267 -59.24691)
			(xy 418.909319 -59.254666) (xy 418.854817 -59.254666) (xy 418.800869 -59.24691) (xy 418.748574 -59.231555)
			(xy 418.698997 -59.208913) (xy 418.653147 -59.179447) (xy 418.611956 -59.143756) (xy 418.576265 -59.102565)
			(xy 418.546799 -59.056715) (xy 418.524157 -59.007138) (xy 418.508802 -58.954843) (xy 418.501046 -58.900895)
			(xy 418.50056 -58.873644) (xy 417.230811 -58.873644) (xy 417.215853 -58.924588) (xy 417.193211 -58.974165)
			(xy 417.163745 -59.020015) (xy 417.128054 -59.061206) (xy 417.086863 -59.096897) (xy 417.041013 -59.126363)
			(xy 416.991436 -59.149005) (xy 416.939141 -59.16436) (xy 416.885193 -59.172116) (xy 416.830691 -59.172116)
			(xy 416.776743 -59.16436) (xy 416.724448 -59.149005) (xy 416.674871 -59.126363) (xy 416.629021 -59.096897)
			(xy 416.58783 -59.061206) (xy 416.552139 -59.020015) (xy 416.522673 -58.974165) (xy 416.500031 -58.924588)
			(xy 416.484676 -58.872293) (xy 416.47692 -58.818345) (xy 416.476434 -58.791094) (xy 414.578476 -58.791094)
			(xy 414.575384 -58.812603) (xy 414.560029 -58.864898) (xy 414.537387 -58.914475) (xy 414.507921 -58.960325)
			(xy 414.47223 -59.001516) (xy 414.431039 -59.037207) (xy 414.385189 -59.066673) (xy 414.335612 -59.089315)
			(xy 414.283317 -59.10467) (xy 414.229369 -59.112426) (xy 414.174867 -59.112426) (xy 414.120919 -59.10467)
			(xy 414.068624 -59.089315) (xy 414.019047 -59.066673) (xy 413.973197 -59.037207) (xy 413.932006 -59.001516)
			(xy 413.896315 -58.960325) (xy 413.866849 -58.914475) (xy 413.844207 -58.864898) (xy 413.828852 -58.812603)
			(xy 413.821096 -58.758655) (xy 413.82061 -58.731404) (xy 411.991048 -58.731404) (xy 411.991048 -60.126455)
			(xy 417.480149 -60.126455) (xy 417.480149 -60.071945) (xy 417.487908 -60.017989) (xy 417.503266 -59.965687)
			(xy 417.525912 -59.916104) (xy 417.555384 -59.870248) (xy 417.591083 -59.829053) (xy 417.632281 -59.793359)
			(xy 417.678141 -59.763892) (xy 417.727727 -59.741251) (xy 417.78003 -59.725899) (xy 417.833987 -59.718146)
			(xy 417.861242 -59.717686) (xy 417.888611 -59.718189) (xy 417.942788 -59.725999) (xy 417.995291 -59.741479)
			(xy 418.045038 -59.764313) (xy 418.091007 -59.794029) (xy 418.11194 -59.811666) (xy 418.119052 -59.817762)
			(xy 418.13607 -59.824112) (xy 418.221414 -59.824112) (xy 418.238432 -59.817762) (xy 418.245544 -59.811666)
			(xy 418.266477 -59.794025) (xy 418.312445 -59.764301) (xy 418.362191 -59.741455) (xy 418.414693 -59.725959)
			(xy 418.468871 -59.71813) (xy 418.523613 -59.71813) (xy 418.577791 -59.725959) (xy 418.630293 -59.741455)
			(xy 418.680039 -59.764301) (xy 418.726007 -59.794025) (xy 418.74694 -59.811666) (xy 418.754052 -59.817762)
			(xy 418.77107 -59.824112) (xy 418.856414 -59.824112) (xy 418.873432 -59.817762) (xy 418.880544 -59.811666)
			(xy 418.901482 -59.794034) (xy 418.947454 -59.764323) (xy 418.9972 -59.741486) (xy 419.049699 -59.725993)
			(xy 419.103873 -59.718162) (xy 419.131242 -59.717686) (xy 419.158491 -59.718187) (xy 419.212433 -59.725948)
			(xy 419.264722 -59.741306) (xy 419.314293 -59.76395) (xy 419.360138 -59.793417) (xy 419.401322 -59.829108)
			(xy 419.437009 -59.870296) (xy 419.466471 -59.916144) (xy 419.489108 -59.965717) (xy 419.504461 -60.018008)
			(xy 419.512216 -60.071951) (xy 419.512216 -60.126449) (xy 419.504461 -60.180392) (xy 419.489108 -60.232683)
			(xy 419.466471 -60.282256) (xy 419.437009 -60.328104) (xy 419.401322 -60.369292) (xy 419.360138 -60.404983)
			(xy 419.314293 -60.43445) (xy 419.264722 -60.457094) (xy 419.212433 -60.472452) (xy 419.158491 -60.480213)
			(xy 419.131242 -60.480702) (xy 419.103873 -60.480211) (xy 419.049695 -60.472399) (xy 418.997192 -60.456916)
			(xy 418.947445 -60.43408) (xy 418.901477 -60.404361) (xy 418.880544 -60.386722) (xy 418.873432 -60.380626)
			(xy 418.856414 -60.374276) (xy 418.77107 -60.374276) (xy 418.754052 -60.380626) (xy 418.74694 -60.386722)
			(xy 418.726007 -60.404363) (xy 418.680039 -60.434087) (xy 418.630293 -60.456933) (xy 418.577791 -60.472429)
			(xy 418.523613 -60.480258) (xy 418.468871 -60.480258) (xy 418.414693 -60.472429) (xy 418.362191 -60.456933)
			(xy 418.312445 -60.434087) (xy 418.266477 -60.404363) (xy 418.245544 -60.386722) (xy 418.238432 -60.380626)
			(xy 418.221414 -60.374276) (xy 418.13607 -60.374276) (xy 418.119052 -60.380626) (xy 418.11194 -60.386722)
			(xy 418.091006 -60.404359) (xy 418.045034 -60.434071) (xy 417.995287 -60.456907) (xy 417.942786 -60.472398)
			(xy 417.888611 -60.480227) (xy 417.861242 -60.480702) (xy 417.833987 -60.480254) (xy 417.78003 -60.472501)
			(xy 417.727727 -60.457149) (xy 417.678141 -60.434508) (xy 417.632281 -60.405041) (xy 417.591083 -60.369347)
			(xy 417.555384 -60.328152) (xy 417.525912 -60.282296) (xy 417.503266 -60.232713) (xy 417.487908 -60.180411)
			(xy 417.480149 -60.126455) (xy 411.991048 -60.126455) (xy 411.991048 -60.999878) (xy 411.990513 -61.009866)
			(xy 411.982799 -61.028299) (xy 411.976062 -61.035692) (xy 411.900624 -61.11113) (xy 411.900116 -61.111892)
			(xy 411.896814 -61.115194) (xy 411.89656 -61.115448) (xy 411.269942 -61.742066) (xy 411.263338 -61.748416)
			(xy 411.26283 -61.748924) (xy 411.200346 -61.811408) (xy 411.192992 -61.818063) (xy 411.174691 -61.825659)
			(xy 411.164786 -61.82614) (xy 411.109922 -61.82614) (xy 411.105604 -61.826902) (xy 411.092936 -61.828912)
			(xy 411.067376 -61.831074) (xy 411.05455 -61.83122) (xy 409.37942 -61.83122) (xy 409.367799 -61.831793)
			(xy 409.346906 -61.841982) (xy 409.339288 -61.850778) (xy 409.282646 -61.923422) (xy 409.27782 -61.946028)
			(xy 409.280868 -61.957712) (xy 409.286334 -61.980757) (xy 409.292188 -62.027757) (xy 409.292552 -62.051438)
			(xy 409.292064 -62.078689) (xy 409.284303 -62.132635) (xy 409.268945 -62.184927) (xy 409.246302 -62.234503)
			(xy 409.216836 -62.280351) (xy 409.181145 -62.321541) (xy 409.139956 -62.357232) (xy 409.094108 -62.386699)
			(xy 409.044533 -62.409343) (xy 408.99224 -62.424702) (xy 408.938295 -62.432463) (xy 408.911044 -62.432946)
			(xy 408.88749 -62.432563) (xy 408.840747 -62.426701) (xy 408.817826 -62.421262) (xy 408.803602 -62.417706)
			(xy 408.776424 -62.426342) (xy 408.698192 -62.517274) (xy 408.69362 -62.545468) (xy 408.699208 -62.55893)
			(xy 408.708533 -62.582314) (xy 408.721652 -62.630918) (xy 408.72827 -62.680824) (xy 408.728672 -62.705996)
			(xy 408.728209 -62.733248) (xy 408.720452 -62.787198) (xy 408.705096 -62.839494) (xy 408.682453 -62.889072)
			(xy 408.652985 -62.934923) (xy 408.617291 -62.976113) (xy 408.576098 -63.011804) (xy 408.530244 -63.041269)
			(xy 408.480664 -63.063907) (xy 408.428366 -63.079259) (xy 408.374416 -63.087011) (xy 408.347164 -63.087504)
			(xy 408.318353 -63.086981) (xy 408.261385 -63.078321) (xy 408.206369 -63.061187) (xy 408.154557 -63.03597)
			(xy 408.10713 -63.003244) (xy 408.085798 -62.983872) (xy 408.077162 -62.975744) (xy 408.055318 -62.968886)
			(xy 407.965402 -62.981332) (xy 407.96337 -62.981586) (xy 407.952628 -62.984087) (xy 407.934575 -62.996719)
			(xy 407.928572 -63.00597) (xy 407.913755 -63.030092) (xy 407.878118 -63.074075) (xy 407.83637 -63.112308)
			(xy 407.789431 -63.14395) (xy 407.73833 -63.168306) (xy 407.68419 -63.184842) (xy 407.628201 -63.193194)
			(xy 407.599896 -63.193676) (xy 407.572647 -63.19319) (xy 407.518705 -63.185433) (xy 407.466415 -63.170079)
			(xy 407.416842 -63.14744) (xy 407.370996 -63.117976) (xy 407.32981 -63.082287) (xy 407.294122 -63.041101)
			(xy 407.264658 -62.995254) (xy 407.24202 -62.945682) (xy 407.226666 -62.893392) (xy 407.21891 -62.839449)
			(xy 407.21891 -62.784951) (xy 407.226666 -62.731008) (xy 407.24202 -62.678718) (xy 407.264658 -62.629146)
			(xy 407.294122 -62.583299) (xy 407.32981 -62.542113) (xy 407.370996 -62.506424) (xy 407.416842 -62.47696)
			(xy 407.466415 -62.454321) (xy 407.518705 -62.438967) (xy 407.572647 -62.43121) (xy 407.599896 -62.43066)
			(xy 407.628706 -62.431187) (xy 407.68567 -62.439855) (xy 407.740681 -62.456994) (xy 407.792488 -62.482215)
			(xy 407.839911 -62.514942) (xy 407.861262 -62.534292) (xy 407.869898 -62.54242) (xy 407.891742 -62.549278)
			(xy 407.981658 -62.536832) (xy 407.983436 -62.536578) (xy 407.994574 -62.533939) (xy 408.013143 -62.520608)
			(xy 408.01925 -62.510924) (xy 408.020012 -62.5094) (xy 408.034913 -62.485596) (xy 408.070601 -62.442236)
			(xy 408.11226 -62.404575) (xy 408.158988 -62.373426) (xy 408.209777 -62.349462) (xy 408.263529 -62.333202)
			(xy 408.319085 -62.324995) (xy 408.347164 -62.324488) (xy 408.36723 -62.324996) (xy 408.367484 -62.324996)
			(xy 408.383232 -62.326012) (xy 408.391868 -62.327028) (xy 408.412696 -62.330076) (xy 408.41295 -62.330076)
			(xy 408.440382 -62.336172) (xy 408.454606 -62.339728) (xy 408.481784 -62.331092) (xy 408.560016 -62.24016)
			(xy 408.564334 -62.21222) (xy 408.558746 -62.198504) (xy 408.548926 -62.173891) (xy 408.535418 -62.122651)
			(xy 408.531822 -62.096396) (xy 408.530552 -62.082426) (xy 408.529282 -62.051438) (xy 408.529282 -62.05093)
			(xy 408.529652 -62.027312) (xy 408.535513 -61.980441) (xy 408.540966 -61.957458) (xy 408.544014 -61.945774)
			(xy 408.539188 -61.923168) (xy 408.4828 -61.850778) (xy 408.475207 -61.841955) (xy 408.454297 -61.831785)
			(xy 408.442668 -61.83122) (xy 407.46426 -61.83122) (xy 407.451561 -61.831072) (xy 407.426255 -61.828908)
			(xy 407.413714 -61.826902) (xy 407.409396 -61.82614) (xy 407.168858 -61.82614) (xy 407.157174 -61.829188)
			(xy 407.152348 -61.831474) (xy 407.15184 -61.831728) (xy 407.125905 -61.84359) (xy 407.071396 -61.860349)
			(xy 407.015 -61.868813) (xy 406.986486 -61.86932) (xy 406.978612 -61.86932) (xy 406.951235 -61.86828)
			(xy 406.897188 -61.859325) (xy 406.844977 -61.84273) (xy 406.820116 -61.83122) (xy 406.815036 -61.82868)
			(xy 406.80386 -61.82614) (xy 406.553924 -61.82614) (xy 406.549606 -61.826902) (xy 406.537064 -61.828894)
			(xy 406.511758 -61.831053) (xy 406.49906 -61.83122) (xy 405.363934 -61.83122) (xy 405.351287 -61.831887)
			(xy 405.329015 -61.843876) (xy 405.321516 -61.85408) (xy 405.278082 -61.920374) (xy 405.273692 -61.927592)
			(xy 405.269508 -61.943951) (xy 405.27091 -61.960777) (xy 405.274018 -61.968634) (xy 405.28407 -61.992769)
			(xy 405.298218 -62.0431) (xy 405.305357 -62.094893) (xy 405.305768 -62.121034) (xy 405.305768 -62.12586)
			(xy 405.304956 -62.152886) (xy 405.296646 -62.206313) (xy 405.280877 -62.258031) (xy 405.257965 -62.307004)
			(xy 405.228368 -62.352253) (xy 405.192679 -62.39287) (xy 405.151614 -62.428042) (xy 405.105995 -62.457064)
			(xy 405.056735 -62.479355) (xy 405.004821 -62.494469) (xy 404.951294 -62.502102) (xy 404.897226 -62.502102)
			(xy 404.843699 -62.494469) (xy 404.791785 -62.479355) (xy 404.742525 -62.457064) (xy 404.696906 -62.428042)
			(xy 404.655841 -62.39287) (xy 404.620152 -62.352253) (xy 404.590555 -62.307004) (xy 404.567643 -62.258031)
			(xy 404.551874 -62.206313) (xy 404.543564 -62.152886) (xy 404.542752 -62.12586) (xy 404.542752 -62.12078)
			(xy 404.5432 -62.094683) (xy 404.550354 -62.042981) (xy 404.564485 -61.992736) (xy 404.574502 -61.968634)
			(xy 404.579328 -61.957712) (xy 404.578312 -61.934852) (xy 404.572978 -61.924438) (xy 404.570438 -61.920374)
			(xy 404.527258 -61.854334) (xy 404.520146 -61.843412) (xy 404.497794 -61.83122) (xy 401.962366 -61.83122)
			(xy 401.952299 -61.83165) (xy 401.933705 -61.839375) (xy 401.926298 -61.846206) (xy 401.522692 -62.249812)
			(xy 401.515326 -62.256924) (xy 401.507706 -62.27572) (xy 401.507706 -63.273432) (xy 403.876762 -63.273432)
			(xy 403.880833 -63.21781) (xy 403.892959 -63.163373) (xy 403.912882 -63.111282) (xy 403.940178 -63.062647)
			(xy 403.974264 -63.018504) (xy 404.014413 -62.979795) (xy 404.059771 -62.947344) (xy 404.109371 -62.921843)
			(xy 404.162155 -62.903836) (xy 404.216998 -62.893706) (xy 404.272732 -62.891669) (xy 404.328169 -62.897769)
			(xy 404.382126 -62.911875) (xy 404.433455 -62.933687) (xy 404.481061 -62.962741) (xy 404.523929 -62.998416)
			(xy 404.561146 -63.039953) (xy 404.591919 -63.086466) (xy 404.615591 -63.136963) (xy 404.631659 -63.19037)
			(xy 404.639779 -63.245546) (xy 404.639779 -63.245548) (xy 417.404592 -63.245548) (xy 417.404592 -63.191052)
			(xy 417.412347 -63.137111) (xy 417.427699 -63.084822) (xy 417.450336 -63.03525) (xy 417.479796 -62.989404)
			(xy 417.515481 -62.948216) (xy 417.556664 -62.912526) (xy 417.602506 -62.88306) (xy 417.652075 -62.860417)
			(xy 417.704362 -62.845058) (xy 417.758302 -62.837296) (xy 417.78555 -62.836806) (xy 417.812919 -62.8373)
			(xy 417.867097 -62.845111) (xy 417.9196 -62.860593) (xy 417.969347 -62.883429) (xy 418.015315 -62.913148)
			(xy 418.036248 -62.930786) (xy 418.04336 -62.936882) (xy 418.060378 -62.943232) (xy 418.145722 -62.943232)
			(xy 418.16274 -62.936882) (xy 418.169852 -62.930786) (xy 418.190785 -62.913145) (xy 418.236753 -62.883421)
			(xy 418.286499 -62.860575) (xy 418.339001 -62.845079) (xy 418.393179 -62.83725) (xy 418.447921 -62.83725)
			(xy 418.502099 -62.845079) (xy 418.554601 -62.860575) (xy 418.604347 -62.883421) (xy 418.650315 -62.913145)
			(xy 418.671248 -62.930786) (xy 418.67836 -62.936882) (xy 418.695378 -62.943232) (xy 418.780722 -62.943232)
			(xy 418.79774 -62.936882) (xy 418.804852 -62.930786) (xy 418.82579 -62.913154) (xy 418.871761 -62.883441)
			(xy 418.921507 -62.860604) (xy 418.974007 -62.845112) (xy 419.028181 -62.837281) (xy 419.05555 -62.836806)
			(xy 419.082806 -62.837237) (xy 419.136765 -62.844989) (xy 419.18907 -62.860341) (xy 419.238659 -62.882982)
			(xy 419.28452 -62.912449) (xy 419.32572 -62.948145) (xy 419.36142 -62.98934) (xy 419.390894 -63.035197)
			(xy 419.413541 -63.084783) (xy 419.4289 -63.137086) (xy 419.436659 -63.191044) (xy 419.436659 -63.245556)
			(xy 419.4289 -63.299514) (xy 419.413541 -63.351817) (xy 419.390894 -63.401403) (xy 419.361421 -63.44726)
			(xy 419.32572 -63.488455) (xy 419.28452 -63.524151) (xy 419.238659 -63.553618) (xy 419.18907 -63.576259)
			(xy 419.136765 -63.591611) (xy 419.082806 -63.599363) (xy 419.05555 -63.599822) (xy 419.02818 -63.599346)
			(xy 418.974001 -63.591533) (xy 418.921497 -63.576048) (xy 418.87175 -63.553208) (xy 418.825783 -63.523483)
			(xy 418.804852 -63.505842) (xy 418.79774 -63.499746) (xy 418.780722 -63.493396) (xy 418.695378 -63.493396)
			(xy 418.67836 -63.499746) (xy 418.671248 -63.505842) (xy 418.650315 -63.523483) (xy 418.604347 -63.553207)
			(xy 418.554601 -63.576053) (xy 418.502099 -63.591549) (xy 418.447921 -63.599378) (xy 418.393179 -63.599378)
			(xy 418.339001 -63.591549) (xy 418.286499 -63.576053) (xy 418.236753 -63.553207) (xy 418.190785 -63.523483)
			(xy 418.169852 -63.505842) (xy 418.16274 -63.499746) (xy 418.145722 -63.493396) (xy 418.060378 -63.493396)
			(xy 418.04336 -63.499746) (xy 418.036248 -63.505842) (xy 418.015314 -63.523479) (xy 417.969341 -63.55319)
			(xy 417.919594 -63.576026) (xy 417.867094 -63.591517) (xy 417.812919 -63.599347) (xy 417.78555 -63.599822)
			(xy 417.758302 -63.599304) (xy 417.704362 -63.591542) (xy 417.652075 -63.576183) (xy 417.602506 -63.55354)
			(xy 417.556664 -63.524074) (xy 417.515481 -63.488384) (xy 417.479796 -63.447196) (xy 417.450336 -63.40135)
			(xy 417.427699 -63.351778) (xy 417.412347 -63.299489) (xy 417.404592 -63.245548) (xy 404.639779 -63.245548)
			(xy 404.640288 -63.273432) (xy 404.639779 -63.301318) (xy 404.631659 -63.356494) (xy 404.615591 -63.409901)
			(xy 404.591919 -63.460398) (xy 404.561146 -63.506911) (xy 404.523929 -63.548448) (xy 404.481061 -63.584123)
			(xy 404.433455 -63.613177) (xy 404.382126 -63.634989) (xy 404.328169 -63.649095) (xy 404.272732 -63.655195)
			(xy 404.216998 -63.653158) (xy 404.162155 -63.643028) (xy 404.109371 -63.625021) (xy 404.059771 -63.59952)
			(xy 404.014413 -63.567069) (xy 403.974264 -63.52836) (xy 403.940178 -63.484217) (xy 403.912882 -63.435582)
			(xy 403.892959 -63.383491) (xy 403.880833 -63.329054) (xy 403.876762 -63.273432) (xy 401.507706 -63.273432)
			(xy 401.507706 -64.102234) (xy 401.687536 -64.102234) (xy 401.691607 -64.046612) (xy 401.703733 -63.992175)
			(xy 401.723656 -63.940084) (xy 401.750952 -63.891449) (xy 401.785038 -63.847306) (xy 401.825187 -63.808597)
			(xy 401.870545 -63.776146) (xy 401.920145 -63.750645) (xy 401.972929 -63.732638) (xy 402.027772 -63.722508)
			(xy 402.083506 -63.720471) (xy 402.138943 -63.726571) (xy 402.1929 -63.740677) (xy 402.244229 -63.762489)
			(xy 402.291835 -63.791543) (xy 402.334703 -63.827218) (xy 402.37192 -63.868755) (xy 402.402693 -63.915268)
			(xy 402.426365 -63.965765) (xy 402.442433 -64.019172) (xy 402.450553 -64.074348) (xy 402.451062 -64.102234)
			(xy 402.450553 -64.13012) (xy 402.442433 -64.185296) (xy 402.426365 -64.238703) (xy 402.402693 -64.2892)
			(xy 402.387415 -64.312292) (xy 405.365964 -64.312292) (xy 405.370035 -64.25667) (xy 405.382161 -64.202233)
			(xy 405.402084 -64.150142) (xy 405.42938 -64.101507) (xy 405.463466 -64.057364) (xy 405.503615 -64.018655)
			(xy 405.548973 -63.986204) (xy 405.598573 -63.960703) (xy 405.651357 -63.942696) (xy 405.7062 -63.932566)
			(xy 405.761934 -63.930529) (xy 405.817371 -63.936629) (xy 405.871328 -63.950735) (xy 405.922657 -63.972547)
			(xy 405.970263 -64.001601) (xy 406.013131 -64.037276) (xy 406.050348 -64.078813) (xy 406.081121 -64.125326)
			(xy 406.104793 -64.175823) (xy 406.120861 -64.22923) (xy 406.128981 -64.284406) (xy 406.12949 -64.312292)
			(xy 407.20594 -64.312292) (xy 407.210011 -64.25667) (xy 407.222137 -64.202233) (xy 407.24206 -64.150142)
			(xy 407.269356 -64.101507) (xy 407.303442 -64.057364) (xy 407.343591 -64.018655) (xy 407.388949 -63.986204)
			(xy 407.438549 -63.960703) (xy 407.491333 -63.942696) (xy 407.546176 -63.932566) (xy 407.60191 -63.930529)
			(xy 407.657347 -63.936629) (xy 407.711304 -63.950735) (xy 407.762633 -63.972547) (xy 407.810239 -64.001601)
			(xy 407.853107 -64.037276) (xy 407.890324 -64.078813) (xy 407.921097 -64.125326) (xy 407.944769 -64.175823)
			(xy 407.960837 -64.22923) (xy 407.968957 -64.284406) (xy 407.969466 -64.312292) (xy 407.968957 -64.340178)
			(xy 407.960837 -64.395354) (xy 407.944769 -64.448761) (xy 407.921097 -64.499258) (xy 407.890324 -64.545771)
			(xy 407.853107 -64.587308) (xy 407.810239 -64.622983) (xy 407.762633 -64.652037) (xy 407.711304 -64.673849)
			(xy 407.657347 -64.687955) (xy 407.60191 -64.694055) (xy 407.546176 -64.692018) (xy 407.491333 -64.681888)
			(xy 407.438549 -64.663881) (xy 407.388949 -64.63838) (xy 407.343591 -64.605929) (xy 407.303442 -64.56722)
			(xy 407.269356 -64.523077) (xy 407.24206 -64.474442) (xy 407.222137 -64.422351) (xy 407.210011 -64.367914)
			(xy 407.20594 -64.312292) (xy 406.12949 -64.312292) (xy 406.128981 -64.340178) (xy 406.120861 -64.395354)
			(xy 406.104793 -64.448761) (xy 406.081121 -64.499258) (xy 406.050348 -64.545771) (xy 406.013131 -64.587308)
			(xy 405.970263 -64.622983) (xy 405.922657 -64.652037) (xy 405.871328 -64.673849) (xy 405.817371 -64.687955)
			(xy 405.761934 -64.694055) (xy 405.7062 -64.692018) (xy 405.651357 -64.681888) (xy 405.598573 -64.663881)
			(xy 405.548973 -64.63838) (xy 405.503615 -64.605929) (xy 405.463466 -64.56722) (xy 405.42938 -64.523077)
			(xy 405.402084 -64.474442) (xy 405.382161 -64.422351) (xy 405.370035 -64.367914) (xy 405.365964 -64.312292)
			(xy 402.387415 -64.312292) (xy 402.37192 -64.335713) (xy 402.334703 -64.37725) (xy 402.291835 -64.412925)
			(xy 402.244229 -64.441979) (xy 402.1929 -64.463791) (xy 402.138943 -64.477897) (xy 402.083506 -64.483997)
			(xy 402.027772 -64.48196) (xy 401.972929 -64.47183) (xy 401.920145 -64.453823) (xy 401.870545 -64.428322)
			(xy 401.825187 -64.395871) (xy 401.785038 -64.357162) (xy 401.750952 -64.313019) (xy 401.723656 -64.264384)
			(xy 401.703733 -64.212293) (xy 401.691607 -64.157856) (xy 401.687536 -64.102234) (xy 401.507706 -64.102234)
			(xy 401.507706 -65.15989) (xy 419.416482 -65.15989) (xy 419.420553 -65.104268) (xy 419.432679 -65.049831)
			(xy 419.452602 -64.99774) (xy 419.479898 -64.949105) (xy 419.513984 -64.904962) (xy 419.554133 -64.866253)
			(xy 419.599491 -64.833802) (xy 419.649091 -64.808301) (xy 419.701875 -64.790294) (xy 419.756718 -64.780164)
			(xy 419.812452 -64.778127) (xy 419.867889 -64.784227) (xy 419.921846 -64.798333) (xy 419.973175 -64.820145)
			(xy 420.020781 -64.849199) (xy 420.063649 -64.884874) (xy 420.100866 -64.926411) (xy 420.131639 -64.972924)
			(xy 420.155311 -65.023421) (xy 420.171379 -65.076828) (xy 420.179499 -65.132004) (xy 420.180008 -65.15989)
			(xy 420.179499 -65.187776) (xy 420.171379 -65.242952) (xy 420.155311 -65.296359) (xy 420.131639 -65.346856)
			(xy 420.100866 -65.393369) (xy 420.063649 -65.434906) (xy 420.020781 -65.470581) (xy 419.973175 -65.499635)
			(xy 419.921846 -65.521447) (xy 419.867889 -65.535553) (xy 419.812452 -65.541653) (xy 419.756718 -65.539616)
			(xy 419.701875 -65.529486) (xy 419.649091 -65.511479) (xy 419.599491 -65.485978) (xy 419.554133 -65.453527)
			(xy 419.513984 -65.414818) (xy 419.479898 -65.370675) (xy 419.452602 -65.32204) (xy 419.432679 -65.269949)
			(xy 419.420553 -65.215512) (xy 419.416482 -65.15989) (xy 401.507706 -65.15989) (xy 401.507706 -65.75552)
			(xy 414.646616 -65.75552) (xy 414.650687 -65.699898) (xy 414.662813 -65.645461) (xy 414.682736 -65.59337)
			(xy 414.710032 -65.544735) (xy 414.744118 -65.500592) (xy 414.784267 -65.461883) (xy 414.829625 -65.429432)
			(xy 414.879225 -65.403931) (xy 414.932009 -65.385924) (xy 414.986852 -65.375794) (xy 415.042586 -65.373757)
			(xy 415.098023 -65.379857) (xy 415.15198 -65.393963) (xy 415.203309 -65.415775) (xy 415.250915 -65.444829)
			(xy 415.293783 -65.480504) (xy 415.331 -65.522041) (xy 415.361773 -65.568554) (xy 415.385445 -65.619051)
			(xy 415.401513 -65.672458) (xy 415.409633 -65.727634) (xy 415.410142 -65.75552) (xy 415.409633 -65.783406)
			(xy 415.401513 -65.838582) (xy 415.385445 -65.891989) (xy 415.361773 -65.942486) (xy 415.331 -65.988999)
			(xy 415.293783 -66.030536) (xy 415.250915 -66.066211) (xy 415.203309 -66.095265) (xy 415.15198 -66.117077)
			(xy 415.098023 -66.131183) (xy 415.042586 -66.137283) (xy 414.986852 -66.135246) (xy 414.932009 -66.125116)
			(xy 414.879225 -66.107109) (xy 414.829625 -66.081608) (xy 414.784267 -66.049157) (xy 414.744118 -66.010448)
			(xy 414.710032 -65.966305) (xy 414.682736 -65.91767) (xy 414.662813 -65.865579) (xy 414.650687 -65.811142)
			(xy 414.646616 -65.75552) (xy 401.507706 -65.75552) (xy 401.507706 -67.488054) (xy 419.07917 -67.488054)
			(xy 419.083241 -67.432432) (xy 419.095367 -67.377995) (xy 419.11529 -67.325904) (xy 419.142586 -67.277269)
			(xy 419.176672 -67.233126) (xy 419.216821 -67.194417) (xy 419.262179 -67.161966) (xy 419.311779 -67.136465)
			(xy 419.364563 -67.118458) (xy 419.419406 -67.108328) (xy 419.47514 -67.106291) (xy 419.530577 -67.112391)
			(xy 419.584534 -67.126497) (xy 419.635863 -67.148309) (xy 419.683469 -67.177363) (xy 419.726337 -67.213038)
			(xy 419.763554 -67.254575) (xy 419.794327 -67.301088) (xy 419.817999 -67.351585) (xy 419.834067 -67.404992)
			(xy 419.842187 -67.460168) (xy 419.842696 -67.488054) (xy 419.842187 -67.51594) (xy 419.834067 -67.571116)
			(xy 419.817999 -67.624523) (xy 419.794327 -67.67502) (xy 419.763554 -67.721533) (xy 419.726337 -67.76307)
			(xy 419.683469 -67.798745) (xy 419.635863 -67.827799) (xy 419.584534 -67.849611) (xy 419.530577 -67.863717)
			(xy 419.47514 -67.869817) (xy 419.419406 -67.86778) (xy 419.364563 -67.85765) (xy 419.311779 -67.839643)
			(xy 419.262179 -67.814142) (xy 419.216821 -67.781691) (xy 419.176672 -67.742982) (xy 419.142586 -67.698839)
			(xy 419.11529 -67.650204) (xy 419.095367 -67.598113) (xy 419.083241 -67.543676) (xy 419.07917 -67.488054)
			(xy 401.507706 -67.488054) (xy 401.507706 -69.9516) (xy 401.508163 -69.961478) (xy 401.515602 -69.979781)
			(xy 401.522184 -69.98716) (xy 401.522438 -69.987414) (xy 401.698714 -70.16369) (xy 401.699222 -70.164198)
			(xy 401.706599 -70.170791) (xy 401.724899 -70.178261) (xy 401.734782 -70.178676)
		)
		(stroke
			(width 0)
			(type solid)
		)
		(fill yes)
		(layer "In9.Cu")
		(net "P12V_SSD14_R")
	)
	(gr_poly
		(pts
			(xy 446.778126 -70.178676) (xy 446.788194 -70.178248) (xy 446.806789 -70.170524) (xy 446.814194 -70.16369)
			(xy 447.14033 -69.837554) (xy 447.140838 -69.837046) (xy 447.147422 -69.829666) (xy 447.154874 -69.811366)
			(xy 447.155316 -69.801486) (xy 447.155316 -67.91579) (xy 447.154918 -67.906269) (xy 447.147959 -67.888546)
			(xy 447.135005 -67.874589) (xy 447.126614 -67.87007) (xy 447.030856 -67.823842) (xy 447.002154 -67.827144)
			(xy 446.99047 -67.836288) (xy 446.970159 -67.851903) (xy 446.926145 -67.878126) (xy 446.879017 -67.89822)
			(xy 446.829622 -67.911821) (xy 446.778851 -67.918686) (xy 446.753234 -67.919092) (xy 446.725981 -67.918631)
			(xy 446.672028 -67.910878) (xy 446.619729 -67.895526) (xy 446.570146 -67.872886) (xy 446.524291 -67.84342)
			(xy 446.483096 -67.807728) (xy 446.4474 -67.766536) (xy 446.41793 -67.720684) (xy 446.395286 -67.671103)
			(xy 446.379929 -67.618805) (xy 446.372171 -67.564853) (xy 446.372171 -67.510347) (xy 446.379929 -67.456395)
			(xy 446.395286 -67.404097) (xy 446.41793 -67.354516) (xy 446.4474 -67.308664) (xy 446.483096 -67.267472)
			(xy 446.524291 -67.23178) (xy 446.570146 -67.202314) (xy 446.619729 -67.179674) (xy 446.672028 -67.164322)
			(xy 446.725981 -67.156569) (xy 446.753234 -67.156076) (xy 446.778849 -67.156493) (xy 446.829618 -67.163359)
			(xy 446.87901 -67.176962) (xy 446.926136 -67.197058) (xy 446.970145 -67.223283) (xy 446.99047 -67.23888)
			(xy 447.002154 -67.248024) (xy 447.030856 -67.251326) (xy 447.126614 -67.205098) (xy 447.135021 -67.200602)
			(xy 447.147977 -67.186633) (xy 447.15495 -67.168903) (xy 447.155316 -67.159378) (xy 447.155316 -65.506854)
			(xy 447.1416 -65.483486) (xy 447.13017 -65.476628) (xy 447.129662 -65.476628) (xy 447.05651 -65.433702)
			(xy 447.047497 -65.428968) (xy 447.027324 -65.426368) (xy 447.017394 -65.428622) (xy 447.003678 -65.432432)
			(xy 446.99809 -65.43548) (xy 446.969804 -65.450253) (xy 446.909528 -65.471193) (xy 446.846607 -65.481811)
			(xy 446.814702 -65.48247) (xy 446.814448 -65.48247) (xy 446.787196 -65.48201) (xy 446.733245 -65.474259)
			(xy 446.680946 -65.458909) (xy 446.631365 -65.436272) (xy 446.585511 -65.406808) (xy 446.544316 -65.371118)
			(xy 446.508621 -65.329928) (xy 446.479152 -65.284077) (xy 446.456508 -65.234499) (xy 446.441151 -65.182202)
			(xy 446.433393 -65.128252) (xy 446.433393 -65.073748) (xy 446.441151 -65.019798) (xy 446.456508 -64.967501)
			(xy 446.479152 -64.917923) (xy 446.508621 -64.872072) (xy 446.544316 -64.830882) (xy 446.585511 -64.795192)
			(xy 446.631365 -64.765728) (xy 446.680946 -64.743091) (xy 446.733245 -64.727741) (xy 446.787196 -64.71999)
			(xy 446.814448 -64.719454) (xy 446.814702 -64.719454) (xy 446.846606 -64.720118) (xy 446.909522 -64.730752)
			(xy 446.969803 -64.751675) (xy 446.99809 -64.766444) (xy 447.003678 -64.769492) (xy 447.017394 -64.773302)
			(xy 447.02732 -64.775565) (xy 447.047495 -64.772953) (xy 447.05651 -64.768222) (xy 447.129916 -64.725296)
			(xy 447.130678 -64.724788) (xy 447.137952 -64.719971) (xy 447.148991 -64.706475) (xy 447.154892 -64.69007)
			(xy 447.155316 -64.681354) (xy 447.155316 -52.622958) (xy 447.153538 -52.616608) (xy 447.147478 -52.592357)
			(xy 447.140981 -52.542795) (xy 447.140584 -52.517802) (xy 447.140584 -52.51577) (xy 447.141049 -52.491159)
			(xy 447.147547 -52.442364) (xy 447.153538 -52.418488) (xy 447.155316 -52.411884) (xy 447.155316 -51.455828)
			(xy 447.155753 -51.445764) (xy 447.163487 -51.42718) (xy 447.170302 -51.41976) (xy 447.277236 -51.312826)
			(xy 447.284635 -51.305982) (xy 447.303234 -51.298257) (xy 447.313304 -51.29784) (xy 448.003676 -51.29784)
			(xy 448.012058 -51.297078) (xy 448.019665 -51.295568) (xy 448.033505 -51.288587) (xy 448.039236 -51.283362)
			(xy 448.104006 -51.218592) (xy 448.104514 -51.218084) (xy 448.111106 -51.210707) (xy 448.118576 -51.192407)
			(xy 448.118992 -51.182524) (xy 448.118992 -49.20615) (xy 448.118395 -49.193826) (xy 448.106939 -49.172003)
			(xy 448.097148 -49.164494) (xy 448.033648 -49.120044) (xy 448.027146 -49.115868) (xy 448.012413 -49.11123)
			(xy 448.004692 -49.1109) (xy 447.982594 -49.1109) (xy 447.97472 -49.113694) (xy 447.944536 -49.123451)
			(xy 447.881976 -49.133926) (xy 447.85026 -49.134522) (xy 447.846196 -49.134522) (xy 447.819134 -49.133764)
			(xy 447.765624 -49.125548) (xy 447.713813 -49.109848) (xy 447.664742 -49.08698) (xy 447.619398 -49.057404)
			(xy 447.578691 -49.021714) (xy 447.543439 -48.980626) (xy 447.514351 -48.934967) (xy 447.49201 -48.885654)
			(xy 447.476867 -48.833678) (xy 447.469224 -48.780083) (xy 447.468752 -48.753014) (xy 447.469237 -48.725761)
			(xy 447.476991 -48.67181) (xy 447.492345 -48.619511) (xy 447.514985 -48.569929) (xy 447.54445 -48.524074)
			(xy 447.580141 -48.482879) (xy 447.621331 -48.447182) (xy 447.667182 -48.417711) (xy 447.71676 -48.395064)
			(xy 447.769057 -48.379703) (xy 447.823007 -48.371941) (xy 447.85026 -48.371506) (xy 447.851022 -48.371506)
			(xy 447.884639 -48.372259) (xy 447.950815 -48.38414) (xy 447.982594 -48.395128) (xy 447.994278 -48.399446)
			(xy 448.018916 -48.396398) (xy 448.097148 -48.341534) (xy 448.106819 -48.333923) (xy 448.118228 -48.312161)
			(xy 448.118992 -48.299878) (xy 448.118992 -41.95445) (xy 448.118559 -41.944384) (xy 448.110831 -41.925794)
			(xy 448.104006 -41.918382) (xy 447.223642 -41.038018) (xy 447.21653 -41.030652) (xy 447.197734 -41.023032)
			(xy 445.416178 -41.023032) (xy 445.407477 -41.023385) (xy 445.391077 -41.029203) (xy 445.377561 -41.040163)
			(xy 445.372744 -41.047416) (xy 445.327786 -41.121584) (xy 445.323722 -41.13022) (xy 445.320397 -41.140527)
			(xy 445.321828 -41.162115) (xy 445.326516 -41.171876) (xy 445.327278 -41.1734) (xy 445.331596 -41.18229)
			(xy 445.343675 -41.20826) (xy 445.36079 -41.262918) (xy 445.369561 -41.319517) (xy 445.370204 -41.348152)
			(xy 445.370204 -41.34866) (xy 445.370204 -41.35501) (xy 445.369293 -41.383073) (xy 445.360247 -41.438486)
			(xy 445.343175 -41.491974) (xy 445.318446 -41.542382) (xy 445.286596 -41.588621) (xy 445.267842 -41.609518)
			(xy 445.267588 -41.609772) (xy 445.261107 -41.617123) (xy 445.253796 -41.635287) (xy 445.253364 -41.645078)
			(xy 445.253364 -41.724072) (xy 445.260222 -41.741852) (xy 445.26708 -41.748964) (xy 445.286349 -41.770291)
			(xy 445.318911 -41.817653) (xy 445.343999 -41.869364) (xy 445.361046 -41.924253) (xy 445.369665 -41.981078)
			(xy 445.369663 -42.038554) (xy 445.361038 -42.095378) (xy 445.343987 -42.150266) (xy 445.318894 -42.201975)
			(xy 445.286329 -42.249334) (xy 445.26708 -42.27068) (xy 445.260222 -42.277792) (xy 445.253364 -42.295572)
			(xy 445.253364 -42.384472) (xy 445.260222 -42.402252) (xy 445.26708 -42.409364) (xy 445.286349 -42.430691)
			(xy 445.318912 -42.478054) (xy 445.344 -42.529766) (xy 445.361047 -42.584657) (xy 445.369666 -42.641484)
			(xy 445.370204 -42.670222) (xy 445.369731 -42.697592) (xy 445.361904 -42.751768) (xy 445.346415 -42.80427)
			(xy 445.323581 -42.854019) (xy 445.293871 -42.899994) (xy 445.276224 -42.92092) (xy 445.270128 -42.928032)
			(xy 445.263778 -42.944796) (xy 445.263778 -43.030648) (xy 445.270128 -43.047412) (xy 445.276224 -43.054524)
			(xy 445.293864 -43.075456) (xy 445.323585 -43.121424) (xy 445.346424 -43.171171) (xy 445.361909 -43.223674)
			(xy 445.369724 -43.277852) (xy 445.370204 -43.305222) (xy 445.369718 -43.332473) (xy 445.361962 -43.386421)
			(xy 445.346607 -43.438716) (xy 445.323965 -43.488293) (xy 445.294499 -43.534143) (xy 445.258808 -43.575334)
			(xy 445.217617 -43.611025) (xy 445.171767 -43.640491) (xy 445.12219 -43.663133) (xy 445.069895 -43.678488)
			(xy 445.015947 -43.686244) (xy 444.961445 -43.686244) (xy 444.907497 -43.678488) (xy 444.855202 -43.663133)
			(xy 444.805625 -43.640491) (xy 444.759775 -43.611025) (xy 444.718584 -43.575334) (xy 444.682893 -43.534143)
			(xy 444.653427 -43.488293) (xy 444.630785 -43.438716) (xy 444.61543 -43.386421) (xy 444.607674 -43.332473)
			(xy 444.607188 -43.305222) (xy 444.607665 -43.277854) (xy 444.615499 -43.223681) (xy 444.630994 -43.171183)
			(xy 444.653833 -43.121439) (xy 444.683546 -43.07547) (xy 444.701168 -43.054524) (xy 444.707264 -43.047412)
			(xy 444.713614 -43.030648) (xy 444.713614 -42.944796) (xy 444.707264 -42.928032) (xy 444.701168 -42.92092)
			(xy 444.683526 -42.899988) (xy 444.6538 -42.854022) (xy 444.630956 -42.804275) (xy 444.615465 -42.751772)
			(xy 444.607644 -42.697593) (xy 444.607188 -42.670222) (xy 444.607707 -42.641482) (xy 444.616327 -42.584653)
			(xy 444.633374 -42.529759) (xy 444.658463 -42.478044) (xy 444.691027 -42.430678) (xy 444.710312 -42.409364)
			(xy 444.71717 -42.402252) (xy 444.724028 -42.384472) (xy 444.724028 -42.295572) (xy 444.71717 -42.277792)
			(xy 444.710312 -42.27068) (xy 444.69104 -42.249353) (xy 444.658473 -42.20199) (xy 444.633379 -42.150277)
			(xy 444.616326 -42.095385) (xy 444.607701 -42.038556) (xy 444.607699 -41.981076) (xy 444.616319 -41.924246)
			(xy 444.633367 -41.869353) (xy 444.658456 -41.817638) (xy 444.69102 -41.770272) (xy 444.710312 -41.748964)
			(xy 444.71717 -41.741852) (xy 444.724028 -41.724072) (xy 444.724028 -41.635172) (xy 444.71717 -41.617646)
			(xy 444.710312 -41.61028) (xy 444.691513 -41.589486) (xy 444.659585 -41.543412) (xy 444.634732 -41.493167)
			(xy 444.617486 -41.439831) (xy 444.608219 -41.384547) (xy 444.607188 -41.356534) (xy 444.607188 -41.349422)
			(xy 444.6077 -41.320529) (xy 444.616387 -41.263399) (xy 444.63361 -41.208239) (xy 444.645796 -41.182036)
			(xy 444.653162 -41.166542) (xy 444.656225 -41.157735) (xy 444.656491 -41.139107) (xy 444.65367 -41.13022)
			(xy 444.649606 -41.121584) (xy 444.604648 -41.04767) (xy 444.59779 -41.035986) (xy 444.574676 -41.023032)
			(xy 443.65418 -41.023032) (xy 443.642553 -41.023594) (xy 443.621642 -41.033769) (xy 443.614048 -41.04259)
			(xy 443.557406 -41.11498) (xy 443.55258 -41.137586) (xy 443.555374 -41.14927) (xy 443.560696 -41.171949)
			(xy 443.566426 -41.21818) (xy 443.566804 -41.241472) (xy 443.566343 -41.268726) (xy 443.558589 -41.32268)
			(xy 443.543235 -41.374981) (xy 443.520594 -41.424564) (xy 443.491127 -41.470421) (xy 443.455433 -41.511616)
			(xy 443.41424 -41.547313) (xy 443.368385 -41.576783) (xy 443.318803 -41.599427) (xy 443.266503 -41.614784)
			(xy 443.21255 -41.622541) (xy 443.185296 -41.62298) (xy 443.156557 -41.622459) (xy 443.09973 -41.613835)
			(xy 443.04484 -41.596784) (xy 442.993129 -41.571691) (xy 442.945768 -41.539124) (xy 442.924438 -41.519856)
			(xy 442.917326 -41.512998) (xy 442.899546 -41.50614) (xy 442.810646 -41.50614) (xy 442.792866 -41.512998)
			(xy 442.785754 -41.519856) (xy 442.764425 -41.539123) (xy 442.717061 -41.571681) (xy 442.665349 -41.596767)
			(xy 442.610459 -41.613812) (xy 442.553634 -41.622432) (xy 442.524896 -41.62298) (xy 442.497644 -41.622516)
			(xy 442.443695 -41.614759) (xy 442.391399 -41.599402) (xy 442.341821 -41.576759) (xy 442.295971 -41.54729)
			(xy 442.254781 -41.511596) (xy 442.21909 -41.470404) (xy 442.189626 -41.42455) (xy 442.166987 -41.374971)
			(xy 442.151634 -41.322674) (xy 442.143881 -41.268724) (xy 442.143388 -41.241472) (xy 442.143767 -41.21818)
			(xy 442.149498 -41.171949) (xy 442.154818 -41.14927) (xy 442.157612 -41.137586) (xy 442.152786 -41.11498)
			(xy 442.096144 -41.04259) (xy 442.088555 -41.033758) (xy 442.067645 -41.023568) (xy 442.056012 -41.023032)
			(xy 438.20842 -41.023032) (xy 438.198357 -41.02347) (xy 438.179777 -41.031209) (xy 438.172352 -41.038018)
			(xy 438.005728 -41.204642) (xy 437.998989 -41.212014) (xy 437.991408 -41.230476) (xy 437.990996 -41.240456)
			(xy 437.990996 -43.73626) (xy 446.512948 -43.73626) (xy 446.517019 -43.680638) (xy 446.529145 -43.626201)
			(xy 446.549068 -43.57411) (xy 446.576364 -43.525475) (xy 446.61045 -43.481332) (xy 446.650599 -43.442623)
			(xy 446.695957 -43.410172) (xy 446.745557 -43.384671) (xy 446.798341 -43.366664) (xy 446.853184 -43.356534)
			(xy 446.908918 -43.354497) (xy 446.964355 -43.360597) (xy 447.018312 -43.374703) (xy 447.069641 -43.396515)
			(xy 447.117247 -43.425569) (xy 447.160115 -43.461244) (xy 447.197332 -43.502781) (xy 447.228105 -43.549294)
			(xy 447.251777 -43.599791) (xy 447.267845 -43.653198) (xy 447.275965 -43.708374) (xy 447.276474 -43.73626)
			(xy 447.275965 -43.764146) (xy 447.267845 -43.819322) (xy 447.251777 -43.872729) (xy 447.228105 -43.923226)
			(xy 447.197332 -43.969739) (xy 447.160115 -44.011276) (xy 447.117247 -44.046951) (xy 447.069641 -44.076005)
			(xy 447.018312 -44.097817) (xy 446.964355 -44.111923) (xy 446.908918 -44.118023) (xy 446.853184 -44.115986)
			(xy 446.798341 -44.105856) (xy 446.745557 -44.087849) (xy 446.695957 -44.062348) (xy 446.650599 -44.029897)
			(xy 446.61045 -43.991188) (xy 446.576364 -43.947045) (xy 446.549068 -43.89841) (xy 446.529145 -43.846319)
			(xy 446.517019 -43.791882) (xy 446.512948 -43.73626) (xy 437.990996 -43.73626) (xy 437.990996 -45.114464)
			(xy 446.365374 -45.114464) (xy 446.369445 -45.058842) (xy 446.381571 -45.004405) (xy 446.401494 -44.952314)
			(xy 446.42879 -44.903679) (xy 446.462876 -44.859536) (xy 446.503025 -44.820827) (xy 446.548383 -44.788376)
			(xy 446.597983 -44.762875) (xy 446.650767 -44.744868) (xy 446.70561 -44.734738) (xy 446.761344 -44.732701)
			(xy 446.816781 -44.738801) (xy 446.870738 -44.752907) (xy 446.922067 -44.774719) (xy 446.969673 -44.803773)
			(xy 447.012541 -44.839448) (xy 447.049758 -44.880985) (xy 447.080531 -44.927498) (xy 447.104203 -44.977995)
			(xy 447.120271 -45.031402) (xy 447.128391 -45.086578) (xy 447.1289 -45.114464) (xy 447.128391 -45.14235)
			(xy 447.120271 -45.197526) (xy 447.104203 -45.250933) (xy 447.080531 -45.30143) (xy 447.049758 -45.347943)
			(xy 447.012541 -45.38948) (xy 446.969673 -45.425155) (xy 446.922067 -45.454209) (xy 446.870738 -45.476021)
			(xy 446.816781 -45.490127) (xy 446.761344 -45.496227) (xy 446.70561 -45.49419) (xy 446.650767 -45.48406)
			(xy 446.597983 -45.466053) (xy 446.548383 -45.440552) (xy 446.503025 -45.408101) (xy 446.462876 -45.369392)
			(xy 446.42879 -45.325249) (xy 446.401494 -45.276614) (xy 446.381571 -45.224523) (xy 446.369445 -45.170086)
			(xy 446.365374 -45.114464) (xy 437.990996 -45.114464) (xy 437.990996 -46.893226) (xy 446.637154 -46.893226)
			(xy 446.641225 -46.837604) (xy 446.653351 -46.783167) (xy 446.673274 -46.731076) (xy 446.70057 -46.682441)
			(xy 446.734656 -46.638298) (xy 446.774805 -46.599589) (xy 446.820163 -46.567138) (xy 446.869763 -46.541637)
			(xy 446.922547 -46.52363) (xy 446.97739 -46.5135) (xy 447.033124 -46.511463) (xy 447.088561 -46.517563)
			(xy 447.142518 -46.531669) (xy 447.193847 -46.553481) (xy 447.241453 -46.582535) (xy 447.284321 -46.61821)
			(xy 447.321538 -46.659747) (xy 447.352311 -46.70626) (xy 447.375983 -46.756757) (xy 447.392051 -46.810164)
			(xy 447.400171 -46.86534) (xy 447.40068 -46.893226) (xy 447.400171 -46.921112) (xy 447.392051 -46.976288)
			(xy 447.375983 -47.029695) (xy 447.352311 -47.080192) (xy 447.321538 -47.126705) (xy 447.284321 -47.168242)
			(xy 447.241453 -47.203917) (xy 447.193847 -47.232971) (xy 447.142518 -47.254783) (xy 447.088561 -47.268889)
			(xy 447.033124 -47.274989) (xy 446.97739 -47.272952) (xy 446.922547 -47.262822) (xy 446.869763 -47.244815)
			(xy 446.820163 -47.219314) (xy 446.774805 -47.186863) (xy 446.734656 -47.148154) (xy 446.70057 -47.104011)
			(xy 446.673274 -47.055376) (xy 446.653351 -47.003285) (xy 446.641225 -46.948848) (xy 446.637154 -46.893226)
			(xy 437.990996 -46.893226) (xy 437.990996 -47.936658) (xy 444.952882 -47.936658) (xy 444.953368 -47.909407)
			(xy 444.961124 -47.855459) (xy 444.976479 -47.803164) (xy 444.999121 -47.753587) (xy 445.028587 -47.707737)
			(xy 445.064278 -47.666546) (xy 445.105469 -47.630855) (xy 445.151319 -47.601389) (xy 445.200896 -47.578747)
			(xy 445.253191 -47.563392) (xy 445.307139 -47.555636) (xy 445.361641 -47.555636) (xy 445.415589 -47.563392)
			(xy 445.467884 -47.578747) (xy 445.517461 -47.601389) (xy 445.563311 -47.630855) (xy 445.604502 -47.666546)
			(xy 445.640193 -47.707737) (xy 445.669659 -47.753587) (xy 445.692301 -47.803164) (xy 445.707656 -47.855459)
			(xy 445.715412 -47.909407) (xy 445.715898 -47.936658) (xy 445.715459 -47.963) (xy 445.708208 -48.015182)
			(xy 445.693851 -48.065872) (xy 445.672661 -48.114106) (xy 445.64504 -48.158969) (xy 445.611514 -48.199608)
			(xy 445.572718 -48.235252) (xy 445.551306 -48.250602) (xy 445.539487 -48.259302) (xy 445.521057 -48.282128)
			(xy 445.509877 -48.309252) (xy 445.506871 -48.338434) (xy 445.512285 -48.367268) (xy 445.525674 -48.393372)
			(xy 445.545932 -48.414592) (xy 445.558418 -48.422306) (xy 445.582964 -48.436985) (xy 445.62772 -48.472591)
			(xy 445.666662 -48.514478) (xy 445.698916 -48.561707) (xy 445.72376 -48.613221) (xy 445.740638 -48.667866)
			(xy 445.749171 -48.724418) (xy 445.74968 -48.753014) (xy 445.749194 -48.780265) (xy 445.741438 -48.834213)
			(xy 445.726083 -48.886508) (xy 445.703441 -48.936085) (xy 445.673975 -48.981935) (xy 445.638284 -49.023126)
			(xy 445.597093 -49.058817) (xy 445.551243 -49.088283) (xy 445.501666 -49.110925) (xy 445.449371 -49.12628)
			(xy 445.395423 -49.134036) (xy 445.340921 -49.134036) (xy 445.286973 -49.12628) (xy 445.234678 -49.110925)
			(xy 445.185101 -49.088283) (xy 445.139251 -49.058817) (xy 445.09806 -49.023126) (xy 445.062369 -48.981935)
			(xy 445.032903 -48.936085) (xy 445.010261 -48.886508) (xy 444.994906 -48.834213) (xy 444.98715 -48.780265)
			(xy 444.986664 -48.753014) (xy 444.987098 -48.726672) (xy 444.994352 -48.67449) (xy 445.008712 -48.623801)
			(xy 445.029903 -48.575567) (xy 445.057524 -48.530705) (xy 445.09105 -48.490065) (xy 445.129845 -48.45442)
			(xy 445.151256 -48.43907) (xy 445.163109 -48.43041) (xy 445.181547 -48.407577) (xy 445.19273 -48.380443)
			(xy 445.195734 -48.351249) (xy 445.190312 -48.322407) (xy 445.176911 -48.296297) (xy 445.156638 -48.275077)
			(xy 445.144144 -48.267366) (xy 445.119621 -48.252651) (xy 445.074867 -48.217049) (xy 445.035926 -48.175168)
			(xy 445.00367 -48.127945) (xy 444.978822 -48.076437) (xy 444.961938 -48.021798) (xy 444.953396 -47.965252)
			(xy 444.952882 -47.936658) (xy 437.990996 -47.936658) (xy 437.990996 -58.731404) (xy 439.820558 -58.731404)
			(xy 439.821012 -58.704033) (xy 439.828831 -58.649853) (xy 439.844322 -58.597349) (xy 439.867167 -58.547603)
			(xy 439.896895 -58.501637) (xy 439.914538 -58.480706) (xy 439.920634 -58.473594) (xy 439.926984 -58.456576)
			(xy 439.926984 -58.371232) (xy 439.920634 -58.354214) (xy 439.914538 -58.347102) (xy 439.896901 -58.326166)
			(xy 439.867175 -58.280199) (xy 439.844329 -58.230454) (xy 439.828832 -58.177952) (xy 439.821002 -58.123774)
			(xy 439.821002 -58.069032) (xy 439.82883 -58.014854) (xy 439.844327 -57.962352) (xy 439.867172 -57.912606)
			(xy 439.896897 -57.866639) (xy 439.914538 -57.845706) (xy 439.920634 -57.838594) (xy 439.926984 -57.821576)
			(xy 439.926984 -57.736232) (xy 439.920634 -57.719214) (xy 439.914538 -57.712102) (xy 439.896901 -57.691166)
			(xy 439.867175 -57.645199) (xy 439.844329 -57.595454) (xy 439.828832 -57.542952) (xy 439.821002 -57.488774)
			(xy 439.821002 -57.434032) (xy 439.82883 -57.379854) (xy 439.844327 -57.327352) (xy 439.867172 -57.277606)
			(xy 439.896897 -57.231639) (xy 439.914538 -57.210706) (xy 439.920634 -57.203594) (xy 439.926984 -57.186576)
			(xy 439.926984 -57.101232) (xy 439.920634 -57.084214) (xy 439.914538 -57.077102) (xy 439.896892 -57.056175)
			(xy 439.86718 -57.010201) (xy 439.844345 -56.960453) (xy 439.828855 -56.907951) (xy 439.82103 -56.853774)
			(xy 439.820558 -56.826404) (xy 439.821044 -56.799153) (xy 439.8288 -56.745205) (xy 439.844155 -56.69291)
			(xy 439.866797 -56.643333) (xy 439.896263 -56.597483) (xy 439.931954 -56.556292) (xy 439.973145 -56.520601)
			(xy 440.018995 -56.491135) (xy 440.068572 -56.468493) (xy 440.120867 -56.453138) (xy 440.174815 -56.445382)
			(xy 440.229317 -56.445382) (xy 440.283265 -56.453138) (xy 440.33556 -56.468493) (xy 440.385137 -56.491135)
			(xy 440.430987 -56.520601) (xy 440.472178 -56.556292) (xy 440.507869 -56.597483) (xy 440.537335 -56.643333)
			(xy 440.559977 -56.69291) (xy 440.575332 -56.745205) (xy 440.583088 -56.799153) (xy 440.583574 -56.826404)
			(xy 440.583117 -56.853775) (xy 440.575298 -56.907954) (xy 440.559807 -56.960458) (xy 440.536963 -57.010205)
			(xy 440.507236 -57.056171) (xy 440.489594 -57.077102) (xy 440.483498 -57.084214) (xy 440.477148 -57.101232)
			(xy 440.477148 -57.186576) (xy 440.483498 -57.203594) (xy 440.489594 -57.210706) (xy 440.507238 -57.231636)
			(xy 440.536961 -57.277605) (xy 440.559805 -57.327352) (xy 440.5753 -57.379854) (xy 440.583127 -57.434032)
			(xy 440.583127 -57.488774) (xy 440.575298 -57.542952) (xy 440.559802 -57.595454) (xy 440.536958 -57.645201)
			(xy 440.507234 -57.691169) (xy 440.489594 -57.712102) (xy 440.483498 -57.719214) (xy 440.477148 -57.736232)
			(xy 440.477148 -57.821576) (xy 440.483498 -57.838594) (xy 440.489594 -57.845706) (xy 440.507238 -57.866636)
			(xy 440.536961 -57.912605) (xy 440.559805 -57.962352) (xy 440.5753 -58.014854) (xy 440.583127 -58.069032)
			(xy 440.583127 -58.123774) (xy 440.575298 -58.177952) (xy 440.559802 -58.230454) (xy 440.536958 -58.280201)
			(xy 440.507234 -58.326169) (xy 440.489594 -58.347102) (xy 440.483498 -58.354214) (xy 440.477148 -58.371232)
			(xy 440.477148 -58.456576) (xy 440.483498 -58.473594) (xy 440.489594 -58.480706) (xy 440.507248 -58.501626)
			(xy 440.536958 -58.547602) (xy 440.559791 -58.597352) (xy 440.575279 -58.649856) (xy 440.583102 -58.704034)
			(xy 440.583574 -58.731404) (xy 440.583088 -58.758655) (xy 440.578424 -58.791094) (xy 442.476382 -58.791094)
			(xy 442.476825 -58.763723) (xy 442.484645 -58.709542) (xy 442.500138 -58.657038) (xy 442.522986 -58.607291)
			(xy 442.552717 -58.561326) (xy 442.570362 -58.540396) (xy 442.576458 -58.533284) (xy 442.582808 -58.516266)
			(xy 442.582808 -58.430922) (xy 442.576458 -58.413904) (xy 442.570362 -58.406792) (xy 442.552714 -58.385865)
			(xy 442.522987 -58.339897) (xy 442.50014 -58.29015) (xy 442.484642 -58.237647) (xy 442.476813 -58.183467)
			(xy 442.476814 -58.128724) (xy 442.484644 -58.074544) (xy 442.500143 -58.022042) (xy 442.522991 -57.972295)
			(xy 442.552719 -57.926328) (xy 442.570362 -57.905396) (xy 442.576458 -57.898284) (xy 442.582808 -57.881266)
			(xy 442.582808 -57.795922) (xy 442.576458 -57.778904) (xy 442.570362 -57.771792) (xy 442.552699 -57.750879)
			(xy 442.522992 -57.7049) (xy 442.500161 -57.655148) (xy 442.484676 -57.602643) (xy 442.476853 -57.548464)
			(xy 442.476382 -57.521094) (xy 442.476857 -57.494779) (xy 442.484074 -57.442646) (xy 442.498383 -57.391998)
			(xy 442.519513 -57.343797) (xy 442.547064 -57.298954) (xy 442.580514 -57.258321) (xy 442.599572 -57.24017)
			(xy 442.606985 -57.232658) (xy 442.615504 -57.213371) (xy 442.616082 -57.202832) (xy 442.616082 -57.128156)
			(xy 442.615541 -57.117608) (xy 442.607015 -57.098312) (xy 442.599572 -57.090818) (xy 442.580515 -57.07266)
			(xy 442.547032 -57.032046) (xy 442.519457 -56.987211) (xy 442.498314 -56.939008) (xy 442.484006 -56.888354)
			(xy 442.476804 -56.836213) (xy 442.476382 -56.809894) (xy 442.476868 -56.782643) (xy 442.484624 -56.728695)
			(xy 442.499979 -56.6764) (xy 442.522621 -56.626823) (xy 442.552087 -56.580973) (xy 442.587778 -56.539782)
			(xy 442.628969 -56.504091) (xy 442.674819 -56.474625) (xy 442.724396 -56.451983) (xy 442.776691 -56.436628)
			(xy 442.830639 -56.428872) (xy 442.885141 -56.428872) (xy 442.939089 -56.436628) (xy 442.991384 -56.451983)
			(xy 443.040961 -56.474625) (xy 443.086811 -56.504091) (xy 443.128002 -56.539782) (xy 443.163693 -56.580973)
			(xy 443.193159 -56.626823) (xy 443.215801 -56.6764) (xy 443.231156 -56.728695) (xy 443.238912 -56.782643)
			(xy 443.239398 -56.809894) (xy 443.238988 -56.836211) (xy 443.231759 -56.888347) (xy 443.217438 -56.938996)
			(xy 443.196295 -56.987198) (xy 443.168732 -57.032039) (xy 443.135272 -57.072669) (xy 443.116208 -57.090818)
			(xy 443.108798 -57.098332) (xy 443.100278 -57.117618) (xy 443.099698 -57.128156) (xy 443.099698 -57.202832)
			(xy 443.100251 -57.213379) (xy 443.10877 -57.232674) (xy 443.116208 -57.24017) (xy 443.135274 -57.258318)
			(xy 443.168753 -57.298936) (xy 443.196325 -57.343773) (xy 443.217466 -57.391978) (xy 443.231773 -57.442633)
			(xy 443.235145 -57.467049) (xy 443.418492 -57.467049) (xy 443.418492 -57.412551) (xy 443.426248 -57.358608)
			(xy 443.4416 -57.306318) (xy 443.464238 -57.256745) (xy 443.493701 -57.210898) (xy 443.529387 -57.16971)
			(xy 443.570572 -57.13402) (xy 443.616417 -57.104554) (xy 443.665988 -57.081912) (xy 443.718277 -57.066554)
			(xy 443.772219 -57.058794) (xy 443.799468 -57.058306) (xy 443.825785 -57.058732) (xy 443.87792 -57.065957)
			(xy 443.928569 -57.080276) (xy 443.976771 -57.101415) (xy 444.021612 -57.128975) (xy 444.062243 -57.162434)
			(xy 444.080392 -57.181496) (xy 444.087915 -57.188895) (xy 444.107194 -57.197421) (xy 444.11773 -57.198006)
			(xy 444.192406 -57.198006) (xy 444.202957 -57.197492) (xy 444.222253 -57.188946) (xy 444.229744 -57.181496)
			(xy 444.247856 -57.162395) (xy 444.288482 -57.128919) (xy 444.333327 -57.101351) (xy 444.381539 -57.080216)
			(xy 444.4322 -57.065917) (xy 444.484347 -57.058724) (xy 444.510668 -57.058306) (xy 444.537923 -57.058739)
			(xy 444.59188 -57.066492) (xy 444.627157 -57.076848) (xy 445.43853 -57.076848) (xy 445.439017 -57.049478)
			(xy 445.446829 -56.9953) (xy 445.462312 -56.942797) (xy 445.48515 -56.89305) (xy 445.51487 -56.847082)
			(xy 445.53251 -56.82615) (xy 445.538606 -56.819038) (xy 445.544956 -56.80202) (xy 445.544956 -56.716676)
			(xy 445.538606 -56.699658) (xy 445.53251 -56.692546) (xy 445.514881 -56.671606) (xy 445.485167 -56.625636)
			(xy 445.462329 -56.57589) (xy 445.446836 -56.523391) (xy 445.439005 -56.469217) (xy 445.43853 -56.441848)
			(xy 445.439016 -56.414597) (xy 445.446772 -56.360649) (xy 445.462127 -56.308354) (xy 445.484769 -56.258777)
			(xy 445.514235 -56.212927) (xy 445.549926 -56.171736) (xy 445.591117 -56.136045) (xy 445.636967 -56.106579)
			(xy 445.686544 -56.083937) (xy 445.738839 -56.068582) (xy 445.792787 -56.060826) (xy 445.847289 -56.060826)
			(xy 445.901237 -56.068582) (xy 445.953532 -56.083937) (xy 446.003109 -56.106579) (xy 446.048959 -56.136045)
			(xy 446.09015 -56.171736) (xy 446.125841 -56.212927) (xy 446.155307 -56.258777) (xy 446.177949 -56.308354)
			(xy 446.193304 -56.360649) (xy 446.20106 -56.414597) (xy 446.201546 -56.441848) (xy 446.201063 -56.469218)
			(xy 446.193251 -56.523397) (xy 446.177767 -56.5759) (xy 446.154928 -56.625647) (xy 446.125206 -56.671614)
			(xy 446.107566 -56.692546) (xy 446.10147 -56.699658) (xy 446.09512 -56.716676) (xy 446.09512 -56.80202)
			(xy 446.10147 -56.819038) (xy 446.107566 -56.82615) (xy 446.12519 -56.847094) (xy 446.154905 -56.893063)
			(xy 446.177745 -56.942808) (xy 446.193239 -56.995306) (xy 446.20107 -57.04948) (xy 446.201546 -57.076848)
			(xy 446.20106 -57.104099) (xy 446.193304 -57.158047) (xy 446.177949 -57.210342) (xy 446.155307 -57.259919)
			(xy 446.125841 -57.305769) (xy 446.09015 -57.34696) (xy 446.048959 -57.382651) (xy 446.003109 -57.412117)
			(xy 445.953532 -57.434759) (xy 445.901237 -57.450114) (xy 445.847289 -57.45787) (xy 445.792787 -57.45787)
			(xy 445.738839 -57.450114) (xy 445.686544 -57.434759) (xy 445.636967 -57.412117) (xy 445.591117 -57.382651)
			(xy 445.549926 -57.34696) (xy 445.514235 -57.305769) (xy 445.484769 -57.259919) (xy 445.462127 -57.210342)
			(xy 445.446772 -57.158047) (xy 445.439016 -57.104099) (xy 445.43853 -57.076848) (xy 444.627157 -57.076848)
			(xy 444.644183 -57.081846) (xy 444.69377 -57.104488) (xy 444.739628 -57.133956) (xy 444.780826 -57.169651)
			(xy 444.816525 -57.210846) (xy 444.845997 -57.256702) (xy 444.868643 -57.306287) (xy 444.884001 -57.358589)
			(xy 444.891759 -57.412545) (xy 444.891759 -57.467055) (xy 444.884001 -57.521011) (xy 444.868643 -57.573313)
			(xy 444.845997 -57.622898) (xy 444.816525 -57.668754) (xy 444.780826 -57.709949) (xy 444.739628 -57.745644)
			(xy 444.69377 -57.775112) (xy 444.644183 -57.797754) (xy 444.59188 -57.813108) (xy 444.537923 -57.820861)
			(xy 444.510668 -57.821322) (xy 444.484352 -57.820863) (xy 444.432219 -57.813643) (xy 444.381571 -57.799331)
			(xy 444.333369 -57.778197) (xy 444.288527 -57.750643) (xy 444.247895 -57.717191) (xy 444.229744 -57.698132)
			(xy 444.222204 -57.690752) (xy 444.202938 -57.682214) (xy 444.192406 -57.681622) (xy 444.11773 -57.681622)
			(xy 444.10718 -57.682147) (xy 444.087884 -57.690684) (xy 444.080392 -57.698132) (xy 444.062248 -57.717202)
			(xy 444.021631 -57.750684) (xy 443.976793 -57.778257) (xy 443.928587 -57.799398) (xy 443.877931 -57.813703)
			(xy 443.825787 -57.820902) (xy 443.799468 -57.821322) (xy 443.772219 -57.820806) (xy 443.718277 -57.813046)
			(xy 443.665988 -57.797688) (xy 443.616417 -57.775046) (xy 443.570572 -57.74558) (xy 443.529387 -57.70989)
			(xy 443.493701 -57.668702) (xy 443.464238 -57.622855) (xy 443.4416 -57.573282) (xy 443.426248 -57.520992)
			(xy 443.418492 -57.467049) (xy 443.235145 -57.467049) (xy 443.238975 -57.494775) (xy 443.239398 -57.521094)
			(xy 443.238929 -57.548464) (xy 443.231112 -57.602643) (xy 443.215624 -57.655146) (xy 443.192782 -57.704893)
			(xy 443.163059 -57.75086) (xy 443.145418 -57.771792) (xy 443.139322 -57.778904) (xy 443.132972 -57.795922)
			(xy 443.132972 -57.881266) (xy 443.139322 -57.898284) (xy 443.145418 -57.905396) (xy 443.163051 -57.926334)
			(xy 443.192773 -57.972302) (xy 443.215616 -58.022048) (xy 443.23111 -58.074549) (xy 443.238938 -58.128726)
			(xy 443.238939 -58.183465) (xy 443.231112 -58.237642) (xy 443.215619 -58.290144) (xy 443.192777 -58.33989)
			(xy 443.163056 -58.385858) (xy 443.145418 -58.406792) (xy 443.139322 -58.413904) (xy 443.132972 -58.430922)
			(xy 443.132972 -58.516266) (xy 443.139322 -58.533284) (xy 443.145418 -58.540396) (xy 443.163071 -58.561316)
			(xy 443.192781 -58.607293) (xy 443.215613 -58.657043) (xy 443.231101 -58.709546) (xy 443.238926 -58.763724)
			(xy 443.239398 -58.791094) (xy 443.238912 -58.818345) (xy 443.231156 -58.872293) (xy 443.230759 -58.873644)
			(xy 444.500508 -58.873644) (xy 444.500998 -58.846275) (xy 444.50881 -58.792096) (xy 444.524293 -58.739594)
			(xy 444.54713 -58.689846) (xy 444.576849 -58.643878) (xy 444.594488 -58.622946) (xy 444.600584 -58.615834)
			(xy 444.606934 -58.598816) (xy 444.606934 -58.513472) (xy 444.600584 -58.496454) (xy 444.594488 -58.489342)
			(xy 444.576853 -58.468406) (xy 444.547141 -58.422434) (xy 444.524305 -58.372688) (xy 444.508812 -58.320188)
			(xy 444.500983 -58.266013) (xy 444.500508 -58.238644) (xy 444.500994 -58.211393) (xy 444.50875 -58.157445)
			(xy 444.524105 -58.10515) (xy 444.546747 -58.055573) (xy 444.576213 -58.009723) (xy 444.611904 -57.968532)
			(xy 444.653095 -57.932841) (xy 444.698945 -57.903375) (xy 444.748522 -57.880733) (xy 444.800817 -57.865378)
			(xy 444.854765 -57.857622) (xy 444.909267 -57.857622) (xy 444.963215 -57.865378) (xy 445.01551 -57.880733)
			(xy 445.065087 -57.903375) (xy 445.110937 -57.932841) (xy 445.152128 -57.968532) (xy 445.187819 -58.009723)
			(xy 445.217285 -58.055573) (xy 445.239927 -58.10515) (xy 445.255282 -58.157445) (xy 445.263038 -58.211393)
			(xy 445.263524 -58.238644) (xy 445.263044 -58.266014) (xy 445.255232 -58.320193) (xy 445.239747 -58.372697)
			(xy 445.216908 -58.422444) (xy 445.187185 -58.468411) (xy 445.169544 -58.489342) (xy 445.163448 -58.496454)
			(xy 445.157098 -58.513472) (xy 445.157098 -58.598816) (xy 445.163448 -58.615834) (xy 445.169544 -58.622946)
			(xy 445.187178 -58.643882) (xy 445.21689 -58.689854) (xy 445.239726 -58.739601) (xy 445.255218 -58.7921)
			(xy 445.263049 -58.846275) (xy 445.263524 -58.873644) (xy 445.263038 -58.900895) (xy 445.255282 -58.954843)
			(xy 445.239927 -59.007138) (xy 445.217285 -59.056715) (xy 445.187819 -59.102565) (xy 445.152128 -59.143756)
			(xy 445.110937 -59.179447) (xy 445.065087 -59.208913) (xy 445.01551 -59.231555) (xy 444.963215 -59.24691)
			(xy 444.909267 -59.254666) (xy 444.854765 -59.254666) (xy 444.800817 -59.24691) (xy 444.748522 -59.231555)
			(xy 444.698945 -59.208913) (xy 444.653095 -59.179447) (xy 444.611904 -59.143756) (xy 444.576213 -59.102565)
			(xy 444.546747 -59.056715) (xy 444.524105 -59.007138) (xy 444.50875 -58.954843) (xy 444.500994 -58.900895)
			(xy 444.500508 -58.873644) (xy 443.230759 -58.873644) (xy 443.215801 -58.924588) (xy 443.193159 -58.974165)
			(xy 443.163693 -59.020015) (xy 443.128002 -59.061206) (xy 443.086811 -59.096897) (xy 443.040961 -59.126363)
			(xy 442.991384 -59.149005) (xy 442.939089 -59.16436) (xy 442.885141 -59.172116) (xy 442.830639 -59.172116)
			(xy 442.776691 -59.16436) (xy 442.724396 -59.149005) (xy 442.674819 -59.126363) (xy 442.628969 -59.096897)
			(xy 442.587778 -59.061206) (xy 442.552087 -59.020015) (xy 442.522621 -58.974165) (xy 442.499979 -58.924588)
			(xy 442.484624 -58.872293) (xy 442.476868 -58.818345) (xy 442.476382 -58.791094) (xy 440.578424 -58.791094)
			(xy 440.575332 -58.812603) (xy 440.559977 -58.864898) (xy 440.537335 -58.914475) (xy 440.507869 -58.960325)
			(xy 440.472178 -59.001516) (xy 440.430987 -59.037207) (xy 440.385137 -59.066673) (xy 440.33556 -59.089315)
			(xy 440.283265 -59.10467) (xy 440.229317 -59.112426) (xy 440.174815 -59.112426) (xy 440.120867 -59.10467)
			(xy 440.068572 -59.089315) (xy 440.018995 -59.066673) (xy 439.973145 -59.037207) (xy 439.931954 -59.001516)
			(xy 439.896263 -58.960325) (xy 439.866797 -58.914475) (xy 439.844155 -58.864898) (xy 439.8288 -58.812603)
			(xy 439.821044 -58.758655) (xy 439.820558 -58.731404) (xy 437.990996 -58.731404) (xy 437.990996 -60.126451)
			(xy 443.480172 -60.126451) (xy 443.480172 -60.071949) (xy 443.487928 -60.018001) (xy 443.503283 -59.965706)
			(xy 443.525924 -59.916129) (xy 443.55539 -59.870278) (xy 443.591081 -59.829088) (xy 443.63227 -59.793396)
			(xy 443.67812 -59.763929) (xy 443.727697 -59.741287) (xy 443.779991 -59.72593) (xy 443.833939 -59.718172)
			(xy 443.86119 -59.717686) (xy 443.88856 -59.718161) (xy 443.942738 -59.725977) (xy 443.995241 -59.741465)
			(xy 444.044988 -59.764304) (xy 444.090956 -59.794026) (xy 444.111888 -59.811666) (xy 444.119 -59.817762)
			(xy 444.136018 -59.824112) (xy 444.221362 -59.824112) (xy 444.23838 -59.817762) (xy 444.245492 -59.811666)
			(xy 444.266425 -59.794025) (xy 444.312393 -59.764301) (xy 444.362139 -59.741455) (xy 444.414641 -59.725959)
			(xy 444.468819 -59.71813) (xy 444.523561 -59.71813) (xy 444.577739 -59.725959) (xy 444.630241 -59.741455)
			(xy 444.679987 -59.764301) (xy 444.725955 -59.794025) (xy 444.746888 -59.811666) (xy 444.754 -59.817762)
			(xy 444.771018 -59.824112) (xy 444.856362 -59.824112) (xy 444.87338 -59.817762) (xy 444.880492 -59.811666)
			(xy 444.901412 -59.794012) (xy 444.947389 -59.764303) (xy 444.997139 -59.741471) (xy 445.049642 -59.725983)
			(xy 445.10382 -59.718158) (xy 445.13119 -59.717686) (xy 445.158443 -59.718161) (xy 445.212394 -59.725916)
			(xy 445.264692 -59.741271) (xy 445.314273 -59.763913) (xy 445.360127 -59.79338) (xy 445.40132 -59.829073)
			(xy 445.437014 -59.870265) (xy 445.466482 -59.916118) (xy 445.489125 -59.965698) (xy 445.504482 -60.017996)
			(xy 445.512239 -60.071947) (xy 445.512239 -60.126453) (xy 445.504482 -60.180404) (xy 445.489125 -60.232702)
			(xy 445.466482 -60.282282) (xy 445.437014 -60.328135) (xy 445.40132 -60.369327) (xy 445.360127 -60.40502)
			(xy 445.314273 -60.434487) (xy 445.264692 -60.457129) (xy 445.212394 -60.472484) (xy 445.158443 -60.480239)
			(xy 445.13119 -60.480702) (xy 445.10382 -60.480241) (xy 445.04964 -60.472422) (xy 444.997137 -60.456932)
			(xy 444.94739 -60.434089) (xy 444.901424 -60.404364) (xy 444.880492 -60.386722) (xy 444.87338 -60.380626)
			(xy 444.856362 -60.374276) (xy 444.771018 -60.374276) (xy 444.754 -60.380626) (xy 444.746888 -60.386722)
			(xy 444.725955 -60.404363) (xy 444.679987 -60.434087) (xy 444.630241 -60.456933) (xy 444.577739 -60.472429)
			(xy 444.523561 -60.480258) (xy 444.468819 -60.480258) (xy 444.414641 -60.472429) (xy 444.362139 -60.456933)
			(xy 444.312393 -60.434087) (xy 444.266425 -60.404363) (xy 444.245492 -60.386722) (xy 444.23838 -60.380626)
			(xy 444.221362 -60.374276) (xy 444.136018 -60.374276) (xy 444.119 -60.380626) (xy 444.111888 -60.386722)
			(xy 444.090936 -60.404337) (xy 444.044969 -60.434051) (xy 443.995226 -60.456892) (xy 443.94273 -60.472389)
			(xy 443.888558 -60.480224) (xy 443.86119 -60.480702) (xy 443.833939 -60.480228) (xy 443.779991 -60.47247)
			(xy 443.727697 -60.457113) (xy 443.67812 -60.434471) (xy 443.63227 -60.405004) (xy 443.591081 -60.369312)
			(xy 443.55539 -60.328122) (xy 443.525924 -60.282271) (xy 443.503283 -60.232694) (xy 443.487928 -60.180399)
			(xy 443.480172 -60.126451) (xy 437.990996 -60.126451) (xy 437.990996 -60.999878) (xy 437.990462 -61.009867)
			(xy 437.982754 -61.028305) (xy 437.97601 -61.035692) (xy 437.900572 -61.11113) (xy 437.900064 -61.111892)
			(xy 437.896762 -61.115194) (xy 437.896508 -61.115448) (xy 437.26989 -61.742066) (xy 437.263286 -61.748416)
			(xy 437.262778 -61.748924) (xy 437.200294 -61.811408) (xy 437.192937 -61.818055) (xy 437.174636 -61.825632)
			(xy 437.164734 -61.82614) (xy 437.10987 -61.82614) (xy 437.105552 -61.826902) (xy 437.092884 -61.828914)
			(xy 437.067324 -61.83108) (xy 437.054498 -61.83122) (xy 435.379368 -61.83122) (xy 435.367742 -61.831783)
			(xy 435.346833 -61.841961) (xy 435.339236 -61.850778) (xy 435.282594 -61.923422) (xy 435.277768 -61.946028)
			(xy 435.280816 -61.957712) (xy 435.286283 -61.980757) (xy 435.292138 -62.027756) (xy 435.2925 -62.051438)
			(xy 435.292012 -62.078687) (xy 435.284251 -62.13263) (xy 435.268892 -62.18492) (xy 435.246249 -62.234492)
			(xy 435.216781 -62.280337) (xy 435.18109 -62.321522) (xy 435.1399 -62.357209) (xy 435.094052 -62.386671)
			(xy 435.044477 -62.409308) (xy 434.992185 -62.42466) (xy 434.938241 -62.432415) (xy 434.910992 -62.432946)
			(xy 434.887437 -62.432566) (xy 434.840693 -62.42671) (xy 434.817774 -62.421262) (xy 434.80355 -62.417706)
			(xy 434.776372 -62.426342) (xy 434.69814 -62.517274) (xy 434.693568 -62.545468) (xy 434.699156 -62.55893)
			(xy 434.708482 -62.582314) (xy 434.721603 -62.630917) (xy 434.728222 -62.680824) (xy 434.72862 -62.705996)
			(xy 434.728135 -62.733248) (xy 434.720379 -62.787197) (xy 434.705024 -62.839492) (xy 434.682383 -62.889071)
			(xy 434.652917 -62.934923) (xy 434.617226 -62.976114) (xy 434.576036 -63.011808) (xy 434.530185 -63.041275)
			(xy 434.480607 -63.063918) (xy 434.428312 -63.079275) (xy 434.374364 -63.087033) (xy 434.347112 -63.087504)
			(xy 434.318302 -63.086978) (xy 434.261338 -63.07831) (xy 434.206327 -63.06117) (xy 434.154521 -63.035949)
			(xy 434.107099 -63.00322) (xy 434.085746 -62.983872) (xy 434.07711 -62.975744) (xy 434.055266 -62.968886)
			(xy 433.96535 -62.981332) (xy 433.963318 -62.981586) (xy 433.952582 -62.984096) (xy 433.934546 -62.996737)
			(xy 433.92852 -63.00597) (xy 433.913702 -63.03009) (xy 433.878063 -63.074068) (xy 433.836315 -63.112295)
			(xy 433.789374 -63.14393) (xy 433.738273 -63.16828) (xy 433.684135 -63.184809) (xy 433.628147 -63.193153)
			(xy 433.599844 -63.193676) (xy 433.572591 -63.193216) (xy 433.51864 -63.185465) (xy 433.466341 -63.170114)
			(xy 433.41676 -63.147475) (xy 433.370905 -63.118011) (xy 433.329711 -63.08232) (xy 433.294015 -63.04113)
			(xy 433.264546 -62.995279) (xy 433.241902 -62.9457) (xy 433.226545 -62.893403) (xy 433.218787 -62.839453)
			(xy 433.218787 -62.784947) (xy 433.226545 -62.730997) (xy 433.241902 -62.6787) (xy 433.264546 -62.629121)
			(xy 433.294015 -62.58327) (xy 433.329711 -62.54208) (xy 433.370905 -62.506389) (xy 433.41676 -62.476925)
			(xy 433.466341 -62.454286) (xy 433.51864 -62.438935) (xy 433.572591 -62.431184) (xy 433.599844 -62.43066)
			(xy 433.628655 -62.431183) (xy 433.685623 -62.439844) (xy 433.740639 -62.456978) (xy 433.792451 -62.482193)
			(xy 433.83988 -62.514918) (xy 433.86121 -62.534292) (xy 433.869846 -62.54242) (xy 433.89169 -62.549278)
			(xy 433.981606 -62.536832) (xy 433.983384 -62.536578) (xy 433.994528 -62.533948) (xy 434.013115 -62.520626)
			(xy 434.019198 -62.510924) (xy 434.01996 -62.5094) (xy 434.03486 -62.485593) (xy 434.070547 -62.442228)
			(xy 434.112204 -62.404561) (xy 434.158931 -62.373407) (xy 434.20972 -62.349436) (xy 434.263474 -62.333168)
			(xy 434.319031 -62.324954) (xy 434.347112 -62.324488) (xy 434.367178 -62.324996) (xy 434.367432 -62.324996)
			(xy 434.38318 -62.326012) (xy 434.391816 -62.327028) (xy 434.412644 -62.330076) (xy 434.412898 -62.330076)
			(xy 434.44033 -62.336172) (xy 434.454554 -62.339728) (xy 434.481732 -62.331092) (xy 434.559964 -62.24016)
			(xy 434.564282 -62.21222) (xy 434.558694 -62.198504) (xy 434.548876 -62.173891) (xy 434.535369 -62.12265)
			(xy 434.53177 -62.096396) (xy 434.5305 -62.082426) (xy 434.52923 -62.051438) (xy 434.52923 -62.05093)
			(xy 434.5296 -62.027312) (xy 434.535461 -61.980441) (xy 434.540914 -61.957458) (xy 434.543962 -61.945774)
			(xy 434.539136 -61.923168) (xy 434.482748 -61.850778) (xy 434.475158 -61.841947) (xy 434.454248 -61.831757)
			(xy 434.442616 -61.83122) (xy 433.464208 -61.83122) (xy 433.451509 -61.831074) (xy 433.426202 -61.828914)
			(xy 433.413662 -61.826902) (xy 433.409344 -61.82614) (xy 433.168806 -61.82614) (xy 433.157122 -61.829188)
			(xy 433.152296 -61.831474) (xy 433.151788 -61.831728) (xy 433.125853 -61.843587) (xy 433.071343 -61.860338)
			(xy 433.014947 -61.868795) (xy 432.986434 -61.86932) (xy 432.97856 -61.86932) (xy 432.951183 -61.868284)
			(xy 432.897133 -61.859334) (xy 432.844919 -61.842745) (xy 432.820064 -61.83122) (xy 432.814984 -61.82868)
			(xy 432.803808 -61.82614) (xy 432.553872 -61.82614) (xy 432.549554 -61.826902) (xy 432.537012 -61.828896)
			(xy 432.511706 -61.831059) (xy 432.499008 -61.83122) (xy 431.363882 -61.83122) (xy 431.351241 -61.831899)
			(xy 431.32899 -61.8439) (xy 431.321464 -61.85408) (xy 431.27803 -61.920374) (xy 431.273644 -61.927593)
			(xy 431.269465 -61.943951) (xy 431.270865 -61.960776) (xy 431.273966 -61.968634) (xy 431.284016 -61.992769)
			(xy 431.298163 -62.043101) (xy 431.305301 -62.094893) (xy 431.305716 -62.121034) (xy 431.305716 -62.12586)
			(xy 431.304904 -62.152886) (xy 431.296594 -62.206313) (xy 431.280825 -62.258031) (xy 431.257913 -62.307004)
			(xy 431.228316 -62.352253) (xy 431.192627 -62.39287) (xy 431.151562 -62.428042) (xy 431.105943 -62.457064)
			(xy 431.056683 -62.479355) (xy 431.004769 -62.494469) (xy 430.951242 -62.502102) (xy 430.897174 -62.502102)
			(xy 430.843647 -62.494469) (xy 430.791733 -62.479355) (xy 430.742473 -62.457064) (xy 430.696854 -62.428042)
			(xy 430.655789 -62.39287) (xy 430.6201 -62.352253) (xy 430.590503 -62.307004) (xy 430.567591 -62.258031)
			(xy 430.551822 -62.206313) (xy 430.543512 -62.152886) (xy 430.5427 -62.12586) (xy 430.5427 -62.12078)
			(xy 430.543148 -62.094683) (xy 430.550301 -62.042981) (xy 430.564431 -61.992735) (xy 430.57445 -61.968634)
			(xy 430.579276 -61.957712) (xy 430.57826 -61.934852) (xy 430.572926 -61.924438) (xy 430.570386 -61.920374)
			(xy 430.527206 -61.854334) (xy 430.520094 -61.843412) (xy 430.497742 -61.83122) (xy 427.962314 -61.83122)
			(xy 427.952251 -61.831659) (xy 427.933671 -61.839398) (xy 427.926246 -61.846206) (xy 427.52264 -62.249812)
			(xy 427.515274 -62.256924) (xy 427.507654 -62.27572) (xy 427.507654 -63.273432) (xy 429.87671 -63.273432)
			(xy 429.880781 -63.21781) (xy 429.892907 -63.163373) (xy 429.91283 -63.111282) (xy 429.940126 -63.062647)
			(xy 429.974212 -63.018504) (xy 430.014361 -62.979795) (xy 430.059719 -62.947344) (xy 430.109319 -62.921843)
			(xy 430.162103 -62.903836) (xy 430.216946 -62.893706) (xy 430.27268 -62.891669) (xy 430.328117 -62.897769)
			(xy 430.382074 -62.911875) (xy 430.433403 -62.933687) (xy 430.481009 -62.962741) (xy 430.523877 -62.998416)
			(xy 430.561094 -63.039953) (xy 430.591867 -63.086466) (xy 430.615539 -63.136963) (xy 430.631607 -63.19037)
			(xy 430.639727 -63.245546) (xy 430.639727 -63.24555) (xy 443.404492 -63.24555) (xy 443.404492 -63.19105)
			(xy 443.412248 -63.137104) (xy 443.427603 -63.084812) (xy 443.450243 -63.035237) (xy 443.479708 -62.989388)
			(xy 443.515398 -62.948199) (xy 443.556586 -62.912509) (xy 443.602435 -62.883044) (xy 443.65201 -62.860404)
			(xy 443.704302 -62.845049) (xy 443.758248 -62.837292) (xy 443.785498 -62.836806) (xy 443.812868 -62.837272)
			(xy 443.867047 -62.845089) (xy 443.919551 -62.860579) (xy 443.969297 -62.88342) (xy 444.015264 -62.913145)
			(xy 444.036196 -62.930786) (xy 444.043308 -62.936882) (xy 444.060326 -62.943232) (xy 444.14567 -62.943232)
			(xy 444.162688 -62.936882) (xy 444.1698 -62.930786) (xy 444.190733 -62.913145) (xy 444.236701 -62.883421)
			(xy 444.286447 -62.860575) (xy 444.338949 -62.845079) (xy 444.393127 -62.83725) (xy 444.447869 -62.83725)
			(xy 444.502047 -62.845079) (xy 444.554549 -62.860575) (xy 444.604295 -62.883421) (xy 444.650263 -62.913145)
			(xy 444.671196 -62.930786) (xy 444.678308 -62.936882) (xy 444.695326 -62.943232) (xy 444.78067 -62.943232)
			(xy 444.797688 -62.936882) (xy 444.8048 -62.930786) (xy 444.825719 -62.913131) (xy 444.871696 -62.883422)
			(xy 444.921447 -62.86059) (xy 444.97395 -62.845102) (xy 445.028128 -62.837278) (xy 445.055498 -62.836806)
			(xy 445.082752 -62.837241) (xy 445.136705 -62.844998) (xy 445.189005 -62.860354) (xy 445.238587 -62.882997)
			(xy 445.284443 -62.912467) (xy 445.325637 -62.948162) (xy 445.361332 -62.989356) (xy 445.390802 -63.035211)
			(xy 445.413445 -63.084793) (xy 445.428802 -63.137093) (xy 445.436559 -63.191046) (xy 445.436559 -63.245554)
			(xy 445.428802 -63.299507) (xy 445.413445 -63.351807) (xy 445.390802 -63.401389) (xy 445.361332 -63.447244)
			(xy 445.325637 -63.488438) (xy 445.284443 -63.524133) (xy 445.238587 -63.553603) (xy 445.189005 -63.576246)
			(xy 445.136705 -63.591602) (xy 445.082752 -63.599359) (xy 445.055498 -63.599822) (xy 445.028127 -63.599376)
			(xy 444.973946 -63.591556) (xy 444.921442 -63.576064) (xy 444.871695 -63.553217) (xy 444.82573 -63.523486)
			(xy 444.8048 -63.505842) (xy 444.797688 -63.499746) (xy 444.78067 -63.493396) (xy 444.695326 -63.493396)
			(xy 444.678308 -63.499746) (xy 444.671196 -63.505842) (xy 444.650263 -63.523483) (xy 444.604295 -63.553207)
			(xy 444.554549 -63.576053) (xy 444.502047 -63.591549) (xy 444.447869 -63.599378) (xy 444.393127 -63.599378)
			(xy 444.338949 -63.591549) (xy 444.286447 -63.576053) (xy 444.236701 -63.553207) (xy 444.190733 -63.523483)
			(xy 444.1698 -63.505842) (xy 444.162688 -63.499746) (xy 444.14567 -63.493396) (xy 444.060326 -63.493396)
			(xy 444.043308 -63.499746) (xy 444.036196 -63.505842) (xy 444.015282 -63.523503) (xy 443.969304 -63.553211)
			(xy 443.919551 -63.576042) (xy 443.867047 -63.591528) (xy 443.812868 -63.599351) (xy 443.785498 -63.599822)
			(xy 443.758248 -63.599308) (xy 443.704302 -63.591551) (xy 443.65201 -63.576196) (xy 443.602435 -63.553556)
			(xy 443.556586 -63.524091) (xy 443.515398 -63.488401) (xy 443.479708 -63.447212) (xy 443.450243 -63.401363)
			(xy 443.427603 -63.351788) (xy 443.412248 -63.299496) (xy 443.404492 -63.24555) (xy 430.639727 -63.24555)
			(xy 430.640236 -63.273432) (xy 430.639727 -63.301318) (xy 430.631607 -63.356494) (xy 430.615539 -63.409901)
			(xy 430.591867 -63.460398) (xy 430.561094 -63.506911) (xy 430.523877 -63.548448) (xy 430.481009 -63.584123)
			(xy 430.433403 -63.613177) (xy 430.382074 -63.634989) (xy 430.328117 -63.649095) (xy 430.27268 -63.655195)
			(xy 430.216946 -63.653158) (xy 430.162103 -63.643028) (xy 430.109319 -63.625021) (xy 430.059719 -63.59952)
			(xy 430.014361 -63.567069) (xy 429.974212 -63.52836) (xy 429.940126 -63.484217) (xy 429.91283 -63.435582)
			(xy 429.892907 -63.383491) (xy 429.880781 -63.329054) (xy 429.87671 -63.273432) (xy 427.507654 -63.273432)
			(xy 427.507654 -64.102234) (xy 427.687484 -64.102234) (xy 427.691555 -64.046612) (xy 427.703681 -63.992175)
			(xy 427.723604 -63.940084) (xy 427.7509 -63.891449) (xy 427.784986 -63.847306) (xy 427.825135 -63.808597)
			(xy 427.870493 -63.776146) (xy 427.920093 -63.750645) (xy 427.972877 -63.732638) (xy 428.02772 -63.722508)
			(xy 428.083454 -63.720471) (xy 428.138891 -63.726571) (xy 428.192848 -63.740677) (xy 428.244177 -63.762489)
			(xy 428.291783 -63.791543) (xy 428.334651 -63.827218) (xy 428.371868 -63.868755) (xy 428.402641 -63.915268)
			(xy 428.426313 -63.965765) (xy 428.442381 -64.019172) (xy 428.450501 -64.074348) (xy 428.45101 -64.102234)
			(xy 428.450501 -64.13012) (xy 428.442381 -64.185296) (xy 428.426313 -64.238703) (xy 428.402641 -64.2892)
			(xy 428.387363 -64.312292) (xy 431.365912 -64.312292) (xy 431.369983 -64.25667) (xy 431.382109 -64.202233)
			(xy 431.402032 -64.150142) (xy 431.429328 -64.101507) (xy 431.463414 -64.057364) (xy 431.503563 -64.018655)
			(xy 431.548921 -63.986204) (xy 431.598521 -63.960703) (xy 431.651305 -63.942696) (xy 431.706148 -63.932566)
			(xy 431.761882 -63.930529) (xy 431.817319 -63.936629) (xy 431.871276 -63.950735) (xy 431.922605 -63.972547)
			(xy 431.970211 -64.001601) (xy 432.013079 -64.037276) (xy 432.050296 -64.078813) (xy 432.081069 -64.125326)
			(xy 432.104741 -64.175823) (xy 432.120809 -64.22923) (xy 432.128929 -64.284406) (xy 432.129438 -64.312292)
			(xy 432.128929 -64.340178) (xy 432.120809 -64.395354) (xy 432.104741 -64.448761) (xy 432.081069 -64.499258)
			(xy 432.050296 -64.545771) (xy 432.013079 -64.587308) (xy 431.970211 -64.622983) (xy 431.922605 -64.652037)
			(xy 431.871276 -64.673849) (xy 431.817319 -64.687955) (xy 431.761882 -64.694055) (xy 431.706148 -64.692018)
			(xy 431.651305 -64.681888) (xy 431.598521 -64.663881) (xy 431.548921 -64.63838) (xy 431.503563 -64.605929)
			(xy 431.463414 -64.56722) (xy 431.429328 -64.523077) (xy 431.402032 -64.474442) (xy 431.382109 -64.422351)
			(xy 431.369983 -64.367914) (xy 431.365912 -64.312292) (xy 428.387363 -64.312292) (xy 428.371868 -64.335713)
			(xy 428.334651 -64.37725) (xy 428.291783 -64.412925) (xy 428.244177 -64.441979) (xy 428.192848 -64.463791)
			(xy 428.138891 -64.477897) (xy 428.083454 -64.483997) (xy 428.02772 -64.48196) (xy 427.972877 -64.47183)
			(xy 427.920093 -64.453823) (xy 427.870493 -64.428322) (xy 427.825135 -64.395871) (xy 427.784986 -64.357162)
			(xy 427.7509 -64.313019) (xy 427.723604 -64.264384) (xy 427.703681 -64.212293) (xy 427.691555 -64.157856)
			(xy 427.687484 -64.102234) (xy 427.507654 -64.102234) (xy 427.507654 -65.124076) (xy 432.407312 -65.124076)
			(xy 432.411383 -65.068454) (xy 432.423509 -65.014017) (xy 432.443432 -64.961926) (xy 432.470728 -64.913291)
			(xy 432.504814 -64.869148) (xy 432.544963 -64.830439) (xy 432.590321 -64.797988) (xy 432.639921 -64.772487)
			(xy 432.692705 -64.75448) (xy 432.747548 -64.74435) (xy 432.803282 -64.742313) (xy 432.858719 -64.748413)
			(xy 432.912676 -64.762519) (xy 432.964005 -64.784331) (xy 433.011611 -64.813385) (xy 433.054479 -64.84906)
			(xy 433.091696 -64.890597) (xy 433.122469 -64.93711) (xy 433.146141 -64.987607) (xy 433.162209 -65.041014)
			(xy 433.170329 -65.09619) (xy 433.170838 -65.124076) (xy 433.170329 -65.151962) (xy 433.169162 -65.15989)
			(xy 445.41643 -65.15989) (xy 445.420501 -65.104268) (xy 445.432627 -65.049831) (xy 445.45255 -64.99774)
			(xy 445.479846 -64.949105) (xy 445.513932 -64.904962) (xy 445.554081 -64.866253) (xy 445.599439 -64.833802)
			(xy 445.649039 -64.808301) (xy 445.701823 -64.790294) (xy 445.756666 -64.780164) (xy 445.8124 -64.778127)
			(xy 445.867837 -64.784227) (xy 445.921794 -64.798333) (xy 445.973123 -64.820145) (xy 446.020729 -64.849199)
			(xy 446.063597 -64.884874) (xy 446.100814 -64.926411) (xy 446.131587 -64.972924) (xy 446.155259 -65.023421)
			(xy 446.171327 -65.076828) (xy 446.179447 -65.132004) (xy 446.179956 -65.15989) (xy 446.179447 -65.187776)
			(xy 446.171327 -65.242952) (xy 446.155259 -65.296359) (xy 446.131587 -65.346856) (xy 446.100814 -65.393369)
			(xy 446.063597 -65.434906) (xy 446.020729 -65.470581) (xy 445.973123 -65.499635) (xy 445.921794 -65.521447)
			(xy 445.867837 -65.535553) (xy 445.8124 -65.541653) (xy 445.756666 -65.539616) (xy 445.701823 -65.529486)
			(xy 445.649039 -65.511479) (xy 445.599439 -65.485978) (xy 445.554081 -65.453527) (xy 445.513932 -65.414818)
			(xy 445.479846 -65.370675) (xy 445.45255 -65.32204) (xy 445.432627 -65.269949) (xy 445.420501 -65.215512)
			(xy 445.41643 -65.15989) (xy 433.169162 -65.15989) (xy 433.162209 -65.207138) (xy 433.146141 -65.260545)
			(xy 433.122469 -65.311042) (xy 433.091696 -65.357555) (xy 433.054479 -65.399092) (xy 433.011611 -65.434767)
			(xy 432.964005 -65.463821) (xy 432.912676 -65.485633) (xy 432.858719 -65.499739) (xy 432.803282 -65.505839)
			(xy 432.747548 -65.503802) (xy 432.692705 -65.493672) (xy 432.639921 -65.475665) (xy 432.590321 -65.450164)
			(xy 432.544963 -65.417713) (xy 432.504814 -65.379004) (xy 432.470728 -65.334861) (xy 432.443432 -65.286226)
			(xy 432.423509 -65.234135) (xy 432.411383 -65.179698) (xy 432.407312 -65.124076) (xy 427.507654 -65.124076)
			(xy 427.507654 -65.75552) (xy 440.646564 -65.75552) (xy 440.650635 -65.699898) (xy 440.662761 -65.645461)
			(xy 440.682684 -65.59337) (xy 440.70998 -65.544735) (xy 440.744066 -65.500592) (xy 440.784215 -65.461883)
			(xy 440.829573 -65.429432) (xy 440.879173 -65.403931) (xy 440.931957 -65.385924) (xy 440.9868 -65.375794)
			(xy 441.042534 -65.373757) (xy 441.097971 -65.379857) (xy 441.151928 -65.393963) (xy 441.203257 -65.415775)
			(xy 441.250863 -65.444829) (xy 441.293731 -65.480504) (xy 441.330948 -65.522041) (xy 441.361721 -65.568554)
			(xy 441.385393 -65.619051) (xy 441.401461 -65.672458) (xy 441.409581 -65.727634) (xy 441.41009 -65.75552)
			(xy 441.409581 -65.783406) (xy 441.401461 -65.838582) (xy 441.385393 -65.891989) (xy 441.361721 -65.942486)
			(xy 441.330948 -65.988999) (xy 441.293731 -66.030536) (xy 441.250863 -66.066211) (xy 441.203257 -66.095265)
			(xy 441.151928 -66.117077) (xy 441.097971 -66.131183) (xy 441.042534 -66.137283) (xy 440.9868 -66.135246)
			(xy 440.931957 -66.125116) (xy 440.879173 -66.107109) (xy 440.829573 -66.081608) (xy 440.784215 -66.049157)
			(xy 440.744066 -66.010448) (xy 440.70998 -65.966305) (xy 440.682684 -65.91767) (xy 440.662761 -65.865579)
			(xy 440.650635 -65.811142) (xy 440.646564 -65.75552) (xy 427.507654 -65.75552) (xy 427.507654 -67.488054)
			(xy 445.079118 -67.488054) (xy 445.083189 -67.432432) (xy 445.095315 -67.377995) (xy 445.115238 -67.325904)
			(xy 445.142534 -67.277269) (xy 445.17662 -67.233126) (xy 445.216769 -67.194417) (xy 445.262127 -67.161966)
			(xy 445.311727 -67.136465) (xy 445.364511 -67.118458) (xy 445.419354 -67.108328) (xy 445.475088 -67.106291)
			(xy 445.530525 -67.112391) (xy 445.584482 -67.126497) (xy 445.635811 -67.148309) (xy 445.683417 -67.177363)
			(xy 445.726285 -67.213038) (xy 445.763502 -67.254575) (xy 445.794275 -67.301088) (xy 445.817947 -67.351585)
			(xy 445.834015 -67.404992) (xy 445.842135 -67.460168) (xy 445.842644 -67.488054) (xy 445.842135 -67.51594)
			(xy 445.834015 -67.571116) (xy 445.817947 -67.624523) (xy 445.794275 -67.67502) (xy 445.763502 -67.721533)
			(xy 445.726285 -67.76307) (xy 445.683417 -67.798745) (xy 445.635811 -67.827799) (xy 445.584482 -67.849611)
			(xy 445.530525 -67.863717) (xy 445.475088 -67.869817) (xy 445.419354 -67.86778) (xy 445.364511 -67.85765)
			(xy 445.311727 -67.839643) (xy 445.262127 -67.814142) (xy 445.216769 -67.781691) (xy 445.17662 -67.742982)
			(xy 445.142534 -67.698839) (xy 445.115238 -67.650204) (xy 445.095315 -67.598113) (xy 445.083189 -67.543676)
			(xy 445.079118 -67.488054) (xy 427.507654 -67.488054) (xy 427.507654 -69.9516) (xy 427.50811 -69.961479)
			(xy 427.515543 -69.979787) (xy 427.522132 -69.98716) (xy 427.522386 -69.987414) (xy 427.698662 -70.16369)
			(xy 427.69917 -70.164198) (xy 427.706549 -70.170784) (xy 427.724849 -70.178236) (xy 427.73473 -70.178676)
		)
		(stroke
			(width 0)
			(type solid)
		)
		(fill yes)
		(layer "In9.Cu")
		(net "P12V_SSD15_R")
	)
	(gr_poly
		(pts
			(xy 304.67808 -70.178676) (xy 304.688143 -70.178238) (xy 304.706724 -70.1705) (xy 304.714148 -70.16369)
			(xy 305.040284 -69.837554) (xy 305.040792 -69.837046) (xy 305.04737 -69.829663) (xy 305.054814 -69.811364)
			(xy 305.05527 -69.801486) (xy 305.05527 -67.91579) (xy 305.054873 -67.906267) (xy 305.047918 -67.888537)
			(xy 305.03497 -67.87457) (xy 305.026568 -67.87007) (xy 304.93081 -67.823842) (xy 304.902108 -67.827144)
			(xy 304.890424 -67.836288) (xy 304.870112 -67.851901) (xy 304.826097 -67.878119) (xy 304.778968 -67.898206)
			(xy 304.729574 -67.911802) (xy 304.678804 -67.91866) (xy 304.653188 -67.919092) (xy 304.625938 -67.918605)
			(xy 304.571994 -67.910847) (xy 304.519703 -67.895492) (xy 304.47013 -67.872851) (xy 304.424283 -67.843386)
			(xy 304.383096 -67.807696) (xy 304.347407 -67.766508) (xy 304.317943 -67.72066) (xy 304.295304 -67.671085)
			(xy 304.27995 -67.618794) (xy 304.272194 -67.56485) (xy 304.272194 -67.51035) (xy 304.27995 -67.456406)
			(xy 304.295304 -67.404115) (xy 304.317943 -67.35454) (xy 304.347407 -67.308692) (xy 304.383096 -67.267504)
			(xy 304.424283 -67.231814) (xy 304.47013 -67.202349) (xy 304.519703 -67.179708) (xy 304.571994 -67.164353)
			(xy 304.625938 -67.156595) (xy 304.653188 -67.156076) (xy 304.678805 -67.15649) (xy 304.729576 -67.16335)
			(xy 304.778972 -67.176949) (xy 304.826101 -67.19704) (xy 304.870115 -67.223262) (xy 304.890424 -67.23888)
			(xy 304.902108 -67.248024) (xy 304.93081 -67.251326) (xy 305.026568 -67.205098) (xy 305.034968 -67.200597)
			(xy 305.047911 -67.186625) (xy 305.054875 -67.1689) (xy 305.05527 -67.159378) (xy 305.05527 -65.506854)
			(xy 305.041554 -65.483486) (xy 305.030124 -65.476628) (xy 305.029616 -65.476628) (xy 304.956464 -65.433702)
			(xy 304.952071 -65.431321) (xy 304.942604 -65.42813) (xy 304.937668 -65.427352) (xy 304.927254 -65.426082)
			(xy 304.903632 -65.432432) (xy 304.898044 -65.43548) (xy 304.869759 -65.450257) (xy 304.809483 -65.471206)
			(xy 304.746562 -65.481833) (xy 304.714656 -65.48247) (xy 304.714402 -65.48247) (xy 304.687152 -65.482007)
			(xy 304.633206 -65.474251) (xy 304.580913 -65.458897) (xy 304.531338 -65.436256) (xy 304.485489 -65.406791)
			(xy 304.4443 -65.371101) (xy 304.40861 -65.329913) (xy 304.379144 -65.284064) (xy 304.356504 -65.234489)
			(xy 304.341149 -65.182196) (xy 304.333393 -65.12825) (xy 304.333393 -65.07375) (xy 304.341149 -65.019804)
			(xy 304.356504 -64.967511) (xy 304.379144 -64.917936) (xy 304.40861 -64.872087) (xy 304.4443 -64.830899)
			(xy 304.485489 -64.795209) (xy 304.531338 -64.765744) (xy 304.580913 -64.743103) (xy 304.633206 -64.727749)
			(xy 304.687152 -64.719993) (xy 304.714402 -64.719454) (xy 304.714656 -64.719454) (xy 304.746559 -64.720122)
			(xy 304.809471 -64.730764) (xy 304.869747 -64.751695) (xy 304.898044 -64.766444) (xy 304.903632 -64.769492)
			(xy 304.917348 -64.773302) (xy 304.922334 -64.774508) (xy 304.93257 -64.775139) (xy 304.937668 -64.774572)
			(xy 304.947574 -64.773302) (xy 305.02987 -64.725296) (xy 305.030632 -64.724788) (xy 305.037911 -64.719974)
			(xy 305.04896 -64.706481) (xy 305.054867 -64.690072) (xy 305.05527 -64.681354) (xy 305.05527 -52.622958)
			(xy 305.053492 -52.616608) (xy 305.047433 -52.592357) (xy 305.040936 -52.542795) (xy 305.040538 -52.517802)
			(xy 305.040538 -52.51577) (xy 305.041003 -52.491159) (xy 305.0475 -52.442363) (xy 305.053492 -52.418488)
			(xy 305.05527 -52.411884) (xy 305.05527 -51.455828) (xy 305.055774 -51.445777) (xy 305.063493 -51.427214)
			(xy 305.070256 -51.41976) (xy 305.17719 -51.312826) (xy 305.184587 -51.305975) (xy 305.203185 -51.298233)
			(xy 305.213258 -51.29784) (xy 305.90363 -51.29784) (xy 305.912012 -51.297078) (xy 305.919615 -51.295561)
			(xy 305.933445 -51.28857) (xy 305.93919 -51.283362) (xy 306.004214 -51.218338) (xy 306.01106 -51.21094)
			(xy 306.018785 -51.192341) (xy 306.0192 -51.18227) (xy 306.0192 -49.20615) (xy 306.018689 -49.196247)
			(xy 306.011122 -49.17794) (xy 306.004468 -49.17059) (xy 306.001166 -49.167034) (xy 305.933602 -49.120044)
			(xy 305.927102 -49.115861) (xy 305.912369 -49.111207) (xy 305.904646 -49.1109) (xy 305.882548 -49.1109)
			(xy 305.874674 -49.113694) (xy 305.844489 -49.123447) (xy 305.781929 -49.133915) (xy 305.750214 -49.134522)
			(xy 305.74615 -49.134522) (xy 305.71909 -49.133761) (xy 305.665585 -49.125539) (xy 305.613779 -49.109836)
			(xy 305.564714 -49.086965) (xy 305.519376 -49.057388) (xy 305.478674 -49.021697) (xy 305.443427 -48.980611)
			(xy 305.414343 -48.934955) (xy 305.392006 -48.885645) (xy 305.376865 -48.833672) (xy 305.369224 -48.780081)
			(xy 305.368706 -48.753014) (xy 305.369168 -48.725761) (xy 305.376924 -48.671809) (xy 305.392279 -48.61951)
			(xy 305.414921 -48.569929) (xy 305.444389 -48.524076) (xy 305.480082 -48.482882) (xy 305.521276 -48.447189)
			(xy 305.567129 -48.417721) (xy 305.61671 -48.395079) (xy 305.669009 -48.379724) (xy 305.722961 -48.371968)
			(xy 305.750214 -48.371506) (xy 305.750976 -48.371506) (xy 305.784592 -48.372264) (xy 305.850765 -48.384153)
			(xy 305.882548 -48.395128) (xy 305.894232 -48.399446) (xy 305.91887 -48.396398) (xy 305.997356 -48.341534)
			(xy 306.004468 -48.335692) (xy 306.004468 -48.335438) (xy 306.011126 -48.328085) (xy 306.018725 -48.309784)
			(xy 306.0192 -48.299878) (xy 306.0192 -41.954704) (xy 306.018819 -41.945872) (xy 306.01284 -41.92925)
			(xy 306.007516 -41.922192) (xy 306.005992 -41.920414) (xy 305.123596 -41.038018) (xy 305.116484 -41.030652)
			(xy 305.097688 -41.023032) (xy 303.316132 -41.023032) (xy 303.307435 -41.023392) (xy 303.291046 -41.02922)
			(xy 303.277542 -41.040184) (xy 303.272698 -41.047416) (xy 303.22774 -41.121584) (xy 303.223676 -41.13022)
			(xy 303.220349 -41.140526) (xy 303.221782 -41.162115) (xy 303.22647 -41.171876) (xy 303.227232 -41.1734)
			(xy 303.23155 -41.18229) (xy 303.243628 -41.208261) (xy 303.26074 -41.262919) (xy 303.26951 -41.319517)
			(xy 303.270158 -41.348152) (xy 303.270158 -41.34866) (xy 303.270158 -41.35501) (xy 303.269247 -41.383073)
			(xy 303.260202 -41.438487) (xy 303.243132 -41.491977) (xy 303.218406 -41.542387) (xy 303.186559 -41.588629)
			(xy 303.167796 -41.609518) (xy 303.167542 -41.609772) (xy 303.161066 -41.617125) (xy 303.153762 -41.635288)
			(xy 303.153318 -41.645078) (xy 303.153318 -41.724072) (xy 303.160176 -41.741852) (xy 303.167034 -41.748964)
			(xy 303.186301 -41.770292) (xy 303.218858 -41.817655) (xy 303.243942 -41.869366) (xy 303.260987 -41.924255)
			(xy 303.269605 -41.981079) (xy 303.269603 -42.038553) (xy 303.260979 -42.095376) (xy 303.24393 -42.150263)
			(xy 303.218842 -42.201972) (xy 303.18628 -42.249333) (xy 303.167034 -42.27068) (xy 303.160176 -42.277792)
			(xy 303.153318 -42.295572) (xy 303.153318 -42.384472) (xy 303.160176 -42.402252) (xy 303.167034 -42.409364)
			(xy 303.186301 -42.430693) (xy 303.218859 -42.478057) (xy 303.243943 -42.529769) (xy 303.260987 -42.584659)
			(xy 303.269605 -42.641484) (xy 303.270158 -42.670222) (xy 303.269685 -42.697591) (xy 303.261857 -42.751767)
			(xy 303.246366 -42.804268) (xy 303.22353 -42.854016) (xy 303.193818 -42.899988) (xy 303.176178 -42.92092)
			(xy 303.170082 -42.928032) (xy 303.163732 -42.944796) (xy 303.163732 -43.030648) (xy 303.170082 -43.047412)
			(xy 303.176178 -43.054524) (xy 303.19382 -43.075455) (xy 303.223544 -43.121422) (xy 303.246386 -43.171169)
			(xy 303.261874 -43.223672) (xy 303.269689 -43.277852) (xy 303.270158 -43.305222) (xy 303.269672 -43.332473)
			(xy 303.261916 -43.386421) (xy 303.246561 -43.438716) (xy 303.223919 -43.488293) (xy 303.194453 -43.534143)
			(xy 303.158762 -43.575334) (xy 303.117571 -43.611025) (xy 303.071721 -43.640491) (xy 303.022144 -43.663133)
			(xy 302.969849 -43.678488) (xy 302.915901 -43.686244) (xy 302.861399 -43.686244) (xy 302.807451 -43.678488)
			(xy 302.755156 -43.663133) (xy 302.705579 -43.640491) (xy 302.659729 -43.611025) (xy 302.618538 -43.575334)
			(xy 302.582847 -43.534143) (xy 302.553381 -43.488293) (xy 302.530739 -43.438716) (xy 302.515384 -43.386421)
			(xy 302.507628 -43.332473) (xy 302.507142 -43.305222) (xy 302.507619 -43.277854) (xy 302.515454 -43.223682)
			(xy 302.530951 -43.171186) (xy 302.553792 -43.121444) (xy 302.583508 -43.075477) (xy 302.601122 -43.054524)
			(xy 302.607218 -43.047412) (xy 302.613568 -43.030648) (xy 302.613568 -42.944796) (xy 302.607218 -42.928032)
			(xy 302.601122 -42.92092) (xy 302.583478 -42.899989) (xy 302.553748 -42.854024) (xy 302.530901 -42.804277)
			(xy 302.515407 -42.751774) (xy 302.507585 -42.697593) (xy 302.507142 -42.670222) (xy 302.507661 -42.641483)
			(xy 302.516282 -42.584654) (xy 302.533331 -42.529762) (xy 302.558423 -42.478049) (xy 302.590989 -42.430686)
			(xy 302.610266 -42.409364) (xy 302.617124 -42.402252) (xy 302.623982 -42.384472) (xy 302.623982 -42.295572)
			(xy 302.617124 -42.277792) (xy 302.610266 -42.27068) (xy 302.590996 -42.249352) (xy 302.558432 -42.201987)
			(xy 302.533342 -42.150275) (xy 302.516291 -42.095383) (xy 302.507667 -42.038555) (xy 302.507665 -41.981077)
			(xy 302.516284 -41.924248) (xy 302.53333 -41.869355) (xy 302.558416 -41.81764) (xy 302.590976 -41.770273)
			(xy 302.610266 -41.748964) (xy 302.617124 -41.741852) (xy 302.623982 -41.724072) (xy 302.623982 -41.635172)
			(xy 302.617124 -41.617646) (xy 302.610266 -41.61028) (xy 302.591465 -41.589487) (xy 302.559533 -41.543415)
			(xy 302.534676 -41.49317) (xy 302.517428 -41.439833) (xy 302.508159 -41.384548) (xy 302.507142 -41.356534)
			(xy 302.507142 -41.349422) (xy 302.507654 -41.320528) (xy 302.51634 -41.263399) (xy 302.533561 -41.208238)
			(xy 302.54575 -41.182036) (xy 302.553116 -41.166542) (xy 302.556177 -41.157735) (xy 302.556442 -41.139107)
			(xy 302.553624 -41.13022) (xy 302.54956 -41.121584) (xy 302.504602 -41.04767) (xy 302.497744 -41.035986)
			(xy 302.47463 -41.023032) (xy 301.554134 -41.023032) (xy 301.542512 -41.023603) (xy 301.521616 -41.03379)
			(xy 301.514002 -41.04259) (xy 301.45736 -41.11498) (xy 301.452534 -41.137586) (xy 301.455328 -41.14927)
			(xy 301.460649 -41.171949) (xy 301.466379 -41.21818) (xy 301.466758 -41.241472) (xy 301.466297 -41.268725)
			(xy 301.458543 -41.322676) (xy 301.443188 -41.374974) (xy 301.420547 -41.424555) (xy 301.391079 -41.470408)
			(xy 301.355384 -41.5116) (xy 301.31419 -41.547292) (xy 301.268336 -41.576757) (xy 301.218754 -41.599396)
			(xy 301.166455 -41.614747) (xy 301.112503 -41.622498) (xy 301.08525 -41.62298) (xy 301.05651 -41.622463)
			(xy 300.999678 -41.613846) (xy 300.944783 -41.596801) (xy 300.893067 -41.571713) (xy 300.845699 -41.539149)
			(xy 300.824392 -41.519856) (xy 300.81728 -41.512998) (xy 300.7995 -41.50614) (xy 300.7106 -41.50614)
			(xy 300.69282 -41.512998) (xy 300.685708 -41.519856) (xy 300.66438 -41.539126) (xy 300.617017 -41.571691)
			(xy 300.565306 -41.596784) (xy 300.510416 -41.613837) (xy 300.453589 -41.622465) (xy 300.42485 -41.62298)
			(xy 300.397596 -41.62252) (xy 300.343641 -41.614769) (xy 300.291338 -41.599417) (xy 300.241754 -41.576777)
			(xy 300.195896 -41.54731) (xy 300.1547 -41.511616) (xy 300.119004 -41.470421) (xy 300.089534 -41.424566)
			(xy 300.066891 -41.374982) (xy 300.051536 -41.322681) (xy 300.043782 -41.268726) (xy 300.043342 -41.241472)
			(xy 300.043721 -41.21818) (xy 300.049451 -41.171949) (xy 300.054772 -41.14927) (xy 300.057566 -41.137586)
			(xy 300.05274 -41.11498) (xy 299.996098 -41.04259) (xy 299.988506 -41.033766) (xy 299.967595 -41.023594)
			(xy 299.955966 -41.023032) (xy 296.108374 -41.023032) (xy 296.098307 -41.023461) (xy 296.079712 -41.031185)
			(xy 296.072306 -41.038018) (xy 295.905682 -41.204642) (xy 295.899006 -41.212054) (xy 295.891442 -41.230491)
			(xy 295.89095 -41.240456) (xy 295.89095 -43.73626) (xy 304.412902 -43.73626) (xy 304.416973 -43.680638)
			(xy 304.429099 -43.626201) (xy 304.449022 -43.57411) (xy 304.476318 -43.525475) (xy 304.510404 -43.481332)
			(xy 304.550553 -43.442623) (xy 304.595911 -43.410172) (xy 304.645511 -43.384671) (xy 304.698295 -43.366664)
			(xy 304.753138 -43.356534) (xy 304.808872 -43.354497) (xy 304.864309 -43.360597) (xy 304.918266 -43.374703)
			(xy 304.969595 -43.396515) (xy 305.017201 -43.425569) (xy 305.060069 -43.461244) (xy 305.097286 -43.502781)
			(xy 305.128059 -43.549294) (xy 305.151731 -43.599791) (xy 305.167799 -43.653198) (xy 305.175919 -43.708374)
			(xy 305.176428 -43.73626) (xy 305.175919 -43.764146) (xy 305.167799 -43.819322) (xy 305.151731 -43.872729)
			(xy 305.128059 -43.923226) (xy 305.097286 -43.969739) (xy 305.060069 -44.011276) (xy 305.017201 -44.046951)
			(xy 304.969595 -44.076005) (xy 304.918266 -44.097817) (xy 304.864309 -44.111923) (xy 304.808872 -44.118023)
			(xy 304.753138 -44.115986) (xy 304.698295 -44.105856) (xy 304.645511 -44.087849) (xy 304.595911 -44.062348)
			(xy 304.550553 -44.029897) (xy 304.510404 -43.991188) (xy 304.476318 -43.947045) (xy 304.449022 -43.89841)
			(xy 304.429099 -43.846319) (xy 304.416973 -43.791882) (xy 304.412902 -43.73626) (xy 295.89095 -43.73626)
			(xy 295.89095 -45.114464) (xy 304.265328 -45.114464) (xy 304.269399 -45.058842) (xy 304.281525 -45.004405)
			(xy 304.301448 -44.952314) (xy 304.328744 -44.903679) (xy 304.36283 -44.859536) (xy 304.402979 -44.820827)
			(xy 304.448337 -44.788376) (xy 304.497937 -44.762875) (xy 304.550721 -44.744868) (xy 304.605564 -44.734738)
			(xy 304.661298 -44.732701) (xy 304.716735 -44.738801) (xy 304.770692 -44.752907) (xy 304.822021 -44.774719)
			(xy 304.869627 -44.803773) (xy 304.912495 -44.839448) (xy 304.949712 -44.880985) (xy 304.980485 -44.927498)
			(xy 305.004157 -44.977995) (xy 305.020225 -45.031402) (xy 305.028345 -45.086578) (xy 305.028854 -45.114464)
			(xy 305.028345 -45.14235) (xy 305.020225 -45.197526) (xy 305.004157 -45.250933) (xy 304.980485 -45.30143)
			(xy 304.949712 -45.347943) (xy 304.912495 -45.38948) (xy 304.869627 -45.425155) (xy 304.822021 -45.454209)
			(xy 304.770692 -45.476021) (xy 304.716735 -45.490127) (xy 304.661298 -45.496227) (xy 304.605564 -45.49419)
			(xy 304.550721 -45.48406) (xy 304.497937 -45.466053) (xy 304.448337 -45.440552) (xy 304.402979 -45.408101)
			(xy 304.36283 -45.369392) (xy 304.328744 -45.325249) (xy 304.301448 -45.276614) (xy 304.281525 -45.224523)
			(xy 304.269399 -45.170086) (xy 304.265328 -45.114464) (xy 295.89095 -45.114464) (xy 295.89095 -46.893226)
			(xy 304.537108 -46.893226) (xy 304.541179 -46.837604) (xy 304.553305 -46.783167) (xy 304.573228 -46.731076)
			(xy 304.600524 -46.682441) (xy 304.63461 -46.638298) (xy 304.674759 -46.599589) (xy 304.720117 -46.567138)
			(xy 304.769717 -46.541637) (xy 304.822501 -46.52363) (xy 304.877344 -46.5135) (xy 304.933078 -46.511463)
			(xy 304.988515 -46.517563) (xy 305.042472 -46.531669) (xy 305.093801 -46.553481) (xy 305.141407 -46.582535)
			(xy 305.184275 -46.61821) (xy 305.221492 -46.659747) (xy 305.252265 -46.70626) (xy 305.275937 -46.756757)
			(xy 305.292005 -46.810164) (xy 305.300125 -46.86534) (xy 305.300634 -46.893226) (xy 305.300125 -46.921112)
			(xy 305.292005 -46.976288) (xy 305.275937 -47.029695) (xy 305.252265 -47.080192) (xy 305.221492 -47.126705)
			(xy 305.184275 -47.168242) (xy 305.141407 -47.203917) (xy 305.093801 -47.232971) (xy 305.042472 -47.254783)
			(xy 304.988515 -47.268889) (xy 304.933078 -47.274989) (xy 304.877344 -47.272952) (xy 304.822501 -47.262822)
			(xy 304.769717 -47.244815) (xy 304.720117 -47.219314) (xy 304.674759 -47.186863) (xy 304.63461 -47.148154)
			(xy 304.600524 -47.104011) (xy 304.573228 -47.055376) (xy 304.553305 -47.003285) (xy 304.541179 -46.948848)
			(xy 304.537108 -46.893226) (xy 295.89095 -46.893226) (xy 295.89095 -47.936658) (xy 302.852836 -47.936658)
			(xy 302.853322 -47.909407) (xy 302.861078 -47.855459) (xy 302.876433 -47.803164) (xy 302.899075 -47.753587)
			(xy 302.928541 -47.707737) (xy 302.964232 -47.666546) (xy 303.005423 -47.630855) (xy 303.051273 -47.601389)
			(xy 303.10085 -47.578747) (xy 303.153145 -47.563392) (xy 303.207093 -47.555636) (xy 303.261595 -47.555636)
			(xy 303.315543 -47.563392) (xy 303.367838 -47.578747) (xy 303.417415 -47.601389) (xy 303.463265 -47.630855)
			(xy 303.504456 -47.666546) (xy 303.540147 -47.707737) (xy 303.569613 -47.753587) (xy 303.592255 -47.803164)
			(xy 303.60761 -47.855459) (xy 303.615366 -47.909407) (xy 303.615852 -47.936658) (xy 303.61539 -47.962999)
			(xy 303.60814 -48.015179) (xy 303.593785 -48.065867) (xy 303.572598 -48.114101) (xy 303.544982 -48.158964)
			(xy 303.51146 -48.199604) (xy 303.472669 -48.235251) (xy 303.45126 -48.250602) (xy 303.439433 -48.259296)
			(xy 303.420993 -48.28212) (xy 303.409806 -48.309247) (xy 303.406798 -48.338435) (xy 303.412215 -48.367273)
			(xy 303.425612 -48.393379) (xy 303.44588 -48.414596) (xy 303.458372 -48.422306) (xy 303.482907 -48.437002)
			(xy 303.527666 -48.472603) (xy 303.56661 -48.514486) (xy 303.598866 -48.561713) (xy 303.623712 -48.613225)
			(xy 303.640591 -48.667868) (xy 303.649125 -48.724419) (xy 303.649634 -48.753014) (xy 303.649148 -48.780265)
			(xy 303.641392 -48.834213) (xy 303.626037 -48.886508) (xy 303.603395 -48.936085) (xy 303.573929 -48.981935)
			(xy 303.538238 -49.023126) (xy 303.497047 -49.058817) (xy 303.451197 -49.088283) (xy 303.40162 -49.110925)
			(xy 303.349325 -49.12628) (xy 303.295377 -49.134036) (xy 303.240875 -49.134036) (xy 303.186927 -49.12628)
			(xy 303.134632 -49.110925) (xy 303.085055 -49.088283) (xy 303.039205 -49.058817) (xy 302.998014 -49.023126)
			(xy 302.962323 -48.981935) (xy 302.932857 -48.936085) (xy 302.910215 -48.886508) (xy 302.89486 -48.834213)
			(xy 302.887104 -48.780265) (xy 302.886618 -48.753014) (xy 302.887071 -48.726673) (xy 302.894325 -48.674493)
			(xy 302.908682 -48.623805) (xy 302.92987 -48.575572) (xy 302.957488 -48.530709) (xy 302.99101 -48.490068)
			(xy 303.0298 -48.454422) (xy 303.05121 -48.43907) (xy 303.063055 -48.430403) (xy 303.081482 -48.407569)
			(xy 303.092658 -48.380438) (xy 303.095661 -48.35125) (xy 303.090242 -48.322412) (xy 303.076849 -48.296304)
			(xy 303.056586 -48.275081) (xy 303.044098 -48.267366) (xy 303.019588 -48.252631) (xy 302.974831 -48.217035)
			(xy 302.935887 -48.175158) (xy 302.903629 -48.127938) (xy 302.878778 -48.076433) (xy 302.861893 -48.021796)
			(xy 302.85335 -47.965251) (xy 302.852836 -47.936658) (xy 295.89095 -47.936658) (xy 295.89095 -58.731404)
			(xy 297.720512 -58.731404) (xy 297.720977 -58.704034) (xy 297.728795 -58.649854) (xy 297.744284 -58.597351)
			(xy 297.767126 -58.547604) (xy 297.796851 -58.501638) (xy 297.814492 -58.480706) (xy 297.820588 -58.473594)
			(xy 297.826938 -58.456576) (xy 297.826938 -58.371232) (xy 297.820588 -58.354214) (xy 297.814492 -58.347102)
			(xy 297.796857 -58.326165) (xy 297.767134 -58.280197) (xy 297.744291 -58.230452) (xy 297.728796 -58.17795)
			(xy 297.720968 -58.123773) (xy 297.720967 -58.069033) (xy 297.728795 -58.014855) (xy 297.744289 -57.962354)
			(xy 297.767131 -57.912608) (xy 297.796853 -57.866639) (xy 297.814492 -57.845706) (xy 297.820588 -57.838594)
			(xy 297.826938 -57.821576) (xy 297.826938 -57.736232) (xy 297.820588 -57.719214) (xy 297.814492 -57.712102)
			(xy 297.796857 -57.691165) (xy 297.767134 -57.645197) (xy 297.744291 -57.595452) (xy 297.728796 -57.54295)
			(xy 297.720968 -57.488773) (xy 297.720967 -57.434033) (xy 297.728795 -57.379855) (xy 297.744289 -57.327354)
			(xy 297.767131 -57.277608) (xy 297.796853 -57.231639) (xy 297.814492 -57.210706) (xy 297.820588 -57.203594)
			(xy 297.826938 -57.186576) (xy 297.826938 -57.101232) (xy 297.820588 -57.084214) (xy 297.814492 -57.077102)
			(xy 297.796839 -57.056181) (xy 297.76713 -57.010205) (xy 297.744296 -56.960455) (xy 297.728809 -56.907952)
			(xy 297.720984 -56.853774) (xy 297.720512 -56.826404) (xy 297.720998 -56.799153) (xy 297.728754 -56.745205)
			(xy 297.744109 -56.69291) (xy 297.766751 -56.643333) (xy 297.796217 -56.597483) (xy 297.831908 -56.556292)
			(xy 297.873099 -56.520601) (xy 297.918949 -56.491135) (xy 297.968526 -56.468493) (xy 298.020821 -56.453138)
			(xy 298.074769 -56.445382) (xy 298.129271 -56.445382) (xy 298.183219 -56.453138) (xy 298.235514 -56.468493)
			(xy 298.285091 -56.491135) (xy 298.330941 -56.520601) (xy 298.372132 -56.556292) (xy 298.407823 -56.597483)
			(xy 298.437289 -56.643333) (xy 298.459931 -56.69291) (xy 298.475286 -56.745205) (xy 298.483042 -56.799153)
			(xy 298.483528 -56.826404) (xy 298.483082 -56.853775) (xy 298.475262 -56.907956) (xy 298.459769 -56.96046)
			(xy 298.436923 -57.010206) (xy 298.407192 -57.056172) (xy 298.389548 -57.077102) (xy 298.383452 -57.084214)
			(xy 298.377102 -57.101232) (xy 298.377102 -57.186576) (xy 298.383452 -57.203594) (xy 298.389548 -57.210706)
			(xy 298.407194 -57.231635) (xy 298.43692 -57.277603) (xy 298.459767 -57.32735) (xy 298.475264 -57.379852)
			(xy 298.483093 -57.434032) (xy 298.483092 -57.488774) (xy 298.475263 -57.542953) (xy 298.459765 -57.595456)
			(xy 298.436917 -57.645202) (xy 298.40719 -57.69117) (xy 298.389548 -57.712102) (xy 298.383452 -57.719214)
			(xy 298.377102 -57.736232) (xy 298.377102 -57.821576) (xy 298.383452 -57.838594) (xy 298.389548 -57.845706)
			(xy 298.407194 -57.866635) (xy 298.43692 -57.912603) (xy 298.459767 -57.96235) (xy 298.475264 -58.014852)
			(xy 298.483093 -58.069032) (xy 298.483092 -58.123774) (xy 298.475263 -58.177953) (xy 298.459765 -58.230456)
			(xy 298.436917 -58.280202) (xy 298.40719 -58.32617) (xy 298.389548 -58.347102) (xy 298.383452 -58.354214)
			(xy 298.377102 -58.371232) (xy 298.377102 -58.456576) (xy 298.383452 -58.473594) (xy 298.389548 -58.480706)
			(xy 298.407195 -58.501632) (xy 298.436908 -58.547605) (xy 298.459743 -58.597354) (xy 298.475232 -58.649857)
			(xy 298.483056 -58.704034) (xy 298.483528 -58.731404) (xy 298.483042 -58.758655) (xy 298.478378 -58.791094)
			(xy 300.376336 -58.791094) (xy 300.37679 -58.763723) (xy 300.384609 -58.709543) (xy 300.400101 -58.65704)
			(xy 300.422945 -58.607293) (xy 300.452673 -58.561327) (xy 300.470316 -58.540396) (xy 300.476412 -58.533284)
			(xy 300.482762 -58.516266) (xy 300.482762 -58.430922) (xy 300.476412 -58.413904) (xy 300.470316 -58.406792)
			(xy 300.45267 -58.385864) (xy 300.422946 -58.339895) (xy 300.400102 -58.290148) (xy 300.384607 -58.237645)
			(xy 300.376779 -58.183466) (xy 300.376779 -58.128725) (xy 300.384608 -58.074546) (xy 300.400105 -58.022044)
			(xy 300.422951 -57.972297) (xy 300.452675 -57.926329) (xy 300.470316 -57.905396) (xy 300.476412 -57.898284)
			(xy 300.482762 -57.881266) (xy 300.482762 -57.795922) (xy 300.476412 -57.778904) (xy 300.470316 -57.771792)
			(xy 300.452662 -57.750872) (xy 300.422952 -57.704896) (xy 300.400119 -57.655145) (xy 300.384631 -57.602642)
			(xy 300.376807 -57.548464) (xy 300.376336 -57.521094) (xy 300.376794 -57.494778) (xy 300.384011 -57.442644)
			(xy 300.398323 -57.391995) (xy 300.419456 -57.343793) (xy 300.447011 -57.298951) (xy 300.480465 -57.25832)
			(xy 300.499526 -57.24017) (xy 300.506932 -57.232652) (xy 300.515457 -57.21337) (xy 300.516036 -57.202832)
			(xy 300.516036 -57.128156) (xy 300.515479 -57.11761) (xy 300.506962 -57.098315) (xy 300.499526 -57.090818)
			(xy 300.48046 -57.072669) (xy 300.44698 -57.032053) (xy 300.419407 -56.987215) (xy 300.398266 -56.93901)
			(xy 300.383959 -56.888355) (xy 300.376758 -56.836213) (xy 300.376336 -56.809894) (xy 300.376822 -56.782643)
			(xy 300.384578 -56.728695) (xy 300.399933 -56.6764) (xy 300.422575 -56.626823) (xy 300.452041 -56.580973)
			(xy 300.487732 -56.539782) (xy 300.528923 -56.504091) (xy 300.574773 -56.474625) (xy 300.62435 -56.451983)
			(xy 300.676645 -56.436628) (xy 300.730593 -56.428872) (xy 300.785095 -56.428872) (xy 300.839043 -56.436628)
			(xy 300.891338 -56.451983) (xy 300.940915 -56.474625) (xy 300.986765 -56.504091) (xy 301.027956 -56.539782)
			(xy 301.063647 -56.580973) (xy 301.093113 -56.626823) (xy 301.115755 -56.6764) (xy 301.13111 -56.728695)
			(xy 301.138866 -56.782643) (xy 301.139352 -56.809894) (xy 301.138957 -56.836212) (xy 301.131727 -56.888349)
			(xy 301.117404 -56.938999) (xy 301.096258 -56.987201) (xy 301.068692 -57.032042) (xy 301.035228 -57.07267)
			(xy 301.016162 -57.090818) (xy 301.00876 -57.098339) (xy 301.000234 -57.117619) (xy 300.999652 -57.128156)
			(xy 300.999652 -57.202832) (xy 301.000219 -57.213377) (xy 301.008729 -57.232672) (xy 301.016162 -57.24017)
			(xy 301.03522 -57.258327) (xy 301.068701 -57.298942) (xy 301.096275 -57.343777) (xy 301.117418 -57.39198)
			(xy 301.131727 -57.442635) (xy 301.1351 -57.467053) (xy 301.318369 -57.467053) (xy 301.318369 -57.412547)
			(xy 301.326127 -57.358596) (xy 301.341483 -57.306299) (xy 301.364126 -57.256719) (xy 301.393595 -57.210866)
			(xy 301.42929 -57.169675) (xy 301.470484 -57.133982) (xy 301.516338 -57.104516) (xy 301.565919 -57.081876)
			(xy 301.618218 -57.066522) (xy 301.672169 -57.058768) (xy 301.699422 -57.058306) (xy 301.725738 -57.058763)
			(xy 301.777872 -57.065982) (xy 301.82852 -57.080294) (xy 301.876722 -57.101428) (xy 301.921564 -57.128983)
			(xy 301.962196 -57.162436) (xy 301.980346 -57.181496) (xy 301.987849 -57.188919) (xy 302.007143 -57.197431)
			(xy 302.017684 -57.198006) (xy 302.09236 -57.198006) (xy 302.102908 -57.197467) (xy 302.122204 -57.188939)
			(xy 302.129698 -57.181496) (xy 302.147833 -57.162417) (xy 302.188453 -57.128939) (xy 302.233294 -57.101369)
			(xy 302.281501 -57.08023) (xy 302.332159 -57.065925) (xy 302.384302 -57.058727) (xy 302.410622 -57.058306)
			(xy 302.437873 -57.058765) (xy 302.491821 -57.066525) (xy 302.526973 -57.076848) (xy 303.338484 -57.076848)
			(xy 303.338958 -57.049478) (xy 303.346771 -56.995298) (xy 303.362257 -56.942794) (xy 303.385097 -56.893047)
			(xy 303.414822 -56.847081) (xy 303.432464 -56.82615) (xy 303.43856 -56.819038) (xy 303.44491 -56.80202)
			(xy 303.44491 -56.716676) (xy 303.43856 -56.699658) (xy 303.432464 -56.692546) (xy 303.414827 -56.671612)
			(xy 303.385116 -56.625639) (xy 303.362281 -56.575892) (xy 303.346789 -56.523392) (xy 303.338959 -56.469217)
			(xy 303.338484 -56.441848) (xy 303.33897 -56.414597) (xy 303.346726 -56.360649) (xy 303.362081 -56.308354)
			(xy 303.384723 -56.258777) (xy 303.414189 -56.212927) (xy 303.44988 -56.171736) (xy 303.491071 -56.136045)
			(xy 303.536921 -56.106579) (xy 303.586498 -56.083937) (xy 303.638793 -56.068582) (xy 303.692741 -56.060826)
			(xy 303.747243 -56.060826) (xy 303.801191 -56.068582) (xy 303.853486 -56.083937) (xy 303.903063 -56.106579)
			(xy 303.948913 -56.136045) (xy 303.990104 -56.171736) (xy 304.025795 -56.212927) (xy 304.055261 -56.258777)
			(xy 304.077903 -56.308354) (xy 304.093258 -56.360649) (xy 304.101014 -56.414597) (xy 304.1015 -56.441848)
			(xy 304.101003 -56.469217) (xy 304.093193 -56.523395) (xy 304.077711 -56.575898) (xy 304.054876 -56.625645)
			(xy 304.025158 -56.671613) (xy 304.00752 -56.692546) (xy 304.001424 -56.699658) (xy 303.995074 -56.716676)
			(xy 303.995074 -56.80202) (xy 304.001424 -56.819038) (xy 304.00752 -56.82615) (xy 304.025152 -56.847088)
			(xy 304.054864 -56.893059) (xy 304.077701 -56.942805) (xy 304.093194 -56.995305) (xy 304.101025 -57.049479)
			(xy 304.1015 -57.076848) (xy 304.101014 -57.104099) (xy 304.093258 -57.158047) (xy 304.077903 -57.210342)
			(xy 304.055261 -57.259919) (xy 304.025795 -57.305769) (xy 303.990104 -57.34696) (xy 303.948913 -57.382651)
			(xy 303.903063 -57.412117) (xy 303.853486 -57.434759) (xy 303.801191 -57.450114) (xy 303.747243 -57.45787)
			(xy 303.692741 -57.45787) (xy 303.638793 -57.450114) (xy 303.586498 -57.434759) (xy 303.536921 -57.412117)
			(xy 303.491071 -57.382651) (xy 303.44988 -57.34696) (xy 303.414189 -57.305769) (xy 303.384723 -57.259919)
			(xy 303.362081 -57.210342) (xy 303.346726 -57.158047) (xy 303.33897 -57.104099) (xy 303.338484 -57.076848)
			(xy 302.526973 -57.076848) (xy 302.544115 -57.081882) (xy 302.593691 -57.104525) (xy 302.63954 -57.133993)
			(xy 302.680729 -57.169686) (xy 302.71642 -57.210877) (xy 302.745885 -57.256728) (xy 302.768525 -57.306306)
			(xy 302.78388 -57.358601) (xy 302.791636 -57.412549) (xy 302.791636 -57.467051) (xy 302.78388 -57.520999)
			(xy 302.768525 -57.573294) (xy 302.745885 -57.622872) (xy 302.71642 -57.668723) (xy 302.680729 -57.709914)
			(xy 302.63954 -57.745607) (xy 302.593691 -57.775075) (xy 302.544115 -57.797718) (xy 302.491821 -57.813075)
			(xy 302.437873 -57.820835) (xy 302.410622 -57.821322) (xy 302.384305 -57.820894) (xy 302.33217 -57.813668)
			(xy 302.281522 -57.799349) (xy 302.23332 -57.77821) (xy 302.188479 -57.750651) (xy 302.147848 -57.717194)
			(xy 302.129698 -57.698132) (xy 302.122175 -57.690732) (xy 302.102896 -57.682206) (xy 302.09236 -57.681622)
			(xy 302.017684 -57.681622) (xy 302.007131 -57.682123) (xy 301.987836 -57.690677) (xy 301.980346 -57.698132)
			(xy 301.962224 -57.717225) (xy 301.921603 -57.750704) (xy 301.87676 -57.778274) (xy 301.82855 -57.799411)
			(xy 301.777889 -57.813712) (xy 301.725743 -57.820905) (xy 301.699422 -57.821322) (xy 301.672169 -57.820832)
			(xy 301.618218 -57.813078) (xy 301.565919 -57.797724) (xy 301.516338 -57.775084) (xy 301.470484 -57.745618)
			(xy 301.42929 -57.709925) (xy 301.393595 -57.668734) (xy 301.364126 -57.622881) (xy 301.341483 -57.573301)
			(xy 301.326127 -57.521004) (xy 301.318369 -57.467053) (xy 301.1351 -57.467053) (xy 301.138929 -57.494776)
			(xy 301.139352 -57.521094) (xy 301.138894 -57.548465) (xy 301.131076 -57.602645) (xy 301.115586 -57.655148)
			(xy 301.092742 -57.704895) (xy 301.063015 -57.750861) (xy 301.045372 -57.771792) (xy 301.039276 -57.778904)
			(xy 301.032926 -57.795922) (xy 301.032926 -57.881266) (xy 301.039276 -57.898284) (xy 301.045372 -57.905396)
			(xy 301.063007 -57.926333) (xy 301.092732 -57.9723) (xy 301.115578 -58.022046) (xy 301.131075 -58.074547)
			(xy 301.138904 -58.128725) (xy 301.138904 -58.183466) (xy 301.131076 -58.237644) (xy 301.115581 -58.290146)
			(xy 301.092736 -58.339892) (xy 301.063012 -58.385859) (xy 301.045372 -58.406792) (xy 301.039276 -58.413904)
			(xy 301.032926 -58.430922) (xy 301.032926 -58.516266) (xy 301.039276 -58.533284) (xy 301.045372 -58.540396)
			(xy 301.063018 -58.561322) (xy 301.09273 -58.607296) (xy 301.115565 -58.657045) (xy 301.131054 -58.709547)
			(xy 301.13888 -58.763724) (xy 301.139352 -58.791094) (xy 301.138866 -58.818345) (xy 301.13111 -58.872293)
			(xy 301.130713 -58.873644) (xy 302.400462 -58.873644) (xy 302.400939 -58.846274) (xy 302.408752 -58.792095)
			(xy 302.424237 -58.739591) (xy 302.447077 -58.689844) (xy 302.476801 -58.643877) (xy 302.494442 -58.622946)
			(xy 302.500538 -58.615834) (xy 302.506888 -58.598816) (xy 302.506888 -58.513472) (xy 302.500538 -58.496454)
			(xy 302.494442 -58.489342) (xy 302.476816 -58.4684) (xy 302.4471 -58.42243) (xy 302.424261 -58.372685)
			(xy 302.408767 -58.320187) (xy 302.400937 -58.266013) (xy 302.400462 -58.238644) (xy 302.400948 -58.211393)
			(xy 302.408704 -58.157445) (xy 302.424059 -58.10515) (xy 302.446701 -58.055573) (xy 302.476167 -58.009723)
			(xy 302.511858 -57.968532) (xy 302.553049 -57.932841) (xy 302.598899 -57.903375) (xy 302.648476 -57.880733)
			(xy 302.700771 -57.865378) (xy 302.754719 -57.857622) (xy 302.809221 -57.857622) (xy 302.863169 -57.865378)
			(xy 302.915464 -57.880733) (xy 302.965041 -57.903375) (xy 303.010891 -57.932841) (xy 303.052082 -57.968532)
			(xy 303.087773 -58.009723) (xy 303.117239 -58.055573) (xy 303.139881 -58.10515) (xy 303.155236 -58.157445)
			(xy 303.162992 -58.211393) (xy 303.163478 -58.238644) (xy 303.162984 -58.266013) (xy 303.155174 -58.320191)
			(xy 303.139692 -58.372694) (xy 303.116856 -58.422442) (xy 303.087137 -58.46841) (xy 303.069498 -58.489342)
			(xy 303.063402 -58.496454) (xy 303.057052 -58.513472) (xy 303.057052 -58.598816) (xy 303.063402 -58.615834)
			(xy 303.069498 -58.622946) (xy 303.087125 -58.643888) (xy 303.116839 -58.689858) (xy 303.139677 -58.739603)
			(xy 303.155171 -58.792101) (xy 303.163002 -58.846275) (xy 303.163478 -58.873644) (xy 303.162992 -58.900895)
			(xy 303.155236 -58.954843) (xy 303.139881 -59.007138) (xy 303.117239 -59.056715) (xy 303.087773 -59.102565)
			(xy 303.052082 -59.143756) (xy 303.010891 -59.179447) (xy 302.965041 -59.208913) (xy 302.915464 -59.231555)
			(xy 302.863169 -59.24691) (xy 302.809221 -59.254666) (xy 302.754719 -59.254666) (xy 302.700771 -59.24691)
			(xy 302.648476 -59.231555) (xy 302.598899 -59.208913) (xy 302.553049 -59.179447) (xy 302.511858 -59.143756)
			(xy 302.476167 -59.102565) (xy 302.446701 -59.056715) (xy 302.424059 -59.007138) (xy 302.408704 -58.954843)
			(xy 302.400948 -58.900895) (xy 302.400462 -58.873644) (xy 301.130713 -58.873644) (xy 301.115755 -58.924588)
			(xy 301.093113 -58.974165) (xy 301.063647 -59.020015) (xy 301.027956 -59.061206) (xy 300.986765 -59.096897)
			(xy 300.940915 -59.126363) (xy 300.891338 -59.149005) (xy 300.839043 -59.16436) (xy 300.785095 -59.172116)
			(xy 300.730593 -59.172116) (xy 300.676645 -59.16436) (xy 300.62435 -59.149005) (xy 300.574773 -59.126363)
			(xy 300.528923 -59.096897) (xy 300.487732 -59.061206) (xy 300.452041 -59.020015) (xy 300.422575 -58.974165)
			(xy 300.399933 -58.924588) (xy 300.384578 -58.872293) (xy 300.376822 -58.818345) (xy 300.376336 -58.791094)
			(xy 298.478378 -58.791094) (xy 298.475286 -58.812603) (xy 298.459931 -58.864898) (xy 298.437289 -58.914475)
			(xy 298.407823 -58.960325) (xy 298.372132 -59.001516) (xy 298.330941 -59.037207) (xy 298.285091 -59.066673)
			(xy 298.235514 -59.089315) (xy 298.183219 -59.10467) (xy 298.129271 -59.112426) (xy 298.074769 -59.112426)
			(xy 298.020821 -59.10467) (xy 297.968526 -59.089315) (xy 297.918949 -59.066673) (xy 297.873099 -59.037207)
			(xy 297.831908 -59.001516) (xy 297.796217 -58.960325) (xy 297.766751 -58.914475) (xy 297.744109 -58.864898)
			(xy 297.728754 -58.812603) (xy 297.720998 -58.758655) (xy 297.720512 -58.731404) (xy 295.89095 -58.731404)
			(xy 295.89095 -60.126455) (xy 301.380049 -60.126455) (xy 301.380049 -60.071945) (xy 301.387808 -60.017989)
			(xy 301.403166 -59.965687) (xy 301.425812 -59.916103) (xy 301.455285 -59.870247) (xy 301.490984 -59.829053)
			(xy 301.532182 -59.793358) (xy 301.578042 -59.763891) (xy 301.627628 -59.741251) (xy 301.679932 -59.725898)
			(xy 301.733889 -59.718146) (xy 301.761144 -59.717686) (xy 301.788513 -59.718188) (xy 301.84269 -59.725998)
			(xy 301.895193 -59.741479) (xy 301.94494 -59.764312) (xy 301.990909 -59.794029) (xy 302.011842 -59.811666)
			(xy 302.018954 -59.817762) (xy 302.035972 -59.824112) (xy 302.121316 -59.824112) (xy 302.138334 -59.817762)
			(xy 302.145446 -59.811666) (xy 302.166379 -59.794025) (xy 302.212347 -59.764301) (xy 302.262093 -59.741455)
			(xy 302.314595 -59.725959) (xy 302.368773 -59.71813) (xy 302.423515 -59.71813) (xy 302.477693 -59.725959)
			(xy 302.530195 -59.741455) (xy 302.579941 -59.764301) (xy 302.625909 -59.794025) (xy 302.646842 -59.811666)
			(xy 302.653954 -59.817762) (xy 302.670972 -59.824112) (xy 302.756316 -59.824112) (xy 302.773334 -59.817762)
			(xy 302.780446 -59.811666) (xy 302.801383 -59.794033) (xy 302.847355 -59.764322) (xy 302.897101 -59.741485)
			(xy 302.949601 -59.725992) (xy 303.003775 -59.718162) (xy 303.031144 -59.717686) (xy 303.058393 -59.718187)
			(xy 303.112335 -59.725948) (xy 303.164624 -59.741307) (xy 303.214194 -59.76395) (xy 303.260039 -59.793417)
			(xy 303.301223 -59.829108) (xy 303.336909 -59.870297) (xy 303.366371 -59.916144) (xy 303.389008 -59.965718)
			(xy 303.404361 -60.018008) (xy 303.412116 -60.071951) (xy 303.412116 -60.126449) (xy 303.404361 -60.180392)
			(xy 303.389008 -60.232682) (xy 303.366371 -60.282256) (xy 303.336909 -60.328103) (xy 303.301223 -60.369292)
			(xy 303.260039 -60.404983) (xy 303.214194 -60.43445) (xy 303.164624 -60.457093) (xy 303.112335 -60.472452)
			(xy 303.058393 -60.480213) (xy 303.031144 -60.480702) (xy 303.003775 -60.48021) (xy 302.949597 -60.472398)
			(xy 302.897094 -60.456915) (xy 302.847347 -60.434079) (xy 302.801379 -60.40436) (xy 302.780446 -60.386722)
			(xy 302.773334 -60.380626) (xy 302.756316 -60.374276) (xy 302.670972 -60.374276) (xy 302.653954 -60.380626)
			(xy 302.646842 -60.386722) (xy 302.625909 -60.404363) (xy 302.579941 -60.434087) (xy 302.530195 -60.456933)
			(xy 302.477693 -60.472429) (xy 302.423515 -60.480258) (xy 302.368773 -60.480258) (xy 302.314595 -60.472429)
			(xy 302.262093 -60.456933) (xy 302.212347 -60.434087) (xy 302.166379 -60.404363) (xy 302.145446 -60.386722)
			(xy 302.138334 -60.380626) (xy 302.121316 -60.374276) (xy 302.035972 -60.374276) (xy 302.018954 -60.380626)
			(xy 302.011842 -60.386722) (xy 301.990908 -60.404358) (xy 301.944935 -60.43407) (xy 301.895188 -60.456906)
			(xy 301.842688 -60.472398) (xy 301.788513 -60.480227) (xy 301.761144 -60.480702) (xy 301.733889 -60.480254)
			(xy 301.679932 -60.472502) (xy 301.627628 -60.457149) (xy 301.578042 -60.434509) (xy 301.532182 -60.405042)
			(xy 301.490984 -60.369347) (xy 301.455285 -60.328153) (xy 301.425812 -60.282297) (xy 301.403166 -60.232713)
			(xy 301.387808 -60.180411) (xy 301.380049 -60.126455) (xy 295.89095 -60.126455) (xy 295.89095 -60.999878)
			(xy 295.890415 -61.009866) (xy 295.882702 -61.028299) (xy 295.875964 -61.035692) (xy 295.800526 -61.11113)
			(xy 295.800018 -61.111892) (xy 295.796716 -61.115194) (xy 295.796462 -61.115448) (xy 295.169844 -61.742066)
			(xy 295.16324 -61.748416) (xy 295.162732 -61.748924) (xy 295.100248 -61.811408) (xy 295.092894 -61.818063)
			(xy 295.074593 -61.82566) (xy 295.064688 -61.82614) (xy 295.009824 -61.82614) (xy 295.005506 -61.826902)
			(xy 294.992838 -61.828912) (xy 294.967278 -61.831074) (xy 294.954452 -61.83122) (xy 293.279322 -61.83122)
			(xy 293.2677 -61.831793) (xy 293.246807 -61.841981) (xy 293.23919 -61.850778) (xy 293.182548 -61.923422)
			(xy 293.177722 -61.946028) (xy 293.18077 -61.957712) (xy 293.186236 -61.980757) (xy 293.19209 -62.027757)
			(xy 293.192454 -62.051438) (xy 293.191966 -62.078689) (xy 293.184205 -62.132635) (xy 293.168847 -62.184928)
			(xy 293.146204 -62.234503) (xy 293.116738 -62.280352) (xy 293.081047 -62.321541) (xy 293.039858 -62.357233)
			(xy 292.99401 -62.386701) (xy 292.944435 -62.409344) (xy 292.892143 -62.424703) (xy 292.838197 -62.432465)
			(xy 292.810946 -62.432946) (xy 292.787392 -62.432563) (xy 292.740649 -62.426702) (xy 292.717728 -62.421262)
			(xy 292.703504 -62.417706) (xy 292.676326 -62.426342) (xy 292.598094 -62.517274) (xy 292.593522 -62.545468)
			(xy 292.59911 -62.55893) (xy 292.608435 -62.582314) (xy 292.621554 -62.630918) (xy 292.628172 -62.680824)
			(xy 292.628574 -62.705996) (xy 292.628111 -62.733248) (xy 292.620354 -62.787198) (xy 292.604998 -62.839494)
			(xy 292.582355 -62.889073) (xy 292.552887 -62.934924) (xy 292.517193 -62.976114) (xy 292.476 -63.011805)
			(xy 292.430146 -63.04127) (xy 292.380566 -63.063909) (xy 292.328268 -63.079261) (xy 292.274318 -63.087013)
			(xy 292.247066 -63.087504) (xy 292.218255 -63.086982) (xy 292.161287 -63.078321) (xy 292.106271 -63.061188)
			(xy 292.054459 -63.035971) (xy 292.007031 -63.003245) (xy 291.9857 -62.983872) (xy 291.977064 -62.975744)
			(xy 291.95522 -62.968886) (xy 291.865304 -62.981332) (xy 291.863272 -62.981586) (xy 291.852542 -62.984104)
			(xy 291.83452 -62.996753) (xy 291.828474 -63.00597) (xy 291.813657 -63.030092) (xy 291.77802 -63.074075)
			(xy 291.736273 -63.112308) (xy 291.689333 -63.143951) (xy 291.638232 -63.168307) (xy 291.584092 -63.184844)
			(xy 291.528103 -63.193196) (xy 291.499798 -63.193676) (xy 291.472549 -63.19319) (xy 291.418606 -63.185434)
			(xy 291.366316 -63.17008) (xy 291.316743 -63.14744) (xy 291.270897 -63.117976) (xy 291.229711 -63.082288)
			(xy 291.194022 -63.041101) (xy 291.164559 -62.995255) (xy 291.14192 -62.945682) (xy 291.126566 -62.893392)
			(xy 291.11881 -62.839449) (xy 291.11881 -62.784951) (xy 291.126566 -62.731008) (xy 291.14192 -62.678718)
			(xy 291.164559 -62.629145) (xy 291.194022 -62.583299) (xy 291.229711 -62.542112) (xy 291.270897 -62.506424)
			(xy 291.316743 -62.47696) (xy 291.366316 -62.45432) (xy 291.418606 -62.438966) (xy 291.472549 -62.43121)
			(xy 291.499798 -62.43066) (xy 291.528608 -62.431187) (xy 291.585571 -62.439855) (xy 291.640583 -62.456995)
			(xy 291.692389 -62.482216) (xy 291.739812 -62.514943) (xy 291.761164 -62.534292) (xy 291.7698 -62.54242)
			(xy 291.791644 -62.549278) (xy 291.893244 -62.535054) (xy 291.912294 -62.522354) (xy 291.91839 -62.512194)
			(xy 291.933209 -62.488077) (xy 291.968851 -62.444103) (xy 292.0106 -62.405881) (xy 292.057541 -62.37425)
			(xy 292.108641 -62.349904) (xy 292.162779 -62.333378) (xy 292.218764 -62.325036) (xy 292.247066 -62.324488)
			(xy 292.267132 -62.324996) (xy 292.267386 -62.324996) (xy 292.283134 -62.326012) (xy 292.29177 -62.327028)
			(xy 292.312598 -62.330076) (xy 292.312852 -62.330076) (xy 292.340284 -62.336172) (xy 292.354508 -62.339728)
			(xy 292.381686 -62.331092) (xy 292.459918 -62.24016) (xy 292.464236 -62.21222) (xy 292.458648 -62.198504)
			(xy 292.448828 -62.173891) (xy 292.43532 -62.122651) (xy 292.431724 -62.096396) (xy 292.430454 -62.082426)
			(xy 292.429184 -62.051438) (xy 292.429184 -62.05093) (xy 292.429554 -62.027312) (xy 292.435414 -61.980441)
			(xy 292.440868 -61.957458) (xy 292.443916 -61.945774) (xy 292.43909 -61.923168) (xy 292.382702 -61.850778)
			(xy 292.375109 -61.841954) (xy 292.354199 -61.831784) (xy 292.34257 -61.83122) (xy 291.364162 -61.83122)
			(xy 291.351463 -61.831072) (xy 291.326157 -61.828909) (xy 291.313616 -61.826902) (xy 291.309298 -61.82614)
			(xy 291.06876 -61.82614) (xy 291.057076 -61.829188) (xy 291.05225 -61.831474) (xy 291.051742 -61.831728)
			(xy 291.036837 -61.838668) (xy 291.00606 -61.850244) (xy 290.990274 -61.854842) (xy 290.962981 -61.86206)
			(xy 290.906993 -61.869298) (xy 290.85055 -61.868196) (xy 290.822634 -61.863986) (xy 290.796057 -61.859023)
			(xy 290.744554 -61.842577) (xy 290.720018 -61.83122) (xy 290.714938 -61.82868) (xy 290.703762 -61.82614)
			(xy 290.453826 -61.82614) (xy 290.449508 -61.826902) (xy 290.436966 -61.828894) (xy 290.41166 -61.831053)
			(xy 290.398962 -61.83122) (xy 289.263836 -61.83122) (xy 289.251189 -61.831887) (xy 289.228916 -61.843875)
			(xy 289.221418 -61.85408) (xy 289.177984 -61.920374) (xy 289.173594 -61.927592) (xy 289.16941 -61.943951)
			(xy 289.170812 -61.960777) (xy 289.17392 -61.968634) (xy 289.183972 -61.992769) (xy 289.19812 -62.043101)
			(xy 289.205259 -62.094893) (xy 289.20567 -62.121034) (xy 289.20567 -62.12586) (xy 289.204858 -62.152886)
			(xy 289.196548 -62.206313) (xy 289.180779 -62.258031) (xy 289.157867 -62.307004) (xy 289.12827 -62.352253)
			(xy 289.092581 -62.39287) (xy 289.051516 -62.428042) (xy 289.005897 -62.457064) (xy 288.956637 -62.479355)
			(xy 288.904723 -62.494469) (xy 288.851196 -62.502102) (xy 288.797128 -62.502102) (xy 288.743601 -62.494469)
			(xy 288.691687 -62.479355) (xy 288.642427 -62.457064) (xy 288.596808 -62.428042) (xy 288.555743 -62.39287)
			(xy 288.520054 -62.352253) (xy 288.490457 -62.307004) (xy 288.467545 -62.258031) (xy 288.451776 -62.206313)
			(xy 288.443466 -62.152886) (xy 288.442654 -62.12586) (xy 288.442654 -62.12078) (xy 288.443102 -62.094683)
			(xy 288.450256 -62.042981) (xy 288.464388 -61.992737) (xy 288.474404 -61.968634) (xy 288.47923 -61.957712)
			(xy 288.478214 -61.934852) (xy 288.47288 -61.924438) (xy 288.47034 -61.920374) (xy 288.42716 -61.854334)
			(xy 288.420048 -61.843412) (xy 288.397696 -61.83122) (xy 285.862268 -61.83122) (xy 285.852201 -61.831649)
			(xy 285.833607 -61.839374) (xy 285.8262 -61.846206) (xy 285.422594 -62.249812) (xy 285.415228 -62.256924)
			(xy 285.407608 -62.27572) (xy 285.407608 -63.273432) (xy 287.776664 -63.273432) (xy 287.780735 -63.21781)
			(xy 287.792861 -63.163373) (xy 287.812784 -63.111282) (xy 287.84008 -63.062647) (xy 287.874166 -63.018504)
			(xy 287.914315 -62.979795) (xy 287.959673 -62.947344) (xy 288.009273 -62.921843) (xy 288.062057 -62.903836)
			(xy 288.1169 -62.893706) (xy 288.172634 -62.891669) (xy 288.228071 -62.897769) (xy 288.282028 -62.911875)
			(xy 288.333357 -62.933687) (xy 288.380963 -62.962741) (xy 288.423831 -62.998416) (xy 288.461048 -63.039953)
			(xy 288.491821 -63.086466) (xy 288.515493 -63.136963) (xy 288.531561 -63.19037) (xy 288.539681 -63.245546)
			(xy 288.539681 -63.245548) (xy 301.304492 -63.245548) (xy 301.304492 -63.191052) (xy 301.312247 -63.137111)
			(xy 301.327599 -63.084822) (xy 301.350236 -63.035249) (xy 301.379697 -62.989403) (xy 301.415382 -62.948216)
			(xy 301.456565 -62.912525) (xy 301.502407 -62.883059) (xy 301.551977 -62.860416) (xy 301.604264 -62.845057)
			(xy 301.658204 -62.837296) (xy 301.685452 -62.836806) (xy 301.712821 -62.837299) (xy 301.766999 -62.84511)
			(xy 301.819502 -62.860593) (xy 301.869249 -62.883428) (xy 301.915217 -62.913147) (xy 301.93615 -62.930786)
			(xy 301.943262 -62.936882) (xy 301.96028 -62.943232) (xy 302.045624 -62.943232) (xy 302.062642 -62.936882)
			(xy 302.069754 -62.930786) (xy 302.090687 -62.913145) (xy 302.136655 -62.883421) (xy 302.186401 -62.860575)
			(xy 302.238903 -62.845079) (xy 302.293081 -62.83725) (xy 302.347823 -62.83725) (xy 302.402001 -62.845079)
			(xy 302.454503 -62.860575) (xy 302.504249 -62.883421) (xy 302.550217 -62.913145) (xy 302.57115 -62.930786)
			(xy 302.578262 -62.936882) (xy 302.59528 -62.943232) (xy 302.680624 -62.943232) (xy 302.697642 -62.936882)
			(xy 302.704754 -62.930786) (xy 302.725691 -62.913153) (xy 302.771663 -62.883441) (xy 302.821409 -62.860604)
			(xy 302.873908 -62.845111) (xy 302.928083 -62.837281) (xy 302.955452 -62.836806) (xy 302.982708 -62.837238)
			(xy 303.036666 -62.844989) (xy 303.088972 -62.860342) (xy 303.13856 -62.882982) (xy 303.184421 -62.91245)
			(xy 303.225621 -62.948145) (xy 303.261321 -62.989341) (xy 303.290795 -63.035198) (xy 303.313441 -63.084783)
			(xy 303.3288 -63.137087) (xy 303.336559 -63.191044) (xy 303.336559 -63.245556) (xy 303.3288 -63.299513)
			(xy 303.313441 -63.351817) (xy 303.290795 -63.401402) (xy 303.261321 -63.447259) (xy 303.225621 -63.488455)
			(xy 303.184421 -63.52415) (xy 303.13856 -63.553618) (xy 303.088972 -63.576258) (xy 303.036666 -63.591611)
			(xy 302.982708 -63.599362) (xy 302.955452 -63.599822) (xy 302.928082 -63.599344) (xy 302.873903 -63.591532)
			(xy 302.821399 -63.576047) (xy 302.771652 -63.553207) (xy 302.725685 -63.523483) (xy 302.704754 -63.505842)
			(xy 302.697642 -63.499746) (xy 302.680624 -63.493396) (xy 302.59528 -63.493396) (xy 302.578262 -63.499746)
			(xy 302.57115 -63.505842) (xy 302.550217 -63.523483) (xy 302.504249 -63.553207) (xy 302.454503 -63.576053)
			(xy 302.402001 -63.591549) (xy 302.347823 -63.599378) (xy 302.293081 -63.599378) (xy 302.238903 -63.591549)
			(xy 302.186401 -63.576053) (xy 302.136655 -63.553207) (xy 302.090687 -63.523483) (xy 302.069754 -63.505842)
			(xy 302.062642 -63.499746) (xy 302.045624 -63.493396) (xy 301.96028 -63.493396) (xy 301.943262 -63.499746)
			(xy 301.93615 -63.505842) (xy 301.915216 -63.523478) (xy 301.869243 -63.553189) (xy 301.819496 -63.576025)
			(xy 301.766996 -63.591517) (xy 301.712821 -63.599347) (xy 301.685452 -63.599822) (xy 301.658204 -63.599304)
			(xy 301.604264 -63.591543) (xy 301.551977 -63.576184) (xy 301.502407 -63.553541) (xy 301.456565 -63.524075)
			(xy 301.415382 -63.488384) (xy 301.379697 -63.447197) (xy 301.350236 -63.401351) (xy 301.327599 -63.351778)
			(xy 301.312247 -63.29949) (xy 301.304492 -63.245548) (xy 288.539681 -63.245548) (xy 288.54019 -63.273432)
			(xy 288.539681 -63.301318) (xy 288.531561 -63.356494) (xy 288.515493 -63.409901) (xy 288.491821 -63.460398)
			(xy 288.461048 -63.506911) (xy 288.423831 -63.548448) (xy 288.380963 -63.584123) (xy 288.333357 -63.613177)
			(xy 288.282028 -63.634989) (xy 288.228071 -63.649095) (xy 288.172634 -63.655195) (xy 288.1169 -63.653158)
			(xy 288.062057 -63.643028) (xy 288.009273 -63.625021) (xy 287.959673 -63.59952) (xy 287.914315 -63.567069)
			(xy 287.874166 -63.52836) (xy 287.84008 -63.484217) (xy 287.812784 -63.435582) (xy 287.792861 -63.383491)
			(xy 287.780735 -63.329054) (xy 287.776664 -63.273432) (xy 285.407608 -63.273432) (xy 285.407608 -64.102234)
			(xy 285.587438 -64.102234) (xy 285.591509 -64.046612) (xy 285.603635 -63.992175) (xy 285.623558 -63.940084)
			(xy 285.650854 -63.891449) (xy 285.68494 -63.847306) (xy 285.725089 -63.808597) (xy 285.770447 -63.776146)
			(xy 285.820047 -63.750645) (xy 285.872831 -63.732638) (xy 285.927674 -63.722508) (xy 285.983408 -63.720471)
			(xy 286.038845 -63.726571) (xy 286.092802 -63.740677) (xy 286.144131 -63.762489) (xy 286.191737 -63.791543)
			(xy 286.234605 -63.827218) (xy 286.271822 -63.868755) (xy 286.302595 -63.915268) (xy 286.326267 -63.965765)
			(xy 286.342335 -64.019172) (xy 286.350455 -64.074348) (xy 286.350964 -64.102234) (xy 286.350455 -64.13012)
			(xy 286.342335 -64.185296) (xy 286.326267 -64.238703) (xy 286.302595 -64.2892) (xy 286.287317 -64.312292)
			(xy 289.265866 -64.312292) (xy 289.269937 -64.25667) (xy 289.282063 -64.202233) (xy 289.301986 -64.150142)
			(xy 289.329282 -64.101507) (xy 289.363368 -64.057364) (xy 289.403517 -64.018655) (xy 289.448875 -63.986204)
			(xy 289.498475 -63.960703) (xy 289.551259 -63.942696) (xy 289.606102 -63.932566) (xy 289.661836 -63.930529)
			(xy 289.717273 -63.936629) (xy 289.77123 -63.950735) (xy 289.822559 -63.972547) (xy 289.870165 -64.001601)
			(xy 289.913033 -64.037276) (xy 289.95025 -64.078813) (xy 289.981023 -64.125326) (xy 290.004695 -64.175823)
			(xy 290.020763 -64.22923) (xy 290.028883 -64.284406) (xy 290.029392 -64.312292) (xy 291.105842 -64.312292)
			(xy 291.109913 -64.25667) (xy 291.122039 -64.202233) (xy 291.141962 -64.150142) (xy 291.169258 -64.101507)
			(xy 291.203344 -64.057364) (xy 291.243493 -64.018655) (xy 291.288851 -63.986204) (xy 291.338451 -63.960703)
			(xy 291.391235 -63.942696) (xy 291.446078 -63.932566) (xy 291.501812 -63.930529) (xy 291.557249 -63.936629)
			(xy 291.611206 -63.950735) (xy 291.662535 -63.972547) (xy 291.710141 -64.001601) (xy 291.753009 -64.037276)
			(xy 291.790226 -64.078813) (xy 291.820999 -64.125326) (xy 291.844671 -64.175823) (xy 291.860739 -64.22923)
			(xy 291.868859 -64.284406) (xy 291.869368 -64.312292) (xy 291.868859 -64.340178) (xy 291.860739 -64.395354)
			(xy 291.844671 -64.448761) (xy 291.820999 -64.499258) (xy 291.790226 -64.545771) (xy 291.753009 -64.587308)
			(xy 291.710141 -64.622983) (xy 291.662535 -64.652037) (xy 291.611206 -64.673849) (xy 291.557249 -64.687955)
			(xy 291.501812 -64.694055) (xy 291.446078 -64.692018) (xy 291.391235 -64.681888) (xy 291.338451 -64.663881)
			(xy 291.288851 -64.63838) (xy 291.243493 -64.605929) (xy 291.203344 -64.56722) (xy 291.169258 -64.523077)
			(xy 291.141962 -64.474442) (xy 291.122039 -64.422351) (xy 291.109913 -64.367914) (xy 291.105842 -64.312292)
			(xy 290.029392 -64.312292) (xy 290.028883 -64.340178) (xy 290.020763 -64.395354) (xy 290.004695 -64.448761)
			(xy 289.981023 -64.499258) (xy 289.95025 -64.545771) (xy 289.913033 -64.587308) (xy 289.870165 -64.622983)
			(xy 289.822559 -64.652037) (xy 289.77123 -64.673849) (xy 289.717273 -64.687955) (xy 289.661836 -64.694055)
			(xy 289.606102 -64.692018) (xy 289.551259 -64.681888) (xy 289.498475 -64.663881) (xy 289.448875 -64.63838)
			(xy 289.403517 -64.605929) (xy 289.363368 -64.56722) (xy 289.329282 -64.523077) (xy 289.301986 -64.474442)
			(xy 289.282063 -64.422351) (xy 289.269937 -64.367914) (xy 289.265866 -64.312292) (xy 286.287317 -64.312292)
			(xy 286.271822 -64.335713) (xy 286.234605 -64.37725) (xy 286.191737 -64.412925) (xy 286.144131 -64.441979)
			(xy 286.092802 -64.463791) (xy 286.038845 -64.477897) (xy 285.983408 -64.483997) (xy 285.927674 -64.48196)
			(xy 285.872831 -64.47183) (xy 285.820047 -64.453823) (xy 285.770447 -64.428322) (xy 285.725089 -64.395871)
			(xy 285.68494 -64.357162) (xy 285.650854 -64.313019) (xy 285.623558 -64.264384) (xy 285.603635 -64.212293)
			(xy 285.591509 -64.157856) (xy 285.587438 -64.102234) (xy 285.407608 -64.102234) (xy 285.407608 -65.511426)
			(xy 298.584872 -65.511426) (xy 298.588943 -65.455804) (xy 298.601069 -65.401367) (xy 298.620992 -65.349276)
			(xy 298.648288 -65.300641) (xy 298.682374 -65.256498) (xy 298.722523 -65.217789) (xy 298.767881 -65.185338)
			(xy 298.817481 -65.159837) (xy 298.870265 -65.14183) (xy 298.925108 -65.1317) (xy 298.980842 -65.129663)
			(xy 299.036279 -65.135763) (xy 299.090236 -65.149869) (xy 299.113818 -65.15989) (xy 303.316384 -65.15989)
			(xy 303.320455 -65.104268) (xy 303.332581 -65.049831) (xy 303.352504 -64.99774) (xy 303.3798 -64.949105)
			(xy 303.413886 -64.904962) (xy 303.454035 -64.866253) (xy 303.499393 -64.833802) (xy 303.548993 -64.808301)
			(xy 303.601777 -64.790294) (xy 303.65662 -64.780164) (xy 303.712354 -64.778127) (xy 303.767791 -64.784227)
			(xy 303.821748 -64.798333) (xy 303.873077 -64.820145) (xy 303.920683 -64.849199) (xy 303.963551 -64.884874)
			(xy 304.000768 -64.926411) (xy 304.031541 -64.972924) (xy 304.055213 -65.023421) (xy 304.071281 -65.076828)
			(xy 304.079401 -65.132004) (xy 304.07991 -65.15989) (xy 304.079401 -65.187776) (xy 304.071281 -65.242952)
			(xy 304.055213 -65.296359) (xy 304.031541 -65.346856) (xy 304.000768 -65.393369) (xy 303.963551 -65.434906)
			(xy 303.920683 -65.470581) (xy 303.873077 -65.499635) (xy 303.821748 -65.521447) (xy 303.767791 -65.535553)
			(xy 303.712354 -65.541653) (xy 303.65662 -65.539616) (xy 303.601777 -65.529486) (xy 303.548993 -65.511479)
			(xy 303.499393 -65.485978) (xy 303.454035 -65.453527) (xy 303.413886 -65.414818) (xy 303.3798 -65.370675)
			(xy 303.352504 -65.32204) (xy 303.332581 -65.269949) (xy 303.320455 -65.215512) (xy 303.316384 -65.15989)
			(xy 299.113818 -65.15989) (xy 299.141565 -65.171681) (xy 299.189171 -65.200735) (xy 299.232039 -65.23641)
			(xy 299.269256 -65.277947) (xy 299.300029 -65.32446) (xy 299.323701 -65.374957) (xy 299.339769 -65.428364)
			(xy 299.347889 -65.48354) (xy 299.348398 -65.511426) (xy 299.347889 -65.539312) (xy 299.339769 -65.594488)
			(xy 299.323701 -65.647895) (xy 299.300029 -65.698392) (xy 299.269256 -65.744905) (xy 299.232039 -65.786442)
			(xy 299.189171 -65.822117) (xy 299.141565 -65.851171) (xy 299.090236 -65.872983) (xy 299.036279 -65.887089)
			(xy 298.980842 -65.893189) (xy 298.925108 -65.891152) (xy 298.870265 -65.881022) (xy 298.817481 -65.863015)
			(xy 298.767881 -65.837514) (xy 298.722523 -65.805063) (xy 298.682374 -65.766354) (xy 298.648288 -65.722211)
			(xy 298.620992 -65.673576) (xy 298.601069 -65.621485) (xy 298.588943 -65.567048) (xy 298.584872 -65.511426)
			(xy 285.407608 -65.511426) (xy 285.407608 -67.488054) (xy 302.979072 -67.488054) (xy 302.983143 -67.432432)
			(xy 302.995269 -67.377995) (xy 303.015192 -67.325904) (xy 303.042488 -67.277269) (xy 303.076574 -67.233126)
			(xy 303.116723 -67.194417) (xy 303.162081 -67.161966) (xy 303.211681 -67.136465) (xy 303.264465 -67.118458)
			(xy 303.319308 -67.108328) (xy 303.375042 -67.106291) (xy 303.430479 -67.112391) (xy 303.484436 -67.126497)
			(xy 303.535765 -67.148309) (xy 303.583371 -67.177363) (xy 303.626239 -67.213038) (xy 303.663456 -67.254575)
			(xy 303.694229 -67.301088) (xy 303.717901 -67.351585) (xy 303.733969 -67.404992) (xy 303.742089 -67.460168)
			(xy 303.742598 -67.488054) (xy 303.742089 -67.51594) (xy 303.733969 -67.571116) (xy 303.717901 -67.624523)
			(xy 303.694229 -67.67502) (xy 303.663456 -67.721533) (xy 303.626239 -67.76307) (xy 303.583371 -67.798745)
			(xy 303.535765 -67.827799) (xy 303.484436 -67.849611) (xy 303.430479 -67.863717) (xy 303.375042 -67.869817)
			(xy 303.319308 -67.86778) (xy 303.264465 -67.85765) (xy 303.211681 -67.839643) (xy 303.162081 -67.814142)
			(xy 303.116723 -67.781691) (xy 303.076574 -67.742982) (xy 303.042488 -67.698839) (xy 303.015192 -67.650204)
			(xy 302.995269 -67.598113) (xy 302.983143 -67.543676) (xy 302.979072 -67.488054) (xy 285.407608 -67.488054)
			(xy 285.407608 -69.9516) (xy 285.408065 -69.961478) (xy 285.415505 -69.979781) (xy 285.422086 -69.98716)
			(xy 285.42234 -69.987414) (xy 285.598616 -70.16369) (xy 285.599124 -70.164198) (xy 285.606501 -70.170791)
			(xy 285.624801 -70.17826) (xy 285.634684 -70.178676)
		)
		(stroke
			(width 0)
			(type solid)
		)
		(fill yes)
		(layer "In9.Cu")
		(net "P12V_SSD10_R")
	)
	(gr_poly
		(pts
			(xy 394.77823 -70.178676) (xy 394.788297 -70.178247) (xy 394.806892 -70.170522) (xy 394.814298 -70.16369)
			(xy 395.140434 -69.837554) (xy 395.140942 -69.837046) (xy 395.147525 -69.829665) (xy 395.154977 -69.811366)
			(xy 395.15542 -69.801486) (xy 395.15542 -67.91579) (xy 395.155022 -67.906269) (xy 395.148063 -67.888545)
			(xy 395.13511 -67.874588) (xy 395.126718 -67.87007) (xy 395.03096 -67.823842) (xy 395.002258 -67.827144)
			(xy 394.990574 -67.836288) (xy 394.970263 -67.851904) (xy 394.926249 -67.878127) (xy 394.879121 -67.898221)
			(xy 394.829726 -67.911823) (xy 394.778955 -67.918688) (xy 394.753338 -67.919092) (xy 394.726085 -67.918631)
			(xy 394.672132 -67.910879) (xy 394.619832 -67.895527) (xy 394.570249 -67.872888) (xy 394.524393 -67.843422)
			(xy 394.483197 -67.80773) (xy 394.447501 -67.766538) (xy 394.418031 -67.720685) (xy 394.395386 -67.671104)
			(xy 394.380029 -67.618805) (xy 394.372271 -67.564853) (xy 394.372271 -67.510347) (xy 394.380029 -67.456395)
			(xy 394.395386 -67.404096) (xy 394.418031 -67.354515) (xy 394.447501 -67.308662) (xy 394.483197 -67.26747)
			(xy 394.524393 -67.231778) (xy 394.570249 -67.202312) (xy 394.619832 -67.179673) (xy 394.672132 -67.164321)
			(xy 394.726085 -67.156569) (xy 394.753338 -67.156076) (xy 394.778953 -67.156494) (xy 394.829722 -67.16336)
			(xy 394.879114 -67.176963) (xy 394.926239 -67.197059) (xy 394.970248 -67.223285) (xy 394.990574 -67.23888)
			(xy 395.002258 -67.248024) (xy 395.03096 -67.251326) (xy 395.126718 -67.205098) (xy 395.135125 -67.200601)
			(xy 395.14808 -67.186633) (xy 395.155051 -67.168903) (xy 395.15542 -67.159378) (xy 395.15542 -65.506854)
			(xy 395.141704 -65.483486) (xy 395.130274 -65.476628) (xy 395.129766 -65.476628) (xy 395.056614 -65.433702)
			(xy 395.047601 -65.428968) (xy 395.027427 -65.426366) (xy 395.017498 -65.428622) (xy 395.003782 -65.432432)
			(xy 394.998194 -65.43548) (xy 394.969908 -65.450254) (xy 394.909632 -65.471194) (xy 394.846711 -65.481813)
			(xy 394.814806 -65.48247) (xy 394.814552 -65.48247) (xy 394.787306 -65.481981) (xy 394.733369 -65.474219)
			(xy 394.681085 -65.458862) (xy 394.631519 -65.43622) (xy 394.585679 -65.406755) (xy 394.544499 -65.371067)
			(xy 394.508816 -65.329883) (xy 394.479357 -65.284039) (xy 394.456722 -65.23447) (xy 394.441371 -65.182184)
			(xy 394.433616 -65.128246) (xy 394.433616 -65.073754) (xy 394.441371 -65.019816) (xy 394.456722 -64.96753)
			(xy 394.479357 -64.917961) (xy 394.508816 -64.872117) (xy 394.544499 -64.830933) (xy 394.585679 -64.795245)
			(xy 394.631519 -64.76578) (xy 394.681085 -64.743138) (xy 394.733369 -64.727781) (xy 394.787306 -64.720019)
			(xy 394.814552 -64.719454) (xy 394.814806 -64.719454) (xy 394.84671 -64.720118) (xy 394.909626 -64.730753)
			(xy 394.969906 -64.751677) (xy 394.998194 -64.766444) (xy 395.003782 -64.769492) (xy 395.017498 -64.773302)
			(xy 395.027424 -64.775565) (xy 395.047599 -64.772951) (xy 395.056614 -64.768222) (xy 395.13002 -64.725296)
			(xy 395.130782 -64.724788) (xy 395.138056 -64.71997) (xy 395.149094 -64.706475) (xy 395.154994 -64.690069)
			(xy 395.15542 -64.681354) (xy 395.15542 -52.622958) (xy 395.153642 -52.616608) (xy 395.147582 -52.592357)
			(xy 395.141084 -52.542795) (xy 395.140688 -52.517802) (xy 395.140688 -52.51577) (xy 395.141153 -52.491159)
			(xy 395.147651 -52.442364) (xy 395.153642 -52.418488) (xy 395.15542 -52.411884) (xy 395.15542 -51.455828)
			(xy 395.155857 -51.445764) (xy 395.163592 -51.42718) (xy 395.170406 -51.41976) (xy 395.27734 -51.312826)
			(xy 395.284739 -51.305983) (xy 395.303338 -51.298259) (xy 395.313408 -51.29784) (xy 396.00378 -51.29784)
			(xy 396.012162 -51.297078) (xy 396.019769 -51.295568) (xy 396.033608 -51.288586) (xy 396.03934 -51.283362)
			(xy 396.10411 -51.218592) (xy 396.104618 -51.218084) (xy 396.11121 -51.210706) (xy 396.118679 -51.192407)
			(xy 396.119096 -51.182524) (xy 396.119096 -49.20615) (xy 396.118499 -49.193826) (xy 396.107044 -49.172003)
			(xy 396.097252 -49.164494) (xy 396.033752 -49.120044) (xy 396.02725 -49.115867) (xy 396.012517 -49.111228)
			(xy 396.004796 -49.1109) (xy 395.982698 -49.1109) (xy 395.974824 -49.113694) (xy 395.94464 -49.123451)
			(xy 395.88208 -49.133927) (xy 395.850364 -49.134522) (xy 395.8463 -49.134522) (xy 395.819238 -49.133765)
			(xy 395.765727 -49.125549) (xy 395.713916 -49.109849) (xy 395.664844 -49.086981) (xy 395.6195 -49.057405)
			(xy 395.578792 -49.021715) (xy 395.54354 -48.980627) (xy 395.514451 -48.934968) (xy 395.492111 -48.885655)
			(xy 395.476967 -48.833679) (xy 395.469324 -48.780083) (xy 395.468856 -48.753014) (xy 395.469341 -48.725761)
			(xy 395.477095 -48.67181) (xy 395.492449 -48.619512) (xy 395.515089 -48.56993) (xy 395.544554 -48.524075)
			(xy 395.580245 -48.482881) (xy 395.621435 -48.447184) (xy 395.667286 -48.417713) (xy 395.716865 -48.395067)
			(xy 395.769161 -48.379706) (xy 395.823111 -48.371944) (xy 395.850364 -48.371506) (xy 395.851126 -48.371506)
			(xy 395.884742 -48.372259) (xy 395.950919 -48.384141) (xy 395.982698 -48.395128) (xy 395.994382 -48.399446)
			(xy 396.01902 -48.396398) (xy 396.097252 -48.341534) (xy 396.106922 -48.333922) (xy 396.11833 -48.312161)
			(xy 396.119096 -48.299878) (xy 396.119096 -41.95445) (xy 396.118664 -41.944384) (xy 396.110936 -41.925793)
			(xy 396.10411 -41.918382) (xy 395.223746 -41.038018) (xy 395.216634 -41.030652) (xy 395.197838 -41.023032)
			(xy 393.416282 -41.023032) (xy 393.407581 -41.023384) (xy 393.39118 -41.029201) (xy 393.377662 -41.040161)
			(xy 393.372848 -41.047416) (xy 393.32789 -41.121584) (xy 393.323826 -41.13022) (xy 393.320501 -41.140526)
			(xy 393.321932 -41.162115) (xy 393.32662 -41.171876) (xy 393.327382 -41.1734) (xy 393.3317 -41.18229)
			(xy 393.343779 -41.20826) (xy 393.360893 -41.262918) (xy 393.369664 -41.319517) (xy 393.370308 -41.348152)
			(xy 393.370308 -41.34866) (xy 393.370308 -41.35501) (xy 393.369397 -41.383073) (xy 393.360351 -41.438486)
			(xy 393.343279 -41.491975) (xy 393.318551 -41.542383) (xy 393.2867 -41.588621) (xy 393.267946 -41.609518)
			(xy 393.267692 -41.609772) (xy 393.26121 -41.617123) (xy 393.253899 -41.635287) (xy 393.253468 -41.645078)
			(xy 393.253468 -41.724072) (xy 393.260326 -41.741852) (xy 393.267184 -41.748964) (xy 393.286453 -41.770291)
			(xy 393.319014 -41.817653) (xy 393.344102 -41.869364) (xy 393.361149 -41.924253) (xy 393.369768 -41.981078)
			(xy 393.369766 -42.038554) (xy 393.361141 -42.095378) (xy 393.34409 -42.150266) (xy 393.318998 -42.201975)
			(xy 393.286433 -42.249334) (xy 393.267184 -42.27068) (xy 393.260326 -42.277792) (xy 393.253468 -42.295572)
			(xy 393.253468 -42.384472) (xy 393.260326 -42.402252) (xy 393.267184 -42.409364) (xy 393.286453 -42.430691)
			(xy 393.319015 -42.478055) (xy 393.344103 -42.529767) (xy 393.36115 -42.584657) (xy 393.369769 -42.641484)
			(xy 393.370308 -42.670222) (xy 393.369835 -42.697592) (xy 393.362008 -42.751768) (xy 393.346519 -42.80427)
			(xy 393.323685 -42.85402) (xy 393.293976 -42.899995) (xy 393.276328 -42.92092) (xy 393.270232 -42.928032)
			(xy 393.263882 -42.944796) (xy 393.263882 -43.030648) (xy 393.270232 -43.047412) (xy 393.276328 -43.054524)
			(xy 393.293967 -43.075456) (xy 393.323688 -43.121424) (xy 393.346527 -43.171171) (xy 393.362013 -43.223674)
			(xy 393.369827 -43.277852) (xy 393.370308 -43.305222) (xy 393.369822 -43.332473) (xy 393.362066 -43.386421)
			(xy 393.346711 -43.438716) (xy 393.324069 -43.488293) (xy 393.294603 -43.534143) (xy 393.258912 -43.575334)
			(xy 393.217721 -43.611025) (xy 393.171871 -43.640491) (xy 393.122294 -43.663133) (xy 393.069999 -43.678488)
			(xy 393.016051 -43.686244) (xy 392.961549 -43.686244) (xy 392.907601 -43.678488) (xy 392.855306 -43.663133)
			(xy 392.805729 -43.640491) (xy 392.759879 -43.611025) (xy 392.718688 -43.575334) (xy 392.682997 -43.534143)
			(xy 392.653531 -43.488293) (xy 392.630889 -43.438716) (xy 392.615534 -43.386421) (xy 392.607778 -43.332473)
			(xy 392.607292 -43.305222) (xy 392.607769 -43.277854) (xy 392.615603 -43.223681) (xy 392.631098 -43.171184)
			(xy 392.653937 -43.12144) (xy 392.683651 -43.07547) (xy 392.701272 -43.054524) (xy 392.707368 -43.047412)
			(xy 392.713718 -43.030648) (xy 392.713718 -42.944796) (xy 392.707368 -42.928032) (xy 392.701272 -42.92092)
			(xy 392.68363 -42.899988) (xy 392.653904 -42.854022) (xy 392.63106 -42.804275) (xy 392.615568 -42.751772)
			(xy 392.607747 -42.697593) (xy 392.607292 -42.670222) (xy 392.607811 -42.641482) (xy 392.616431 -42.584653)
			(xy 392.633478 -42.529759) (xy 392.658568 -42.478045) (xy 392.691131 -42.430679) (xy 392.710416 -42.409364)
			(xy 392.717274 -42.402252) (xy 392.724132 -42.384472) (xy 392.724132 -42.295572) (xy 392.717274 -42.277792)
			(xy 392.710416 -42.27068) (xy 392.691144 -42.249353) (xy 392.658576 -42.20199) (xy 392.633482 -42.150277)
			(xy 392.616429 -42.095385) (xy 392.607804 -42.038556) (xy 392.607802 -41.981076) (xy 392.616422 -41.924246)
			(xy 392.63347 -41.869353) (xy 392.65856 -41.817638) (xy 392.691124 -41.770272) (xy 392.710416 -41.748964)
			(xy 392.717274 -41.741852) (xy 392.724132 -41.724072) (xy 392.724132 -41.635172) (xy 392.717274 -41.617646)
			(xy 392.710416 -41.61028) (xy 392.691617 -41.589486) (xy 392.659689 -41.543412) (xy 392.634835 -41.493168)
			(xy 392.61759 -41.439831) (xy 392.608322 -41.384547) (xy 392.607292 -41.356534) (xy 392.607292 -41.349422)
			(xy 392.607804 -41.320529) (xy 392.616491 -41.263399) (xy 392.633714 -41.208239) (xy 392.6459 -41.182036)
			(xy 392.653266 -41.166542) (xy 392.656329 -41.157735) (xy 392.656594 -41.139107) (xy 392.653774 -41.13022)
			(xy 392.64971 -41.121584) (xy 392.604752 -41.04767) (xy 392.597894 -41.035986) (xy 392.57478 -41.023032)
			(xy 391.654284 -41.023032) (xy 391.642667 -41.023613) (xy 391.621788 -41.033813) (xy 391.614152 -41.04259)
			(xy 391.55751 -41.11498) (xy 391.552684 -41.137586) (xy 391.555478 -41.14927) (xy 391.5608 -41.171949)
			(xy 391.56653 -41.21818) (xy 391.566908 -41.241472) (xy 391.566447 -41.268726) (xy 391.558693 -41.32268)
			(xy 391.543339 -41.374981) (xy 391.520698 -41.424565) (xy 391.491231 -41.470422) (xy 391.455537 -41.511618)
			(xy 391.414344 -41.547314) (xy 391.36849 -41.576785) (xy 391.318908 -41.599429) (xy 391.266608 -41.614787)
			(xy 391.212654 -41.622545) (xy 391.1854 -41.62298) (xy 391.156661 -41.622459) (xy 391.099834 -41.613836)
			(xy 391.044943 -41.596785) (xy 390.993232 -41.571692) (xy 390.94587 -41.539126) (xy 390.924542 -41.519856)
			(xy 390.91743 -41.512998) (xy 390.89965 -41.50614) (xy 390.81075 -41.50614) (xy 390.79297 -41.512998)
			(xy 390.785858 -41.519856) (xy 390.764529 -41.539123) (xy 390.717165 -41.571682) (xy 390.665453 -41.596768)
			(xy 390.610563 -41.613814) (xy 390.553738 -41.622435) (xy 390.525 -41.62298) (xy 390.497748 -41.622517)
			(xy 390.443798 -41.61476) (xy 390.391502 -41.599403) (xy 390.341924 -41.57676) (xy 390.296073 -41.547292)
			(xy 390.254882 -41.511598) (xy 390.219191 -41.470405) (xy 390.189726 -41.424552) (xy 390.167087 -41.374972)
			(xy 390.151735 -41.322674) (xy 390.143981 -41.268724) (xy 390.143492 -41.241472) (xy 390.143871 -41.21818)
			(xy 390.149602 -41.171949) (xy 390.154922 -41.14927) (xy 390.157716 -41.137586) (xy 390.15289 -41.11498)
			(xy 390.096248 -41.04259) (xy 390.088659 -41.033757) (xy 390.067749 -41.023565) (xy 390.056116 -41.023032)
			(xy 386.208524 -41.023032) (xy 386.198461 -41.02347) (xy 386.179879 -41.031207) (xy 386.172456 -41.038018)
			(xy 386.005832 -41.204642) (xy 385.999093 -41.212014) (xy 385.991511 -41.230476) (xy 385.9911 -41.240456)
			(xy 385.9911 -43.73626) (xy 394.513052 -43.73626) (xy 394.517123 -43.680638) (xy 394.529249 -43.626201)
			(xy 394.549172 -43.57411) (xy 394.576468 -43.525475) (xy 394.610554 -43.481332) (xy 394.650703 -43.442623)
			(xy 394.696061 -43.410172) (xy 394.745661 -43.384671) (xy 394.798445 -43.366664) (xy 394.853288 -43.356534)
			(xy 394.909022 -43.354497) (xy 394.964459 -43.360597) (xy 395.018416 -43.374703) (xy 395.069745 -43.396515)
			(xy 395.117351 -43.425569) (xy 395.160219 -43.461244) (xy 395.197436 -43.502781) (xy 395.228209 -43.549294)
			(xy 395.251881 -43.599791) (xy 395.267949 -43.653198) (xy 395.276069 -43.708374) (xy 395.276578 -43.73626)
			(xy 395.276069 -43.764146) (xy 395.267949 -43.819322) (xy 395.251881 -43.872729) (xy 395.228209 -43.923226)
			(xy 395.197436 -43.969739) (xy 395.160219 -44.011276) (xy 395.117351 -44.046951) (xy 395.069745 -44.076005)
			(xy 395.018416 -44.097817) (xy 394.964459 -44.111923) (xy 394.909022 -44.118023) (xy 394.853288 -44.115986)
			(xy 394.798445 -44.105856) (xy 394.745661 -44.087849) (xy 394.696061 -44.062348) (xy 394.650703 -44.029897)
			(xy 394.610554 -43.991188) (xy 394.576468 -43.947045) (xy 394.549172 -43.89841) (xy 394.529249 -43.846319)
			(xy 394.517123 -43.791882) (xy 394.513052 -43.73626) (xy 385.9911 -43.73626) (xy 385.9911 -45.114464)
			(xy 394.365478 -45.114464) (xy 394.369549 -45.058842) (xy 394.381675 -45.004405) (xy 394.401598 -44.952314)
			(xy 394.428894 -44.903679) (xy 394.46298 -44.859536) (xy 394.503129 -44.820827) (xy 394.548487 -44.788376)
			(xy 394.598087 -44.762875) (xy 394.650871 -44.744868) (xy 394.705714 -44.734738) (xy 394.761448 -44.732701)
			(xy 394.816885 -44.738801) (xy 394.870842 -44.752907) (xy 394.922171 -44.774719) (xy 394.969777 -44.803773)
			(xy 395.012645 -44.839448) (xy 395.049862 -44.880985) (xy 395.080635 -44.927498) (xy 395.104307 -44.977995)
			(xy 395.120375 -45.031402) (xy 395.128495 -45.086578) (xy 395.129004 -45.114464) (xy 395.128495 -45.14235)
			(xy 395.120375 -45.197526) (xy 395.104307 -45.250933) (xy 395.080635 -45.30143) (xy 395.049862 -45.347943)
			(xy 395.012645 -45.38948) (xy 394.969777 -45.425155) (xy 394.922171 -45.454209) (xy 394.870842 -45.476021)
			(xy 394.816885 -45.490127) (xy 394.761448 -45.496227) (xy 394.705714 -45.49419) (xy 394.650871 -45.48406)
			(xy 394.598087 -45.466053) (xy 394.548487 -45.440552) (xy 394.503129 -45.408101) (xy 394.46298 -45.369392)
			(xy 394.428894 -45.325249) (xy 394.401598 -45.276614) (xy 394.381675 -45.224523) (xy 394.369549 -45.170086)
			(xy 394.365478 -45.114464) (xy 385.9911 -45.114464) (xy 385.9911 -46.893226) (xy 394.637258 -46.893226)
			(xy 394.641329 -46.837604) (xy 394.653455 -46.783167) (xy 394.673378 -46.731076) (xy 394.700674 -46.682441)
			(xy 394.73476 -46.638298) (xy 394.774909 -46.599589) (xy 394.820267 -46.567138) (xy 394.869867 -46.541637)
			(xy 394.922651 -46.52363) (xy 394.977494 -46.5135) (xy 395.033228 -46.511463) (xy 395.088665 -46.517563)
			(xy 395.142622 -46.531669) (xy 395.193951 -46.553481) (xy 395.241557 -46.582535) (xy 395.284425 -46.61821)
			(xy 395.321642 -46.659747) (xy 395.352415 -46.70626) (xy 395.376087 -46.756757) (xy 395.392155 -46.810164)
			(xy 395.400275 -46.86534) (xy 395.400784 -46.893226) (xy 395.400275 -46.921112) (xy 395.392155 -46.976288)
			(xy 395.376087 -47.029695) (xy 395.352415 -47.080192) (xy 395.321642 -47.126705) (xy 395.284425 -47.168242)
			(xy 395.241557 -47.203917) (xy 395.193951 -47.232971) (xy 395.142622 -47.254783) (xy 395.088665 -47.268889)
			(xy 395.033228 -47.274989) (xy 394.977494 -47.272952) (xy 394.922651 -47.262822) (xy 394.869867 -47.244815)
			(xy 394.820267 -47.219314) (xy 394.774909 -47.186863) (xy 394.73476 -47.148154) (xy 394.700674 -47.104011)
			(xy 394.673378 -47.055376) (xy 394.653455 -47.003285) (xy 394.641329 -46.948848) (xy 394.637258 -46.893226)
			(xy 385.9911 -46.893226) (xy 385.9911 -47.936658) (xy 392.952986 -47.936658) (xy 392.953472 -47.909407)
			(xy 392.961228 -47.855459) (xy 392.976583 -47.803164) (xy 392.999225 -47.753587) (xy 393.028691 -47.707737)
			(xy 393.064382 -47.666546) (xy 393.105573 -47.630855) (xy 393.151423 -47.601389) (xy 393.201 -47.578747)
			(xy 393.253295 -47.563392) (xy 393.307243 -47.555636) (xy 393.361745 -47.555636) (xy 393.415693 -47.563392)
			(xy 393.467988 -47.578747) (xy 393.517565 -47.601389) (xy 393.563415 -47.630855) (xy 393.604606 -47.666546)
			(xy 393.640297 -47.707737) (xy 393.669763 -47.753587) (xy 393.692405 -47.803164) (xy 393.70776 -47.855459)
			(xy 393.715516 -47.909407) (xy 393.716002 -47.936658) (xy 393.715561 -47.963) (xy 393.70831 -48.015182)
			(xy 393.693953 -48.065872) (xy 393.672763 -48.114106) (xy 393.645143 -48.158969) (xy 393.611617 -48.199608)
			(xy 393.572822 -48.235252) (xy 393.55141 -48.250602) (xy 393.53959 -48.259301) (xy 393.52116 -48.282127)
			(xy 393.50998 -48.309251) (xy 393.506973 -48.338435) (xy 393.512387 -48.367268) (xy 393.525777 -48.393372)
			(xy 393.546035 -48.414593) (xy 393.558522 -48.422306) (xy 393.583069 -48.436983) (xy 393.627825 -48.47259)
			(xy 393.666766 -48.514477) (xy 393.69902 -48.561706) (xy 393.723864 -48.613221) (xy 393.740742 -48.667866)
			(xy 393.749275 -48.724418) (xy 393.749784 -48.753014) (xy 393.749298 -48.780265) (xy 393.741542 -48.834213)
			(xy 393.726187 -48.886508) (xy 393.703545 -48.936085) (xy 393.674079 -48.981935) (xy 393.638388 -49.023126)
			(xy 393.597197 -49.058817) (xy 393.551347 -49.088283) (xy 393.50177 -49.110925) (xy 393.449475 -49.12628)
			(xy 393.395527 -49.134036) (xy 393.341025 -49.134036) (xy 393.287077 -49.12628) (xy 393.234782 -49.110925)
			(xy 393.185205 -49.088283) (xy 393.139355 -49.058817) (xy 393.098164 -49.023126) (xy 393.062473 -48.981935)
			(xy 393.033007 -48.936085) (xy 393.010365 -48.886508) (xy 392.99501 -48.834213) (xy 392.987254 -48.780265)
			(xy 392.986768 -48.753014) (xy 392.9872 -48.726672) (xy 392.994455 -48.67449) (xy 393.008814 -48.623801)
			(xy 393.030006 -48.575567) (xy 393.057627 -48.530704) (xy 393.091153 -48.490065) (xy 393.129948 -48.45442)
			(xy 393.15136 -48.43907) (xy 393.163212 -48.430409) (xy 393.181649 -48.407576) (xy 393.192832 -48.380443)
			(xy 393.195836 -48.351249) (xy 393.190414 -48.322407) (xy 393.177014 -48.296298) (xy 393.156741 -48.275077)
			(xy 393.144248 -48.267366) (xy 393.119726 -48.25265) (xy 393.074972 -48.217048) (xy 393.03603 -48.175167)
			(xy 393.003774 -48.127944) (xy 392.978926 -48.076437) (xy 392.962042 -48.021798) (xy 392.9535 -47.965252)
			(xy 392.952986 -47.936658) (xy 385.9911 -47.936658) (xy 385.9911 -58.731404) (xy 387.820662 -58.731404)
			(xy 387.821115 -58.704033) (xy 387.828934 -58.649853) (xy 387.844425 -58.597349) (xy 387.86727 -58.547602)
			(xy 387.896999 -58.501637) (xy 387.914642 -58.480706) (xy 387.920738 -58.473594) (xy 387.927088 -58.456576)
			(xy 387.927088 -58.371232) (xy 387.920738 -58.354214) (xy 387.914642 -58.347102) (xy 387.897005 -58.326166)
			(xy 387.867279 -58.280199) (xy 387.844432 -58.230454) (xy 387.828935 -58.177952) (xy 387.821105 -58.123774)
			(xy 387.821105 -58.069032) (xy 387.828933 -58.014854) (xy 387.84443 -57.962352) (xy 387.867276 -57.912606)
			(xy 387.897001 -57.866638) (xy 387.914642 -57.845706) (xy 387.920738 -57.838594) (xy 387.927088 -57.821576)
			(xy 387.927088 -57.736232) (xy 387.920738 -57.719214) (xy 387.914642 -57.712102) (xy 387.897005 -57.691166)
			(xy 387.867279 -57.645199) (xy 387.844432 -57.595454) (xy 387.828935 -57.542952) (xy 387.821105 -57.488774)
			(xy 387.821105 -57.434032) (xy 387.828933 -57.379854) (xy 387.84443 -57.327352) (xy 387.867276 -57.277606)
			(xy 387.897001 -57.231638) (xy 387.914642 -57.210706) (xy 387.920738 -57.203594) (xy 387.927088 -57.186576)
			(xy 387.927088 -57.101232) (xy 387.920738 -57.084214) (xy 387.914642 -57.077102) (xy 387.896997 -57.056175)
			(xy 387.867285 -57.010201) (xy 387.844449 -56.960453) (xy 387.82896 -56.907951) (xy 387.821134 -56.853774)
			(xy 387.820662 -56.826404) (xy 387.821148 -56.799153) (xy 387.828904 -56.745205) (xy 387.844259 -56.69291)
			(xy 387.866901 -56.643333) (xy 387.896367 -56.597483) (xy 387.932058 -56.556292) (xy 387.973249 -56.520601)
			(xy 388.019099 -56.491135) (xy 388.068676 -56.468493) (xy 388.120971 -56.453138) (xy 388.174919 -56.445382)
			(xy 388.229421 -56.445382) (xy 388.283369 -56.453138) (xy 388.335664 -56.468493) (xy 388.385241 -56.491135)
			(xy 388.431091 -56.520601) (xy 388.472282 -56.556292) (xy 388.507973 -56.597483) (xy 388.537439 -56.643333)
			(xy 388.560081 -56.69291) (xy 388.575436 -56.745205) (xy 388.583192 -56.799153) (xy 388.583678 -56.826404)
			(xy 388.58322 -56.853775) (xy 388.575401 -56.907954) (xy 388.55991 -56.960458) (xy 388.537067 -57.010204)
			(xy 388.50734 -57.056171) (xy 388.489698 -57.077102) (xy 388.483602 -57.084214) (xy 388.477252 -57.101232)
			(xy 388.477252 -57.186576) (xy 388.483602 -57.203594) (xy 388.489698 -57.210706) (xy 388.507342 -57.231636)
			(xy 388.537064 -57.277605) (xy 388.559908 -57.327352) (xy 388.575403 -57.379854) (xy 388.58323 -57.434033)
			(xy 388.58323 -57.488774) (xy 388.575401 -57.542952) (xy 388.559906 -57.595454) (xy 388.537061 -57.6452)
			(xy 388.507338 -57.691169) (xy 388.489698 -57.712102) (xy 388.483602 -57.719214) (xy 388.477252 -57.736232)
			(xy 388.477252 -57.821576) (xy 388.483602 -57.838594) (xy 388.489698 -57.845706) (xy 388.507342 -57.866636)
			(xy 388.537064 -57.912605) (xy 388.559908 -57.962352) (xy 388.575403 -58.014854) (xy 388.58323 -58.069033)
			(xy 388.58323 -58.123774) (xy 388.575401 -58.177952) (xy 388.559906 -58.230454) (xy 388.537061 -58.2802)
			(xy 388.507338 -58.326169) (xy 388.489698 -58.347102) (xy 388.483602 -58.354214) (xy 388.477252 -58.371232)
			(xy 388.477252 -58.456576) (xy 388.483602 -58.473594) (xy 388.489698 -58.480706) (xy 388.507353 -58.501625)
			(xy 388.537063 -58.547602) (xy 388.559895 -58.597352) (xy 388.575383 -58.649856) (xy 388.583206 -58.704034)
			(xy 388.583678 -58.731404) (xy 388.583192 -58.758655) (xy 388.578528 -58.791094) (xy 390.476486 -58.791094)
			(xy 390.476952 -58.763724) (xy 390.48477 -58.709545) (xy 390.50026 -58.657042) (xy 390.523101 -58.607295)
			(xy 390.552825 -58.561328) (xy 390.570466 -58.540396) (xy 390.576562 -58.533284) (xy 390.582912 -58.516266)
			(xy 390.582912 -58.430922) (xy 390.576562 -58.413904) (xy 390.570466 -58.406792) (xy 390.552818 -58.385865)
			(xy 390.52309 -58.339897) (xy 390.500243 -58.29015) (xy 390.484745 -58.237647) (xy 390.476917 -58.183467)
			(xy 390.476917 -58.128724) (xy 390.484747 -58.074544) (xy 390.500246 -58.022041) (xy 390.523095 -57.972295)
			(xy 390.552823 -57.926328) (xy 390.570466 -57.905396) (xy 390.576562 -57.898284) (xy 390.582912 -57.881266)
			(xy 390.582912 -57.795922) (xy 390.576562 -57.778904) (xy 390.570466 -57.771792) (xy 390.552804 -57.750878)
			(xy 390.523097 -57.7049) (xy 390.500266 -57.655148) (xy 390.48478 -57.602643) (xy 390.476957 -57.548464)
			(xy 390.476486 -57.521094) (xy 390.47696 -57.494779) (xy 390.484176 -57.442646) (xy 390.498486 -57.391998)
			(xy 390.519616 -57.343796) (xy 390.547168 -57.298954) (xy 390.580618 -57.258321) (xy 390.599676 -57.24017)
			(xy 390.607089 -57.232658) (xy 390.615608 -57.213371) (xy 390.616186 -57.202832) (xy 390.616186 -57.128156)
			(xy 390.615644 -57.117608) (xy 390.607118 -57.098312) (xy 390.599676 -57.090818) (xy 390.58062 -57.07266)
			(xy 390.547137 -57.032046) (xy 390.519561 -56.987211) (xy 390.498418 -56.939008) (xy 390.48411 -56.888354)
			(xy 390.476908 -56.836212) (xy 390.476486 -56.809894) (xy 390.476972 -56.782643) (xy 390.484728 -56.728695)
			(xy 390.500083 -56.6764) (xy 390.522725 -56.626823) (xy 390.552191 -56.580973) (xy 390.587882 -56.539782)
			(xy 390.629073 -56.504091) (xy 390.674923 -56.474625) (xy 390.7245 -56.451983) (xy 390.776795 -56.436628)
			(xy 390.830743 -56.428872) (xy 390.885245 -56.428872) (xy 390.939193 -56.436628) (xy 390.991488 -56.451983)
			(xy 391.041065 -56.474625) (xy 391.086915 -56.504091) (xy 391.128106 -56.539782) (xy 391.163797 -56.580973)
			(xy 391.193263 -56.626823) (xy 391.215905 -56.6764) (xy 391.23126 -56.728695) (xy 391.239016 -56.782643)
			(xy 391.239502 -56.809894) (xy 391.239091 -56.836211) (xy 391.231862 -56.888347) (xy 391.217541 -56.938996)
			(xy 391.196398 -56.987198) (xy 391.168836 -57.032039) (xy 391.135375 -57.072669) (xy 391.116312 -57.090818)
			(xy 391.108902 -57.098333) (xy 391.100382 -57.117618) (xy 391.099802 -57.128156) (xy 391.099802 -57.202832)
			(xy 391.100354 -57.213379) (xy 391.108873 -57.232675) (xy 391.116312 -57.24017) (xy 391.135379 -57.258317)
			(xy 391.168858 -57.298935) (xy 391.19643 -57.343773) (xy 391.21757 -57.391978) (xy 391.231877 -57.442633)
			(xy 391.235249 -57.467049) (xy 391.418592 -57.467049) (xy 391.418592 -57.412551) (xy 391.426348 -57.358608)
			(xy 391.441701 -57.306317) (xy 391.464339 -57.256744) (xy 391.493802 -57.210896) (xy 391.529489 -57.169709)
			(xy 391.570674 -57.134018) (xy 391.616519 -57.104552) (xy 391.666091 -57.081911) (xy 391.71838 -57.066554)
			(xy 391.772323 -57.058794) (xy 391.799572 -57.058306) (xy 391.825889 -57.058729) (xy 391.878024 -57.065955)
			(xy 391.928673 -57.080274) (xy 391.976875 -57.101414) (xy 392.021716 -57.128975) (xy 392.062347 -57.162433)
			(xy 392.080496 -57.181496) (xy 392.088018 -57.188897) (xy 392.107298 -57.197422) (xy 392.117834 -57.198006)
			(xy 392.19251 -57.198006) (xy 392.203062 -57.197494) (xy 392.222357 -57.188947) (xy 392.229848 -57.181496)
			(xy 392.247958 -57.162393) (xy 392.288584 -57.128917) (xy 392.33343 -57.10135) (xy 392.381642 -57.080215)
			(xy 392.432304 -57.065916) (xy 392.484451 -57.058723) (xy 392.510772 -57.058306) (xy 392.538027 -57.058739)
			(xy 392.591983 -57.066493) (xy 392.627257 -57.076848) (xy 393.438634 -57.076848) (xy 393.43912 -57.049478)
			(xy 393.446932 -56.9953) (xy 393.462416 -56.942797) (xy 393.485253 -56.893049) (xy 393.514974 -56.847082)
			(xy 393.532614 -56.82615) (xy 393.53871 -56.819038) (xy 393.54506 -56.80202) (xy 393.54506 -56.716676)
			(xy 393.53871 -56.699658) (xy 393.532614 -56.692546) (xy 393.514985 -56.671606) (xy 393.485271 -56.625635)
			(xy 393.462433 -56.57589) (xy 393.44694 -56.523391) (xy 393.439109 -56.469217) (xy 393.438634 -56.441848)
			(xy 393.43912 -56.414597) (xy 393.446876 -56.360649) (xy 393.462231 -56.308354) (xy 393.484873 -56.258777)
			(xy 393.514339 -56.212927) (xy 393.55003 -56.171736) (xy 393.591221 -56.136045) (xy 393.637071 -56.106579)
			(xy 393.686648 -56.083937) (xy 393.738943 -56.068582) (xy 393.792891 -56.060826) (xy 393.847393 -56.060826)
			(xy 393.901341 -56.068582) (xy 393.953636 -56.083937) (xy 394.003213 -56.106579) (xy 394.049063 -56.136045)
			(xy 394.090254 -56.171736) (xy 394.125945 -56.212927) (xy 394.155411 -56.258777) (xy 394.178053 -56.308354)
			(xy 394.193408 -56.360649) (xy 394.201164 -56.414597) (xy 394.20165 -56.441848) (xy 394.201166 -56.469218)
			(xy 394.193354 -56.523397) (xy 394.17787 -56.5759) (xy 394.155032 -56.625647) (xy 394.12531 -56.671614)
			(xy 394.10767 -56.692546) (xy 394.101574 -56.699658) (xy 394.095224 -56.716676) (xy 394.095224 -56.80202)
			(xy 394.101574 -56.819038) (xy 394.10767 -56.82615) (xy 394.125294 -56.847094) (xy 394.15501 -56.893063)
			(xy 394.177849 -56.942807) (xy 394.193343 -56.995306) (xy 394.201174 -57.04948) (xy 394.20165 -57.076848)
			(xy 394.201164 -57.104099) (xy 394.193408 -57.158047) (xy 394.178053 -57.210342) (xy 394.155411 -57.259919)
			(xy 394.125945 -57.305769) (xy 394.090254 -57.34696) (xy 394.049063 -57.382651) (xy 394.003213 -57.412117)
			(xy 393.953636 -57.434759) (xy 393.901341 -57.450114) (xy 393.847393 -57.45787) (xy 393.792891 -57.45787)
			(xy 393.738943 -57.450114) (xy 393.686648 -57.434759) (xy 393.637071 -57.412117) (xy 393.591221 -57.382651)
			(xy 393.55003 -57.34696) (xy 393.514339 -57.305769) (xy 393.484873 -57.259919) (xy 393.462231 -57.210342)
			(xy 393.446876 -57.158047) (xy 393.43912 -57.104099) (xy 393.438634 -57.076848) (xy 392.627257 -57.076848)
			(xy 392.644286 -57.081847) (xy 392.693872 -57.104489) (xy 392.73973 -57.133957) (xy 392.780928 -57.169652)
			(xy 392.816626 -57.210847) (xy 392.846098 -57.256703) (xy 392.868743 -57.306287) (xy 392.884101 -57.358589)
			(xy 392.891859 -57.412545) (xy 392.891859 -57.467055) (xy 392.884101 -57.521011) (xy 392.868743 -57.573313)
			(xy 392.846098 -57.622897) (xy 392.816626 -57.668753) (xy 392.780928 -57.709948) (xy 392.73973 -57.745643)
			(xy 392.693872 -57.775111) (xy 392.644286 -57.797753) (xy 392.591983 -57.813107) (xy 392.538027 -57.820861)
			(xy 392.510772 -57.821322) (xy 392.484456 -57.82086) (xy 392.432323 -57.813641) (xy 392.381675 -57.799329)
			(xy 392.333473 -57.778196) (xy 392.288631 -57.750643) (xy 392.247999 -57.717191) (xy 392.229848 -57.698132)
			(xy 392.222343 -57.69071) (xy 392.203051 -57.682196) (xy 392.19251 -57.681622) (xy 392.117834 -57.681622)
			(xy 392.107284 -57.682149) (xy 392.087988 -57.690685) (xy 392.080496 -57.698132) (xy 392.06235 -57.7172)
			(xy 392.021733 -57.750682) (xy 391.976896 -57.778256) (xy 391.92869 -57.799397) (xy 391.878034 -57.813703)
			(xy 391.825891 -57.820901) (xy 391.799572 -57.821322) (xy 391.772323 -57.820806) (xy 391.71838 -57.813046)
			(xy 391.666091 -57.797689) (xy 391.616519 -57.775048) (xy 391.570674 -57.745582) (xy 391.529489 -57.709891)
			(xy 391.493802 -57.668704) (xy 391.464339 -57.622856) (xy 391.441701 -57.573283) (xy 391.426348 -57.520992)
			(xy 391.418592 -57.467049) (xy 391.235249 -57.467049) (xy 391.239079 -57.494775) (xy 391.239502 -57.521094)
			(xy 391.239032 -57.548464) (xy 391.231215 -57.602643) (xy 391.215727 -57.655146) (xy 391.192886 -57.704893)
			(xy 391.163163 -57.75086) (xy 391.145522 -57.771792) (xy 391.139426 -57.778904) (xy 391.133076 -57.795922)
			(xy 391.133076 -57.881266) (xy 391.139426 -57.898284) (xy 391.145522 -57.905396) (xy 391.163155 -57.926334)
			(xy 391.192876 -57.972302) (xy 391.215719 -58.022048) (xy 391.231213 -58.074549) (xy 391.239042 -58.128726)
			(xy 391.239042 -58.183465) (xy 391.231215 -58.237642) (xy 391.215722 -58.290143) (xy 391.19288 -58.33989)
			(xy 391.16316 -58.385858) (xy 391.145522 -58.406792) (xy 391.139426 -58.413904) (xy 391.133076 -58.430922)
			(xy 391.133076 -58.516266) (xy 391.139426 -58.533284) (xy 391.145522 -58.540396) (xy 391.163176 -58.561316)
			(xy 391.192885 -58.607292) (xy 391.215718 -58.657043) (xy 391.231205 -58.709546) (xy 391.23903 -58.763724)
			(xy 391.239502 -58.791094) (xy 391.239016 -58.818345) (xy 391.23126 -58.872293) (xy 391.230863 -58.873644)
			(xy 392.500612 -58.873644) (xy 392.501101 -58.846275) (xy 392.508913 -58.792096) (xy 392.524396 -58.739593)
			(xy 392.547233 -58.689846) (xy 392.576953 -58.643878) (xy 392.594592 -58.622946) (xy 392.600688 -58.615834)
			(xy 392.607038 -58.598816) (xy 392.607038 -58.513472) (xy 392.600688 -58.496454) (xy 392.594592 -58.489342)
			(xy 392.576958 -58.468406) (xy 392.547246 -58.422434) (xy 392.524409 -58.372688) (xy 392.508917 -58.320188)
			(xy 392.501087 -58.266013) (xy 392.500612 -58.238644) (xy 392.501098 -58.211393) (xy 392.508854 -58.157445)
			(xy 392.524209 -58.10515) (xy 392.546851 -58.055573) (xy 392.576317 -58.009723) (xy 392.612008 -57.968532)
			(xy 392.653199 -57.932841) (xy 392.699049 -57.903375) (xy 392.748626 -57.880733) (xy 392.800921 -57.865378)
			(xy 392.854869 -57.857622) (xy 392.909371 -57.857622) (xy 392.963319 -57.865378) (xy 393.015614 -57.880733)
			(xy 393.065191 -57.903375) (xy 393.111041 -57.932841) (xy 393.152232 -57.968532) (xy 393.187923 -58.009723)
			(xy 393.217389 -58.055573) (xy 393.240031 -58.10515) (xy 393.255386 -58.157445) (xy 393.263142 -58.211393)
			(xy 393.263628 -58.238644) (xy 393.263147 -58.266014) (xy 393.255335 -58.320193) (xy 393.239851 -58.372697)
			(xy 393.217012 -58.422444) (xy 393.187289 -58.468411) (xy 393.169648 -58.489342) (xy 393.163552 -58.496454)
			(xy 393.157202 -58.513472) (xy 393.157202 -58.598816) (xy 393.163552 -58.615834) (xy 393.169648 -58.622946)
			(xy 393.187267 -58.643894) (xy 393.216984 -58.689862) (xy 393.239824 -58.739605) (xy 393.25532 -58.792103)
			(xy 393.263152 -58.846276) (xy 393.263628 -58.873644) (xy 393.263142 -58.900895) (xy 393.255386 -58.954843)
			(xy 393.240031 -59.007138) (xy 393.217389 -59.056715) (xy 393.187923 -59.102565) (xy 393.152232 -59.143756)
			(xy 393.111041 -59.179447) (xy 393.065191 -59.208913) (xy 393.015614 -59.231555) (xy 392.963319 -59.24691)
			(xy 392.909371 -59.254666) (xy 392.854869 -59.254666) (xy 392.800921 -59.24691) (xy 392.748626 -59.231555)
			(xy 392.699049 -59.208913) (xy 392.653199 -59.179447) (xy 392.612008 -59.143756) (xy 392.576317 -59.102565)
			(xy 392.546851 -59.056715) (xy 392.524209 -59.007138) (xy 392.508854 -58.954843) (xy 392.501098 -58.900895)
			(xy 392.500612 -58.873644) (xy 391.230863 -58.873644) (xy 391.215905 -58.924588) (xy 391.193263 -58.974165)
			(xy 391.163797 -59.020015) (xy 391.128106 -59.061206) (xy 391.086915 -59.096897) (xy 391.041065 -59.126363)
			(xy 390.991488 -59.149005) (xy 390.939193 -59.16436) (xy 390.885245 -59.172116) (xy 390.830743 -59.172116)
			(xy 390.776795 -59.16436) (xy 390.7245 -59.149005) (xy 390.674923 -59.126363) (xy 390.629073 -59.096897)
			(xy 390.587882 -59.061206) (xy 390.552191 -59.020015) (xy 390.522725 -58.974165) (xy 390.500083 -58.924588)
			(xy 390.484728 -58.872293) (xy 390.476972 -58.818345) (xy 390.476486 -58.791094) (xy 388.578528 -58.791094)
			(xy 388.575436 -58.812603) (xy 388.560081 -58.864898) (xy 388.537439 -58.914475) (xy 388.507973 -58.960325)
			(xy 388.472282 -59.001516) (xy 388.431091 -59.037207) (xy 388.385241 -59.066673) (xy 388.335664 -59.089315)
			(xy 388.283369 -59.10467) (xy 388.229421 -59.112426) (xy 388.174919 -59.112426) (xy 388.120971 -59.10467)
			(xy 388.068676 -59.089315) (xy 388.019099 -59.066673) (xy 387.973249 -59.037207) (xy 387.932058 -59.001516)
			(xy 387.896367 -58.960325) (xy 387.866901 -58.914475) (xy 387.844259 -58.864898) (xy 387.828904 -58.812603)
			(xy 387.821148 -58.758655) (xy 387.820662 -58.731404) (xy 385.9911 -58.731404) (xy 385.9911 -60.126451)
			(xy 391.480272 -60.126451) (xy 391.480272 -60.071949) (xy 391.488028 -60.018001) (xy 391.503383 -59.965705)
			(xy 391.526024 -59.916128) (xy 391.555491 -59.870277) (xy 391.591182 -59.829086) (xy 391.632372 -59.793394)
			(xy 391.678223 -59.763927) (xy 391.7278 -59.741285) (xy 391.780095 -59.72593) (xy 391.834043 -59.718172)
			(xy 391.861294 -59.717686) (xy 391.888664 -59.718159) (xy 391.942843 -59.725976) (xy 391.995346 -59.741463)
			(xy 392.045092 -59.764303) (xy 392.09106 -59.794026) (xy 392.111992 -59.811666) (xy 392.119104 -59.817762)
			(xy 392.136122 -59.824112) (xy 392.221466 -59.824112) (xy 392.238484 -59.817762) (xy 392.245596 -59.811666)
			(xy 392.266529 -59.794025) (xy 392.312497 -59.764301) (xy 392.362243 -59.741455) (xy 392.414745 -59.725959)
			(xy 392.468923 -59.71813) (xy 392.523665 -59.71813) (xy 392.577843 -59.725959) (xy 392.630345 -59.741455)
			(xy 392.680091 -59.764301) (xy 392.726059 -59.794025) (xy 392.746992 -59.811666) (xy 392.754104 -59.817762)
			(xy 392.771122 -59.824112) (xy 392.856466 -59.824112) (xy 392.873484 -59.817762) (xy 392.880596 -59.811666)
			(xy 392.901514 -59.79401) (xy 392.947491 -59.764302) (xy 392.997243 -59.74147) (xy 393.049746 -59.725983)
			(xy 393.103924 -59.718158) (xy 393.131294 -59.717686) (xy 393.158547 -59.718161) (xy 393.212497 -59.725917)
			(xy 393.264795 -59.741272) (xy 393.314375 -59.763914) (xy 393.360228 -59.793382) (xy 393.401421 -59.829075)
			(xy 393.437115 -59.870267) (xy 393.466583 -59.916119) (xy 393.489226 -59.965699) (xy 393.504582 -60.017997)
			(xy 393.512339 -60.071947) (xy 393.512339 -60.126453) (xy 393.504582 -60.180403) (xy 393.489226 -60.232701)
			(xy 393.466583 -60.282281) (xy 393.437115 -60.328133) (xy 393.401421 -60.369325) (xy 393.360228 -60.405018)
			(xy 393.314375 -60.434486) (xy 393.264795 -60.457128) (xy 393.212497 -60.472483) (xy 393.158547 -60.480239)
			(xy 393.131294 -60.480702) (xy 393.103924 -60.480239) (xy 393.049744 -60.47242) (xy 392.997241 -60.456931)
			(xy 392.947495 -60.434088) (xy 392.901528 -60.404363) (xy 392.880596 -60.386722) (xy 392.873484 -60.380626)
			(xy 392.856466 -60.374276) (xy 392.771122 -60.374276) (xy 392.754104 -60.380626) (xy 392.746992 -60.386722)
			(xy 392.726059 -60.404363) (xy 392.680091 -60.434087) (xy 392.630345 -60.456933) (xy 392.577843 -60.472429)
			(xy 392.523665 -60.480258) (xy 392.468923 -60.480258) (xy 392.414745 -60.472429) (xy 392.362243 -60.456933)
			(xy 392.312497 -60.434087) (xy 392.266529 -60.404363) (xy 392.245596 -60.386722) (xy 392.238484 -60.380626)
			(xy 392.221466 -60.374276) (xy 392.136122 -60.374276) (xy 392.119104 -60.380626) (xy 392.111992 -60.386722)
			(xy 392.091077 -60.404382) (xy 392.045099 -60.43409) (xy 391.995347 -60.456921) (xy 391.942843 -60.472408)
			(xy 391.888664 -60.480231) (xy 391.861294 -60.480702) (xy 391.834043 -60.480228) (xy 391.780095 -60.47247)
			(xy 391.7278 -60.457115) (xy 391.678223 -60.434473) (xy 391.632372 -60.405006) (xy 391.591182 -60.369314)
			(xy 391.555491 -60.328123) (xy 391.526024 -60.282272) (xy 391.503383 -60.232695) (xy 391.488028 -60.180399)
			(xy 391.480272 -60.126451) (xy 385.9911 -60.126451) (xy 385.9911 -60.999878) (xy 385.990566 -61.009867)
			(xy 385.982859 -61.028305) (xy 385.976114 -61.035692) (xy 385.200398 -61.811408) (xy 385.193041 -61.818056)
			(xy 385.174741 -61.825634) (xy 385.164838 -61.82614) (xy 385.108958 -61.82614) (xy 385.104894 -61.826902)
			(xy 385.089704 -61.829207) (xy 385.059038 -61.831115) (xy 385.04368 -61.830712) (xy 383.379472 -61.830712)
			(xy 383.37486 -61.830814) (xy 383.365788 -61.832477) (xy 383.361438 -61.834014) (xy 383.35204 -61.83757)
			(xy 383.344928 -61.844174) (xy 383.339086 -61.850524) (xy 383.282698 -61.923168) (xy 383.277872 -61.946028)
			(xy 383.28092 -61.957458) (xy 383.28628 -61.980005) (xy 383.292132 -62.025981) (xy 383.292604 -62.049152)
			(xy 383.292604 -62.054232) (xy 383.291926 -62.081351) (xy 383.283844 -62.134992) (xy 383.268245 -62.186948)
			(xy 383.245444 -62.23617) (xy 383.2159 -62.281666) (xy 383.18021 -62.322518) (xy 383.139094 -62.357904)
			(xy 383.093379 -62.387108) (xy 383.043989 -62.409542) (xy 382.991919 -62.424755) (xy 382.938219 -62.432438)
			(xy 382.911096 -62.432946) (xy 382.887541 -62.432566) (xy 382.840797 -62.426711) (xy 382.817878 -62.421262)
			(xy 382.803654 -62.417706) (xy 382.776476 -62.426342) (xy 382.698244 -62.517274) (xy 382.693672 -62.545468)
			(xy 382.69926 -62.55893) (xy 382.708586 -62.582314) (xy 382.721707 -62.630918) (xy 382.728325 -62.680824)
			(xy 382.728724 -62.705996) (xy 382.728239 -62.733248) (xy 382.720483 -62.787197) (xy 382.705128 -62.839493)
			(xy 382.682487 -62.889072) (xy 382.653021 -62.934924) (xy 382.61733 -62.976116) (xy 382.57614 -63.011809)
			(xy 382.530289 -63.041278) (xy 382.480712 -63.063921) (xy 382.428416 -63.079278) (xy 382.374468 -63.087037)
			(xy 382.347216 -63.087504) (xy 382.318406 -63.086978) (xy 382.261442 -63.078311) (xy 382.20643 -63.061172)
			(xy 382.154624 -63.03595) (xy 382.107202 -63.003221) (xy 382.08585 -62.983872) (xy 382.077214 -62.975744)
			(xy 382.05537 -62.968886) (xy 381.965454 -62.981332) (xy 381.963422 -62.981586) (xy 381.952686 -62.984095)
			(xy 381.934649 -62.996736) (xy 381.928624 -63.00597) (xy 381.913806 -63.03009) (xy 381.878167 -63.074068)
			(xy 381.836419 -63.112296) (xy 381.789479 -63.143932) (xy 381.738378 -63.168282) (xy 381.684239 -63.184811)
			(xy 381.628251 -63.193156) (xy 381.599948 -63.193676) (xy 381.572695 -63.193216) (xy 381.518744 -63.185465)
			(xy 381.466444 -63.170115) (xy 381.416862 -63.147477) (xy 381.371007 -63.118013) (xy 381.329812 -63.082322)
			(xy 381.294116 -63.041131) (xy 381.264646 -62.99528) (xy 381.242002 -62.945701) (xy 381.226645 -62.893403)
			(xy 381.218887 -62.839453) (xy 381.218887 -62.784947) (xy 381.226645 -62.730997) (xy 381.242002 -62.678699)
			(xy 381.264646 -62.62912) (xy 381.294116 -62.583269) (xy 381.329812 -62.542078) (xy 381.371007 -62.506387)
			(xy 381.416862 -62.476923) (xy 381.466444 -62.454285) (xy 381.518744 -62.438935) (xy 381.572695 -62.431184)
			(xy 381.599948 -62.43066) (xy 381.628759 -62.431183) (xy 381.685727 -62.439845) (xy 381.740742 -62.456979)
			(xy 381.792554 -62.482195) (xy 381.839982 -62.514919) (xy 381.861314 -62.534292) (xy 381.86995 -62.54242)
			(xy 381.891794 -62.549278) (xy 381.98171 -62.536832) (xy 381.983488 -62.536578) (xy 381.994632 -62.533947)
			(xy 382.013217 -62.520625) (xy 382.019302 -62.510924) (xy 382.020064 -62.5094) (xy 382.034964 -62.485593)
			(xy 382.070651 -62.442229) (xy 382.112308 -62.404562) (xy 382.159036 -62.373408) (xy 382.209825 -62.349438)
			(xy 382.263578 -62.333171) (xy 382.319135 -62.324957) (xy 382.347216 -62.324488) (xy 382.367282 -62.324996)
			(xy 382.367536 -62.324996) (xy 382.383284 -62.326012) (xy 382.39192 -62.327028) (xy 382.412748 -62.330076)
			(xy 382.413002 -62.330076) (xy 382.440434 -62.336172) (xy 382.454658 -62.339728) (xy 382.481836 -62.331092)
			(xy 382.560068 -62.24016) (xy 382.56464 -62.211966) (xy 382.559052 -62.198504) (xy 382.549897 -62.175554)
			(xy 382.536909 -62.127882) (xy 382.530175 -62.078933) (xy 382.529588 -62.054232) (xy 382.529588 -62.051184)
			(xy 382.529936 -62.027702) (xy 382.535672 -61.981089) (xy 382.541018 -61.95822) (xy 382.541272 -61.957966)
			(xy 382.543701 -61.946435) (xy 382.538938 -61.923386) (xy 382.532128 -61.91377) (xy 382.483106 -61.850524)
			(xy 382.477264 -61.844174) (xy 382.470152 -61.83757) (xy 382.460754 -61.834014) (xy 382.456406 -61.832475)
			(xy 382.447332 -61.830821) (xy 382.44272 -61.830712) (xy 381.464058 -61.830712) (xy 381.451686 -61.830642)
			(xy 381.427017 -61.828737) (xy 381.414782 -61.826902) (xy 381.410718 -61.82614) (xy 381.16891 -61.82614)
			(xy 381.157226 -61.829188) (xy 381.1524 -61.831474) (xy 381.151892 -61.831728) (xy 381.125957 -61.843587)
			(xy 381.071447 -61.860338) (xy 381.015051 -61.868796) (xy 380.986538 -61.86932) (xy 380.978664 -61.86932)
			(xy 380.951287 -61.868284) (xy 380.897236 -61.859335) (xy 380.845022 -61.842746) (xy 380.820168 -61.83122)
			(xy 380.815088 -61.82868) (xy 380.803912 -61.82614) (xy 380.552198 -61.82614) (xy 380.548134 -61.826902)
			(xy 380.535898 -61.828727) (xy 380.511229 -61.830637) (xy 380.498858 -61.830712) (xy 379.36424 -61.830712)
			(xy 379.355815 -61.831057) (xy 379.339865 -61.836489) (xy 379.332998 -61.84138) (xy 379.32614 -61.846714)
			(xy 379.278134 -61.920374) (xy 379.271022 -61.931296) (xy 379.270006 -61.94425) (xy 379.26899 -61.956696)
			(xy 379.274832 -61.970158) (xy 379.284649 -61.994086) (xy 379.298467 -62.043925) (xy 379.305424 -62.095174)
			(xy 379.30582 -62.121034) (xy 379.30582 -62.12586) (xy 379.305008 -62.152886) (xy 379.296698 -62.206313)
			(xy 379.280929 -62.258031) (xy 379.258017 -62.307004) (xy 379.22842 -62.352253) (xy 379.192731 -62.39287)
			(xy 379.151666 -62.428042) (xy 379.106047 -62.457064) (xy 379.056787 -62.479355) (xy 379.004873 -62.494469)
			(xy 378.951346 -62.502102) (xy 378.897278 -62.502102) (xy 378.843751 -62.494469) (xy 378.791837 -62.479355)
			(xy 378.742577 -62.457064) (xy 378.696958 -62.428042) (xy 378.655893 -62.39287) (xy 378.620204 -62.352253)
			(xy 378.590607 -62.307004) (xy 378.567695 -62.258031) (xy 378.551926 -62.206313) (xy 378.543616 -62.152886)
			(xy 378.542804 -62.12586) (xy 378.542804 -62.12078) (xy 378.543252 -62.094683) (xy 378.550405 -62.042981)
			(xy 378.564535 -61.992735) (xy 378.574554 -61.968634) (xy 378.578997 -61.956712) (xy 378.576852 -61.931394)
			(xy 378.57049 -61.920374) (xy 378.527056 -61.85408) (xy 378.519544 -61.843884) (xy 378.497285 -61.83187)
			(xy 378.484638 -61.83122) (xy 375.962418 -61.83122) (xy 375.952458 -61.831709) (xy 375.934039 -61.839303)
			(xy 375.926604 -61.845952) (xy 375.522744 -62.249812) (xy 375.515378 -62.256924) (xy 375.507758 -62.27572)
			(xy 375.507758 -63.273432) (xy 377.876814 -63.273432) (xy 377.880885 -63.21781) (xy 377.893011 -63.163373)
			(xy 377.912934 -63.111282) (xy 377.94023 -63.062647) (xy 377.974316 -63.018504) (xy 378.014465 -62.979795)
			(xy 378.059823 -62.947344) (xy 378.109423 -62.921843) (xy 378.162207 -62.903836) (xy 378.21705 -62.893706)
			(xy 378.272784 -62.891669) (xy 378.328221 -62.897769) (xy 378.382178 -62.911875) (xy 378.433507 -62.933687)
			(xy 378.481113 -62.962741) (xy 378.523981 -62.998416) (xy 378.561198 -63.039953) (xy 378.591971 -63.086466)
			(xy 378.615643 -63.136963) (xy 378.631711 -63.19037) (xy 378.639831 -63.245546) (xy 378.639831 -63.245552)
			(xy 391.404569 -63.245552) (xy 391.404569 -63.191048) (xy 391.412326 -63.137099) (xy 391.427682 -63.084803)
			(xy 391.450323 -63.035224) (xy 391.479791 -62.989373) (xy 391.515483 -62.948182) (xy 391.556674 -62.912489)
			(xy 391.602526 -62.883022) (xy 391.652105 -62.860381) (xy 391.704401 -62.845026) (xy 391.75835 -62.837269)
			(xy 391.785602 -62.836806) (xy 391.812972 -62.837269) (xy 391.867152 -62.845088) (xy 391.919655 -62.860577)
			(xy 391.969402 -62.88342) (xy 392.015368 -62.913145) (xy 392.0363 -62.930786) (xy 392.043412 -62.936882)
			(xy 392.06043 -62.943232) (xy 392.145774 -62.943232) (xy 392.162792 -62.936882) (xy 392.169904 -62.930786)
			(xy 392.190837 -62.913145) (xy 392.236805 -62.883421) (xy 392.286551 -62.860575) (xy 392.339053 -62.845079)
			(xy 392.393231 -62.83725) (xy 392.447973 -62.83725) (xy 392.502151 -62.845079) (xy 392.554653 -62.860575)
			(xy 392.604399 -62.883421) (xy 392.650367 -62.913145) (xy 392.6713 -62.930786) (xy 392.678412 -62.936882)
			(xy 392.69543 -62.943232) (xy 392.780774 -62.943232) (xy 392.797792 -62.936882) (xy 392.804904 -62.930786)
			(xy 392.825822 -62.913129) (xy 392.871799 -62.883421) (xy 392.92155 -62.860588) (xy 392.974054 -62.845101)
			(xy 393.028232 -62.837278) (xy 393.055602 -62.836806) (xy 393.082854 -62.837264) (xy 393.136804 -62.845021)
			(xy 393.1891 -62.860377) (xy 393.238679 -62.883019) (xy 393.284531 -62.912486) (xy 393.325722 -62.948179)
			(xy 393.361415 -62.989371) (xy 393.390882 -63.035223) (xy 393.413524 -63.084802) (xy 393.428879 -63.137098)
			(xy 393.436636 -63.191048) (xy 393.436636 -63.245552) (xy 393.428879 -63.299502) (xy 393.413524 -63.351798)
			(xy 393.390882 -63.401377) (xy 393.361415 -63.447229) (xy 393.325722 -63.488421) (xy 393.284531 -63.524114)
			(xy 393.238679 -63.553581) (xy 393.1891 -63.576223) (xy 393.136804 -63.591579) (xy 393.082854 -63.599336)
			(xy 393.055602 -63.599822) (xy 393.028231 -63.599374) (xy 392.97405 -63.591555) (xy 392.921546 -63.576062)
			(xy 392.8718 -63.553216) (xy 392.825834 -63.523486) (xy 392.804904 -63.505842) (xy 392.797792 -63.499746)
			(xy 392.780774 -63.493396) (xy 392.69543 -63.493396) (xy 392.678412 -63.499746) (xy 392.6713 -63.505842)
			(xy 392.650367 -63.523483) (xy 392.604399 -63.553207) (xy 392.554653 -63.576053) (xy 392.502151 -63.591549)
			(xy 392.447973 -63.599378) (xy 392.393231 -63.599378) (xy 392.339053 -63.591549) (xy 392.286551 -63.576053)
			(xy 392.236805 -63.553207) (xy 392.190837 -63.523483) (xy 392.169904 -63.505842) (xy 392.162792 -63.499746)
			(xy 392.145774 -63.493396) (xy 392.06043 -63.493396) (xy 392.043412 -63.499746) (xy 392.0363 -63.505842)
			(xy 392.015384 -63.523501) (xy 391.969406 -63.553209) (xy 391.919655 -63.57604) (xy 391.867151 -63.591527)
			(xy 391.812972 -63.599351) (xy 391.785602 -63.599822) (xy 391.75835 -63.599331) (xy 391.704401 -63.591574)
			(xy 391.652105 -63.576219) (xy 391.602526 -63.553578) (xy 391.556674 -63.524111) (xy 391.515483 -63.488418)
			(xy 391.479791 -63.447227) (xy 391.450323 -63.401376) (xy 391.427682 -63.351797) (xy 391.412326 -63.299501)
			(xy 391.404569 -63.245552) (xy 378.639831 -63.245552) (xy 378.64034 -63.273432) (xy 378.639831 -63.301318)
			(xy 378.631711 -63.356494) (xy 378.615643 -63.409901) (xy 378.591971 -63.460398) (xy 378.561198 -63.506911)
			(xy 378.523981 -63.548448) (xy 378.481113 -63.584123) (xy 378.433507 -63.613177) (xy 378.382178 -63.634989)
			(xy 378.328221 -63.649095) (xy 378.272784 -63.655195) (xy 378.21705 -63.653158) (xy 378.162207 -63.643028)
			(xy 378.109423 -63.625021) (xy 378.059823 -63.59952) (xy 378.014465 -63.567069) (xy 377.974316 -63.52836)
			(xy 377.94023 -63.484217) (xy 377.912934 -63.435582) (xy 377.893011 -63.383491) (xy 377.880885 -63.329054)
			(xy 377.876814 -63.273432) (xy 375.507758 -63.273432) (xy 375.507758 -64.102234) (xy 375.687588 -64.102234)
			(xy 375.691659 -64.046612) (xy 375.703785 -63.992175) (xy 375.723708 -63.940084) (xy 375.751004 -63.891449)
			(xy 375.78509 -63.847306) (xy 375.825239 -63.808597) (xy 375.870597 -63.776146) (xy 375.920197 -63.750645)
			(xy 375.972981 -63.732638) (xy 376.027824 -63.722508) (xy 376.083558 -63.720471) (xy 376.138995 -63.726571)
			(xy 376.192952 -63.740677) (xy 376.244281 -63.762489) (xy 376.291887 -63.791543) (xy 376.334755 -63.827218)
			(xy 376.371972 -63.868755) (xy 376.402745 -63.915268) (xy 376.426417 -63.965765) (xy 376.442485 -64.019172)
			(xy 376.450605 -64.074348) (xy 376.451114 -64.102234) (xy 376.450605 -64.13012) (xy 376.442485 -64.185296)
			(xy 376.426417 -64.238703) (xy 376.402745 -64.2892) (xy 376.387467 -64.312292) (xy 379.366016 -64.312292)
			(xy 379.370087 -64.25667) (xy 379.382213 -64.202233) (xy 379.402136 -64.150142) (xy 379.429432 -64.101507)
			(xy 379.463518 -64.057364) (xy 379.503667 -64.018655) (xy 379.549025 -63.986204) (xy 379.598625 -63.960703)
			(xy 379.651409 -63.942696) (xy 379.706252 -63.932566) (xy 379.761986 -63.930529) (xy 379.817423 -63.936629)
			(xy 379.87138 -63.950735) (xy 379.922709 -63.972547) (xy 379.970315 -64.001601) (xy 380.013183 -64.037276)
			(xy 380.0504 -64.078813) (xy 380.081173 -64.125326) (xy 380.104845 -64.175823) (xy 380.120913 -64.22923)
			(xy 380.129033 -64.284406) (xy 380.129542 -64.312292) (xy 380.129033 -64.340178) (xy 380.120913 -64.395354)
			(xy 380.104845 -64.448761) (xy 380.081173 -64.499258) (xy 380.0504 -64.545771) (xy 380.013183 -64.587308)
			(xy 379.970315 -64.622983) (xy 379.922709 -64.652037) (xy 379.87138 -64.673849) (xy 379.817423 -64.687955)
			(xy 379.761986 -64.694055) (xy 379.706252 -64.692018) (xy 379.651409 -64.681888) (xy 379.598625 -64.663881)
			(xy 379.549025 -64.63838) (xy 379.503667 -64.605929) (xy 379.463518 -64.56722) (xy 379.429432 -64.523077)
			(xy 379.402136 -64.474442) (xy 379.382213 -64.422351) (xy 379.370087 -64.367914) (xy 379.366016 -64.312292)
			(xy 376.387467 -64.312292) (xy 376.371972 -64.335713) (xy 376.334755 -64.37725) (xy 376.291887 -64.412925)
			(xy 376.244281 -64.441979) (xy 376.192952 -64.463791) (xy 376.138995 -64.477897) (xy 376.083558 -64.483997)
			(xy 376.027824 -64.48196) (xy 375.972981 -64.47183) (xy 375.920197 -64.453823) (xy 375.870597 -64.428322)
			(xy 375.825239 -64.395871) (xy 375.78509 -64.357162) (xy 375.751004 -64.313019) (xy 375.723708 -64.264384)
			(xy 375.703785 -64.212293) (xy 375.691659 -64.157856) (xy 375.687588 -64.102234) (xy 375.507758 -64.102234)
			(xy 375.507758 -65.124076) (xy 380.407416 -65.124076) (xy 380.411487 -65.068454) (xy 380.423613 -65.014017)
			(xy 380.443536 -64.961926) (xy 380.470832 -64.913291) (xy 380.504918 -64.869148) (xy 380.545067 -64.830439)
			(xy 380.590425 -64.797988) (xy 380.640025 -64.772487) (xy 380.692809 -64.75448) (xy 380.747652 -64.74435)
			(xy 380.803386 -64.742313) (xy 380.858823 -64.748413) (xy 380.91278 -64.762519) (xy 380.964109 -64.784331)
			(xy 381.011715 -64.813385) (xy 381.054583 -64.84906) (xy 381.0918 -64.890597) (xy 381.122573 -64.93711)
			(xy 381.146245 -64.987607) (xy 381.162313 -65.041014) (xy 381.170433 -65.09619) (xy 381.170942 -65.124076)
			(xy 381.170433 -65.151962) (xy 381.169266 -65.15989) (xy 393.416534 -65.15989) (xy 393.420605 -65.104268)
			(xy 393.432731 -65.049831) (xy 393.452654 -64.99774) (xy 393.47995 -64.949105) (xy 393.514036 -64.904962)
			(xy 393.554185 -64.866253) (xy 393.599543 -64.833802) (xy 393.649143 -64.808301) (xy 393.701927 -64.790294)
			(xy 393.75677 -64.780164) (xy 393.812504 -64.778127) (xy 393.867941 -64.784227) (xy 393.921898 -64.798333)
			(xy 393.973227 -64.820145) (xy 394.020833 -64.849199) (xy 394.063701 -64.884874) (xy 394.100918 -64.926411)
			(xy 394.131691 -64.972924) (xy 394.155363 -65.023421) (xy 394.171431 -65.076828) (xy 394.179551 -65.132004)
			(xy 394.18006 -65.15989) (xy 394.179551 -65.187776) (xy 394.171431 -65.242952) (xy 394.155363 -65.296359)
			(xy 394.131691 -65.346856) (xy 394.100918 -65.393369) (xy 394.063701 -65.434906) (xy 394.020833 -65.470581)
			(xy 393.973227 -65.499635) (xy 393.921898 -65.521447) (xy 393.867941 -65.535553) (xy 393.812504 -65.541653)
			(xy 393.75677 -65.539616) (xy 393.701927 -65.529486) (xy 393.649143 -65.511479) (xy 393.599543 -65.485978)
			(xy 393.554185 -65.453527) (xy 393.514036 -65.414818) (xy 393.47995 -65.370675) (xy 393.452654 -65.32204)
			(xy 393.432731 -65.269949) (xy 393.420605 -65.215512) (xy 393.416534 -65.15989) (xy 381.169266 -65.15989)
			(xy 381.162313 -65.207138) (xy 381.146245 -65.260545) (xy 381.122573 -65.311042) (xy 381.0918 -65.357555)
			(xy 381.054583 -65.399092) (xy 381.011715 -65.434767) (xy 380.964109 -65.463821) (xy 380.91278 -65.485633)
			(xy 380.858823 -65.499739) (xy 380.803386 -65.505839) (xy 380.747652 -65.503802) (xy 380.692809 -65.493672)
			(xy 380.640025 -65.475665) (xy 380.590425 -65.450164) (xy 380.545067 -65.417713) (xy 380.504918 -65.379004)
			(xy 380.470832 -65.334861) (xy 380.443536 -65.286226) (xy 380.423613 -65.234135) (xy 380.411487 -65.179698)
			(xy 380.407416 -65.124076) (xy 375.507758 -65.124076) (xy 375.507758 -65.75552) (xy 388.646668 -65.75552)
			(xy 388.650739 -65.699898) (xy 388.662865 -65.645461) (xy 388.682788 -65.59337) (xy 388.710084 -65.544735)
			(xy 388.74417 -65.500592) (xy 388.784319 -65.461883) (xy 388.829677 -65.429432) (xy 388.879277 -65.403931)
			(xy 388.932061 -65.385924) (xy 388.986904 -65.375794) (xy 389.042638 -65.373757) (xy 389.098075 -65.379857)
			(xy 389.152032 -65.393963) (xy 389.203361 -65.415775) (xy 389.250967 -65.444829) (xy 389.293835 -65.480504)
			(xy 389.331052 -65.522041) (xy 389.361825 -65.568554) (xy 389.385497 -65.619051) (xy 389.401565 -65.672458)
			(xy 389.409685 -65.727634) (xy 389.410194 -65.75552) (xy 389.409685 -65.783406) (xy 389.401565 -65.838582)
			(xy 389.385497 -65.891989) (xy 389.361825 -65.942486) (xy 389.331052 -65.988999) (xy 389.293835 -66.030536)
			(xy 389.250967 -66.066211) (xy 389.203361 -66.095265) (xy 389.152032 -66.117077) (xy 389.098075 -66.131183)
			(xy 389.042638 -66.137283) (xy 388.986904 -66.135246) (xy 388.932061 -66.125116) (xy 388.879277 -66.107109)
			(xy 388.829677 -66.081608) (xy 388.784319 -66.049157) (xy 388.74417 -66.010448) (xy 388.710084 -65.966305)
			(xy 388.682788 -65.91767) (xy 388.662865 -65.865579) (xy 388.650739 -65.811142) (xy 388.646668 -65.75552)
			(xy 375.507758 -65.75552) (xy 375.507758 -67.488054) (xy 393.079222 -67.488054) (xy 393.083293 -67.432432)
			(xy 393.095419 -67.377995) (xy 393.115342 -67.325904) (xy 393.142638 -67.277269) (xy 393.176724 -67.233126)
			(xy 393.216873 -67.194417) (xy 393.262231 -67.161966) (xy 393.311831 -67.136465) (xy 393.364615 -67.118458)
			(xy 393.419458 -67.108328) (xy 393.475192 -67.106291) (xy 393.530629 -67.112391) (xy 393.584586 -67.126497)
			(xy 393.635915 -67.148309) (xy 393.683521 -67.177363) (xy 393.726389 -67.213038) (xy 393.763606 -67.254575)
			(xy 393.794379 -67.301088) (xy 393.818051 -67.351585) (xy 393.834119 -67.404992) (xy 393.842239 -67.460168)
			(xy 393.842748 -67.488054) (xy 393.842239 -67.51594) (xy 393.834119 -67.571116) (xy 393.818051 -67.624523)
			(xy 393.794379 -67.67502) (xy 393.763606 -67.721533) (xy 393.726389 -67.76307) (xy 393.683521 -67.798745)
			(xy 393.635915 -67.827799) (xy 393.584586 -67.849611) (xy 393.530629 -67.863717) (xy 393.475192 -67.869817)
			(xy 393.419458 -67.86778) (xy 393.364615 -67.85765) (xy 393.311831 -67.839643) (xy 393.262231 -67.814142)
			(xy 393.216873 -67.781691) (xy 393.176724 -67.742982) (xy 393.142638 -67.698839) (xy 393.115342 -67.650204)
			(xy 393.095419 -67.598113) (xy 393.083293 -67.543676) (xy 393.079222 -67.488054) (xy 375.507758 -67.488054)
			(xy 375.507758 -69.9516) (xy 375.508214 -69.961479) (xy 375.515648 -69.979786) (xy 375.522236 -69.98716)
			(xy 375.52249 -69.987414) (xy 375.698766 -70.16369) (xy 375.699274 -70.164198) (xy 375.706654 -70.170783)
			(xy 375.724953 -70.178234) (xy 375.734834 -70.178676)
		)
		(stroke
			(width 0)
			(type solid)
		)
		(fill yes)
		(layer "In9.Cu")
		(net "P12V_SSD13_R")
	)
	(gr_poly
		(pts
			(xy 330.678028 -70.178676) (xy 330.688095 -70.178247) (xy 330.70669 -70.170523) (xy 330.714096 -70.16369)
			(xy 331.040232 -69.837554) (xy 331.04074 -69.837046) (xy 331.047324 -69.829665) (xy 331.054776 -69.811366)
			(xy 331.055218 -69.801486) (xy 331.055218 -67.91579) (xy 331.05482 -67.906269) (xy 331.047861 -67.888545)
			(xy 331.034907 -67.874589) (xy 331.026516 -67.87007) (xy 330.930758 -67.823842) (xy 330.902056 -67.827144)
			(xy 330.890372 -67.836288) (xy 330.870061 -67.851903) (xy 330.826047 -67.878127) (xy 330.778919 -67.89822)
			(xy 330.729524 -67.911822) (xy 330.678753 -67.918687) (xy 330.653136 -67.919092) (xy 330.625883 -67.918631)
			(xy 330.57193 -67.910879) (xy 330.51963 -67.895526) (xy 330.470048 -67.872887) (xy 330.424192 -67.843421)
			(xy 330.382997 -67.807729) (xy 330.3473 -67.766537) (xy 330.31783 -67.720684) (xy 330.295186 -67.671104)
			(xy 330.279829 -67.618805) (xy 330.272071 -67.564853) (xy 330.272071 -67.510347) (xy 330.279829 -67.456395)
			(xy 330.295186 -67.404096) (xy 330.31783 -67.354516) (xy 330.3473 -67.308663) (xy 330.382997 -67.267471)
			(xy 330.424192 -67.231779) (xy 330.470047 -67.202313) (xy 330.51963 -67.179674) (xy 330.57193 -67.164321)
			(xy 330.625883 -67.156569) (xy 330.653136 -67.156076) (xy 330.678751 -67.156493) (xy 330.72952 -67.163359)
			(xy 330.778912 -67.176963) (xy 330.826037 -67.197058) (xy 330.870047 -67.223284) (xy 330.890372 -67.23888)
			(xy 330.902056 -67.248024) (xy 330.930758 -67.251326) (xy 331.026516 -67.205098) (xy 331.034923 -67.200602)
			(xy 331.047878 -67.186633) (xy 331.054851 -67.168903) (xy 331.055218 -67.159378) (xy 331.055218 -65.506854)
			(xy 331.041502 -65.483486) (xy 331.030072 -65.476628) (xy 331.029564 -65.476628) (xy 330.956412 -65.433702)
			(xy 330.947399 -65.428968) (xy 330.927226 -65.426367) (xy 330.917296 -65.428622) (xy 330.90358 -65.432432)
			(xy 330.897992 -65.43548) (xy 330.869706 -65.450254) (xy 330.80943 -65.471194) (xy 330.746509 -65.481812)
			(xy 330.714604 -65.48247) (xy 330.71435 -65.48247) (xy 330.687104 -65.48198) (xy 330.633167 -65.474219)
			(xy 330.580883 -65.458861) (xy 330.531318 -65.436219) (xy 330.485478 -65.406755) (xy 330.444298 -65.371067)
			(xy 330.408615 -65.329882) (xy 330.379157 -65.284039) (xy 330.356522 -65.23447) (xy 330.34117 -65.182184)
			(xy 330.333416 -65.128246) (xy 330.333416 -65.073754) (xy 330.34117 -65.019816) (xy 330.356522 -64.96753)
			(xy 330.379157 -64.917961) (xy 330.408615 -64.872118) (xy 330.444298 -64.830933) (xy 330.485478 -64.795245)
			(xy 330.531318 -64.765781) (xy 330.580883 -64.743139) (xy 330.633167 -64.727781) (xy 330.687104 -64.72002)
			(xy 330.71435 -64.719454) (xy 330.714604 -64.719454) (xy 330.746508 -64.720118) (xy 330.809424 -64.730752)
			(xy 330.869705 -64.751676) (xy 330.897992 -64.766444) (xy 330.90358 -64.769492) (xy 330.917296 -64.773302)
			(xy 330.927222 -64.775565) (xy 330.947397 -64.772952) (xy 330.956412 -64.768222) (xy 331.029818 -64.725296)
			(xy 331.03058 -64.724788) (xy 331.037854 -64.719971) (xy 331.048892 -64.706475) (xy 331.054793 -64.690069)
			(xy 331.055218 -64.681354) (xy 331.055218 -52.622958) (xy 331.05344 -52.616608) (xy 331.04738 -52.592357)
			(xy 331.040883 -52.542795) (xy 331.040486 -52.517802) (xy 331.040486 -52.51577) (xy 331.040951 -52.491159)
			(xy 331.047449 -52.442364) (xy 331.05344 -52.418488) (xy 331.055218 -52.411884) (xy 331.055218 -51.455828)
			(xy 331.055655 -51.445764) (xy 331.06339 -51.42718) (xy 331.070204 -51.41976) (xy 331.177138 -51.312826)
			(xy 331.184537 -51.305983) (xy 331.203136 -51.298258) (xy 331.213206 -51.29784) (xy 331.903578 -51.29784)
			(xy 331.91196 -51.297078) (xy 331.919567 -51.295568) (xy 331.933407 -51.288587) (xy 331.939138 -51.283362)
			(xy 332.004162 -51.218338) (xy 332.011003 -51.210938) (xy 332.018721 -51.192339) (xy 332.019148 -51.18227)
			(xy 332.019148 -49.20615) (xy 332.018636 -49.196249) (xy 332.011063 -49.177946) (xy 332.004416 -49.17059)
			(xy 332.001114 -49.167034) (xy 331.93355 -49.120044) (xy 331.927048 -49.115868) (xy 331.912315 -49.111229)
			(xy 331.904594 -49.1109) (xy 331.882496 -49.1109) (xy 331.874622 -49.113694) (xy 331.844438 -49.123451)
			(xy 331.781878 -49.133927) (xy 331.750162 -49.134522) (xy 331.746098 -49.134522) (xy 331.719036 -49.133765)
			(xy 331.665525 -49.125548) (xy 331.613714 -49.109848) (xy 331.564643 -49.086981) (xy 331.519299 -49.057405)
			(xy 331.478591 -49.021714) (xy 331.443339 -48.980627) (xy 331.414251 -48.934968) (xy 331.39191 -48.885655)
			(xy 331.376767 -48.833678) (xy 331.369124 -48.780083) (xy 331.368654 -48.753014) (xy 331.369139 -48.725761)
			(xy 331.376893 -48.67181) (xy 331.392247 -48.619511) (xy 331.414887 -48.56993) (xy 331.444352 -48.524075)
			(xy 331.480043 -48.48288) (xy 331.521233 -48.447183) (xy 331.567084 -48.417712) (xy 331.616662 -48.395065)
			(xy 331.668959 -48.379705) (xy 331.722909 -48.371943) (xy 331.750162 -48.371506) (xy 331.750924 -48.371506)
			(xy 331.78454 -48.372259) (xy 331.850717 -48.38414) (xy 331.882496 -48.395128) (xy 331.89418 -48.399446)
			(xy 331.918818 -48.396398) (xy 331.997304 -48.341534) (xy 332.004416 -48.335692) (xy 332.004416 -48.335438)
			(xy 332.011069 -48.328083) (xy 332.01866 -48.309783) (xy 332.019148 -48.299878) (xy 332.019148 -41.954704)
			(xy 332.018768 -41.945871) (xy 332.012794 -41.929246) (xy 332.007464 -41.922192) (xy 332.00594 -41.920414)
			(xy 331.123544 -41.038018) (xy 331.116432 -41.030652) (xy 331.097636 -41.023032) (xy 329.31608 -41.023032)
			(xy 329.307379 -41.023385) (xy 329.290978 -41.029202) (xy 329.277461 -41.040162) (xy 329.272646 -41.047416)
			(xy 329.227688 -41.121584) (xy 329.223624 -41.13022) (xy 329.220299 -41.140526) (xy 329.22173 -41.162115)
			(xy 329.226418 -41.171876) (xy 329.22718 -41.1734) (xy 329.231498 -41.18229) (xy 329.243577 -41.20826)
			(xy 329.260691 -41.262918) (xy 329.269463 -41.319517) (xy 329.270106 -41.348152) (xy 329.270106 -41.34866)
			(xy 329.270106 -41.35501) (xy 329.269195 -41.383073) (xy 329.260149 -41.438486) (xy 329.243077 -41.491975)
			(xy 329.218349 -41.542383) (xy 329.186498 -41.588621) (xy 329.167744 -41.609518) (xy 329.16749 -41.609772)
			(xy 329.161009 -41.617123) (xy 329.153698 -41.635287) (xy 329.153266 -41.645078) (xy 329.153266 -41.724072)
			(xy 329.160124 -41.741852) (xy 329.166982 -41.748964) (xy 329.186251 -41.770291) (xy 329.218812 -41.817653)
			(xy 329.2439 -41.869364) (xy 329.260947 -41.924253) (xy 329.269567 -41.981078) (xy 329.269564 -42.038554)
			(xy 329.26094 -42.095378) (xy 329.243889 -42.150266) (xy 329.218796 -42.201975) (xy 329.186231 -42.249334)
			(xy 329.166982 -42.27068) (xy 329.160124 -42.277792) (xy 329.153266 -42.295572) (xy 329.153266 -42.384472)
			(xy 329.160124 -42.402252) (xy 329.166982 -42.409364) (xy 329.186251 -42.430691) (xy 329.218813 -42.478055)
			(xy 329.243901 -42.529767) (xy 329.260948 -42.584657) (xy 329.269567 -42.641484) (xy 329.270106 -42.670222)
			(xy 329.269633 -42.697592) (xy 329.261806 -42.751768) (xy 329.246317 -42.80427) (xy 329.223483 -42.85402)
			(xy 329.193773 -42.899995) (xy 329.176126 -42.92092) (xy 329.17003 -42.928032) (xy 329.16368 -42.944796)
			(xy 329.16368 -43.030648) (xy 329.17003 -43.047412) (xy 329.176126 -43.054524) (xy 329.193766 -43.075456)
			(xy 329.223487 -43.121424) (xy 329.246325 -43.171171) (xy 329.261811 -43.223674) (xy 329.269626 -43.277852)
			(xy 329.270106 -43.305222) (xy 329.26962 -43.332473) (xy 329.261864 -43.386421) (xy 329.246509 -43.438716)
			(xy 329.223867 -43.488293) (xy 329.194401 -43.534143) (xy 329.15871 -43.575334) (xy 329.117519 -43.611025)
			(xy 329.071669 -43.640491) (xy 329.022092 -43.663133) (xy 328.969797 -43.678488) (xy 328.915849 -43.686244)
			(xy 328.861347 -43.686244) (xy 328.807399 -43.678488) (xy 328.755104 -43.663133) (xy 328.705527 -43.640491)
			(xy 328.659677 -43.611025) (xy 328.618486 -43.575334) (xy 328.582795 -43.534143) (xy 328.553329 -43.488293)
			(xy 328.530687 -43.438716) (xy 328.515332 -43.386421) (xy 328.507576 -43.332473) (xy 328.50709 -43.305222)
			(xy 328.507567 -43.277854) (xy 328.515401 -43.223681) (xy 328.530896 -43.171184) (xy 328.553735 -43.121439)
			(xy 328.583448 -43.07547) (xy 328.60107 -43.054524) (xy 328.607166 -43.047412) (xy 328.613516 -43.030648)
			(xy 328.613516 -42.944796) (xy 328.607166 -42.928032) (xy 328.60107 -42.92092) (xy 328.583428 -42.899988)
			(xy 328.553702 -42.854022) (xy 328.530858 -42.804275) (xy 328.515366 -42.751772) (xy 328.507546 -42.697593)
			(xy 328.50709 -42.670222) (xy 328.507609 -42.641482) (xy 328.516229 -42.584653) (xy 328.533276 -42.529759)
			(xy 328.558365 -42.478044) (xy 328.590929 -42.430679) (xy 328.610214 -42.409364) (xy 328.617072 -42.402252)
			(xy 328.62393 -42.384472) (xy 328.62393 -42.295572) (xy 328.617072 -42.277792) (xy 328.610214 -42.27068)
			(xy 328.590942 -42.249353) (xy 328.558374 -42.20199) (xy 328.53328 -42.150277) (xy 328.516228 -42.095385)
			(xy 328.507603 -42.038556) (xy 328.5076 -41.981076) (xy 328.516221 -41.924246) (xy 328.533268 -41.869353)
			(xy 328.558358 -41.817638) (xy 328.590922 -41.770272) (xy 328.610214 -41.748964) (xy 328.617072 -41.741852)
			(xy 328.62393 -41.724072) (xy 328.62393 -41.635172) (xy 328.617072 -41.617646) (xy 328.610214 -41.61028)
			(xy 328.591415 -41.589486) (xy 328.559487 -41.543412) (xy 328.534634 -41.493168) (xy 328.517388 -41.439831)
			(xy 328.50812 -41.384547) (xy 328.50709 -41.356534) (xy 328.50709 -41.349422) (xy 328.507602 -41.320529)
			(xy 328.516289 -41.263399) (xy 328.533512 -41.208239) (xy 328.545698 -41.182036) (xy 328.553064 -41.166542)
			(xy 328.556127 -41.157735) (xy 328.556393 -41.139107) (xy 328.553572 -41.13022) (xy 328.549508 -41.121584)
			(xy 328.50455 -41.04767) (xy 328.497692 -41.035986) (xy 328.474578 -41.023032) (xy 327.554082 -41.023032)
			(xy 327.542465 -41.023614) (xy 327.521587 -41.033814) (xy 327.51395 -41.04259) (xy 327.457308 -41.11498)
			(xy 327.452482 -41.137586) (xy 327.455276 -41.14927) (xy 327.460598 -41.171949) (xy 327.466328 -41.21818)
			(xy 327.466706 -41.241472) (xy 327.466245 -41.268726) (xy 327.458491 -41.32268) (xy 327.443137 -41.374981)
			(xy 327.420496 -41.424565) (xy 327.391029 -41.470421) (xy 327.355335 -41.511617) (xy 327.314142 -41.547313)
			(xy 327.268287 -41.576784) (xy 327.218705 -41.599428) (xy 327.166405 -41.614785) (xy 327.112452 -41.622543)
			(xy 327.085198 -41.62298) (xy 327.056459 -41.622459) (xy 326.999632 -41.613836) (xy 326.944741 -41.596785)
			(xy 326.89303 -41.571692) (xy 326.845669 -41.539125) (xy 326.82434 -41.519856) (xy 326.817228 -41.512998)
			(xy 326.799448 -41.50614) (xy 326.710548 -41.50614) (xy 326.692768 -41.512998) (xy 326.685656 -41.519856)
			(xy 326.664327 -41.539123) (xy 326.616963 -41.571681) (xy 326.565251 -41.596767) (xy 326.510361 -41.613813)
			(xy 326.453536 -41.622434) (xy 326.424798 -41.62298) (xy 326.397546 -41.622517) (xy 326.343597 -41.614759)
			(xy 326.291301 -41.599403) (xy 326.241723 -41.57676) (xy 326.195872 -41.547291) (xy 326.154682 -41.511597)
			(xy 326.118991 -41.470404) (xy 326.089526 -41.424551) (xy 326.066887 -41.374971) (xy 326.051534 -41.322674)
			(xy 326.043781 -41.268724) (xy 326.04329 -41.241472) (xy 326.043669 -41.21818) (xy 326.0494 -41.171949)
			(xy 326.05472 -41.14927) (xy 326.057514 -41.137586) (xy 326.052688 -41.11498) (xy 325.996046 -41.04259)
			(xy 325.988457 -41.033758) (xy 325.967547 -41.023566) (xy 325.955914 -41.023032) (xy 322.108322 -41.023032)
			(xy 322.098259 -41.02347) (xy 322.079678 -41.031208) (xy 322.072254 -41.038018) (xy 321.90563 -41.204642)
			(xy 321.898891 -41.212014) (xy 321.891309 -41.230476) (xy 321.890898 -41.240456) (xy 321.890898 -43.73626)
			(xy 330.41285 -43.73626) (xy 330.416921 -43.680638) (xy 330.429047 -43.626201) (xy 330.44897 -43.57411)
			(xy 330.476266 -43.525475) (xy 330.510352 -43.481332) (xy 330.550501 -43.442623) (xy 330.595859 -43.410172)
			(xy 330.645459 -43.384671) (xy 330.698243 -43.366664) (xy 330.753086 -43.356534) (xy 330.80882 -43.354497)
			(xy 330.864257 -43.360597) (xy 330.918214 -43.374703) (xy 330.969543 -43.396515) (xy 331.017149 -43.425569)
			(xy 331.060017 -43.461244) (xy 331.097234 -43.502781) (xy 331.128007 -43.549294) (xy 331.151679 -43.599791)
			(xy 331.167747 -43.653198) (xy 331.175867 -43.708374) (xy 331.176376 -43.73626) (xy 331.175867 -43.764146)
			(xy 331.167747 -43.819322) (xy 331.151679 -43.872729) (xy 331.128007 -43.923226) (xy 331.097234 -43.969739)
			(xy 331.060017 -44.011276) (xy 331.017149 -44.046951) (xy 330.969543 -44.076005) (xy 330.918214 -44.097817)
			(xy 330.864257 -44.111923) (xy 330.80882 -44.118023) (xy 330.753086 -44.115986) (xy 330.698243 -44.105856)
			(xy 330.645459 -44.087849) (xy 330.595859 -44.062348) (xy 330.550501 -44.029897) (xy 330.510352 -43.991188)
			(xy 330.476266 -43.947045) (xy 330.44897 -43.89841) (xy 330.429047 -43.846319) (xy 330.416921 -43.791882)
			(xy 330.41285 -43.73626) (xy 321.890898 -43.73626) (xy 321.890898 -45.114464) (xy 330.265276 -45.114464)
			(xy 330.269347 -45.058842) (xy 330.281473 -45.004405) (xy 330.301396 -44.952314) (xy 330.328692 -44.903679)
			(xy 330.362778 -44.859536) (xy 330.402927 -44.820827) (xy 330.448285 -44.788376) (xy 330.497885 -44.762875)
			(xy 330.550669 -44.744868) (xy 330.605512 -44.734738) (xy 330.661246 -44.732701) (xy 330.716683 -44.738801)
			(xy 330.77064 -44.752907) (xy 330.821969 -44.774719) (xy 330.869575 -44.803773) (xy 330.912443 -44.839448)
			(xy 330.94966 -44.880985) (xy 330.980433 -44.927498) (xy 331.004105 -44.977995) (xy 331.020173 -45.031402)
			(xy 331.028293 -45.086578) (xy 331.028802 -45.114464) (xy 331.028293 -45.14235) (xy 331.020173 -45.197526)
			(xy 331.004105 -45.250933) (xy 330.980433 -45.30143) (xy 330.94966 -45.347943) (xy 330.912443 -45.38948)
			(xy 330.869575 -45.425155) (xy 330.821969 -45.454209) (xy 330.77064 -45.476021) (xy 330.716683 -45.490127)
			(xy 330.661246 -45.496227) (xy 330.605512 -45.49419) (xy 330.550669 -45.48406) (xy 330.497885 -45.466053)
			(xy 330.448285 -45.440552) (xy 330.402927 -45.408101) (xy 330.362778 -45.369392) (xy 330.328692 -45.325249)
			(xy 330.301396 -45.276614) (xy 330.281473 -45.224523) (xy 330.269347 -45.170086) (xy 330.265276 -45.114464)
			(xy 321.890898 -45.114464) (xy 321.890898 -46.893226) (xy 330.537056 -46.893226) (xy 330.541127 -46.837604)
			(xy 330.553253 -46.783167) (xy 330.573176 -46.731076) (xy 330.600472 -46.682441) (xy 330.634558 -46.638298)
			(xy 330.674707 -46.599589) (xy 330.720065 -46.567138) (xy 330.769665 -46.541637) (xy 330.822449 -46.52363)
			(xy 330.877292 -46.5135) (xy 330.933026 -46.511463) (xy 330.988463 -46.517563) (xy 331.04242 -46.531669)
			(xy 331.093749 -46.553481) (xy 331.141355 -46.582535) (xy 331.184223 -46.61821) (xy 331.22144 -46.659747)
			(xy 331.252213 -46.70626) (xy 331.275885 -46.756757) (xy 331.291953 -46.810164) (xy 331.300073 -46.86534)
			(xy 331.300582 -46.893226) (xy 331.300073 -46.921112) (xy 331.291953 -46.976288) (xy 331.275885 -47.029695)
			(xy 331.252213 -47.080192) (xy 331.22144 -47.126705) (xy 331.184223 -47.168242) (xy 331.141355 -47.203917)
			(xy 331.093749 -47.232971) (xy 331.04242 -47.254783) (xy 330.988463 -47.268889) (xy 330.933026 -47.274989)
			(xy 330.877292 -47.272952) (xy 330.822449 -47.262822) (xy 330.769665 -47.244815) (xy 330.720065 -47.219314)
			(xy 330.674707 -47.186863) (xy 330.634558 -47.148154) (xy 330.600472 -47.104011) (xy 330.573176 -47.055376)
			(xy 330.553253 -47.003285) (xy 330.541127 -46.948848) (xy 330.537056 -46.893226) (xy 321.890898 -46.893226)
			(xy 321.890898 -47.936658) (xy 328.852784 -47.936658) (xy 328.85327 -47.909407) (xy 328.861026 -47.855459)
			(xy 328.876381 -47.803164) (xy 328.899023 -47.753587) (xy 328.928489 -47.707737) (xy 328.96418 -47.666546)
			(xy 329.005371 -47.630855) (xy 329.051221 -47.601389) (xy 329.100798 -47.578747) (xy 329.153093 -47.563392)
			(xy 329.207041 -47.555636) (xy 329.261543 -47.555636) (xy 329.315491 -47.563392) (xy 329.367786 -47.578747)
			(xy 329.417363 -47.601389) (xy 329.463213 -47.630855) (xy 329.504404 -47.666546) (xy 329.540095 -47.707737)
			(xy 329.569561 -47.753587) (xy 329.592203 -47.803164) (xy 329.607558 -47.855459) (xy 329.615314 -47.909407)
			(xy 329.6158 -47.936658) (xy 329.61536 -47.963) (xy 329.608109 -48.015182) (xy 329.593752 -48.065872)
			(xy 329.572562 -48.114106) (xy 329.544942 -48.158969) (xy 329.511415 -48.199608) (xy 329.47262 -48.235252)
			(xy 329.451208 -48.250602) (xy 329.439389 -48.259302) (xy 329.420958 -48.282128) (xy 329.409778 -48.309251)
			(xy 329.406772 -48.338434) (xy 329.412186 -48.367268) (xy 329.425575 -48.393372) (xy 329.445834 -48.414592)
			(xy 329.45832 -48.422306) (xy 329.482866 -48.436984) (xy 329.527623 -48.47259) (xy 329.566564 -48.514477)
			(xy 329.598818 -48.561707) (xy 329.623662 -48.613221) (xy 329.64054 -48.667866) (xy 329.649073 -48.724418)
			(xy 329.649582 -48.753014) (xy 329.649096 -48.780265) (xy 329.64134 -48.834213) (xy 329.625985 -48.886508)
			(xy 329.603343 -48.936085) (xy 329.573877 -48.981935) (xy 329.538186 -49.023126) (xy 329.496995 -49.058817)
			(xy 329.451145 -49.088283) (xy 329.401568 -49.110925) (xy 329.349273 -49.12628) (xy 329.295325 -49.134036)
			(xy 329.240823 -49.134036) (xy 329.186875 -49.12628) (xy 329.13458 -49.110925) (xy 329.085003 -49.088283)
			(xy 329.039153 -49.058817) (xy 328.997962 -49.023126) (xy 328.962271 -48.981935) (xy 328.932805 -48.936085)
			(xy 328.910163 -48.886508) (xy 328.894808 -48.834213) (xy 328.887052 -48.780265) (xy 328.886566 -48.753014)
			(xy 328.886999 -48.726672) (xy 328.894254 -48.67449) (xy 328.908613 -48.623801) (xy 328.929804 -48.575567)
			(xy 328.957425 -48.530705) (xy 328.990952 -48.490065) (xy 329.029746 -48.45442) (xy 329.051158 -48.43907)
			(xy 329.06301 -48.430409) (xy 329.081448 -48.407576) (xy 329.092631 -48.380443) (xy 329.095635 -48.351249)
			(xy 329.090213 -48.322407) (xy 329.076812 -48.296298) (xy 329.05654 -48.275077) (xy 329.044046 -48.267366)
			(xy 329.019524 -48.25265) (xy 328.974769 -48.217049) (xy 328.935828 -48.175167) (xy 328.903572 -48.127944)
			(xy 328.878724 -48.076437) (xy 328.86184 -48.021798) (xy 328.853298 -47.965252) (xy 328.852784 -47.936658)
			(xy 321.890898 -47.936658) (xy 321.890898 -58.731404) (xy 323.72046 -58.731404) (xy 323.720914 -58.704033)
			(xy 323.728732 -58.649853) (xy 323.744223 -58.597349) (xy 323.767068 -58.547602) (xy 323.796797 -58.501637)
			(xy 323.81444 -58.480706) (xy 323.820536 -58.473594) (xy 323.826886 -58.456576) (xy 323.826886 -58.371232)
			(xy 323.820536 -58.354214) (xy 323.81444 -58.347102) (xy 323.796803 -58.326166) (xy 323.767077 -58.280199)
			(xy 323.74423 -58.230454) (xy 323.728733 -58.177952) (xy 323.720904 -58.123774) (xy 323.720904 -58.069032)
			(xy 323.728732 -58.014854) (xy 323.744228 -57.962352) (xy 323.767074 -57.912606) (xy 323.796799 -57.866638)
			(xy 323.81444 -57.845706) (xy 323.820536 -57.838594) (xy 323.826886 -57.821576) (xy 323.826886 -57.736232)
			(xy 323.820536 -57.719214) (xy 323.81444 -57.712102) (xy 323.796803 -57.691166) (xy 323.767077 -57.645199)
			(xy 323.74423 -57.595454) (xy 323.728733 -57.542952) (xy 323.720904 -57.488774) (xy 323.720904 -57.434032)
			(xy 323.728732 -57.379854) (xy 323.744228 -57.327352) (xy 323.767074 -57.277606) (xy 323.796799 -57.231638)
			(xy 323.81444 -57.210706) (xy 323.820536 -57.203594) (xy 323.826886 -57.186576) (xy 323.826886 -57.101232)
			(xy 323.820536 -57.084214) (xy 323.81444 -57.077102) (xy 323.796795 -57.056175) (xy 323.767082 -57.010201)
			(xy 323.744247 -56.960453) (xy 323.728758 -56.907951) (xy 323.720932 -56.853774) (xy 323.72046 -56.826404)
			(xy 323.720946 -56.799153) (xy 323.728702 -56.745205) (xy 323.744057 -56.69291) (xy 323.766699 -56.643333)
			(xy 323.796165 -56.597483) (xy 323.831856 -56.556292) (xy 323.873047 -56.520601) (xy 323.918897 -56.491135)
			(xy 323.968474 -56.468493) (xy 324.020769 -56.453138) (xy 324.074717 -56.445382) (xy 324.129219 -56.445382)
			(xy 324.183167 -56.453138) (xy 324.235462 -56.468493) (xy 324.285039 -56.491135) (xy 324.330889 -56.520601)
			(xy 324.37208 -56.556292) (xy 324.407771 -56.597483) (xy 324.437237 -56.643333) (xy 324.459879 -56.69291)
			(xy 324.475234 -56.745205) (xy 324.48299 -56.799153) (xy 324.483476 -56.826404) (xy 324.483018 -56.853775)
			(xy 324.475199 -56.907954) (xy 324.459709 -56.960458) (xy 324.436865 -57.010204) (xy 324.407138 -57.056171)
			(xy 324.389496 -57.077102) (xy 324.3834 -57.084214) (xy 324.37705 -57.101232) (xy 324.37705 -57.186576)
			(xy 324.3834 -57.203594) (xy 324.389496 -57.210706) (xy 324.40714 -57.231636) (xy 324.436863 -57.277605)
			(xy 324.459706 -57.327352) (xy 324.475201 -57.379854) (xy 324.483029 -57.434032) (xy 324.483029 -57.488774)
			(xy 324.4752 -57.542952) (xy 324.459704 -57.595454) (xy 324.43686 -57.6452) (xy 324.407136 -57.691169)
			(xy 324.389496 -57.712102) (xy 324.3834 -57.719214) (xy 324.37705 -57.736232) (xy 324.37705 -57.821576)
			(xy 324.3834 -57.838594) (xy 324.389496 -57.845706) (xy 324.40714 -57.866636) (xy 324.436863 -57.912605)
			(xy 324.459706 -57.962352) (xy 324.475201 -58.014854) (xy 324.483029 -58.069032) (xy 324.483029 -58.123774)
			(xy 324.4752 -58.177952) (xy 324.459704 -58.230454) (xy 324.43686 -58.2802) (xy 324.407136 -58.326169)
			(xy 324.389496 -58.347102) (xy 324.3834 -58.354214) (xy 324.37705 -58.371232) (xy 324.37705 -58.456576)
			(xy 324.3834 -58.473594) (xy 324.389496 -58.480706) (xy 324.407151 -58.501625) (xy 324.43686 -58.547602)
			(xy 324.459693 -58.597352) (xy 324.475181 -58.649856) (xy 324.483004 -58.704034) (xy 324.483476 -58.731404)
			(xy 324.48299 -58.758655) (xy 324.478326 -58.791094) (xy 326.376284 -58.791094) (xy 326.376726 -58.763723)
			(xy 326.384547 -58.709542) (xy 326.40004 -58.657038) (xy 326.422888 -58.607291) (xy 326.452619 -58.561326)
			(xy 326.470264 -58.540396) (xy 326.47636 -58.533284) (xy 326.48271 -58.516266) (xy 326.48271 -58.430922)
			(xy 326.47636 -58.413904) (xy 326.470264 -58.406792) (xy 326.452616 -58.385865) (xy 326.422889 -58.339897)
			(xy 326.400041 -58.29015) (xy 326.384544 -58.237647) (xy 326.376715 -58.183467) (xy 326.376716 -58.128724)
			(xy 326.384546 -58.074544) (xy 326.400044 -58.022042) (xy 326.422893 -57.972295) (xy 326.452621 -57.926328)
			(xy 326.470264 -57.905396) (xy 326.47636 -57.898284) (xy 326.48271 -57.881266) (xy 326.48271 -57.795922)
			(xy 326.47636 -57.778904) (xy 326.470264 -57.771792) (xy 326.452602 -57.750878) (xy 326.422895 -57.7049)
			(xy 326.400064 -57.655148) (xy 326.384578 -57.602643) (xy 326.376755 -57.548464) (xy 326.376284 -57.521094)
			(xy 326.376758 -57.494779) (xy 326.383975 -57.442646) (xy 326.398284 -57.391998) (xy 326.419415 -57.343796)
			(xy 326.446966 -57.298954) (xy 326.480416 -57.258321) (xy 326.499474 -57.24017) (xy 326.506887 -57.232658)
			(xy 326.515406 -57.213371) (xy 326.515984 -57.202832) (xy 326.515984 -57.128156) (xy 326.515443 -57.117608)
			(xy 326.506916 -57.098312) (xy 326.499474 -57.090818) (xy 326.480417 -57.07266) (xy 326.446935 -57.032046)
			(xy 326.419359 -56.987211) (xy 326.398216 -56.939008) (xy 326.383908 -56.888354) (xy 326.376706 -56.836212)
			(xy 326.376284 -56.809894) (xy 326.37677 -56.782643) (xy 326.384526 -56.728695) (xy 326.399881 -56.6764)
			(xy 326.422523 -56.626823) (xy 326.451989 -56.580973) (xy 326.48768 -56.539782) (xy 326.528871 -56.504091)
			(xy 326.574721 -56.474625) (xy 326.624298 -56.451983) (xy 326.676593 -56.436628) (xy 326.730541 -56.428872)
			(xy 326.785043 -56.428872) (xy 326.838991 -56.436628) (xy 326.891286 -56.451983) (xy 326.940863 -56.474625)
			(xy 326.986713 -56.504091) (xy 327.027904 -56.539782) (xy 327.063595 -56.580973) (xy 327.093061 -56.626823)
			(xy 327.115703 -56.6764) (xy 327.131058 -56.728695) (xy 327.138814 -56.782643) (xy 327.1393 -56.809894)
			(xy 327.138889 -56.836211) (xy 327.131661 -56.888347) (xy 327.117339 -56.938996) (xy 327.096197 -56.987198)
			(xy 327.068634 -57.032039) (xy 327.035173 -57.072669) (xy 327.01611 -57.090818) (xy 327.0087 -57.098332)
			(xy 327.00018 -57.117618) (xy 326.9996 -57.128156) (xy 326.9996 -57.202832) (xy 327.000153 -57.213379)
			(xy 327.008671 -57.232674) (xy 327.01611 -57.24017) (xy 327.035177 -57.258317) (xy 327.068655 -57.298935)
			(xy 327.096227 -57.343773) (xy 327.117368 -57.391978) (xy 327.131675 -57.442633) (xy 327.135047 -57.467049)
			(xy 327.318392 -57.467049) (xy 327.318392 -57.412551) (xy 327.326148 -57.358608) (xy 327.341501 -57.306318)
			(xy 327.364139 -57.256744) (xy 327.393601 -57.210897) (xy 327.429288 -57.169709) (xy 327.470473 -57.134019)
			(xy 327.516318 -57.104553) (xy 327.56589 -57.081911) (xy 327.618179 -57.066554) (xy 327.672121 -57.058794)
			(xy 327.69937 -57.058306) (xy 327.725687 -57.058731) (xy 327.777822 -57.065956) (xy 327.828471 -57.080275)
			(xy 327.876673 -57.101415) (xy 327.921514 -57.128975) (xy 327.962145 -57.162433) (xy 327.980294 -57.181496)
			(xy 327.987817 -57.188896) (xy 328.007096 -57.197421) (xy 328.017632 -57.198006) (xy 328.092308 -57.198006)
			(xy 328.10286 -57.197493) (xy 328.122155 -57.188946) (xy 328.129646 -57.181496) (xy 328.147757 -57.162394)
			(xy 328.188383 -57.128918) (xy 328.233228 -57.10135) (xy 328.28144 -57.080216) (xy 328.332102 -57.065916)
			(xy 328.384249 -57.058724) (xy 328.41057 -57.058306) (xy 328.437825 -57.058739) (xy 328.491781 -57.066493)
			(xy 328.527056 -57.076848) (xy 329.338432 -57.076848) (xy 329.338918 -57.049478) (xy 329.34673 -56.9953)
			(xy 329.362214 -56.942797) (xy 329.385051 -56.893049) (xy 329.414772 -56.847082) (xy 329.432412 -56.82615)
			(xy 329.438508 -56.819038) (xy 329.444858 -56.80202) (xy 329.444858 -56.716676) (xy 329.438508 -56.699658)
			(xy 329.432412 -56.692546) (xy 329.414783 -56.671606) (xy 329.385069 -56.625635) (xy 329.362231 -56.57589)
			(xy 329.346738 -56.523391) (xy 329.338907 -56.469217) (xy 329.338432 -56.441848) (xy 329.338918 -56.414597)
			(xy 329.346674 -56.360649) (xy 329.362029 -56.308354) (xy 329.384671 -56.258777) (xy 329.414137 -56.212927)
			(xy 329.449828 -56.171736) (xy 329.491019 -56.136045) (xy 329.536869 -56.106579) (xy 329.586446 -56.083937)
			(xy 329.638741 -56.068582) (xy 329.692689 -56.060826) (xy 329.747191 -56.060826) (xy 329.801139 -56.068582)
			(xy 329.853434 -56.083937) (xy 329.903011 -56.106579) (xy 329.948861 -56.136045) (xy 329.990052 -56.171736)
			(xy 330.025743 -56.212927) (xy 330.055209 -56.258777) (xy 330.077851 -56.308354) (xy 330.093206 -56.360649)
			(xy 330.100962 -56.414597) (xy 330.101448 -56.441848) (xy 330.100964 -56.469218) (xy 330.093153 -56.523397)
			(xy 330.077668 -56.5759) (xy 330.05483 -56.625647) (xy 330.025108 -56.671614) (xy 330.007468 -56.692546)
			(xy 330.001372 -56.699658) (xy 329.995022 -56.716676) (xy 329.995022 -56.80202) (xy 330.001372 -56.819038)
			(xy 330.007468 -56.82615) (xy 330.025092 -56.847094) (xy 330.054807 -56.893063) (xy 330.077647 -56.942808)
			(xy 330.093141 -56.995306) (xy 330.100972 -57.04948) (xy 330.101448 -57.076848) (xy 330.100962 -57.104099)
			(xy 330.093206 -57.158047) (xy 330.077851 -57.210342) (xy 330.055209 -57.259919) (xy 330.025743 -57.305769)
			(xy 329.990052 -57.34696) (xy 329.948861 -57.382651) (xy 329.903011 -57.412117) (xy 329.853434 -57.434759)
			(xy 329.801139 -57.450114) (xy 329.747191 -57.45787) (xy 329.692689 -57.45787) (xy 329.638741 -57.450114)
			(xy 329.586446 -57.434759) (xy 329.536869 -57.412117) (xy 329.491019 -57.382651) (xy 329.449828 -57.34696)
			(xy 329.414137 -57.305769) (xy 329.384671 -57.259919) (xy 329.362029 -57.210342) (xy 329.346674 -57.158047)
			(xy 329.338918 -57.104099) (xy 329.338432 -57.076848) (xy 328.527056 -57.076848) (xy 328.544085 -57.081847)
			(xy 328.593671 -57.104488) (xy 328.639529 -57.133957) (xy 328.680727 -57.169652) (xy 328.716425 -57.210847)
			(xy 328.745897 -57.256703) (xy 328.768543 -57.306287) (xy 328.783901 -57.358589) (xy 328.791659 -57.412545)
			(xy 328.791659 -57.467055) (xy 328.783901 -57.521011) (xy 328.768543 -57.573313) (xy 328.745897 -57.622897)
			(xy 328.716425 -57.668753) (xy 328.680727 -57.709948) (xy 328.639529 -57.745643) (xy 328.593671 -57.775112)
			(xy 328.544085 -57.797753) (xy 328.491781 -57.813107) (xy 328.437825 -57.820861) (xy 328.41057 -57.821322)
			(xy 328.384254 -57.820862) (xy 328.332121 -57.813642) (xy 328.281473 -57.79933) (xy 328.233271 -57.778197)
			(xy 328.188429 -57.750643) (xy 328.147797 -57.717191) (xy 328.129646 -57.698132) (xy 328.122142 -57.690709)
			(xy 328.102849 -57.682196) (xy 328.092308 -57.681622) (xy 328.017632 -57.681622) (xy 328.007082 -57.682148)
			(xy 327.987786 -57.690685) (xy 327.980294 -57.698132) (xy 327.962149 -57.717201) (xy 327.921532 -57.750683)
			(xy 327.876694 -57.778256) (xy 327.828489 -57.799397) (xy 327.777832 -57.813703) (xy 327.725689 -57.820902)
			(xy 327.69937 -57.821322) (xy 327.672121 -57.820806) (xy 327.618179 -57.813046) (xy 327.56589 -57.797689)
			(xy 327.516318 -57.775047) (xy 327.470473 -57.745581) (xy 327.429288 -57.709891) (xy 327.393601 -57.668703)
			(xy 327.364139 -57.622856) (xy 327.341501 -57.573282) (xy 327.326148 -57.520992) (xy 327.318392 -57.467049)
			(xy 327.135047 -57.467049) (xy 327.138877 -57.494775) (xy 327.1393 -57.521094) (xy 327.13883 -57.548464)
			(xy 327.131013 -57.602643) (xy 327.115525 -57.655146) (xy 327.092684 -57.704893) (xy 327.062961 -57.75086)
			(xy 327.04532 -57.771792) (xy 327.039224 -57.778904) (xy 327.032874 -57.795922) (xy 327.032874 -57.881266)
			(xy 327.039224 -57.898284) (xy 327.04532 -57.905396) (xy 327.062953 -57.926334) (xy 327.092674 -57.972302)
			(xy 327.115517 -58.022048) (xy 327.131012 -58.074549) (xy 327.13884 -58.128726) (xy 327.138841 -58.183465)
			(xy 327.131014 -58.237642) (xy 327.11552 -58.290144) (xy 327.092679 -58.33989) (xy 327.062958 -58.385858)
			(xy 327.04532 -58.406792) (xy 327.039224 -58.413904) (xy 327.032874 -58.430922) (xy 327.032874 -58.516266)
			(xy 327.039224 -58.533284) (xy 327.04532 -58.540396) (xy 327.062974 -58.561316) (xy 327.092683 -58.607293)
			(xy 327.115516 -58.657043) (xy 327.131003 -58.709546) (xy 327.138828 -58.763724) (xy 327.1393 -58.791094)
			(xy 327.138814 -58.818345) (xy 327.131058 -58.872293) (xy 327.130661 -58.873644) (xy 328.40041 -58.873644)
			(xy 328.400899 -58.846275) (xy 328.408711 -58.792096) (xy 328.424195 -58.739593) (xy 328.447031 -58.689846)
			(xy 328.476751 -58.643878) (xy 328.49439 -58.622946) (xy 328.500486 -58.615834) (xy 328.506836 -58.598816)
			(xy 328.506836 -58.513472) (xy 328.500486 -58.496454) (xy 328.49439 -58.489342) (xy 328.476756 -58.468406)
			(xy 328.447043 -58.422434) (xy 328.424207 -58.372688) (xy 328.408715 -58.320188) (xy 328.400885 -58.266013)
			(xy 328.40041 -58.238644) (xy 328.400896 -58.211393) (xy 328.408652 -58.157445) (xy 328.424007 -58.10515)
			(xy 328.446649 -58.055573) (xy 328.476115 -58.009723) (xy 328.511806 -57.968532) (xy 328.552997 -57.932841)
			(xy 328.598847 -57.903375) (xy 328.648424 -57.880733) (xy 328.700719 -57.865378) (xy 328.754667 -57.857622)
			(xy 328.809169 -57.857622) (xy 328.863117 -57.865378) (xy 328.915412 -57.880733) (xy 328.964989 -57.903375)
			(xy 329.010839 -57.932841) (xy 329.05203 -57.968532) (xy 329.087721 -58.009723) (xy 329.117187 -58.055573)
			(xy 329.139829 -58.10515) (xy 329.155184 -58.157445) (xy 329.16294 -58.211393) (xy 329.163426 -58.238644)
			(xy 329.162945 -58.266014) (xy 329.155134 -58.320193) (xy 329.139649 -58.372697) (xy 329.11681 -58.422444)
			(xy 329.087087 -58.468411) (xy 329.069446 -58.489342) (xy 329.06335 -58.496454) (xy 329.057 -58.513472)
			(xy 329.057 -58.598816) (xy 329.06335 -58.615834) (xy 329.069446 -58.622946) (xy 329.087065 -58.643895)
			(xy 329.116782 -58.689862) (xy 329.139622 -58.739605) (xy 329.155118 -58.792103) (xy 329.16295 -58.846276)
			(xy 329.163426 -58.873644) (xy 329.16294 -58.900895) (xy 329.155184 -58.954843) (xy 329.139829 -59.007138)
			(xy 329.117187 -59.056715) (xy 329.087721 -59.102565) (xy 329.05203 -59.143756) (xy 329.010839 -59.179447)
			(xy 328.964989 -59.208913) (xy 328.915412 -59.231555) (xy 328.863117 -59.24691) (xy 328.809169 -59.254666)
			(xy 328.754667 -59.254666) (xy 328.700719 -59.24691) (xy 328.648424 -59.231555) (xy 328.598847 -59.208913)
			(xy 328.552997 -59.179447) (xy 328.511806 -59.143756) (xy 328.476115 -59.102565) (xy 328.446649 -59.056715)
			(xy 328.424007 -59.007138) (xy 328.408652 -58.954843) (xy 328.400896 -58.900895) (xy 328.40041 -58.873644)
			(xy 327.130661 -58.873644) (xy 327.115703 -58.924588) (xy 327.093061 -58.974165) (xy 327.063595 -59.020015)
			(xy 327.027904 -59.061206) (xy 326.986713 -59.096897) (xy 326.940863 -59.126363) (xy 326.891286 -59.149005)
			(xy 326.838991 -59.16436) (xy 326.785043 -59.172116) (xy 326.730541 -59.172116) (xy 326.676593 -59.16436)
			(xy 326.624298 -59.149005) (xy 326.574721 -59.126363) (xy 326.528871 -59.096897) (xy 326.48768 -59.061206)
			(xy 326.451989 -59.020015) (xy 326.422523 -58.974165) (xy 326.399881 -58.924588) (xy 326.384526 -58.872293)
			(xy 326.37677 -58.818345) (xy 326.376284 -58.791094) (xy 324.478326 -58.791094) (xy 324.475234 -58.812603)
			(xy 324.459879 -58.864898) (xy 324.437237 -58.914475) (xy 324.407771 -58.960325) (xy 324.37208 -59.001516)
			(xy 324.330889 -59.037207) (xy 324.285039 -59.066673) (xy 324.235462 -59.089315) (xy 324.183167 -59.10467)
			(xy 324.129219 -59.112426) (xy 324.074717 -59.112426) (xy 324.020769 -59.10467) (xy 323.968474 -59.089315)
			(xy 323.918897 -59.066673) (xy 323.873047 -59.037207) (xy 323.831856 -59.001516) (xy 323.796165 -58.960325)
			(xy 323.766699 -58.914475) (xy 323.744057 -58.864898) (xy 323.728702 -58.812603) (xy 323.720946 -58.758655)
			(xy 323.72046 -58.731404) (xy 321.890898 -58.731404) (xy 321.890898 -60.126451) (xy 327.380072 -60.126451)
			(xy 327.380072 -60.071949) (xy 327.387828 -60.018001) (xy 327.403183 -59.965706) (xy 327.425824 -59.916128)
			(xy 327.45529 -59.870278) (xy 327.490981 -59.829087) (xy 327.532171 -59.793395) (xy 327.578021 -59.763928)
			(xy 327.627598 -59.741286) (xy 327.679893 -59.72593) (xy 327.733841 -59.718172) (xy 327.761092 -59.717686)
			(xy 327.788462 -59.71816) (xy 327.84264 -59.725977) (xy 327.895143 -59.741464) (xy 327.94489 -59.764304)
			(xy 327.990858 -59.794026) (xy 328.01179 -59.811666) (xy 328.018902 -59.817762) (xy 328.03592 -59.824112)
			(xy 328.121264 -59.824112) (xy 328.138282 -59.817762) (xy 328.145394 -59.811666) (xy 328.166327 -59.794025)
			(xy 328.212295 -59.764301) (xy 328.262041 -59.741455) (xy 328.314543 -59.725959) (xy 328.368721 -59.71813)
			(xy 328.423463 -59.71813) (xy 328.477641 -59.725959) (xy 328.530143 -59.741455) (xy 328.579889 -59.764301)
			(xy 328.625857 -59.794025) (xy 328.64679 -59.811666) (xy 328.653902 -59.817762) (xy 328.67092 -59.824112)
			(xy 328.756264 -59.824112) (xy 328.773282 -59.817762) (xy 328.780394 -59.811666) (xy 328.801313 -59.794011)
			(xy 328.84729 -59.764303) (xy 328.897041 -59.74147) (xy 328.949544 -59.725983) (xy 329.003722 -59.718158)
			(xy 329.031092 -59.717686) (xy 329.058345 -59.718161) (xy 329.112296 -59.725917) (xy 329.164594 -59.741272)
			(xy 329.214174 -59.763913) (xy 329.260027 -59.793381) (xy 329.30122 -59.829074) (xy 329.336914 -59.870266)
			(xy 329.366383 -59.916119) (xy 329.389025 -59.965699) (xy 329.404382 -60.017996) (xy 329.412139 -60.071947)
			(xy 329.412139 -60.126453) (xy 329.404382 -60.180404) (xy 329.389025 -60.232701) (xy 329.366383 -60.282281)
			(xy 329.336914 -60.328134) (xy 329.30122 -60.369326) (xy 329.260027 -60.405019) (xy 329.214174 -60.434487)
			(xy 329.164594 -60.457128) (xy 329.112296 -60.472483) (xy 329.058345 -60.480239) (xy 329.031092 -60.480702)
			(xy 329.003722 -60.48024) (xy 328.949542 -60.472421) (xy 328.897039 -60.456931) (xy 328.847292 -60.434089)
			(xy 328.801326 -60.404363) (xy 328.780394 -60.386722) (xy 328.773282 -60.380626) (xy 328.756264 -60.374276)
			(xy 328.67092 -60.374276) (xy 328.653902 -60.380626) (xy 328.64679 -60.386722) (xy 328.625857 -60.404363)
			(xy 328.579889 -60.434087) (xy 328.530143 -60.456933) (xy 328.477641 -60.472429) (xy 328.423463 -60.480258)
			(xy 328.368721 -60.480258) (xy 328.314543 -60.472429) (xy 328.262041 -60.456933) (xy 328.212295 -60.434087)
			(xy 328.166327 -60.404363) (xy 328.145394 -60.386722) (xy 328.138282 -60.380626) (xy 328.121264 -60.374276)
			(xy 328.03592 -60.374276) (xy 328.018902 -60.380626) (xy 328.01179 -60.386722) (xy 327.990875 -60.404383)
			(xy 327.944897 -60.434091) (xy 327.895145 -60.456922) (xy 327.842641 -60.472408) (xy 327.788462 -60.480231)
			(xy 327.761092 -60.480702) (xy 327.733841 -60.480228) (xy 327.679893 -60.47247) (xy 327.627598 -60.457114)
			(xy 327.578021 -60.434472) (xy 327.532171 -60.405005) (xy 327.490981 -60.369313) (xy 327.45529 -60.328122)
			(xy 327.425824 -60.282272) (xy 327.403183 -60.232694) (xy 327.387828 -60.180399) (xy 327.380072 -60.126451)
			(xy 321.890898 -60.126451) (xy 321.890898 -60.999878) (xy 321.890364 -61.009867) (xy 321.882656 -61.028305)
			(xy 321.875912 -61.035692) (xy 321.800474 -61.11113) (xy 321.799966 -61.111892) (xy 321.796664 -61.115194)
			(xy 321.79641 -61.115448) (xy 321.169792 -61.742066) (xy 321.163188 -61.748416) (xy 321.16268 -61.748924)
			(xy 321.100196 -61.811408) (xy 321.092839 -61.818055) (xy 321.074538 -61.825633) (xy 321.064636 -61.82614)
			(xy 321.009772 -61.82614) (xy 321.005454 -61.826902) (xy 320.992786 -61.828914) (xy 320.967226 -61.83108)
			(xy 320.9544 -61.83122) (xy 319.27927 -61.83122) (xy 319.267643 -61.831783) (xy 319.246734 -61.84196)
			(xy 319.239138 -61.850778) (xy 319.182496 -61.923422) (xy 319.17767 -61.946028) (xy 319.180718 -61.957712)
			(xy 319.186185 -61.980757) (xy 319.19204 -62.027756) (xy 319.192402 -62.051438) (xy 319.191914 -62.078687)
			(xy 319.184153 -62.132631) (xy 319.168794 -62.18492) (xy 319.146151 -62.234493) (xy 319.116683 -62.280338)
			(xy 319.080992 -62.321523) (xy 319.039802 -62.35721) (xy 318.993954 -62.386672) (xy 318.944379 -62.40931)
			(xy 318.892088 -62.424662) (xy 318.838143 -62.432417) (xy 318.810894 -62.432946) (xy 318.787339 -62.432566)
			(xy 318.740595 -62.42671) (xy 318.717676 -62.421262) (xy 318.703452 -62.417706) (xy 318.676274 -62.426342)
			(xy 318.598042 -62.517274) (xy 318.59347 -62.545468) (xy 318.599058 -62.55893) (xy 318.608384 -62.582314)
			(xy 318.621505 -62.630917) (xy 318.628124 -62.680824) (xy 318.628522 -62.705996) (xy 318.628037 -62.733248)
			(xy 318.620281 -62.787197) (xy 318.604926 -62.839493) (xy 318.582285 -62.889071) (xy 318.552819 -62.934923)
			(xy 318.517128 -62.976115) (xy 318.475938 -63.011808) (xy 318.430087 -63.041277) (xy 318.38051 -63.06392)
			(xy 318.328214 -63.079277) (xy 318.274266 -63.087035) (xy 318.247014 -63.087504) (xy 318.218204 -63.086978)
			(xy 318.16124 -63.07831) (xy 318.106229 -63.061171) (xy 318.054422 -63.03595) (xy 318.007001 -63.003221)
			(xy 317.985648 -62.983872) (xy 317.977012 -62.975744) (xy 317.955168 -62.968886) (xy 317.865252 -62.981332)
			(xy 317.86322 -62.981586) (xy 317.852484 -62.984095) (xy 317.834447 -62.996736) (xy 317.828422 -63.00597)
			(xy 317.813604 -63.03009) (xy 317.777965 -63.074068) (xy 317.736217 -63.112295) (xy 317.689277 -63.143931)
			(xy 317.638176 -63.168281) (xy 317.584037 -63.18481) (xy 317.528049 -63.193155) (xy 317.499746 -63.193676)
			(xy 317.472493 -63.193216) (xy 317.418542 -63.185465) (xy 317.366243 -63.170114) (xy 317.316661 -63.147476)
			(xy 317.270806 -63.118012) (xy 317.229611 -63.082321) (xy 317.193916 -63.041131) (xy 317.164446 -62.995279)
			(xy 317.141802 -62.9457) (xy 317.126445 -62.893403) (xy 317.118687 -62.839453) (xy 317.118687 -62.784947)
			(xy 317.126445 -62.730997) (xy 317.141802 -62.6787) (xy 317.164446 -62.629121) (xy 317.193916 -62.583269)
			(xy 317.229611 -62.542079) (xy 317.270806 -62.506388) (xy 317.316661 -62.476924) (xy 317.366243 -62.454286)
			(xy 317.418542 -62.438935) (xy 317.472493 -62.431184) (xy 317.499746 -62.43066) (xy 317.528557 -62.431183)
			(xy 317.585525 -62.439845) (xy 317.640541 -62.456978) (xy 317.692353 -62.482194) (xy 317.739781 -62.514918)
			(xy 317.761112 -62.534292) (xy 317.769748 -62.54242) (xy 317.791592 -62.549278) (xy 317.881508 -62.536832)
			(xy 317.883286 -62.536578) (xy 317.89443 -62.533948) (xy 317.913016 -62.520625) (xy 317.9191 -62.510924)
			(xy 317.919862 -62.5094) (xy 317.934762 -62.485593) (xy 317.970449 -62.442228) (xy 318.012106 -62.404562)
			(xy 318.058834 -62.373407) (xy 318.109623 -62.349437) (xy 318.163376 -62.33317) (xy 318.218933 -62.324955)
			(xy 318.247014 -62.324488) (xy 318.26708 -62.324996) (xy 318.267334 -62.324996) (xy 318.283082 -62.326012)
			(xy 318.291718 -62.327028) (xy 318.312546 -62.330076) (xy 318.3128 -62.330076) (xy 318.340232 -62.336172)
			(xy 318.354456 -62.339728) (xy 318.381634 -62.331092) (xy 318.459866 -62.24016) (xy 318.464184 -62.21222)
			(xy 318.458596 -62.198504) (xy 318.448777 -62.173891) (xy 318.435271 -62.12265) (xy 318.431672 -62.096396)
			(xy 318.430402 -62.082426) (xy 318.429132 -62.051438) (xy 318.429132 -62.05093) (xy 318.429502 -62.027312)
			(xy 318.435363 -61.980441) (xy 318.440816 -61.957458) (xy 318.443864 -61.945774) (xy 318.439038 -61.923168)
			(xy 318.38265 -61.850778) (xy 318.37506 -61.841946) (xy 318.35415 -61.831756) (xy 318.342518 -61.83122)
			(xy 317.36411 -61.83122) (xy 317.351411 -61.831074) (xy 317.326104 -61.828915) (xy 317.313564 -61.826902)
			(xy 317.309246 -61.82614) (xy 317.068708 -61.82614) (xy 317.057024 -61.829188) (xy 317.052198 -61.831474)
			(xy 317.05169 -61.831728) (xy 317.036784 -61.838666) (xy 317.006006 -61.850238) (xy 316.990222 -61.854842)
			(xy 316.962929 -61.862056) (xy 316.906941 -61.869286) (xy 316.8505 -61.868177) (xy 316.822582 -61.863986)
			(xy 316.796004 -61.859027) (xy 316.744498 -61.842586) (xy 316.719966 -61.83122) (xy 316.714886 -61.82868)
			(xy 316.70371 -61.82614) (xy 316.453774 -61.82614) (xy 316.449456 -61.826902) (xy 316.436914 -61.828896)
			(xy 316.411608 -61.831059) (xy 316.39891 -61.83122) (xy 315.263784 -61.83122) (xy 315.251143 -61.831898)
			(xy 315.228891 -61.843899) (xy 315.221366 -61.85408) (xy 315.177932 -61.920374) (xy 315.173546 -61.927593)
			(xy 315.169367 -61.943951) (xy 315.170767 -61.960776) (xy 315.173868 -61.968634) (xy 315.183918 -61.992769)
			(xy 315.198065 -62.043101) (xy 315.205203 -62.094893) (xy 315.205618 -62.121034) (xy 315.205618 -62.12586)
			(xy 315.204806 -62.152886) (xy 315.196496 -62.206313) (xy 315.180727 -62.258031) (xy 315.157815 -62.307004)
			(xy 315.128218 -62.352253) (xy 315.092529 -62.39287) (xy 315.051464 -62.428042) (xy 315.005845 -62.457064)
			(xy 314.956585 -62.479355) (xy 314.904671 -62.494469) (xy 314.851144 -62.502102) (xy 314.797076 -62.502102)
			(xy 314.743549 -62.494469) (xy 314.691635 -62.479355) (xy 314.642375 -62.457064) (xy 314.596756 -62.428042)
			(xy 314.555691 -62.39287) (xy 314.520002 -62.352253) (xy 314.490405 -62.307004) (xy 314.467493 -62.258031)
			(xy 314.451724 -62.206313) (xy 314.443414 -62.152886) (xy 314.442602 -62.12586) (xy 314.442602 -62.12078)
			(xy 314.44305 -62.094683) (xy 314.450203 -62.042981) (xy 314.464333 -61.992735) (xy 314.474352 -61.968634)
			(xy 314.479178 -61.957712) (xy 314.478162 -61.934852) (xy 314.472828 -61.924438) (xy 314.470288 -61.920374)
			(xy 314.427108 -61.854334) (xy 314.419996 -61.843412) (xy 314.397644 -61.83122) (xy 311.862216 -61.83122)
			(xy 311.852153 -61.831659) (xy 311.833573 -61.839397) (xy 311.826148 -61.846206) (xy 311.422542 -62.249812)
			(xy 311.415176 -62.256924) (xy 311.407556 -62.27572) (xy 311.407556 -63.273432) (xy 313.776612 -63.273432)
			(xy 313.780683 -63.21781) (xy 313.792809 -63.163373) (xy 313.812732 -63.111282) (xy 313.840028 -63.062647)
			(xy 313.874114 -63.018504) (xy 313.914263 -62.979795) (xy 313.959621 -62.947344) (xy 314.009221 -62.921843)
			(xy 314.062005 -62.903836) (xy 314.116848 -62.893706) (xy 314.172582 -62.891669) (xy 314.228019 -62.897769)
			(xy 314.281976 -62.911875) (xy 314.333305 -62.933687) (xy 314.380911 -62.962741) (xy 314.423779 -62.998416)
			(xy 314.460996 -63.039953) (xy 314.491769 -63.086466) (xy 314.515441 -63.136963) (xy 314.531509 -63.19037)
			(xy 314.539629 -63.245546) (xy 314.539629 -63.24555) (xy 327.304392 -63.24555) (xy 327.304392 -63.19105)
			(xy 327.312148 -63.137104) (xy 327.327503 -63.084811) (xy 327.350143 -63.035236) (xy 327.379608 -62.989387)
			(xy 327.415299 -62.948199) (xy 327.456487 -62.912508) (xy 327.502336 -62.883043) (xy 327.551911 -62.860403)
			(xy 327.604204 -62.845048) (xy 327.65815 -62.837292) (xy 327.6854 -62.836806) (xy 327.71277 -62.837271)
			(xy 327.76695 -62.845089) (xy 327.819453 -62.860578) (xy 327.8692 -62.88342) (xy 327.915166 -62.913145)
			(xy 327.936098 -62.930786) (xy 327.94321 -62.936882) (xy 327.960228 -62.943232) (xy 328.045572 -62.943232)
			(xy 328.06259 -62.936882) (xy 328.069702 -62.930786) (xy 328.090635 -62.913145) (xy 328.136603 -62.883421)
			(xy 328.186349 -62.860575) (xy 328.238851 -62.845079) (xy 328.293029 -62.83725) (xy 328.347771 -62.83725)
			(xy 328.401949 -62.845079) (xy 328.454451 -62.860575) (xy 328.504197 -62.883421) (xy 328.550165 -62.913145)
			(xy 328.571098 -62.930786) (xy 328.57821 -62.936882) (xy 328.595228 -62.943232) (xy 328.680572 -62.943232)
			(xy 328.69759 -62.936882) (xy 328.704702 -62.930786) (xy 328.725621 -62.91313) (xy 328.771597 -62.883421)
			(xy 328.821348 -62.860589) (xy 328.873852 -62.845102) (xy 328.92803 -62.837278) (xy 328.9554 -62.836806)
			(xy 328.982652 -62.837264) (xy 329.036602 -62.845021) (xy 329.088899 -62.860376) (xy 329.138478 -62.883018)
			(xy 329.18433 -62.912486) (xy 329.225522 -62.948178) (xy 329.261214 -62.98937) (xy 329.290682 -63.035222)
			(xy 329.313324 -63.084801) (xy 329.328679 -63.137098) (xy 329.336436 -63.191048) (xy 329.336436 -63.245552)
			(xy 329.328679 -63.299502) (xy 329.313324 -63.351799) (xy 329.290682 -63.401378) (xy 329.261214 -63.44723)
			(xy 329.225522 -63.488422) (xy 329.18433 -63.524114) (xy 329.138478 -63.553582) (xy 329.088899 -63.576224)
			(xy 329.036602 -63.591579) (xy 328.982652 -63.599336) (xy 328.9554 -63.599822) (xy 328.928029 -63.599375)
			(xy 328.873848 -63.591555) (xy 328.821344 -63.576063) (xy 328.771598 -63.553217) (xy 328.725632 -63.523486)
			(xy 328.704702 -63.505842) (xy 328.69759 -63.499746) (xy 328.680572 -63.493396) (xy 328.595228 -63.493396)
			(xy 328.57821 -63.499746) (xy 328.571098 -63.505842) (xy 328.550165 -63.523483) (xy 328.504197 -63.553207)
			(xy 328.454451 -63.576053) (xy 328.401949 -63.591549) (xy 328.347771 -63.599378) (xy 328.293029 -63.599378)
			(xy 328.238851 -63.591549) (xy 328.186349 -63.576053) (xy 328.136603 -63.553207) (xy 328.090635 -63.523483)
			(xy 328.069702 -63.505842) (xy 328.06259 -63.499746) (xy 328.045572 -63.493396) (xy 327.960228 -63.493396)
			(xy 327.94321 -63.499746) (xy 327.936098 -63.505842) (xy 327.915183 -63.523502) (xy 327.869205 -63.55321)
			(xy 327.819453 -63.576041) (xy 327.766949 -63.591527) (xy 327.71277 -63.599351) (xy 327.6854 -63.599822)
			(xy 327.65815 -63.599308) (xy 327.604204 -63.591552) (xy 327.551911 -63.576197) (xy 327.502336 -63.553557)
			(xy 327.456487 -63.524092) (xy 327.415299 -63.488401) (xy 327.379608 -63.447213) (xy 327.350143 -63.401364)
			(xy 327.327503 -63.351789) (xy 327.312148 -63.299496) (xy 327.304392 -63.24555) (xy 314.539629 -63.24555)
			(xy 314.540138 -63.273432) (xy 314.539629 -63.301318) (xy 314.531509 -63.356494) (xy 314.515441 -63.409901)
			(xy 314.491769 -63.460398) (xy 314.460996 -63.506911) (xy 314.423779 -63.548448) (xy 314.380911 -63.584123)
			(xy 314.333305 -63.613177) (xy 314.281976 -63.634989) (xy 314.228019 -63.649095) (xy 314.172582 -63.655195)
			(xy 314.116848 -63.653158) (xy 314.062005 -63.643028) (xy 314.009221 -63.625021) (xy 313.959621 -63.59952)
			(xy 313.914263 -63.567069) (xy 313.874114 -63.52836) (xy 313.840028 -63.484217) (xy 313.812732 -63.435582)
			(xy 313.792809 -63.383491) (xy 313.780683 -63.329054) (xy 313.776612 -63.273432) (xy 311.407556 -63.273432)
			(xy 311.407556 -64.102234) (xy 311.587386 -64.102234) (xy 311.591457 -64.046612) (xy 311.603583 -63.992175)
			(xy 311.623506 -63.940084) (xy 311.650802 -63.891449) (xy 311.684888 -63.847306) (xy 311.725037 -63.808597)
			(xy 311.770395 -63.776146) (xy 311.819995 -63.750645) (xy 311.872779 -63.732638) (xy 311.927622 -63.722508)
			(xy 311.983356 -63.720471) (xy 312.038793 -63.726571) (xy 312.09275 -63.740677) (xy 312.144079 -63.762489)
			(xy 312.191685 -63.791543) (xy 312.234553 -63.827218) (xy 312.27177 -63.868755) (xy 312.302543 -63.915268)
			(xy 312.326215 -63.965765) (xy 312.342283 -64.019172) (xy 312.350403 -64.074348) (xy 312.350912 -64.102234)
			(xy 312.350403 -64.13012) (xy 312.342283 -64.185296) (xy 312.326215 -64.238703) (xy 312.302543 -64.2892)
			(xy 312.287265 -64.312292) (xy 315.265814 -64.312292) (xy 315.269885 -64.25667) (xy 315.282011 -64.202233)
			(xy 315.301934 -64.150142) (xy 315.32923 -64.101507) (xy 315.363316 -64.057364) (xy 315.403465 -64.018655)
			(xy 315.448823 -63.986204) (xy 315.498423 -63.960703) (xy 315.551207 -63.942696) (xy 315.60605 -63.932566)
			(xy 315.661784 -63.930529) (xy 315.717221 -63.936629) (xy 315.771178 -63.950735) (xy 315.822507 -63.972547)
			(xy 315.870113 -64.001601) (xy 315.912981 -64.037276) (xy 315.950198 -64.078813) (xy 315.980971 -64.125326)
			(xy 316.004643 -64.175823) (xy 316.020711 -64.22923) (xy 316.028831 -64.284406) (xy 316.02934 -64.312292)
			(xy 316.028831 -64.340178) (xy 316.020711 -64.395354) (xy 316.004643 -64.448761) (xy 315.980971 -64.499258)
			(xy 315.950198 -64.545771) (xy 315.912981 -64.587308) (xy 315.870113 -64.622983) (xy 315.822507 -64.652037)
			(xy 315.771178 -64.673849) (xy 315.717221 -64.687955) (xy 315.661784 -64.694055) (xy 315.60605 -64.692018)
			(xy 315.551207 -64.681888) (xy 315.498423 -64.663881) (xy 315.448823 -64.63838) (xy 315.403465 -64.605929)
			(xy 315.363316 -64.56722) (xy 315.32923 -64.523077) (xy 315.301934 -64.474442) (xy 315.282011 -64.422351)
			(xy 315.269885 -64.367914) (xy 315.265814 -64.312292) (xy 312.287265 -64.312292) (xy 312.27177 -64.335713)
			(xy 312.234553 -64.37725) (xy 312.191685 -64.412925) (xy 312.144079 -64.441979) (xy 312.09275 -64.463791)
			(xy 312.038793 -64.477897) (xy 311.983356 -64.483997) (xy 311.927622 -64.48196) (xy 311.872779 -64.47183)
			(xy 311.819995 -64.453823) (xy 311.770395 -64.428322) (xy 311.725037 -64.395871) (xy 311.684888 -64.357162)
			(xy 311.650802 -64.313019) (xy 311.623506 -64.264384) (xy 311.603583 -64.212293) (xy 311.591457 -64.157856)
			(xy 311.587386 -64.102234) (xy 311.407556 -64.102234) (xy 311.407556 -65.124076) (xy 316.307214 -65.124076)
			(xy 316.311285 -65.068454) (xy 316.323411 -65.014017) (xy 316.343334 -64.961926) (xy 316.37063 -64.913291)
			(xy 316.404716 -64.869148) (xy 316.444865 -64.830439) (xy 316.490223 -64.797988) (xy 316.539823 -64.772487)
			(xy 316.592607 -64.75448) (xy 316.64745 -64.74435) (xy 316.703184 -64.742313) (xy 316.758621 -64.748413)
			(xy 316.812578 -64.762519) (xy 316.863907 -64.784331) (xy 316.911513 -64.813385) (xy 316.954381 -64.84906)
			(xy 316.991598 -64.890597) (xy 317.022371 -64.93711) (xy 317.046043 -64.987607) (xy 317.062111 -65.041014)
			(xy 317.070231 -65.09619) (xy 317.07074 -65.124076) (xy 317.070231 -65.151962) (xy 317.069064 -65.15989)
			(xy 329.316332 -65.15989) (xy 329.320403 -65.104268) (xy 329.332529 -65.049831) (xy 329.352452 -64.99774)
			(xy 329.379748 -64.949105) (xy 329.413834 -64.904962) (xy 329.453983 -64.866253) (xy 329.499341 -64.833802)
			(xy 329.548941 -64.808301) (xy 329.601725 -64.790294) (xy 329.656568 -64.780164) (xy 329.712302 -64.778127)
			(xy 329.767739 -64.784227) (xy 329.821696 -64.798333) (xy 329.873025 -64.820145) (xy 329.920631 -64.849199)
			(xy 329.963499 -64.884874) (xy 330.000716 -64.926411) (xy 330.031489 -64.972924) (xy 330.055161 -65.023421)
			(xy 330.071229 -65.076828) (xy 330.079349 -65.132004) (xy 330.079858 -65.15989) (xy 330.079349 -65.187776)
			(xy 330.071229 -65.242952) (xy 330.055161 -65.296359) (xy 330.031489 -65.346856) (xy 330.000716 -65.393369)
			(xy 329.963499 -65.434906) (xy 329.920631 -65.470581) (xy 329.873025 -65.499635) (xy 329.821696 -65.521447)
			(xy 329.767739 -65.535553) (xy 329.712302 -65.541653) (xy 329.656568 -65.539616) (xy 329.601725 -65.529486)
			(xy 329.548941 -65.511479) (xy 329.499341 -65.485978) (xy 329.453983 -65.453527) (xy 329.413834 -65.414818)
			(xy 329.379748 -65.370675) (xy 329.352452 -65.32204) (xy 329.332529 -65.269949) (xy 329.320403 -65.215512)
			(xy 329.316332 -65.15989) (xy 317.069064 -65.15989) (xy 317.062111 -65.207138) (xy 317.046043 -65.260545)
			(xy 317.022371 -65.311042) (xy 316.991598 -65.357555) (xy 316.954381 -65.399092) (xy 316.911513 -65.434767)
			(xy 316.863907 -65.463821) (xy 316.812578 -65.485633) (xy 316.758621 -65.499739) (xy 316.703184 -65.505839)
			(xy 316.64745 -65.503802) (xy 316.592607 -65.493672) (xy 316.539823 -65.475665) (xy 316.490223 -65.450164)
			(xy 316.444865 -65.417713) (xy 316.404716 -65.379004) (xy 316.37063 -65.334861) (xy 316.343334 -65.286226)
			(xy 316.323411 -65.234135) (xy 316.311285 -65.179698) (xy 316.307214 -65.124076) (xy 311.407556 -65.124076)
			(xy 311.407556 -65.75552) (xy 324.546466 -65.75552) (xy 324.550537 -65.699898) (xy 324.562663 -65.645461)
			(xy 324.582586 -65.59337) (xy 324.609882 -65.544735) (xy 324.643968 -65.500592) (xy 324.684117 -65.461883)
			(xy 324.729475 -65.429432) (xy 324.779075 -65.403931) (xy 324.831859 -65.385924) (xy 324.886702 -65.375794)
			(xy 324.942436 -65.373757) (xy 324.997873 -65.379857) (xy 325.05183 -65.393963) (xy 325.103159 -65.415775)
			(xy 325.150765 -65.444829) (xy 325.193633 -65.480504) (xy 325.23085 -65.522041) (xy 325.261623 -65.568554)
			(xy 325.285295 -65.619051) (xy 325.301363 -65.672458) (xy 325.309483 -65.727634) (xy 325.309992 -65.75552)
			(xy 325.309483 -65.783406) (xy 325.301363 -65.838582) (xy 325.285295 -65.891989) (xy 325.261623 -65.942486)
			(xy 325.23085 -65.988999) (xy 325.193633 -66.030536) (xy 325.150765 -66.066211) (xy 325.103159 -66.095265)
			(xy 325.05183 -66.117077) (xy 324.997873 -66.131183) (xy 324.942436 -66.137283) (xy 324.886702 -66.135246)
			(xy 324.831859 -66.125116) (xy 324.779075 -66.107109) (xy 324.729475 -66.081608) (xy 324.684117 -66.049157)
			(xy 324.643968 -66.010448) (xy 324.609882 -65.966305) (xy 324.582586 -65.91767) (xy 324.562663 -65.865579)
			(xy 324.550537 -65.811142) (xy 324.546466 -65.75552) (xy 311.407556 -65.75552) (xy 311.407556 -67.488054)
			(xy 328.97902 -67.488054) (xy 328.983091 -67.432432) (xy 328.995217 -67.377995) (xy 329.01514 -67.325904)
			(xy 329.042436 -67.277269) (xy 329.076522 -67.233126) (xy 329.116671 -67.194417) (xy 329.162029 -67.161966)
			(xy 329.211629 -67.136465) (xy 329.264413 -67.118458) (xy 329.319256 -67.108328) (xy 329.37499 -67.106291)
			(xy 329.430427 -67.112391) (xy 329.484384 -67.126497) (xy 329.535713 -67.148309) (xy 329.583319 -67.177363)
			(xy 329.626187 -67.213038) (xy 329.663404 -67.254575) (xy 329.694177 -67.301088) (xy 329.717849 -67.351585)
			(xy 329.733917 -67.404992) (xy 329.742037 -67.460168) (xy 329.742546 -67.488054) (xy 329.742037 -67.51594)
			(xy 329.733917 -67.571116) (xy 329.717849 -67.624523) (xy 329.694177 -67.67502) (xy 329.663404 -67.721533)
			(xy 329.626187 -67.76307) (xy 329.583319 -67.798745) (xy 329.535713 -67.827799) (xy 329.484384 -67.849611)
			(xy 329.430427 -67.863717) (xy 329.37499 -67.869817) (xy 329.319256 -67.86778) (xy 329.264413 -67.85765)
			(xy 329.211629 -67.839643) (xy 329.162029 -67.814142) (xy 329.116671 -67.781691) (xy 329.076522 -67.742982)
			(xy 329.042436 -67.698839) (xy 329.01514 -67.650204) (xy 328.995217 -67.598113) (xy 328.983091 -67.543676)
			(xy 328.97902 -67.488054) (xy 311.407556 -67.488054) (xy 311.407556 -69.9516) (xy 311.408012 -69.961479)
			(xy 311.415446 -69.979786) (xy 311.422034 -69.98716) (xy 311.422288 -69.987414) (xy 311.598564 -70.16369)
			(xy 311.599072 -70.164198) (xy 311.606452 -70.170783) (xy 311.624751 -70.178235) (xy 311.634632 -70.178676)
		)
		(stroke
			(width 0)
			(type solid)
		)
		(fill yes)
		(layer "In9.Cu")
		(net "P12V_SSD11_R")
	)
	(gr_poly
		(pts
			(xy 214.578184 -70.178676) (xy 214.588247 -70.178237) (xy 214.606827 -70.170498) (xy 214.614252 -70.16369)
			(xy 214.940388 -69.837554) (xy 214.940896 -69.837046) (xy 214.947474 -69.829663) (xy 214.954917 -69.811364)
			(xy 214.955374 -69.801486) (xy 214.955374 -67.91579) (xy 214.954977 -67.906267) (xy 214.948022 -67.888537)
			(xy 214.935075 -67.874568) (xy 214.926672 -67.87007) (xy 214.830914 -67.823842) (xy 214.802212 -67.827144)
			(xy 214.790528 -67.836288) (xy 214.770216 -67.851901) (xy 214.726202 -67.878119) (xy 214.679073 -67.898207)
			(xy 214.629678 -67.911803) (xy 214.578908 -67.918663) (xy 214.553292 -67.919092) (xy 214.526042 -67.918605)
			(xy 214.472098 -67.910848) (xy 214.419806 -67.895493) (xy 214.370232 -67.872852) (xy 214.324385 -67.843387)
			(xy 214.283197 -67.807697) (xy 214.247508 -67.766509) (xy 214.218044 -67.720661) (xy 214.195404 -67.671086)
			(xy 214.18005 -67.618794) (xy 214.172294 -67.56485) (xy 214.172294 -67.51035) (xy 214.18005 -67.456406)
			(xy 214.195404 -67.404114) (xy 214.218044 -67.354539) (xy 214.247508 -67.308691) (xy 214.283197 -67.267503)
			(xy 214.324385 -67.231813) (xy 214.370232 -67.202348) (xy 214.419806 -67.179707) (xy 214.472098 -67.164352)
			(xy 214.526042 -67.156595) (xy 214.553292 -67.156076) (xy 214.578908 -67.156491) (xy 214.62968 -67.163351)
			(xy 214.679075 -67.17695) (xy 214.726204 -67.197042) (xy 214.770217 -67.223264) (xy 214.790528 -67.23888)
			(xy 214.802212 -67.248024) (xy 214.830914 -67.251326) (xy 214.926672 -67.205098) (xy 214.935072 -67.200596)
			(xy 214.948013 -67.186625) (xy 214.954977 -67.168899) (xy 214.955374 -67.159378) (xy 214.955374 -65.506854)
			(xy 214.941658 -65.483486) (xy 214.930228 -65.476628) (xy 214.92972 -65.476628) (xy 214.856568 -65.433702)
			(xy 214.852175 -65.431321) (xy 214.842708 -65.428129) (xy 214.837772 -65.427352) (xy 214.827358 -65.426082)
			(xy 214.803736 -65.432432) (xy 214.798148 -65.43548) (xy 214.769863 -65.450258) (xy 214.709587 -65.471207)
			(xy 214.646666 -65.481834) (xy 214.61476 -65.48247) (xy 214.614506 -65.48247) (xy 214.587256 -65.482007)
			(xy 214.533309 -65.474252) (xy 214.481016 -65.458898) (xy 214.43144 -65.436258) (xy 214.385591 -65.406793)
			(xy 214.344401 -65.371103) (xy 214.308711 -65.329914) (xy 214.279245 -65.284065) (xy 214.256604 -65.23449)
			(xy 214.24125 -65.182196) (xy 214.233493 -65.12825) (xy 214.233493 -65.07375) (xy 214.24125 -65.019804)
			(xy 214.256604 -64.96751) (xy 214.279245 -64.917935) (xy 214.308711 -64.872086) (xy 214.344401 -64.830897)
			(xy 214.385591 -64.795207) (xy 214.43144 -64.765742) (xy 214.481016 -64.743102) (xy 214.533309 -64.727748)
			(xy 214.587256 -64.719993) (xy 214.614506 -64.719454) (xy 214.61476 -64.719454) (xy 214.646663 -64.720122)
			(xy 214.709575 -64.730765) (xy 214.769851 -64.751696) (xy 214.798148 -64.766444) (xy 214.803736 -64.769492)
			(xy 214.817452 -64.773302) (xy 214.822438 -64.774507) (xy 214.832674 -64.775138) (xy 214.837772 -64.774572)
			(xy 214.847678 -64.773302) (xy 214.929974 -64.725296) (xy 214.930736 -64.724788) (xy 214.938015 -64.719974)
			(xy 214.949063 -64.706481) (xy 214.95497 -64.690072) (xy 214.955374 -64.681354) (xy 214.955374 -52.63261)
			(xy 214.954866 -52.626006) (xy 214.953596 -52.615592) (xy 214.952834 -52.612798) (xy 214.947122 -52.589272)
			(xy 214.941009 -52.541247) (xy 214.940642 -52.51704) (xy 214.940642 -52.49926) (xy 214.940896 -52.49418)
			(xy 214.942674 -52.477162) (xy 214.94385 -52.466351) (xy 214.947282 -52.444875) (xy 214.949532 -52.434236)
			(xy 214.95131 -52.427378) (xy 214.951564 -52.42687) (xy 214.95258 -52.422552) (xy 214.95258 -52.421536)
			(xy 214.953596 -52.418234) (xy 214.955374 -52.41163) (xy 214.955374 -51.455828) (xy 214.955878 -51.445777)
			(xy 214.963598 -51.427214) (xy 214.97036 -51.41976) (xy 215.077294 -51.312826) (xy 215.084691 -51.305976)
			(xy 215.103289 -51.298235) (xy 215.113362 -51.29784) (xy 215.803734 -51.29784) (xy 215.812116 -51.297078)
			(xy 215.819719 -51.295561) (xy 215.833548 -51.288568) (xy 215.839294 -51.283362) (xy 215.919304 -51.203352)
			(xy 215.919304 -49.20615) (xy 215.918708 -49.193826) (xy 215.907254 -49.172001) (xy 215.89746 -49.164494)
			(xy 215.833706 -49.120044) (xy 215.827206 -49.115861) (xy 215.812473 -49.111206) (xy 215.80475 -49.1109)
			(xy 215.782652 -49.1109) (xy 215.774778 -49.113694) (xy 215.744593 -49.123448) (xy 215.682034 -49.133916)
			(xy 215.650318 -49.134522) (xy 215.646254 -49.134522) (xy 215.619194 -49.133762) (xy 215.565688 -49.12554)
			(xy 215.513882 -49.109837) (xy 215.464817 -49.086966) (xy 215.419478 -49.057389) (xy 215.378776 -49.021699)
			(xy 215.343528 -48.980613) (xy 215.314444 -48.934956) (xy 215.292107 -48.885646) (xy 215.276965 -48.833673)
			(xy 215.269324 -48.780081) (xy 215.26881 -48.753014) (xy 215.269272 -48.725761) (xy 215.277028 -48.671809)
			(xy 215.292383 -48.619511) (xy 215.315025 -48.56993) (xy 215.344493 -48.524077) (xy 215.380187 -48.482884)
			(xy 215.42138 -48.44719) (xy 215.467234 -48.417723) (xy 215.516815 -48.395081) (xy 215.569113 -48.379727)
			(xy 215.623065 -48.371972) (xy 215.650318 -48.371506) (xy 215.65108 -48.371506) (xy 215.684696 -48.372264)
			(xy 215.750869 -48.384154) (xy 215.782652 -48.395128) (xy 215.794336 -48.399446) (xy 215.818974 -48.396398)
			(xy 215.89746 -48.341534) (xy 215.907129 -48.333922) (xy 215.918535 -48.31216) (xy 215.919304 -48.299878)
			(xy 215.919304 -41.95445) (xy 215.918776 -41.944458) (xy 215.911075 -41.926013) (xy 215.904318 -41.918636)
			(xy 215.0237 -41.038018) (xy 215.016588 -41.030652) (xy 214.997792 -41.023032) (xy 213.216236 -41.023032)
			(xy 213.207539 -41.023392) (xy 213.191149 -41.029219) (xy 213.177644 -41.040182) (xy 213.172802 -41.047416)
			(xy 213.127844 -41.121584) (xy 213.12378 -41.13022) (xy 213.120453 -41.140526) (xy 213.121886 -41.162115)
			(xy 213.126574 -41.171876) (xy 213.127336 -41.1734) (xy 213.131654 -41.18229) (xy 213.143731 -41.208261)
			(xy 213.160843 -41.262919) (xy 213.169613 -41.319517) (xy 213.170262 -41.348152) (xy 213.170262 -41.34866)
			(xy 213.170262 -41.35501) (xy 213.169351 -41.383073) (xy 213.160306 -41.438487) (xy 213.143236 -41.491977)
			(xy 213.118511 -41.542388) (xy 213.086663 -41.588629) (xy 213.0679 -41.609518) (xy 213.067646 -41.609772)
			(xy 213.06117 -41.617125) (xy 213.053865 -41.635288) (xy 213.053422 -41.645078) (xy 213.053422 -41.724072)
			(xy 213.06028 -41.741852) (xy 213.067138 -41.748964) (xy 213.086409 -41.77029) (xy 213.118974 -41.817651)
			(xy 213.144065 -41.869362) (xy 213.161114 -41.924251) (xy 213.169735 -41.981078) (xy 213.169732 -42.038554)
			(xy 213.161107 -42.09538) (xy 213.144053 -42.150268) (xy 213.118958 -42.201977) (xy 213.086389 -42.249335)
			(xy 213.067138 -42.27068) (xy 213.06028 -42.277792) (xy 213.053422 -42.295572) (xy 213.053422 -42.384472)
			(xy 213.06028 -42.402252) (xy 213.067138 -42.409364) (xy 213.086405 -42.430693) (xy 213.118962 -42.478057)
			(xy 213.144047 -42.529769) (xy 213.16109 -42.584659) (xy 213.169708 -42.641484) (xy 213.170262 -42.670222)
			(xy 213.169789 -42.697591) (xy 213.161961 -42.751767) (xy 213.146471 -42.804268) (xy 213.123635 -42.854016)
			(xy 213.093922 -42.899989) (xy 213.076282 -42.92092) (xy 213.070186 -42.928032) (xy 213.063836 -42.944796)
			(xy 213.063836 -43.030648) (xy 213.070186 -43.047412) (xy 213.076282 -43.054524) (xy 213.093923 -43.075455)
			(xy 213.123648 -43.121422) (xy 213.146489 -43.171169) (xy 213.161977 -43.223672) (xy 213.169792 -43.277852)
			(xy 213.170262 -43.305222) (xy 213.169776 -43.332473) (xy 213.16202 -43.386421) (xy 213.146665 -43.438716)
			(xy 213.124023 -43.488293) (xy 213.094557 -43.534143) (xy 213.058866 -43.575334) (xy 213.017675 -43.611025)
			(xy 212.971825 -43.640491) (xy 212.922248 -43.663133) (xy 212.869953 -43.678488) (xy 212.816005 -43.686244)
			(xy 212.761503 -43.686244) (xy 212.707555 -43.678488) (xy 212.65526 -43.663133) (xy 212.605683 -43.640491)
			(xy 212.559833 -43.611025) (xy 212.518642 -43.575334) (xy 212.482951 -43.534143) (xy 212.453485 -43.488293)
			(xy 212.430843 -43.438716) (xy 212.415488 -43.386421) (xy 212.407732 -43.332473) (xy 212.407246 -43.305222)
			(xy 212.407723 -43.277854) (xy 212.415558 -43.223682) (xy 212.431055 -43.171186) (xy 212.453896 -43.121444)
			(xy 212.483613 -43.075477) (xy 212.501226 -43.054524) (xy 212.507322 -43.047412) (xy 212.513672 -43.030648)
			(xy 212.513672 -42.944796) (xy 212.507322 -42.928032) (xy 212.501226 -42.92092) (xy 212.483582 -42.89999)
			(xy 212.453851 -42.854024) (xy 212.431004 -42.804278) (xy 212.41551 -42.751774) (xy 212.407688 -42.697593)
			(xy 212.407246 -42.670222) (xy 212.407765 -42.641483) (xy 212.416386 -42.584654) (xy 212.433435 -42.529762)
			(xy 212.458527 -42.478049) (xy 212.491094 -42.430687) (xy 212.51037 -42.409364) (xy 212.517228 -42.402252)
			(xy 212.524086 -42.384472) (xy 212.524086 -42.295572) (xy 212.517228 -42.277792) (xy 212.51037 -42.27068)
			(xy 212.4911 -42.249352) (xy 212.458536 -42.201988) (xy 212.433445 -42.150275) (xy 212.416394 -42.095383)
			(xy 212.40777 -42.038555) (xy 212.407768 -41.981077) (xy 212.416387 -41.924248) (xy 212.433433 -41.869355)
			(xy 212.45852 -41.81764) (xy 212.49108 -41.770273) (xy 212.51037 -41.748964) (xy 212.517228 -41.741852)
			(xy 212.524086 -41.724072) (xy 212.524086 -41.635172) (xy 212.517228 -41.617646) (xy 212.51037 -41.61028)
			(xy 212.491568 -41.589487) (xy 212.459636 -41.543415) (xy 212.434779 -41.49317) (xy 212.417531 -41.439833)
			(xy 212.408262 -41.384548) (xy 212.407246 -41.356534) (xy 212.407246 -41.354248) (xy 212.407246 -41.349422)
			(xy 212.40777 -41.32057) (xy 212.416461 -41.263525) (xy 212.433663 -41.208445) (xy 212.445854 -41.18229)
			(xy 212.452966 -41.167558) (xy 212.45628 -41.158545) (xy 212.456677 -41.139359) (xy 212.453728 -41.13022)
			(xy 212.449664 -41.121584) (xy 212.404706 -41.04767) (xy 212.397848 -41.035986) (xy 212.374734 -41.023032)
			(xy 211.454238 -41.023032) (xy 211.442615 -41.023602) (xy 211.421719 -41.033788) (xy 211.414106 -41.04259)
			(xy 211.357464 -41.11498) (xy 211.352638 -41.137586) (xy 211.355432 -41.14927) (xy 211.360753 -41.171949)
			(xy 211.366483 -41.21818) (xy 211.366862 -41.241472) (xy 211.366401 -41.268725) (xy 211.358647 -41.322676)
			(xy 211.343292 -41.374975) (xy 211.320651 -41.424556) (xy 211.291183 -41.470409) (xy 211.255489 -41.511601)
			(xy 211.214295 -41.547294) (xy 211.16844 -41.57676) (xy 211.118858 -41.599399) (xy 211.066559 -41.61475)
			(xy 211.012607 -41.622502) (xy 210.985354 -41.62298) (xy 210.956613 -41.622463) (xy 210.899782 -41.613847)
			(xy 210.844886 -41.596802) (xy 210.793169 -41.571714) (xy 210.745802 -41.539151) (xy 210.724496 -41.519856)
			(xy 210.717384 -41.512998) (xy 210.699604 -41.50614) (xy 210.610704 -41.50614) (xy 210.592924 -41.512998)
			(xy 210.585812 -41.519856) (xy 210.564484 -41.539126) (xy 210.517121 -41.571692) (xy 210.46541 -41.596785)
			(xy 210.41052 -41.613839) (xy 210.353693 -41.622468) (xy 210.324954 -41.62298) (xy 210.297706 -41.622491)
			(xy 210.243764 -41.614729) (xy 210.191477 -41.599369) (xy 210.141907 -41.576725) (xy 210.096065 -41.547257)
			(xy 210.054882 -41.511565) (xy 210.019198 -41.470376) (xy 209.989739 -41.424528) (xy 209.967105 -41.374954)
			(xy 209.951756 -41.322663) (xy 209.944004 -41.26872) (xy 209.943446 -41.241472) (xy 209.943825 -41.21818)
			(xy 209.949555 -41.171949) (xy 209.954876 -41.14927) (xy 209.95767 -41.137586) (xy 209.952844 -41.11498)
			(xy 209.896202 -41.04259) (xy 209.88861 -41.033765) (xy 209.8677 -41.023592) (xy 209.85607 -41.023032)
			(xy 206.008478 -41.023032) (xy 205.99841 -41.02346) (xy 205.979815 -41.031183) (xy 205.97241 -41.038018)
			(xy 205.805786 -41.204642) (xy 205.79911 -41.212055) (xy 205.791545 -41.230491) (xy 205.791054 -41.240456)
			(xy 205.791054 -43.73626) (xy 214.313006 -43.73626) (xy 214.317077 -43.680638) (xy 214.329203 -43.626201)
			(xy 214.349126 -43.57411) (xy 214.376422 -43.525475) (xy 214.410508 -43.481332) (xy 214.450657 -43.442623)
			(xy 214.496015 -43.410172) (xy 214.545615 -43.384671) (xy 214.598399 -43.366664) (xy 214.653242 -43.356534)
			(xy 214.708976 -43.354497) (xy 214.764413 -43.360597) (xy 214.81837 -43.374703) (xy 214.869699 -43.396515)
			(xy 214.917305 -43.425569) (xy 214.960173 -43.461244) (xy 214.99739 -43.502781) (xy 215.028163 -43.549294)
			(xy 215.051835 -43.599791) (xy 215.067903 -43.653198) (xy 215.076023 -43.708374) (xy 215.076532 -43.73626)
			(xy 215.076023 -43.764146) (xy 215.067903 -43.819322) (xy 215.051835 -43.872729) (xy 215.028163 -43.923226)
			(xy 214.99739 -43.969739) (xy 214.960173 -44.011276) (xy 214.917305 -44.046951) (xy 214.869699 -44.076005)
			(xy 214.81837 -44.097817) (xy 214.764413 -44.111923) (xy 214.708976 -44.118023) (xy 214.653242 -44.115986)
			(xy 214.598399 -44.105856) (xy 214.545615 -44.087849) (xy 214.496015 -44.062348) (xy 214.450657 -44.029897)
			(xy 214.410508 -43.991188) (xy 214.376422 -43.947045) (xy 214.349126 -43.89841) (xy 214.329203 -43.846319)
			(xy 214.317077 -43.791882) (xy 214.313006 -43.73626) (xy 205.791054 -43.73626) (xy 205.791054 -45.114464)
			(xy 214.165432 -45.114464) (xy 214.169503 -45.058842) (xy 214.181629 -45.004405) (xy 214.201552 -44.952314)
			(xy 214.228848 -44.903679) (xy 214.262934 -44.859536) (xy 214.303083 -44.820827) (xy 214.348441 -44.788376)
			(xy 214.398041 -44.762875) (xy 214.450825 -44.744868) (xy 214.505668 -44.734738) (xy 214.561402 -44.732701)
			(xy 214.616839 -44.738801) (xy 214.670796 -44.752907) (xy 214.722125 -44.774719) (xy 214.769731 -44.803773)
			(xy 214.812599 -44.839448) (xy 214.849816 -44.880985) (xy 214.880589 -44.927498) (xy 214.904261 -44.977995)
			(xy 214.920329 -45.031402) (xy 214.928449 -45.086578) (xy 214.928958 -45.114464) (xy 214.928449 -45.14235)
			(xy 214.920329 -45.197526) (xy 214.904261 -45.250933) (xy 214.880589 -45.30143) (xy 214.849816 -45.347943)
			(xy 214.812599 -45.38948) (xy 214.769731 -45.425155) (xy 214.722125 -45.454209) (xy 214.670796 -45.476021)
			(xy 214.616839 -45.490127) (xy 214.561402 -45.496227) (xy 214.505668 -45.49419) (xy 214.450825 -45.48406)
			(xy 214.398041 -45.466053) (xy 214.348441 -45.440552) (xy 214.303083 -45.408101) (xy 214.262934 -45.369392)
			(xy 214.228848 -45.325249) (xy 214.201552 -45.276614) (xy 214.181629 -45.224523) (xy 214.169503 -45.170086)
			(xy 214.165432 -45.114464) (xy 205.791054 -45.114464) (xy 205.791054 -46.893226) (xy 214.437212 -46.893226)
			(xy 214.441283 -46.837604) (xy 214.453409 -46.783167) (xy 214.473332 -46.731076) (xy 214.500628 -46.682441)
			(xy 214.534714 -46.638298) (xy 214.574863 -46.599589) (xy 214.620221 -46.567138) (xy 214.669821 -46.541637)
			(xy 214.722605 -46.52363) (xy 214.777448 -46.5135) (xy 214.833182 -46.511463) (xy 214.888619 -46.517563)
			(xy 214.942576 -46.531669) (xy 214.993905 -46.553481) (xy 215.041511 -46.582535) (xy 215.084379 -46.61821)
			(xy 215.121596 -46.659747) (xy 215.152369 -46.70626) (xy 215.176041 -46.756757) (xy 215.192109 -46.810164)
			(xy 215.200229 -46.86534) (xy 215.200738 -46.893226) (xy 215.200229 -46.921112) (xy 215.192109 -46.976288)
			(xy 215.176041 -47.029695) (xy 215.152369 -47.080192) (xy 215.121596 -47.126705) (xy 215.084379 -47.168242)
			(xy 215.041511 -47.203917) (xy 214.993905 -47.232971) (xy 214.942576 -47.254783) (xy 214.888619 -47.268889)
			(xy 214.833182 -47.274989) (xy 214.777448 -47.272952) (xy 214.722605 -47.262822) (xy 214.669821 -47.244815)
			(xy 214.620221 -47.219314) (xy 214.574863 -47.186863) (xy 214.534714 -47.148154) (xy 214.500628 -47.104011)
			(xy 214.473332 -47.055376) (xy 214.453409 -47.003285) (xy 214.441283 -46.948848) (xy 214.437212 -46.893226)
			(xy 205.791054 -46.893226) (xy 205.791054 -47.936658) (xy 212.75294 -47.936658) (xy 212.753426 -47.909407)
			(xy 212.761182 -47.855459) (xy 212.776537 -47.803164) (xy 212.799179 -47.753587) (xy 212.828645 -47.707737)
			(xy 212.864336 -47.666546) (xy 212.905527 -47.630855) (xy 212.951377 -47.601389) (xy 213.000954 -47.578747)
			(xy 213.053249 -47.563392) (xy 213.107197 -47.555636) (xy 213.161699 -47.555636) (xy 213.215647 -47.563392)
			(xy 213.267942 -47.578747) (xy 213.317519 -47.601389) (xy 213.363369 -47.630855) (xy 213.40456 -47.666546)
			(xy 213.440251 -47.707737) (xy 213.469717 -47.753587) (xy 213.492359 -47.803164) (xy 213.507714 -47.855459)
			(xy 213.51547 -47.909407) (xy 213.515956 -47.936658) (xy 213.515492 -47.962999) (xy 213.508242 -48.015179)
			(xy 213.493888 -48.065867) (xy 213.472701 -48.1141) (xy 213.445085 -48.158963) (xy 213.411563 -48.199604)
			(xy 213.372773 -48.23525) (xy 213.351364 -48.250602) (xy 213.339537 -48.259295) (xy 213.321096 -48.282119)
			(xy 213.309908 -48.309246) (xy 213.3069 -48.338435) (xy 213.312317 -48.367273) (xy 213.325715 -48.393379)
			(xy 213.345984 -48.414596) (xy 213.358476 -48.422306) (xy 213.383012 -48.437) (xy 213.427771 -48.472602)
			(xy 213.466714 -48.514485) (xy 213.49897 -48.561712) (xy 213.523816 -48.613224) (xy 213.540695 -48.667868)
			(xy 213.549229 -48.724418) (xy 213.549738 -48.753014) (xy 213.549252 -48.780265) (xy 213.541496 -48.834213)
			(xy 213.526141 -48.886508) (xy 213.503499 -48.936085) (xy 213.474033 -48.981935) (xy 213.438342 -49.023126)
			(xy 213.397151 -49.058817) (xy 213.351301 -49.088283) (xy 213.301724 -49.110925) (xy 213.249429 -49.12628)
			(xy 213.195481 -49.134036) (xy 213.140979 -49.134036) (xy 213.087031 -49.12628) (xy 213.034736 -49.110925)
			(xy 212.985159 -49.088283) (xy 212.939309 -49.058817) (xy 212.898118 -49.023126) (xy 212.862427 -48.981935)
			(xy 212.832961 -48.936085) (xy 212.810319 -48.886508) (xy 212.794964 -48.834213) (xy 212.787208 -48.780265)
			(xy 212.786722 -48.753014) (xy 212.787174 -48.726673) (xy 212.794427 -48.674493) (xy 212.808785 -48.623805)
			(xy 212.829974 -48.575572) (xy 212.857591 -48.530709) (xy 212.891114 -48.490068) (xy 212.929905 -48.454422)
			(xy 212.951314 -48.43907) (xy 212.963158 -48.430403) (xy 212.981585 -48.407568) (xy 212.992761 -48.380438)
			(xy 212.995763 -48.35125) (xy 212.990344 -48.322412) (xy 212.976951 -48.296305) (xy 212.95669 -48.275081)
			(xy 212.944202 -48.267366) (xy 212.919693 -48.252629) (xy 212.874935 -48.217034) (xy 212.835991 -48.175157)
			(xy 212.803733 -48.127937) (xy 212.778883 -48.076433) (xy 212.761997 -48.021796) (xy 212.753454 -47.965251)
			(xy 212.75294 -47.936658) (xy 205.791054 -47.936658) (xy 205.791054 -58.731404) (xy 207.620616 -58.731404)
			(xy 207.621081 -58.704034) (xy 207.628898 -58.649854) (xy 207.644387 -58.597351) (xy 207.66723 -58.547604)
			(xy 207.696955 -58.501638) (xy 207.714596 -58.480706) (xy 207.720692 -58.473594) (xy 207.727042 -58.456576)
			(xy 207.727042 -58.371232) (xy 207.720692 -58.354214) (xy 207.714596 -58.347102) (xy 207.696961 -58.326165)
			(xy 207.667238 -58.280198) (xy 207.644394 -58.230452) (xy 207.628899 -58.177951) (xy 207.621071 -58.123773)
			(xy 207.62107 -58.069033) (xy 207.628898 -58.014855) (xy 207.644392 -57.962354) (xy 207.667235 -57.912608)
			(xy 207.696957 -57.866639) (xy 207.714596 -57.845706) (xy 207.720692 -57.838594) (xy 207.727042 -57.821576)
			(xy 207.727042 -57.736232) (xy 207.720692 -57.719214) (xy 207.714596 -57.712102) (xy 207.696961 -57.691165)
			(xy 207.667238 -57.645198) (xy 207.644394 -57.595452) (xy 207.628899 -57.542951) (xy 207.621071 -57.488773)
			(xy 207.62107 -57.434033) (xy 207.628898 -57.379855) (xy 207.644392 -57.327354) (xy 207.667235 -57.277608)
			(xy 207.696957 -57.231639) (xy 207.714596 -57.210706) (xy 207.720692 -57.203594) (xy 207.727042 -57.186576)
			(xy 207.727042 -57.101232) (xy 207.720692 -57.084214) (xy 207.714596 -57.077102) (xy 207.696944 -57.056181)
			(xy 207.667234 -57.010205) (xy 207.644401 -56.960455) (xy 207.628913 -56.907952) (xy 207.621088 -56.853774)
			(xy 207.620616 -56.826404) (xy 207.621102 -56.799153) (xy 207.628858 -56.745205) (xy 207.644213 -56.69291)
			(xy 207.666855 -56.643333) (xy 207.696321 -56.597483) (xy 207.732012 -56.556292) (xy 207.773203 -56.520601)
			(xy 207.819053 -56.491135) (xy 207.86863 -56.468493) (xy 207.920925 -56.453138) (xy 207.974873 -56.445382)
			(xy 208.029375 -56.445382) (xy 208.083323 -56.453138) (xy 208.135618 -56.468493) (xy 208.185195 -56.491135)
			(xy 208.231045 -56.520601) (xy 208.272236 -56.556292) (xy 208.307927 -56.597483) (xy 208.337393 -56.643333)
			(xy 208.360035 -56.69291) (xy 208.37539 -56.745205) (xy 208.383146 -56.799153) (xy 208.383632 -56.826404)
			(xy 208.383185 -56.853775) (xy 208.375365 -56.907956) (xy 208.359872 -56.96046) (xy 208.337026 -57.010206)
			(xy 208.307296 -57.056172) (xy 208.289652 -57.077102) (xy 208.283556 -57.084214) (xy 208.277206 -57.101232)
			(xy 208.277206 -57.186576) (xy 208.283556 -57.203594) (xy 208.289652 -57.210706) (xy 208.307297 -57.231635)
			(xy 208.337024 -57.277603) (xy 208.35987 -57.32735) (xy 208.375367 -57.379853) (xy 208.383196 -57.434032)
			(xy 208.383195 -57.488774) (xy 208.375366 -57.542953) (xy 208.359868 -57.595456) (xy 208.337021 -57.645202)
			(xy 208.307294 -57.69117) (xy 208.289652 -57.712102) (xy 208.283556 -57.719214) (xy 208.277206 -57.736232)
			(xy 208.277206 -57.821576) (xy 208.283556 -57.838594) (xy 208.289652 -57.845706) (xy 208.307297 -57.866635)
			(xy 208.337024 -57.912603) (xy 208.35987 -57.96235) (xy 208.375367 -58.014853) (xy 208.383196 -58.069032)
			(xy 208.383195 -58.123774) (xy 208.375366 -58.177953) (xy 208.359868 -58.230456) (xy 208.337021 -58.280202)
			(xy 208.307294 -58.32617) (xy 208.289652 -58.347102) (xy 208.283556 -58.354214) (xy 208.277206 -58.371232)
			(xy 208.277206 -58.456576) (xy 208.283556 -58.473594) (xy 208.289652 -58.480706) (xy 208.3073 -58.501631)
			(xy 208.337012 -58.547605) (xy 208.359847 -58.597354) (xy 208.375336 -58.649857) (xy 208.38316 -58.704034)
			(xy 208.383632 -58.731404) (xy 208.383146 -58.758655) (xy 208.378482 -58.791094) (xy 210.27644 -58.791094)
			(xy 210.276893 -58.763723) (xy 210.284712 -58.709543) (xy 210.300204 -58.657039) (xy 210.323049 -58.607293)
			(xy 210.352777 -58.561327) (xy 210.37042 -58.540396) (xy 210.376516 -58.533284) (xy 210.382866 -58.516266)
			(xy 210.382866 -58.430922) (xy 210.376516 -58.413904) (xy 210.37042 -58.406792) (xy 210.352774 -58.385864)
			(xy 210.32305 -58.339895) (xy 210.300205 -58.290148) (xy 210.28471 -58.237645) (xy 210.276882 -58.183466)
			(xy 210.276882 -58.128725) (xy 210.284712 -58.074546) (xy 210.300208 -58.022043) (xy 210.323054 -57.972297)
			(xy 210.352779 -57.926329) (xy 210.37042 -57.905396) (xy 210.376516 -57.898284) (xy 210.382866 -57.881266)
			(xy 210.382866 -57.795922) (xy 210.376516 -57.778904) (xy 210.37042 -57.771792) (xy 210.352767 -57.750871)
			(xy 210.323056 -57.704896) (xy 210.300223 -57.655145) (xy 210.284735 -57.602642) (xy 210.276911 -57.548464)
			(xy 210.27644 -57.521094) (xy 210.276897 -57.494778) (xy 210.284114 -57.442644) (xy 210.298426 -57.391995)
			(xy 210.319559 -57.343793) (xy 210.347115 -57.298951) (xy 210.380569 -57.258319) (xy 210.39963 -57.24017)
			(xy 210.407037 -57.232652) (xy 210.415561 -57.21337) (xy 210.41614 -57.202832) (xy 210.41614 -57.128156)
			(xy 210.415582 -57.11761) (xy 210.407066 -57.098315) (xy 210.39963 -57.090818) (xy 210.380565 -57.072669)
			(xy 210.347085 -57.032052) (xy 210.319511 -56.987215) (xy 210.29837 -56.93901) (xy 210.284063 -56.888355)
			(xy 210.276862 -56.836213) (xy 210.27644 -56.809894) (xy 210.276926 -56.782643) (xy 210.284682 -56.728695)
			(xy 210.300037 -56.6764) (xy 210.322679 -56.626823) (xy 210.352145 -56.580973) (xy 210.387836 -56.539782)
			(xy 210.429027 -56.504091) (xy 210.474877 -56.474625) (xy 210.524454 -56.451983) (xy 210.576749 -56.436628)
			(xy 210.630697 -56.428872) (xy 210.685199 -56.428872) (xy 210.739147 -56.436628) (xy 210.791442 -56.451983)
			(xy 210.841019 -56.474625) (xy 210.886869 -56.504091) (xy 210.92806 -56.539782) (xy 210.963751 -56.580973)
			(xy 210.993217 -56.626823) (xy 211.015859 -56.6764) (xy 211.031214 -56.728695) (xy 211.03897 -56.782643)
			(xy 211.039456 -56.809894) (xy 211.039059 -56.836212) (xy 211.03183 -56.888349) (xy 211.017507 -56.938999)
			(xy 210.996362 -56.987201) (xy 210.968796 -57.032041) (xy 210.935331 -57.07267) (xy 210.916266 -57.090818)
			(xy 210.908864 -57.09834) (xy 210.900338 -57.117619) (xy 210.899756 -57.128156) (xy 210.899756 -57.202832)
			(xy 210.900321 -57.213377) (xy 210.908833 -57.232672) (xy 210.916266 -57.24017) (xy 210.935324 -57.258326)
			(xy 210.968806 -57.298941) (xy 210.99638 -57.343777) (xy 211.017522 -57.39198) (xy 211.031831 -57.442634)
			(xy 211.035204 -57.467053) (xy 211.218469 -57.467053) (xy 211.218469 -57.412547) (xy 211.226227 -57.358596)
			(xy 211.241584 -57.306298) (xy 211.264227 -57.256718) (xy 211.293696 -57.210865) (xy 211.329392 -57.169673)
			(xy 211.370586 -57.133981) (xy 211.416441 -57.104515) (xy 211.466022 -57.081874) (xy 211.518321 -57.066521)
			(xy 211.572273 -57.058768) (xy 211.599526 -57.058306) (xy 211.625842 -57.05876) (xy 211.677976 -57.06598)
			(xy 211.728624 -57.080292) (xy 211.776826 -57.101427) (xy 211.821668 -57.128982) (xy 211.8623 -57.162436)
			(xy 211.88045 -57.181496) (xy 211.887952 -57.188921) (xy 211.907247 -57.197432) (xy 211.917788 -57.198006)
			(xy 211.992464 -57.198006) (xy 212.003013 -57.197469) (xy 212.022308 -57.188939) (xy 212.029802 -57.181496)
			(xy 212.047935 -57.162415) (xy 212.088556 -57.128937) (xy 212.133397 -57.101367) (xy 212.181605 -57.080229)
			(xy 212.232262 -57.065925) (xy 212.284406 -57.058727) (xy 212.310726 -57.058306) (xy 212.337977 -57.058766)
			(xy 212.391924 -57.066525) (xy 212.427073 -57.076848) (xy 213.238588 -57.076848) (xy 213.239085 -57.049479)
			(xy 213.246896 -56.995301) (xy 213.262378 -56.942799) (xy 213.285213 -56.893051) (xy 213.31493 -56.847083)
			(xy 213.332568 -56.82615) (xy 213.338664 -56.819038) (xy 213.345014 -56.80202) (xy 213.345014 -56.716676)
			(xy 213.338664 -56.699658) (xy 213.332568 -56.692546) (xy 213.314932 -56.671612) (xy 213.285221 -56.625639)
			(xy 213.262385 -56.575892) (xy 213.246893 -56.523392) (xy 213.239063 -56.469217) (xy 213.238588 -56.441848)
			(xy 213.239074 -56.414597) (xy 213.24683 -56.360649) (xy 213.262185 -56.308354) (xy 213.284827 -56.258777)
			(xy 213.314293 -56.212927) (xy 213.349984 -56.171736) (xy 213.391175 -56.136045) (xy 213.437025 -56.106579)
			(xy 213.486602 -56.083937) (xy 213.538897 -56.068582) (xy 213.592845 -56.060826) (xy 213.647347 -56.060826)
			(xy 213.701295 -56.068582) (xy 213.75359 -56.083937) (xy 213.803167 -56.106579) (xy 213.849017 -56.136045)
			(xy 213.890208 -56.171736) (xy 213.925899 -56.212927) (xy 213.955365 -56.258777) (xy 213.978007 -56.308354)
			(xy 213.993362 -56.360649) (xy 214.001118 -56.414597) (xy 214.001604 -56.441848) (xy 214.001106 -56.469217)
			(xy 213.993296 -56.523395) (xy 213.977814 -56.575898) (xy 213.95498 -56.625645) (xy 213.925262 -56.671613)
			(xy 213.907624 -56.692546) (xy 213.901528 -56.699658) (xy 213.895178 -56.716676) (xy 213.895178 -56.80202)
			(xy 213.901528 -56.819038) (xy 213.907624 -56.82615) (xy 213.925257 -56.847087) (xy 213.954969 -56.893059)
			(xy 213.977806 -56.942805) (xy 213.993298 -56.995305) (xy 214.001129 -57.049479) (xy 214.001604 -57.076848)
			(xy 214.001118 -57.104099) (xy 213.993362 -57.158047) (xy 213.978007 -57.210342) (xy 213.955365 -57.259919)
			(xy 213.925899 -57.305769) (xy 213.890208 -57.34696) (xy 213.849017 -57.382651) (xy 213.803167 -57.412117)
			(xy 213.75359 -57.434759) (xy 213.701295 -57.450114) (xy 213.647347 -57.45787) (xy 213.592845 -57.45787)
			(xy 213.538897 -57.450114) (xy 213.486602 -57.434759) (xy 213.437025 -57.412117) (xy 213.391175 -57.382651)
			(xy 213.349984 -57.34696) (xy 213.314293 -57.305769) (xy 213.284827 -57.259919) (xy 213.262185 -57.210342)
			(xy 213.24683 -57.158047) (xy 213.239074 -57.104099) (xy 213.238588 -57.076848) (xy 212.427073 -57.076848)
			(xy 212.444217 -57.081883) (xy 212.493793 -57.104527) (xy 212.539642 -57.133995) (xy 212.580831 -57.169688)
			(xy 212.616521 -57.210879) (xy 212.645986 -57.25673) (xy 212.668626 -57.306307) (xy 212.68398 -57.358602)
			(xy 212.691736 -57.412549) (xy 212.691736 -57.467051) (xy 212.68398 -57.520998) (xy 212.668626 -57.573293)
			(xy 212.645986 -57.62287) (xy 212.616521 -57.668721) (xy 212.580831 -57.709912) (xy 212.539642 -57.745605)
			(xy 212.493793 -57.775073) (xy 212.444217 -57.797717) (xy 212.391924 -57.813075) (xy 212.337977 -57.820834)
			(xy 212.310726 -57.821322) (xy 212.284409 -57.820891) (xy 212.232275 -57.813665) (xy 212.181626 -57.799348)
			(xy 212.133425 -57.778209) (xy 212.088583 -57.75065) (xy 212.047952 -57.717193) (xy 212.029802 -57.698132)
			(xy 212.022277 -57.690734) (xy 212.003 -57.682206) (xy 211.992464 -57.681622) (xy 211.917788 -57.681622)
			(xy 211.907235 -57.682125) (xy 211.88794 -57.690678) (xy 211.88045 -57.698132) (xy 211.862326 -57.717223)
			(xy 211.821705 -57.750702) (xy 211.776863 -57.778273) (xy 211.728653 -57.79941) (xy 211.677993 -57.813711)
			(xy 211.625846 -57.820905) (xy 211.599526 -57.821322) (xy 211.572273 -57.820832) (xy 211.518321 -57.813079)
			(xy 211.466022 -57.797726) (xy 211.416441 -57.775085) (xy 211.370586 -57.745619) (xy 211.329392 -57.709927)
			(xy 211.293696 -57.668735) (xy 211.264227 -57.622882) (xy 211.241584 -57.573302) (xy 211.226227 -57.521004)
			(xy 211.218469 -57.467053) (xy 211.035204 -57.467053) (xy 211.039033 -57.494776) (xy 211.039456 -57.521094)
			(xy 211.038997 -57.548465) (xy 211.031179 -57.602644) (xy 211.015689 -57.655148) (xy 210.992845 -57.704895)
			(xy 210.963119 -57.750861) (xy 210.945476 -57.771792) (xy 210.93938 -57.778904) (xy 210.93303 -57.795922)
			(xy 210.93303 -57.881266) (xy 210.93938 -57.898284) (xy 210.945476 -57.905396) (xy 210.963111 -57.926334)
			(xy 210.992835 -57.972301) (xy 211.015681 -58.022046) (xy 211.031178 -58.074547) (xy 211.039007 -58.128725)
			(xy 211.039007 -58.183466) (xy 211.03118 -58.237644) (xy 211.015684 -58.290145) (xy 210.99284 -58.339891)
			(xy 210.963116 -58.385859) (xy 210.945476 -58.406792) (xy 210.93938 -58.413904) (xy 210.93303 -58.430922)
			(xy 210.93303 -58.516266) (xy 210.93938 -58.533284) (xy 210.945476 -58.540396) (xy 210.963123 -58.561322)
			(xy 210.992834 -58.607296) (xy 211.015669 -58.657045) (xy 211.031158 -58.709547) (xy 211.038984 -58.763724)
			(xy 211.039456 -58.791094) (xy 211.03897 -58.818345) (xy 211.031214 -58.872293) (xy 211.030817 -58.873644)
			(xy 212.300566 -58.873644) (xy 212.301042 -58.846274) (xy 212.308855 -58.792095) (xy 212.324341 -58.739591)
			(xy 212.347181 -58.689844) (xy 212.376905 -58.643877) (xy 212.394546 -58.622946) (xy 212.400642 -58.615834)
			(xy 212.406992 -58.598816) (xy 212.406992 -58.513472) (xy 212.400642 -58.496454) (xy 212.394546 -58.489342)
			(xy 212.37692 -58.468399) (xy 212.347205 -58.42243) (xy 212.324366 -58.372685) (xy 212.308872 -58.320187)
			(xy 212.301041 -58.266013) (xy 212.300566 -58.238644) (xy 212.301052 -58.211393) (xy 212.308808 -58.157445)
			(xy 212.324163 -58.10515) (xy 212.346805 -58.055573) (xy 212.376271 -58.009723) (xy 212.411962 -57.968532)
			(xy 212.453153 -57.932841) (xy 212.499003 -57.903375) (xy 212.54858 -57.880733) (xy 212.600875 -57.865378)
			(xy 212.654823 -57.857622) (xy 212.709325 -57.857622) (xy 212.763273 -57.865378) (xy 212.815568 -57.880733)
			(xy 212.865145 -57.903375) (xy 212.910995 -57.932841) (xy 212.952186 -57.968532) (xy 212.987877 -58.009723)
			(xy 213.017343 -58.055573) (xy 213.039985 -58.10515) (xy 213.05534 -58.157445) (xy 213.063096 -58.211393)
			(xy 213.063582 -58.238644) (xy 213.063087 -58.266013) (xy 213.055277 -58.320191) (xy 213.039795 -58.372694)
			(xy 213.016959 -58.422442) (xy 212.987241 -58.46841) (xy 212.969602 -58.489342) (xy 212.963506 -58.496454)
			(xy 212.957156 -58.513472) (xy 212.957156 -58.598816) (xy 212.963506 -58.615834) (xy 212.969602 -58.622946)
			(xy 212.98723 -58.643887) (xy 213.016943 -58.689858) (xy 213.039781 -58.739603) (xy 213.055275 -58.792101)
			(xy 213.063106 -58.846275) (xy 213.063582 -58.873644) (xy 213.063096 -58.900895) (xy 213.05534 -58.954843)
			(xy 213.039985 -59.007138) (xy 213.017343 -59.056715) (xy 212.987877 -59.102565) (xy 212.952186 -59.143756)
			(xy 212.910995 -59.179447) (xy 212.865145 -59.208913) (xy 212.815568 -59.231555) (xy 212.763273 -59.24691)
			(xy 212.709325 -59.254666) (xy 212.654823 -59.254666) (xy 212.600875 -59.24691) (xy 212.54858 -59.231555)
			(xy 212.499003 -59.208913) (xy 212.453153 -59.179447) (xy 212.411962 -59.143756) (xy 212.376271 -59.102565)
			(xy 212.346805 -59.056715) (xy 212.324163 -59.007138) (xy 212.308808 -58.954843) (xy 212.301052 -58.900895)
			(xy 212.300566 -58.873644) (xy 211.030817 -58.873644) (xy 211.015859 -58.924588) (xy 210.993217 -58.974165)
			(xy 210.963751 -59.020015) (xy 210.92806 -59.061206) (xy 210.886869 -59.096897) (xy 210.841019 -59.126363)
			(xy 210.791442 -59.149005) (xy 210.739147 -59.16436) (xy 210.685199 -59.172116) (xy 210.630697 -59.172116)
			(xy 210.576749 -59.16436) (xy 210.524454 -59.149005) (xy 210.474877 -59.126363) (xy 210.429027 -59.096897)
			(xy 210.387836 -59.061206) (xy 210.352145 -59.020015) (xy 210.322679 -58.974165) (xy 210.300037 -58.924588)
			(xy 210.284682 -58.872293) (xy 210.276926 -58.818345) (xy 210.27644 -58.791094) (xy 208.378482 -58.791094)
			(xy 208.37539 -58.812603) (xy 208.360035 -58.864898) (xy 208.337393 -58.914475) (xy 208.307927 -58.960325)
			(xy 208.272236 -59.001516) (xy 208.231045 -59.037207) (xy 208.185195 -59.066673) (xy 208.135618 -59.089315)
			(xy 208.083323 -59.10467) (xy 208.029375 -59.112426) (xy 207.974873 -59.112426) (xy 207.920925 -59.10467)
			(xy 207.86863 -59.089315) (xy 207.819053 -59.066673) (xy 207.773203 -59.037207) (xy 207.732012 -59.001516)
			(xy 207.696321 -58.960325) (xy 207.666855 -58.914475) (xy 207.644213 -58.864898) (xy 207.628858 -58.812603)
			(xy 207.621102 -58.758655) (xy 207.620616 -58.731404) (xy 205.791054 -58.731404) (xy 205.791054 -60.126455)
			(xy 211.28015 -60.126455) (xy 211.28015 -60.071945) (xy 211.287908 -60.017989) (xy 211.303267 -59.965686)
			(xy 211.325913 -59.916102) (xy 211.355386 -59.870246) (xy 211.391085 -59.829051) (xy 211.432284 -59.793357)
			(xy 211.478144 -59.76389) (xy 211.527731 -59.74125) (xy 211.580036 -59.725898) (xy 211.633992 -59.718146)
			(xy 211.661248 -59.717686) (xy 211.688617 -59.718186) (xy 211.742794 -59.725996) (xy 211.795297 -59.741477)
			(xy 211.845044 -59.764312) (xy 211.891013 -59.794028) (xy 211.911946 -59.811666) (xy 211.919058 -59.817762)
			(xy 211.936076 -59.824112) (xy 212.02142 -59.824112) (xy 212.038438 -59.817762) (xy 212.04555 -59.811666)
			(xy 212.066483 -59.794025) (xy 212.112451 -59.764301) (xy 212.162197 -59.741455) (xy 212.214699 -59.725959)
			(xy 212.268877 -59.71813) (xy 212.323619 -59.71813) (xy 212.377797 -59.725959) (xy 212.430299 -59.741455)
			(xy 212.480045 -59.764301) (xy 212.526013 -59.794025) (xy 212.546946 -59.811666) (xy 212.554058 -59.817762)
			(xy 212.571076 -59.824112) (xy 212.65642 -59.824112) (xy 212.673438 -59.817762) (xy 212.68055 -59.811666)
			(xy 212.701486 -59.794032) (xy 212.747458 -59.76432) (xy 212.797205 -59.741484) (xy 212.849704 -59.725992)
			(xy 212.903879 -59.718161) (xy 212.931248 -59.717686) (xy 212.958497 -59.718187) (xy 213.012438 -59.725949)
			(xy 213.064726 -59.741308) (xy 213.114297 -59.763952) (xy 213.160141 -59.793419) (xy 213.201324 -59.82911)
			(xy 213.23701 -59.870298) (xy 213.266471 -59.916145) (xy 213.289109 -59.965719) (xy 213.304461 -60.018009)
			(xy 213.312216 -60.071951) (xy 213.312216 -60.126449) (xy 213.304461 -60.180391) (xy 213.289109 -60.232681)
			(xy 213.266471 -60.282255) (xy 213.23701 -60.328102) (xy 213.201324 -60.36929) (xy 213.160141 -60.404981)
			(xy 213.114297 -60.434448) (xy 213.064726 -60.457092) (xy 213.012438 -60.472451) (xy 212.958497 -60.480213)
			(xy 212.931248 -60.480702) (xy 212.903879 -60.480207) (xy 212.849701 -60.472396) (xy 212.797198 -60.456914)
			(xy 212.747451 -60.434079) (xy 212.701483 -60.40436) (xy 212.68055 -60.386722) (xy 212.673438 -60.380626)
			(xy 212.65642 -60.374276) (xy 212.571076 -60.374276) (xy 212.554058 -60.380626) (xy 212.546946 -60.386722)
			(xy 212.526013 -60.404363) (xy 212.480045 -60.434087) (xy 212.430299 -60.456933) (xy 212.377797 -60.472429)
			(xy 212.323619 -60.480258) (xy 212.268877 -60.480258) (xy 212.214699 -60.472429) (xy 212.162197 -60.456933)
			(xy 212.112451 -60.434087) (xy 212.066483 -60.404363) (xy 212.04555 -60.386722) (xy 212.038438 -60.380626)
			(xy 212.02142 -60.374276) (xy 211.936076 -60.374276) (xy 211.919058 -60.380626) (xy 211.911946 -60.386722)
			(xy 211.89101 -60.404356) (xy 211.845038 -60.434068) (xy 211.795291 -60.456905) (xy 211.742792 -60.472397)
			(xy 211.688617 -60.480227) (xy 211.661248 -60.480702) (xy 211.633992 -60.480254) (xy 211.580036 -60.472502)
			(xy 211.527731 -60.45715) (xy 211.478144 -60.43451) (xy 211.432284 -60.405043) (xy 211.391085 -60.369349)
			(xy 211.355386 -60.328154) (xy 211.325913 -60.282298) (xy 211.303267 -60.232714) (xy 211.287908 -60.180411)
			(xy 211.28015 -60.126455) (xy 205.791054 -60.126455) (xy 205.791054 -60.999878) (xy 205.790519 -61.009866)
			(xy 205.782806 -61.0283) (xy 205.776068 -61.035692) (xy 205.70063 -61.11113) (xy 205.700122 -61.111892)
			(xy 205.69682 -61.115194) (xy 205.696566 -61.115448) (xy 205.069948 -61.742066) (xy 205.062328 -61.749432)
			(xy 205.000352 -61.811408) (xy 204.992998 -61.818064) (xy 204.974698 -61.825662) (xy 204.964792 -61.82614)
			(xy 204.909928 -61.82614) (xy 204.90561 -61.826902) (xy 204.892942 -61.828912) (xy 204.867382 -61.831075)
			(xy 204.854556 -61.83122) (xy 203.179426 -61.83122) (xy 203.167804 -61.831792) (xy 203.14691 -61.84198)
			(xy 203.139294 -61.850778) (xy 203.082652 -61.923422) (xy 203.077826 -61.946028) (xy 203.080874 -61.957712)
			(xy 203.08634 -61.980757) (xy 203.092194 -62.027757) (xy 203.092558 -62.051438) (xy 203.092092 -62.078688)
			(xy 203.08433 -62.132632) (xy 203.068971 -62.184922) (xy 203.046325 -62.234495) (xy 203.016855 -62.280339)
			(xy 202.981161 -62.321523) (xy 202.939969 -62.357208) (xy 202.894117 -62.386667) (xy 202.84454 -62.409301)
			(xy 202.792246 -62.424649) (xy 202.7383 -62.432398) (xy 202.71105 -62.432946) (xy 202.687496 -62.432563)
			(xy 202.640753 -62.426702) (xy 202.617832 -62.421262) (xy 202.603608 -62.417706) (xy 202.57643 -62.426342)
			(xy 202.498198 -62.517274) (xy 202.493626 -62.545468) (xy 202.499214 -62.55893) (xy 202.508539 -62.582314)
			(xy 202.521658 -62.630918) (xy 202.528275 -62.680824) (xy 202.528678 -62.705996) (xy 202.528215 -62.733248)
			(xy 202.520458 -62.787198) (xy 202.505102 -62.839495) (xy 202.48246 -62.889073) (xy 202.452991 -62.934925)
			(xy 202.417297 -62.976116) (xy 202.376104 -63.011807) (xy 202.330251 -63.041272) (xy 202.28067 -63.063911)
			(xy 202.228373 -63.079264) (xy 202.174422 -63.087017) (xy 202.14717 -63.087504) (xy 202.118359 -63.086982)
			(xy 202.06139 -63.078322) (xy 202.006374 -63.061189) (xy 201.954562 -63.035972) (xy 201.907134 -63.003247)
			(xy 201.885804 -62.983872) (xy 201.877168 -62.975744) (xy 201.855324 -62.968886) (xy 201.765408 -62.981332)
			(xy 201.763376 -62.981586) (xy 201.752645 -62.984103) (xy 201.734623 -62.996751) (xy 201.728578 -63.00597)
			(xy 201.713761 -63.030092) (xy 201.678124 -63.074076) (xy 201.636377 -63.112309) (xy 201.589437 -63.143952)
			(xy 201.538336 -63.168309) (xy 201.484196 -63.184846) (xy 201.428207 -63.193199) (xy 201.399902 -63.193676)
			(xy 201.372651 -63.193213) (xy 201.318705 -63.185457) (xy 201.266411 -63.170102) (xy 201.216835 -63.147462)
			(xy 201.170985 -63.117996) (xy 201.129796 -63.082306) (xy 201.094105 -63.041116) (xy 201.064639 -62.995267)
			(xy 201.041998 -62.945691) (xy 201.026644 -62.893397) (xy 201.018887 -62.839451) (xy 201.018887 -62.784949)
			(xy 201.026644 -62.731003) (xy 201.041998 -62.678709) (xy 201.064639 -62.629133) (xy 201.094105 -62.583284)
			(xy 201.129796 -62.542094) (xy 201.170985 -62.506404) (xy 201.216835 -62.476938) (xy 201.266411 -62.454298)
			(xy 201.318705 -62.438943) (xy 201.372651 -62.431187) (xy 201.399902 -62.43066) (xy 201.428712 -62.431187)
			(xy 201.485675 -62.439856) (xy 201.540686 -62.456996) (xy 201.592492 -62.482217) (xy 201.639914 -62.514945)
			(xy 201.661268 -62.534292) (xy 201.669904 -62.54242) (xy 201.691748 -62.549278) (xy 201.793348 -62.535054)
			(xy 201.812398 -62.522354) (xy 201.818494 -62.512194) (xy 201.833313 -62.488077) (xy 201.868955 -62.444104)
			(xy 201.910705 -62.405882) (xy 201.957645 -62.374251) (xy 202.008745 -62.349906) (xy 202.062883 -62.333381)
			(xy 202.118868 -62.325039) (xy 202.14717 -62.324488) (xy 202.167236 -62.324996) (xy 202.16749 -62.324996)
			(xy 202.183238 -62.326012) (xy 202.191874 -62.327028) (xy 202.212702 -62.330076) (xy 202.212956 -62.330076)
			(xy 202.240388 -62.336172) (xy 202.254612 -62.339728) (xy 202.28179 -62.331092) (xy 202.360022 -62.24016)
			(xy 202.36434 -62.21222) (xy 202.358752 -62.198504) (xy 202.348932 -62.173891) (xy 202.335423 -62.122651)
			(xy 202.331828 -62.096396) (xy 202.330558 -62.082426) (xy 202.329288 -62.051438) (xy 202.329288 -62.05093)
			(xy 202.329658 -62.027312) (xy 202.335518 -61.980441) (xy 202.340972 -61.957458) (xy 202.34402 -61.945774)
			(xy 202.339194 -61.923168) (xy 202.282806 -61.850778) (xy 202.275214 -61.841954) (xy 202.254303 -61.831781)
			(xy 202.242674 -61.83122) (xy 201.264266 -61.83122) (xy 201.251567 -61.831072) (xy 201.22626 -61.828909)
			(xy 201.21372 -61.826902) (xy 201.209402 -61.82614) (xy 200.968864 -61.82614) (xy 200.95718 -61.829188)
			(xy 200.952354 -61.831474) (xy 200.951846 -61.831728) (xy 200.936941 -61.838668) (xy 200.906164 -61.850244)
			(xy 200.890378 -61.854842) (xy 200.863085 -61.86206) (xy 200.807097 -61.869299) (xy 200.750654 -61.868197)
			(xy 200.722738 -61.863986) (xy 200.696161 -61.859024) (xy 200.644657 -61.842578) (xy 200.620122 -61.83122)
			(xy 200.615042 -61.82868) (xy 200.603866 -61.82614) (xy 200.35393 -61.82614) (xy 200.349612 -61.826902)
			(xy 200.33707 -61.828894) (xy 200.311764 -61.831054) (xy 200.299066 -61.83122) (xy 199.16394 -61.83122)
			(xy 199.151292 -61.831886) (xy 199.129018 -61.843873) (xy 199.121522 -61.85408) (xy 199.070976 -61.931296)
			(xy 199.06996 -61.94425) (xy 199.068944 -61.956696) (xy 199.071992 -61.963808) (xy 199.071992 -61.964062)
			(xy 199.074278 -61.969142) (xy 199.08426 -61.993204) (xy 199.098295 -62.043373) (xy 199.105355 -62.094986)
			(xy 199.105774 -62.121034) (xy 199.105774 -62.12586) (xy 199.104962 -62.152886) (xy 199.096652 -62.206313)
			(xy 199.080883 -62.258031) (xy 199.057971 -62.307004) (xy 199.028374 -62.352253) (xy 198.992685 -62.39287)
			(xy 198.95162 -62.428042) (xy 198.906001 -62.457064) (xy 198.856741 -62.479355) (xy 198.804827 -62.494469)
			(xy 198.7513 -62.502102) (xy 198.697232 -62.502102) (xy 198.643705 -62.494469) (xy 198.591791 -62.479355)
			(xy 198.542531 -62.457064) (xy 198.496912 -62.428042) (xy 198.455847 -62.39287) (xy 198.420158 -62.352253)
			(xy 198.390561 -62.307004) (xy 198.367649 -62.258031) (xy 198.35188 -62.206313) (xy 198.34357 -62.152886)
			(xy 198.342758 -62.12586) (xy 198.342758 -62.12078) (xy 198.343206 -62.094683) (xy 198.35036 -62.042981)
			(xy 198.364492 -61.992737) (xy 198.374508 -61.968634) (xy 198.379588 -61.95695) (xy 198.378572 -61.94425)
			(xy 198.377556 -61.931296) (xy 198.327264 -61.854334) (xy 198.320152 -61.843412) (xy 198.2978 -61.83122)
			(xy 195.762372 -61.83122) (xy 195.752304 -61.831649) (xy 195.733709 -61.839373) (xy 195.726304 -61.846206)
			(xy 195.322698 -62.249812) (xy 195.315332 -62.256924) (xy 195.307712 -62.27572) (xy 195.307712 -63.273432)
			(xy 197.676768 -63.273432) (xy 197.680839 -63.21781) (xy 197.692965 -63.163373) (xy 197.712888 -63.111282)
			(xy 197.740184 -63.062647) (xy 197.77427 -63.018504) (xy 197.814419 -62.979795) (xy 197.859777 -62.947344)
			(xy 197.909377 -62.921843) (xy 197.962161 -62.903836) (xy 198.017004 -62.893706) (xy 198.072738 -62.891669)
			(xy 198.128175 -62.897769) (xy 198.182132 -62.911875) (xy 198.233461 -62.933687) (xy 198.281067 -62.962741)
			(xy 198.323935 -62.998416) (xy 198.361152 -63.039953) (xy 198.391925 -63.086466) (xy 198.415597 -63.136963)
			(xy 198.431665 -63.19037) (xy 198.439785 -63.245546) (xy 198.439785 -63.245548) (xy 211.204592 -63.245548)
			(xy 211.204592 -63.191052) (xy 211.212347 -63.13711) (xy 211.2277 -63.084821) (xy 211.250337 -63.035248)
			(xy 211.279798 -62.989402) (xy 211.315483 -62.948214) (xy 211.356666 -62.912524) (xy 211.40251 -62.883058)
			(xy 211.452079 -62.860415) (xy 211.504367 -62.845057) (xy 211.558308 -62.837295) (xy 211.585556 -62.836806)
			(xy 211.612925 -62.837296) (xy 211.667103 -62.845108) (xy 211.719606 -62.860591) (xy 211.769354 -62.883428)
			(xy 211.815322 -62.913147) (xy 211.836254 -62.930786) (xy 211.843366 -62.936882) (xy 211.860384 -62.943232)
			(xy 211.945728 -62.943232) (xy 211.962746 -62.936882) (xy 211.969858 -62.930786) (xy 211.990791 -62.913145)
			(xy 212.036759 -62.883421) (xy 212.086505 -62.860575) (xy 212.139007 -62.845079) (xy 212.193185 -62.83725)
			(xy 212.247927 -62.83725) (xy 212.302105 -62.845079) (xy 212.354607 -62.860575) (xy 212.404353 -62.883421)
			(xy 212.450321 -62.913145) (xy 212.471254 -62.930786) (xy 212.478366 -62.936882) (xy 212.495384 -62.943232)
			(xy 212.580728 -62.943232) (xy 212.597746 -62.936882) (xy 212.604858 -62.930786) (xy 212.625793 -62.913151)
			(xy 212.671765 -62.883439) (xy 212.721512 -62.860602) (xy 212.774012 -62.84511) (xy 212.828187 -62.837281)
			(xy 212.855556 -62.836806) (xy 212.882812 -62.837238) (xy 212.93677 -62.84499) (xy 212.989075 -62.860343)
			(xy 213.038662 -62.882984) (xy 213.084523 -62.912452) (xy 213.125722 -62.948147) (xy 213.161422 -62.989342)
			(xy 213.190895 -63.035199) (xy 213.213542 -63.084784) (xy 213.228901 -63.137087) (xy 213.236659 -63.191044)
			(xy 213.236659 -63.245556) (xy 213.228901 -63.299513) (xy 213.213542 -63.351816) (xy 213.190895 -63.401401)
			(xy 213.161422 -63.447258) (xy 213.125722 -63.488453) (xy 213.084523 -63.524148) (xy 213.038662 -63.553616)
			(xy 212.989075 -63.576257) (xy 212.93677 -63.59161) (xy 212.882812 -63.599362) (xy 212.855556 -63.599822)
			(xy 212.828186 -63.599342) (xy 212.774007 -63.591531) (xy 212.721503 -63.576046) (xy 212.671756 -63.553207)
			(xy 212.625789 -63.523483) (xy 212.604858 -63.505842) (xy 212.597746 -63.499746) (xy 212.580728 -63.493396)
			(xy 212.495384 -63.493396) (xy 212.478366 -63.499746) (xy 212.471254 -63.505842) (xy 212.450321 -63.523483)
			(xy 212.404353 -63.553207) (xy 212.354607 -63.576053) (xy 212.302105 -63.591549) (xy 212.247927 -63.599378)
			(xy 212.193185 -63.599378) (xy 212.139007 -63.591549) (xy 212.086505 -63.576053) (xy 212.036759 -63.553207)
			(xy 211.990791 -63.523483) (xy 211.969858 -63.505842) (xy 211.962746 -63.499746) (xy 211.945728 -63.493396)
			(xy 211.860384 -63.493396) (xy 211.843366 -63.499746) (xy 211.836254 -63.505842) (xy 211.815318 -63.523476)
			(xy 211.769346 -63.553187) (xy 211.719599 -63.576024) (xy 211.6671 -63.591516) (xy 211.612925 -63.599347)
			(xy 211.585556 -63.599822) (xy 211.558308 -63.599305) (xy 211.504367 -63.591543) (xy 211.452079 -63.576185)
			(xy 211.40251 -63.553542) (xy 211.356666 -63.524076) (xy 211.315483 -63.488386) (xy 211.279798 -63.447198)
			(xy 211.250337 -63.401352) (xy 211.2277 -63.351779) (xy 211.212347 -63.29949) (xy 211.204592 -63.245548)
			(xy 198.439785 -63.245548) (xy 198.440294 -63.273432) (xy 198.439785 -63.301318) (xy 198.431665 -63.356494)
			(xy 198.415597 -63.409901) (xy 198.391925 -63.460398) (xy 198.361152 -63.506911) (xy 198.323935 -63.548448)
			(xy 198.281067 -63.584123) (xy 198.233461 -63.613177) (xy 198.182132 -63.634989) (xy 198.128175 -63.649095)
			(xy 198.072738 -63.655195) (xy 198.017004 -63.653158) (xy 197.962161 -63.643028) (xy 197.909377 -63.625021)
			(xy 197.859777 -63.59952) (xy 197.814419 -63.567069) (xy 197.77427 -63.52836) (xy 197.740184 -63.484217)
			(xy 197.712888 -63.435582) (xy 197.692965 -63.383491) (xy 197.680839 -63.329054) (xy 197.676768 -63.273432)
			(xy 195.307712 -63.273432) (xy 195.307712 -64.102234) (xy 195.487542 -64.102234) (xy 195.491613 -64.046612)
			(xy 195.503739 -63.992175) (xy 195.523662 -63.940084) (xy 195.550958 -63.891449) (xy 195.585044 -63.847306)
			(xy 195.625193 -63.808597) (xy 195.670551 -63.776146) (xy 195.720151 -63.750645) (xy 195.772935 -63.732638)
			(xy 195.827778 -63.722508) (xy 195.883512 -63.720471) (xy 195.938949 -63.726571) (xy 195.992906 -63.740677)
			(xy 196.044235 -63.762489) (xy 196.091841 -63.791543) (xy 196.134709 -63.827218) (xy 196.171926 -63.868755)
			(xy 196.202699 -63.915268) (xy 196.226371 -63.965765) (xy 196.242439 -64.019172) (xy 196.250559 -64.074348)
			(xy 196.251068 -64.102234) (xy 196.250559 -64.13012) (xy 196.242439 -64.185296) (xy 196.226371 -64.238703)
			(xy 196.202699 -64.2892) (xy 196.187421 -64.312292) (xy 199.16597 -64.312292) (xy 199.170041 -64.25667)
			(xy 199.182167 -64.202233) (xy 199.20209 -64.150142) (xy 199.229386 -64.101507) (xy 199.263472 -64.057364)
			(xy 199.303621 -64.018655) (xy 199.348979 -63.986204) (xy 199.398579 -63.960703) (xy 199.451363 -63.942696)
			(xy 199.506206 -63.932566) (xy 199.56194 -63.930529) (xy 199.617377 -63.936629) (xy 199.671334 -63.950735)
			(xy 199.722663 -63.972547) (xy 199.770269 -64.001601) (xy 199.813137 -64.037276) (xy 199.850354 -64.078813)
			(xy 199.881127 -64.125326) (xy 199.904799 -64.175823) (xy 199.920867 -64.22923) (xy 199.928987 -64.284406)
			(xy 199.929496 -64.312292) (xy 199.928987 -64.340178) (xy 199.920867 -64.395354) (xy 199.904799 -64.448761)
			(xy 199.881127 -64.499258) (xy 199.850354 -64.545771) (xy 199.813137 -64.587308) (xy 199.770269 -64.622983)
			(xy 199.722663 -64.652037) (xy 199.671334 -64.673849) (xy 199.617377 -64.687955) (xy 199.56194 -64.694055)
			(xy 199.506206 -64.692018) (xy 199.451363 -64.681888) (xy 199.398579 -64.663881) (xy 199.348979 -64.63838)
			(xy 199.303621 -64.605929) (xy 199.263472 -64.56722) (xy 199.229386 -64.523077) (xy 199.20209 -64.474442)
			(xy 199.182167 -64.422351) (xy 199.170041 -64.367914) (xy 199.16597 -64.312292) (xy 196.187421 -64.312292)
			(xy 196.171926 -64.335713) (xy 196.134709 -64.37725) (xy 196.091841 -64.412925) (xy 196.044235 -64.441979)
			(xy 195.992906 -64.463791) (xy 195.938949 -64.477897) (xy 195.883512 -64.483997) (xy 195.827778 -64.48196)
			(xy 195.772935 -64.47183) (xy 195.720151 -64.453823) (xy 195.670551 -64.428322) (xy 195.625193 -64.395871)
			(xy 195.585044 -64.357162) (xy 195.550958 -64.313019) (xy 195.523662 -64.264384) (xy 195.503739 -64.212293)
			(xy 195.491613 -64.157856) (xy 195.487542 -64.102234) (xy 195.307712 -64.102234) (xy 195.307712 -65.124076)
			(xy 200.20737 -65.124076) (xy 200.211441 -65.068454) (xy 200.223567 -65.014017) (xy 200.24349 -64.961926)
			(xy 200.270786 -64.913291) (xy 200.304872 -64.869148) (xy 200.345021 -64.830439) (xy 200.390379 -64.797988)
			(xy 200.439979 -64.772487) (xy 200.492763 -64.75448) (xy 200.547606 -64.74435) (xy 200.60334 -64.742313)
			(xy 200.658777 -64.748413) (xy 200.712734 -64.762519) (xy 200.764063 -64.784331) (xy 200.811669 -64.813385)
			(xy 200.854537 -64.84906) (xy 200.891754 -64.890597) (xy 200.922527 -64.93711) (xy 200.946199 -64.987607)
			(xy 200.962267 -65.041014) (xy 200.970387 -65.09619) (xy 200.970896 -65.124076) (xy 200.970387 -65.151962)
			(xy 200.96922 -65.15989) (xy 213.216488 -65.15989) (xy 213.220559 -65.104268) (xy 213.232685 -65.049831)
			(xy 213.252608 -64.99774) (xy 213.279904 -64.949105) (xy 213.31399 -64.904962) (xy 213.354139 -64.866253)
			(xy 213.399497 -64.833802) (xy 213.449097 -64.808301) (xy 213.501881 -64.790294) (xy 213.556724 -64.780164)
			(xy 213.612458 -64.778127) (xy 213.667895 -64.784227) (xy 213.721852 -64.798333) (xy 213.773181 -64.820145)
			(xy 213.820787 -64.849199) (xy 213.863655 -64.884874) (xy 213.900872 -64.926411) (xy 213.931645 -64.972924)
			(xy 213.955317 -65.023421) (xy 213.971385 -65.076828) (xy 213.979505 -65.132004) (xy 213.980014 -65.15989)
			(xy 213.979505 -65.187776) (xy 213.971385 -65.242952) (xy 213.955317 -65.296359) (xy 213.931645 -65.346856)
			(xy 213.900872 -65.393369) (xy 213.863655 -65.434906) (xy 213.820787 -65.470581) (xy 213.773181 -65.499635)
			(xy 213.721852 -65.521447) (xy 213.667895 -65.535553) (xy 213.612458 -65.541653) (xy 213.556724 -65.539616)
			(xy 213.501881 -65.529486) (xy 213.449097 -65.511479) (xy 213.399497 -65.485978) (xy 213.354139 -65.453527)
			(xy 213.31399 -65.414818) (xy 213.279904 -65.370675) (xy 213.252608 -65.32204) (xy 213.232685 -65.269949)
			(xy 213.220559 -65.215512) (xy 213.216488 -65.15989) (xy 200.96922 -65.15989) (xy 200.962267 -65.207138)
			(xy 200.946199 -65.260545) (xy 200.922527 -65.311042) (xy 200.891754 -65.357555) (xy 200.854537 -65.399092)
			(xy 200.811669 -65.434767) (xy 200.764063 -65.463821) (xy 200.712734 -65.485633) (xy 200.658777 -65.499739)
			(xy 200.60334 -65.505839) (xy 200.547606 -65.503802) (xy 200.492763 -65.493672) (xy 200.439979 -65.475665)
			(xy 200.390379 -65.450164) (xy 200.345021 -65.417713) (xy 200.304872 -65.379004) (xy 200.270786 -65.334861)
			(xy 200.24349 -65.286226) (xy 200.223567 -65.234135) (xy 200.211441 -65.179698) (xy 200.20737 -65.124076)
			(xy 195.307712 -65.124076) (xy 195.307712 -65.75552) (xy 208.446622 -65.75552) (xy 208.450693 -65.699898)
			(xy 208.462819 -65.645461) (xy 208.482742 -65.59337) (xy 208.510038 -65.544735) (xy 208.544124 -65.500592)
			(xy 208.584273 -65.461883) (xy 208.629631 -65.429432) (xy 208.679231 -65.403931) (xy 208.732015 -65.385924)
			(xy 208.786858 -65.375794) (xy 208.842592 -65.373757) (xy 208.898029 -65.379857) (xy 208.951986 -65.393963)
			(xy 209.003315 -65.415775) (xy 209.050921 -65.444829) (xy 209.093789 -65.480504) (xy 209.131006 -65.522041)
			(xy 209.161779 -65.568554) (xy 209.185451 -65.619051) (xy 209.201519 -65.672458) (xy 209.209639 -65.727634)
			(xy 209.210148 -65.75552) (xy 209.209639 -65.783406) (xy 209.201519 -65.838582) (xy 209.185451 -65.891989)
			(xy 209.161779 -65.942486) (xy 209.131006 -65.988999) (xy 209.093789 -66.030536) (xy 209.050921 -66.066211)
			(xy 209.003315 -66.095265) (xy 208.951986 -66.117077) (xy 208.898029 -66.131183) (xy 208.842592 -66.137283)
			(xy 208.786858 -66.135246) (xy 208.732015 -66.125116) (xy 208.679231 -66.107109) (xy 208.629631 -66.081608)
			(xy 208.584273 -66.049157) (xy 208.544124 -66.010448) (xy 208.510038 -65.966305) (xy 208.482742 -65.91767)
			(xy 208.462819 -65.865579) (xy 208.450693 -65.811142) (xy 208.446622 -65.75552) (xy 195.307712 -65.75552)
			(xy 195.307712 -67.488054) (xy 212.879176 -67.488054) (xy 212.883247 -67.432432) (xy 212.895373 -67.377995)
			(xy 212.915296 -67.325904) (xy 212.942592 -67.277269) (xy 212.976678 -67.233126) (xy 213.016827 -67.194417)
			(xy 213.062185 -67.161966) (xy 213.111785 -67.136465) (xy 213.164569 -67.118458) (xy 213.219412 -67.108328)
			(xy 213.275146 -67.106291) (xy 213.330583 -67.112391) (xy 213.38454 -67.126497) (xy 213.435869 -67.148309)
			(xy 213.483475 -67.177363) (xy 213.526343 -67.213038) (xy 213.56356 -67.254575) (xy 213.594333 -67.301088)
			(xy 213.618005 -67.351585) (xy 213.634073 -67.404992) (xy 213.642193 -67.460168) (xy 213.642702 -67.488054)
			(xy 213.642193 -67.51594) (xy 213.634073 -67.571116) (xy 213.618005 -67.624523) (xy 213.594333 -67.67502)
			(xy 213.56356 -67.721533) (xy 213.526343 -67.76307) (xy 213.483475 -67.798745) (xy 213.435869 -67.827799)
			(xy 213.38454 -67.849611) (xy 213.330583 -67.863717) (xy 213.275146 -67.869817) (xy 213.219412 -67.86778)
			(xy 213.164569 -67.85765) (xy 213.111785 -67.839643) (xy 213.062185 -67.814142) (xy 213.016827 -67.781691)
			(xy 212.976678 -67.742982) (xy 212.942592 -67.698839) (xy 212.915296 -67.650204) (xy 212.895373 -67.598113)
			(xy 212.883247 -67.543676) (xy 212.879176 -67.488054) (xy 195.307712 -67.488054) (xy 195.307712 -69.9516)
			(xy 195.308169 -69.961478) (xy 195.315609 -69.97978) (xy 195.32219 -69.98716) (xy 195.322444 -69.987414)
			(xy 195.49872 -70.16369) (xy 195.499228 -70.164198) (xy 195.506605 -70.17079) (xy 195.524905 -70.178258)
			(xy 195.534788 -70.178676)
		)
		(stroke
			(width 0)
			(type solid)
		)
		(fill yes)
		(layer "In9.Cu")
		(net "P12V_SSD7_R")
	)
	(gr_poly
		(pts
			(xy 188.578236 -70.178676) (xy 188.588303 -70.178246) (xy 188.606896 -70.170519) (xy 188.614304 -70.16369)
			(xy 188.94044 -69.837554) (xy 188.940948 -69.837046) (xy 188.947531 -69.829665) (xy 188.954982 -69.811366)
			(xy 188.955426 -69.801486) (xy 188.955426 -67.91579) (xy 188.955028 -67.906269) (xy 188.948069 -67.888544)
			(xy 188.935117 -67.874586) (xy 188.926724 -67.87007) (xy 188.830966 -67.823842) (xy 188.802264 -67.827144)
			(xy 188.79058 -67.836288) (xy 188.770269 -67.851904) (xy 188.726256 -67.878128) (xy 188.679127 -67.898223)
			(xy 188.629732 -67.911825) (xy 188.578961 -67.918692) (xy 188.553344 -67.919092) (xy 188.52609 -67.918632)
			(xy 188.472137 -67.91088) (xy 188.419836 -67.895529) (xy 188.370252 -67.87289) (xy 188.324396 -67.843424)
			(xy 188.283199 -67.807732) (xy 188.247502 -67.76654) (xy 188.218032 -67.720686) (xy 188.195387 -67.671105)
			(xy 188.180029 -67.618806) (xy 188.172271 -67.564854) (xy 188.172271 -67.510346) (xy 188.180029 -67.456394)
			(xy 188.195387 -67.404095) (xy 188.218032 -67.354514) (xy 188.247502 -67.30866) (xy 188.283199 -67.267468)
			(xy 188.324396 -67.231776) (xy 188.370252 -67.20231) (xy 188.419836 -67.179671) (xy 188.472137 -67.16432)
			(xy 188.52609 -67.156568) (xy 188.553344 -67.156076) (xy 188.578959 -67.156494) (xy 188.629728 -67.163361)
			(xy 188.679119 -67.176965) (xy 188.726243 -67.197062) (xy 188.770252 -67.223288) (xy 188.79058 -67.23888)
			(xy 188.802264 -67.248024) (xy 188.830966 -67.251326) (xy 188.926724 -67.205098) (xy 188.93513 -67.200601)
			(xy 188.948083 -67.186632) (xy 188.955054 -67.168903) (xy 188.955426 -67.159378) (xy 188.955426 -65.506854)
			(xy 188.94171 -65.483486) (xy 188.93028 -65.476628) (xy 188.929772 -65.476628) (xy 188.85662 -65.433702)
			(xy 188.852229 -65.431316) (xy 188.842763 -65.428115) (xy 188.837824 -65.427352) (xy 188.82741 -65.426082)
			(xy 188.803788 -65.432432) (xy 188.7982 -65.43548) (xy 188.769914 -65.450254) (xy 188.709638 -65.471196)
			(xy 188.646717 -65.481815) (xy 188.614812 -65.48247) (xy 188.614558 -65.48247) (xy 188.587311 -65.481981)
			(xy 188.533374 -65.47422) (xy 188.481089 -65.458863) (xy 188.431522 -65.436222) (xy 188.385682 -65.406757)
			(xy 188.344501 -65.37107) (xy 188.308817 -65.329885) (xy 188.279358 -65.284041) (xy 188.256722 -65.234471)
			(xy 188.241371 -65.182185) (xy 188.233616 -65.128247) (xy 188.233616 -65.073753) (xy 188.241371 -65.019815)
			(xy 188.256722 -64.967529) (xy 188.279358 -64.917959) (xy 188.308817 -64.872115) (xy 188.344501 -64.83093)
			(xy 188.385682 -64.795243) (xy 188.431522 -64.765778) (xy 188.481089 -64.743137) (xy 188.533374 -64.72778)
			(xy 188.587311 -64.720019) (xy 188.614558 -64.719454) (xy 188.614812 -64.719454) (xy 188.646716 -64.720118)
			(xy 188.709631 -64.730754) (xy 188.769911 -64.751679) (xy 188.7982 -64.766444) (xy 188.803788 -64.769492)
			(xy 188.817504 -64.773302) (xy 188.822489 -64.774512) (xy 188.832727 -64.775152) (xy 188.837824 -64.774572)
			(xy 188.84773 -64.773302) (xy 188.930026 -64.725296) (xy 188.930788 -64.724788) (xy 188.938072 -64.719978)
			(xy 188.949131 -64.706486) (xy 188.955043 -64.690074) (xy 188.955426 -64.681354) (xy 188.955426 -52.63261)
			(xy 188.954918 -52.626006) (xy 188.953648 -52.615592) (xy 188.952886 -52.612798) (xy 188.947174 -52.589272)
			(xy 188.941063 -52.541247) (xy 188.940694 -52.51704) (xy 188.940694 -52.49926) (xy 188.940948 -52.49418)
			(xy 188.942726 -52.477162) (xy 188.943901 -52.466351) (xy 188.947333 -52.444875) (xy 188.949584 -52.434236)
			(xy 188.951362 -52.427378) (xy 188.951616 -52.42687) (xy 188.952632 -52.422552) (xy 188.952632 -52.421536)
			(xy 188.953648 -52.418234) (xy 188.955426 -52.41163) (xy 188.955426 -51.455828) (xy 188.955863 -51.445764)
			(xy 188.963599 -51.427181) (xy 188.970412 -51.41976) (xy 189.077346 -51.312826) (xy 189.084746 -51.305984)
			(xy 189.103344 -51.298262) (xy 189.113414 -51.29784) (xy 189.803786 -51.29784) (xy 189.812168 -51.297078)
			(xy 189.819775 -51.295567) (xy 189.833613 -51.288584) (xy 189.839346 -51.283362) (xy 189.919356 -51.203352)
			(xy 189.919356 -49.20615) (xy 189.918758 -49.193828) (xy 189.907297 -49.172011) (xy 189.897512 -49.164494)
			(xy 189.833758 -49.120044) (xy 189.827257 -49.115867) (xy 189.812524 -49.111225) (xy 189.804802 -49.1109)
			(xy 189.782704 -49.1109) (xy 189.77483 -49.113694) (xy 189.744646 -49.123452) (xy 189.682086 -49.133929)
			(xy 189.65037 -49.134522) (xy 189.646306 -49.134522) (xy 189.619248 -49.133758) (xy 189.565747 -49.125531)
			(xy 189.513947 -49.109824) (xy 189.464888 -49.086951) (xy 189.419555 -49.057372) (xy 189.378858 -49.021682)
			(xy 189.343616 -48.980597) (xy 189.314536 -48.934943) (xy 189.292202 -48.885635) (xy 189.277063 -48.833666)
			(xy 189.269423 -48.780079) (xy 189.268862 -48.753014) (xy 189.269347 -48.725761) (xy 189.277102 -48.67181)
			(xy 189.292455 -48.619512) (xy 189.315095 -48.569931) (xy 189.344561 -48.524077) (xy 189.380252 -48.482883)
			(xy 189.421442 -48.447187) (xy 189.467293 -48.417716) (xy 189.516871 -48.395071) (xy 189.569167 -48.379711)
			(xy 189.623117 -48.37195) (xy 189.65037 -48.371506) (xy 189.651132 -48.371506) (xy 189.684748 -48.37226)
			(xy 189.750924 -48.384142) (xy 189.782704 -48.395128) (xy 189.794388 -48.399446) (xy 189.819026 -48.396398)
			(xy 189.897512 -48.341534) (xy 189.907173 -48.333917) (xy 189.918567 -48.312157) (xy 189.919356 -48.299878)
			(xy 189.919356 -41.95445) (xy 189.918826 -41.944459) (xy 189.911121 -41.926019) (xy 189.90437 -41.918636)
			(xy 189.023752 -41.038018) (xy 189.01664 -41.030652) (xy 188.997844 -41.023032) (xy 187.216288 -41.023032)
			(xy 187.207586 -41.023384) (xy 187.191184 -41.029199) (xy 187.177665 -41.040158) (xy 187.172854 -41.047416)
			(xy 187.127896 -41.121584) (xy 187.123832 -41.13022) (xy 187.120506 -41.140526) (xy 187.121938 -41.162115)
			(xy 187.126626 -41.171876) (xy 187.127388 -41.1734) (xy 187.131706 -41.18229) (xy 187.143785 -41.20826)
			(xy 187.160899 -41.262918) (xy 187.16967 -41.319517) (xy 187.170314 -41.348152) (xy 187.170314 -41.34866)
			(xy 187.170314 -41.35501) (xy 187.169403 -41.383073) (xy 187.160357 -41.438486) (xy 187.143285 -41.491975)
			(xy 187.118557 -41.542383) (xy 187.086707 -41.588622) (xy 187.067952 -41.609518) (xy 187.067698 -41.609772)
			(xy 187.061226 -41.617127) (xy 187.053929 -41.63529) (xy 187.053474 -41.645078) (xy 187.053474 -41.724072)
			(xy 187.060332 -41.741852) (xy 187.06719 -41.748964) (xy 187.086459 -41.770291) (xy 187.119019 -41.817653)
			(xy 187.144107 -41.869364) (xy 187.161153 -41.924253) (xy 187.169773 -41.981078) (xy 187.16977 -42.038554)
			(xy 187.161146 -42.095378) (xy 187.144095 -42.150266) (xy 187.119003 -42.201974) (xy 187.086438 -42.249334)
			(xy 187.06719 -42.27068) (xy 187.060332 -42.277792) (xy 187.053474 -42.295572) (xy 187.053474 -42.384472)
			(xy 187.060332 -42.402252) (xy 187.06719 -42.409364) (xy 187.086459 -42.430692) (xy 187.11902 -42.478055)
			(xy 187.144108 -42.529767) (xy 187.161154 -42.584657) (xy 187.169773 -42.641484) (xy 187.170314 -42.670222)
			(xy 187.169841 -42.697592) (xy 187.162014 -42.751768) (xy 187.146525 -42.804271) (xy 187.123692 -42.85402)
			(xy 187.093982 -42.899996) (xy 187.076334 -42.92092) (xy 187.070238 -42.928032) (xy 187.063888 -42.944796)
			(xy 187.063888 -43.030648) (xy 187.070238 -43.047412) (xy 187.076334 -43.054524) (xy 187.093973 -43.075456)
			(xy 187.123694 -43.121424) (xy 187.146532 -43.171171) (xy 187.162017 -43.223674) (xy 187.169832 -43.277852)
			(xy 187.170314 -43.305222) (xy 187.169828 -43.332473) (xy 187.162072 -43.386421) (xy 187.146717 -43.438716)
			(xy 187.124075 -43.488293) (xy 187.094609 -43.534143) (xy 187.058918 -43.575334) (xy 187.017727 -43.611025)
			(xy 186.971877 -43.640491) (xy 186.9223 -43.663133) (xy 186.870005 -43.678488) (xy 186.816057 -43.686244)
			(xy 186.761555 -43.686244) (xy 186.707607 -43.678488) (xy 186.655312 -43.663133) (xy 186.605735 -43.640491)
			(xy 186.559885 -43.611025) (xy 186.518694 -43.575334) (xy 186.483003 -43.534143) (xy 186.453537 -43.488293)
			(xy 186.430895 -43.438716) (xy 186.41554 -43.386421) (xy 186.407784 -43.332473) (xy 186.407298 -43.305222)
			(xy 186.407775 -43.277854) (xy 186.415609 -43.223681) (xy 186.431105 -43.171184) (xy 186.453944 -43.12144)
			(xy 186.483658 -43.075471) (xy 186.501278 -43.054524) (xy 186.507374 -43.047412) (xy 186.513724 -43.030648)
			(xy 186.513724 -42.944796) (xy 186.507374 -42.928032) (xy 186.501278 -42.92092) (xy 186.483636 -42.899989)
			(xy 186.453909 -42.854022) (xy 186.431065 -42.804276) (xy 186.415573 -42.751772) (xy 186.407752 -42.697593)
			(xy 186.407298 -42.670222) (xy 186.407817 -42.641482) (xy 186.416437 -42.584653) (xy 186.433485 -42.52976)
			(xy 186.458574 -42.478045) (xy 186.491138 -42.43068) (xy 186.510422 -42.409364) (xy 186.51728 -42.402252)
			(xy 186.524138 -42.384472) (xy 186.524138 -42.295572) (xy 186.51728 -42.277792) (xy 186.510422 -42.27068)
			(xy 186.49115 -42.249353) (xy 186.458581 -42.20199) (xy 186.433487 -42.150277) (xy 186.416434 -42.095385)
			(xy 186.407808 -42.038556) (xy 186.407806 -41.981076) (xy 186.416427 -41.924246) (xy 186.433475 -41.869353)
			(xy 186.458565 -41.817638) (xy 186.491129 -41.770272) (xy 186.510422 -41.748964) (xy 186.51728 -41.741852)
			(xy 186.524138 -41.724072) (xy 186.524138 -41.635172) (xy 186.51728 -41.617646) (xy 186.510422 -41.61028)
			(xy 186.491623 -41.589486) (xy 186.459694 -41.543412) (xy 186.43484 -41.493168) (xy 186.417594 -41.439831)
			(xy 186.408326 -41.384547) (xy 186.407298 -41.356534) (xy 186.407298 -41.354248) (xy 186.407298 -41.349422)
			(xy 186.407822 -41.32057) (xy 186.416514 -41.263525) (xy 186.433718 -41.208446) (xy 186.445906 -41.18229)
			(xy 186.453018 -41.167558) (xy 186.45633 -41.158544) (xy 186.456726 -41.139359) (xy 186.45378 -41.13022)
			(xy 186.449716 -41.121584) (xy 186.404758 -41.04767) (xy 186.3979 -41.035986) (xy 186.374786 -41.023032)
			(xy 185.45429 -41.023032) (xy 185.442672 -41.023612) (xy 185.421792 -41.03381) (xy 185.414158 -41.04259)
			(xy 185.357516 -41.11498) (xy 185.35269 -41.137586) (xy 185.355484 -41.14927) (xy 185.360806 -41.171949)
			(xy 185.366536 -41.21818) (xy 185.366914 -41.241472) (xy 185.366453 -41.268726) (xy 185.358699 -41.322681)
			(xy 185.343345 -41.374982) (xy 185.320705 -41.424566) (xy 185.291237 -41.470423) (xy 185.255544 -41.51162)
			(xy 185.21435 -41.547317) (xy 185.168496 -41.576788) (xy 185.118914 -41.599433) (xy 185.066614 -41.614792)
			(xy 185.01266 -41.62255) (xy 184.985406 -41.62298) (xy 184.956667 -41.622459) (xy 184.899839 -41.613837)
			(xy 184.844948 -41.596787) (xy 184.793236 -41.571695) (xy 184.745873 -41.539129) (xy 184.724548 -41.519856)
			(xy 184.717436 -41.512998) (xy 184.699656 -41.50614) (xy 184.610756 -41.50614) (xy 184.592976 -41.512998)
			(xy 184.585864 -41.519856) (xy 184.564536 -41.539124) (xy 184.517171 -41.571683) (xy 184.465459 -41.59677)
			(xy 184.41057 -41.613817) (xy 184.353744 -41.622439) (xy 184.325006 -41.62298) (xy 184.297754 -41.622517)
			(xy 184.243804 -41.614761) (xy 184.191507 -41.599405) (xy 184.141927 -41.576762) (xy 184.096076 -41.547294)
			(xy 184.054884 -41.5116) (xy 184.019193 -41.470407) (xy 183.989727 -41.424553) (xy 183.967087 -41.374973)
			(xy 183.951735 -41.322675) (xy 183.943981 -41.268724) (xy 183.943498 -41.241472) (xy 183.943877 -41.21818)
			(xy 183.949608 -41.171949) (xy 183.954928 -41.14927) (xy 183.957722 -41.137586) (xy 183.952896 -41.11498)
			(xy 183.896254 -41.04259) (xy 183.888666 -41.033756) (xy 183.867755 -41.023561) (xy 183.856122 -41.023032)
			(xy 180.00853 -41.023032) (xy 179.998466 -41.023469) (xy 179.979883 -41.031204) (xy 179.972462 -41.038018)
			(xy 179.805838 -41.204642) (xy 179.799098 -41.212013) (xy 179.791515 -41.230475) (xy 179.791106 -41.240456)
			(xy 179.791106 -43.73626) (xy 188.313058 -43.73626) (xy 188.317129 -43.680638) (xy 188.329255 -43.626201)
			(xy 188.349178 -43.57411) (xy 188.376474 -43.525475) (xy 188.41056 -43.481332) (xy 188.450709 -43.442623)
			(xy 188.496067 -43.410172) (xy 188.545667 -43.384671) (xy 188.598451 -43.366664) (xy 188.653294 -43.356534)
			(xy 188.709028 -43.354497) (xy 188.764465 -43.360597) (xy 188.818422 -43.374703) (xy 188.869751 -43.396515)
			(xy 188.917357 -43.425569) (xy 188.960225 -43.461244) (xy 188.997442 -43.502781) (xy 189.028215 -43.549294)
			(xy 189.051887 -43.599791) (xy 189.067955 -43.653198) (xy 189.076075 -43.708374) (xy 189.076584 -43.73626)
			(xy 189.076075 -43.764146) (xy 189.067955 -43.819322) (xy 189.051887 -43.872729) (xy 189.028215 -43.923226)
			(xy 188.997442 -43.969739) (xy 188.960225 -44.011276) (xy 188.917357 -44.046951) (xy 188.869751 -44.076005)
			(xy 188.818422 -44.097817) (xy 188.764465 -44.111923) (xy 188.709028 -44.118023) (xy 188.653294 -44.115986)
			(xy 188.598451 -44.105856) (xy 188.545667 -44.087849) (xy 188.496067 -44.062348) (xy 188.450709 -44.029897)
			(xy 188.41056 -43.991188) (xy 188.376474 -43.947045) (xy 188.349178 -43.89841) (xy 188.329255 -43.846319)
			(xy 188.317129 -43.791882) (xy 188.313058 -43.73626) (xy 179.791106 -43.73626) (xy 179.791106 -45.114464)
			(xy 188.165484 -45.114464) (xy 188.169555 -45.058842) (xy 188.181681 -45.004405) (xy 188.201604 -44.952314)
			(xy 188.2289 -44.903679) (xy 188.262986 -44.859536) (xy 188.303135 -44.820827) (xy 188.348493 -44.788376)
			(xy 188.398093 -44.762875) (xy 188.450877 -44.744868) (xy 188.50572 -44.734738) (xy 188.561454 -44.732701)
			(xy 188.616891 -44.738801) (xy 188.670848 -44.752907) (xy 188.722177 -44.774719) (xy 188.769783 -44.803773)
			(xy 188.812651 -44.839448) (xy 188.849868 -44.880985) (xy 188.880641 -44.927498) (xy 188.904313 -44.977995)
			(xy 188.920381 -45.031402) (xy 188.928501 -45.086578) (xy 188.92901 -45.114464) (xy 188.928501 -45.14235)
			(xy 188.920381 -45.197526) (xy 188.904313 -45.250933) (xy 188.880641 -45.30143) (xy 188.849868 -45.347943)
			(xy 188.812651 -45.38948) (xy 188.769783 -45.425155) (xy 188.722177 -45.454209) (xy 188.670848 -45.476021)
			(xy 188.616891 -45.490127) (xy 188.561454 -45.496227) (xy 188.50572 -45.49419) (xy 188.450877 -45.48406)
			(xy 188.398093 -45.466053) (xy 188.348493 -45.440552) (xy 188.303135 -45.408101) (xy 188.262986 -45.369392)
			(xy 188.2289 -45.325249) (xy 188.201604 -45.276614) (xy 188.181681 -45.224523) (xy 188.169555 -45.170086)
			(xy 188.165484 -45.114464) (xy 179.791106 -45.114464) (xy 179.791106 -46.893226) (xy 188.437264 -46.893226)
			(xy 188.441335 -46.837604) (xy 188.453461 -46.783167) (xy 188.473384 -46.731076) (xy 188.50068 -46.682441)
			(xy 188.534766 -46.638298) (xy 188.574915 -46.599589) (xy 188.620273 -46.567138) (xy 188.669873 -46.541637)
			(xy 188.722657 -46.52363) (xy 188.7775 -46.5135) (xy 188.833234 -46.511463) (xy 188.888671 -46.517563)
			(xy 188.942628 -46.531669) (xy 188.993957 -46.553481) (xy 189.041563 -46.582535) (xy 189.084431 -46.61821)
			(xy 189.121648 -46.659747) (xy 189.152421 -46.70626) (xy 189.176093 -46.756757) (xy 189.192161 -46.810164)
			(xy 189.200281 -46.86534) (xy 189.20079 -46.893226) (xy 189.200281 -46.921112) (xy 189.192161 -46.976288)
			(xy 189.176093 -47.029695) (xy 189.152421 -47.080192) (xy 189.121648 -47.126705) (xy 189.084431 -47.168242)
			(xy 189.041563 -47.203917) (xy 188.993957 -47.232971) (xy 188.942628 -47.254783) (xy 188.888671 -47.268889)
			(xy 188.833234 -47.274989) (xy 188.7775 -47.272952) (xy 188.722657 -47.262822) (xy 188.669873 -47.244815)
			(xy 188.620273 -47.219314) (xy 188.574915 -47.186863) (xy 188.534766 -47.148154) (xy 188.50068 -47.104011)
			(xy 188.473384 -47.055376) (xy 188.453461 -47.003285) (xy 188.441335 -46.948848) (xy 188.437264 -46.893226)
			(xy 179.791106 -46.893226) (xy 179.791106 -47.936658) (xy 186.752992 -47.936658) (xy 186.753478 -47.909407)
			(xy 186.761234 -47.855459) (xy 186.776589 -47.803164) (xy 186.799231 -47.753587) (xy 186.828697 -47.707737)
			(xy 186.864388 -47.666546) (xy 186.905579 -47.630855) (xy 186.951429 -47.601389) (xy 187.001006 -47.578747)
			(xy 187.053301 -47.563392) (xy 187.107249 -47.555636) (xy 187.161751 -47.555636) (xy 187.215699 -47.563392)
			(xy 187.267994 -47.578747) (xy 187.317571 -47.601389) (xy 187.363421 -47.630855) (xy 187.404612 -47.666546)
			(xy 187.440303 -47.707737) (xy 187.469769 -47.753587) (xy 187.492411 -47.803164) (xy 187.507766 -47.855459)
			(xy 187.515522 -47.909407) (xy 187.516008 -47.936658) (xy 187.515565 -47.963) (xy 187.508314 -48.015182)
			(xy 187.493957 -48.065871) (xy 187.472768 -48.114105) (xy 187.445148 -48.158968) (xy 187.411622 -48.199608)
			(xy 187.372828 -48.235252) (xy 187.351416 -48.250602) (xy 187.339595 -48.259301) (xy 187.321164 -48.282126)
			(xy 187.309983 -48.309251) (xy 187.306976 -48.338435) (xy 187.312391 -48.367269) (xy 187.325781 -48.393373)
			(xy 187.346041 -48.414593) (xy 187.358528 -48.422306) (xy 187.383076 -48.436981) (xy 187.427832 -48.472588)
			(xy 187.466773 -48.514476) (xy 187.499027 -48.561706) (xy 187.52387 -48.61322) (xy 187.540748 -48.667866)
			(xy 187.549281 -48.724418) (xy 187.54979 -48.753014) (xy 187.549304 -48.780265) (xy 187.541548 -48.834213)
			(xy 187.526193 -48.886508) (xy 187.503551 -48.936085) (xy 187.474085 -48.981935) (xy 187.438394 -49.023126)
			(xy 187.397203 -49.058817) (xy 187.351353 -49.088283) (xy 187.301776 -49.110925) (xy 187.249481 -49.12628)
			(xy 187.195533 -49.134036) (xy 187.141031 -49.134036) (xy 187.087083 -49.12628) (xy 187.034788 -49.110925)
			(xy 186.985211 -49.088283) (xy 186.939361 -49.058817) (xy 186.89817 -49.023126) (xy 186.862479 -48.981935)
			(xy 186.833013 -48.936085) (xy 186.810371 -48.886508) (xy 186.795016 -48.834213) (xy 186.78726 -48.780265)
			(xy 186.786774 -48.753014) (xy 186.787204 -48.726672) (xy 186.794458 -48.67449) (xy 186.808818 -48.6238)
			(xy 186.83001 -48.575566) (xy 186.857631 -48.530704) (xy 186.891158 -48.490064) (xy 186.929954 -48.45442)
			(xy 186.951366 -48.43907) (xy 186.963217 -48.430408) (xy 186.981653 -48.407575) (xy 186.992835 -48.380442)
			(xy 186.995839 -48.351249) (xy 186.990417 -48.322408) (xy 186.977018 -48.296299) (xy 186.956747 -48.275078)
			(xy 186.944254 -48.267366) (xy 186.919734 -48.252647) (xy 186.874979 -48.217047) (xy 186.836037 -48.175166)
			(xy 186.803781 -48.127943) (xy 186.778933 -48.076436) (xy 186.762048 -48.021798) (xy 186.753506 -47.965252)
			(xy 186.752992 -47.936658) (xy 179.791106 -47.936658) (xy 179.791106 -58.731404) (xy 181.620668 -58.731404)
			(xy 181.62112 -58.704033) (xy 181.628939 -58.649853) (xy 181.64443 -58.597349) (xy 181.667275 -58.547602)
			(xy 181.697004 -58.501637) (xy 181.714648 -58.480706) (xy 181.720744 -58.473594) (xy 181.727094 -58.456576)
			(xy 181.727094 -58.371232) (xy 181.720744 -58.354214) (xy 181.714648 -58.347102) (xy 181.69701 -58.326167)
			(xy 181.667284 -58.2802) (xy 181.644437 -58.230454) (xy 181.628939 -58.177952) (xy 181.62111 -58.123774)
			(xy 181.62111 -58.069032) (xy 181.628938 -58.014854) (xy 181.644435 -57.962352) (xy 181.667281 -57.912606)
			(xy 181.697007 -57.866638) (xy 181.714648 -57.845706) (xy 181.720744 -57.838594) (xy 181.727094 -57.821576)
			(xy 181.727094 -57.736232) (xy 181.720744 -57.719214) (xy 181.714648 -57.712102) (xy 181.69701 -57.691167)
			(xy 181.667284 -57.6452) (xy 181.644437 -57.595454) (xy 181.628939 -57.542952) (xy 181.62111 -57.488774)
			(xy 181.62111 -57.434032) (xy 181.628938 -57.379854) (xy 181.644435 -57.327352) (xy 181.667281 -57.277606)
			(xy 181.697007 -57.231638) (xy 181.714648 -57.210706) (xy 181.720744 -57.203594) (xy 181.727094 -57.186576)
			(xy 181.727094 -57.101232) (xy 181.720744 -57.084214) (xy 181.714648 -57.077102) (xy 181.697004 -57.056174)
			(xy 181.667291 -57.010201) (xy 181.644455 -56.960452) (xy 181.628966 -56.90795) (xy 181.62114 -56.853774)
			(xy 181.620668 -56.826404) (xy 181.621154 -56.799153) (xy 181.62891 -56.745205) (xy 181.644265 -56.69291)
			(xy 181.666907 -56.643333) (xy 181.696373 -56.597483) (xy 181.732064 -56.556292) (xy 181.773255 -56.520601)
			(xy 181.819105 -56.491135) (xy 181.868682 -56.468493) (xy 181.920977 -56.453138) (xy 181.974925 -56.445382)
			(xy 182.029427 -56.445382) (xy 182.083375 -56.453138) (xy 182.13567 -56.468493) (xy 182.185247 -56.491135)
			(xy 182.231097 -56.520601) (xy 182.272288 -56.556292) (xy 182.307979 -56.597483) (xy 182.337445 -56.643333)
			(xy 182.360087 -56.69291) (xy 182.375442 -56.745205) (xy 182.383198 -56.799153) (xy 182.383684 -56.826404)
			(xy 182.383224 -56.853774) (xy 182.375405 -56.907954) (xy 182.359915 -56.960457) (xy 182.337072 -57.010204)
			(xy 182.307346 -57.056171) (xy 182.289704 -57.077102) (xy 182.283608 -57.084214) (xy 182.277258 -57.101232)
			(xy 182.277258 -57.186576) (xy 182.283608 -57.203594) (xy 182.289704 -57.210706) (xy 182.307347 -57.231636)
			(xy 182.33707 -57.277605) (xy 182.359913 -57.327352) (xy 182.375407 -57.379854) (xy 182.383235 -57.434033)
			(xy 182.383235 -57.488773) (xy 182.375406 -57.542952) (xy 182.359911 -57.595454) (xy 182.337067 -57.6452)
			(xy 182.307344 -57.691169) (xy 182.289704 -57.712102) (xy 182.283608 -57.719214) (xy 182.277258 -57.736232)
			(xy 182.277258 -57.821576) (xy 182.283608 -57.838594) (xy 182.289704 -57.845706) (xy 182.307347 -57.866636)
			(xy 182.33707 -57.912605) (xy 182.359913 -57.962352) (xy 182.375407 -58.014854) (xy 182.383235 -58.069033)
			(xy 182.383235 -58.123773) (xy 182.375406 -58.177952) (xy 182.359911 -58.230454) (xy 182.337067 -58.2802)
			(xy 182.307344 -58.326169) (xy 182.289704 -58.347102) (xy 182.283608 -58.354214) (xy 182.277258 -58.371232)
			(xy 182.277258 -58.456576) (xy 182.283608 -58.473594) (xy 182.289704 -58.480706) (xy 182.30736 -58.501624)
			(xy 182.337069 -58.547601) (xy 182.359902 -58.597352) (xy 182.375389 -58.649856) (xy 182.383212 -58.704034)
			(xy 182.383684 -58.731404) (xy 182.383198 -58.758655) (xy 182.378534 -58.791094) (xy 184.276492 -58.791094)
			(xy 184.276957 -58.763724) (xy 184.284775 -58.709545) (xy 184.300265 -58.657042) (xy 184.323107 -58.607295)
			(xy 184.352831 -58.561328) (xy 184.370472 -58.540396) (xy 184.376568 -58.533284) (xy 184.382918 -58.516266)
			(xy 184.382918 -58.430922) (xy 184.376568 -58.413904) (xy 184.370472 -58.406792) (xy 184.352824 -58.385865)
			(xy 184.323096 -58.339897) (xy 184.300248 -58.29015) (xy 184.28475 -58.237647) (xy 184.276921 -58.183467)
			(xy 184.276922 -58.128724) (xy 184.284752 -58.074544) (xy 184.300251 -58.022041) (xy 184.3231 -57.972295)
			(xy 184.352829 -57.926328) (xy 184.370472 -57.905396) (xy 184.376568 -57.898284) (xy 184.382918 -57.881266)
			(xy 184.382918 -57.795922) (xy 184.376568 -57.778904) (xy 184.370472 -57.771792) (xy 184.352811 -57.750877)
			(xy 184.323104 -57.704899) (xy 184.300272 -57.655147) (xy 184.284786 -57.602643) (xy 184.276963 -57.548464)
			(xy 184.276492 -57.521094) (xy 184.276964 -57.494779) (xy 184.284181 -57.442646) (xy 184.29849 -57.391998)
			(xy 184.319621 -57.343796) (xy 184.347173 -57.298953) (xy 184.380623 -57.258321) (xy 184.399682 -57.24017)
			(xy 184.407096 -57.232659) (xy 184.415614 -57.213371) (xy 184.416192 -57.202832) (xy 184.416192 -57.128156)
			(xy 184.415648 -57.117608) (xy 184.407123 -57.098312) (xy 184.399682 -57.090818) (xy 184.380627 -57.072658)
			(xy 184.347144 -57.032045) (xy 184.319568 -56.987211) (xy 184.298425 -56.939008) (xy 184.284116 -56.888354)
			(xy 184.276914 -56.836212) (xy 184.276492 -56.809894) (xy 184.276978 -56.782643) (xy 184.284734 -56.728695)
			(xy 184.300089 -56.6764) (xy 184.322731 -56.626823) (xy 184.352197 -56.580973) (xy 184.387888 -56.539782)
			(xy 184.429079 -56.504091) (xy 184.474929 -56.474625) (xy 184.524506 -56.451983) (xy 184.576801 -56.436628)
			(xy 184.630749 -56.428872) (xy 184.685251 -56.428872) (xy 184.739199 -56.436628) (xy 184.791494 -56.451983)
			(xy 184.841071 -56.474625) (xy 184.886921 -56.504091) (xy 184.928112 -56.539782) (xy 184.963803 -56.580973)
			(xy 184.993269 -56.626823) (xy 185.015911 -56.6764) (xy 185.031266 -56.728695) (xy 185.039022 -56.782643)
			(xy 185.039508 -56.809894) (xy 185.039095 -56.836211) (xy 185.031866 -56.888347) (xy 185.017545 -56.938996)
			(xy 184.996403 -56.987198) (xy 184.968841 -57.032039) (xy 184.935381 -57.072669) (xy 184.916318 -57.090818)
			(xy 184.908909 -57.098333) (xy 184.900388 -57.117618) (xy 184.899808 -57.128156) (xy 184.899808 -57.202832)
			(xy 184.900358 -57.213379) (xy 184.908878 -57.232675) (xy 184.916318 -57.24017) (xy 184.935367 -57.258336)
			(xy 184.968851 -57.298947) (xy 184.996428 -57.343781) (xy 185.017572 -57.391983) (xy 185.031882 -57.442636)
			(xy 185.035255 -57.467049) (xy 185.218592 -57.467049) (xy 185.218592 -57.412551) (xy 185.226348 -57.358607)
			(xy 185.241701 -57.306316) (xy 185.26434 -57.256742) (xy 185.293803 -57.210895) (xy 185.329491 -57.169706)
			(xy 185.370677 -57.134016) (xy 185.416523 -57.10455) (xy 185.466095 -57.081909) (xy 185.518386 -57.066553)
			(xy 185.572329 -57.058794) (xy 185.599578 -57.058306) (xy 185.625895 -57.058725) (xy 185.678031 -57.065952)
			(xy 185.72868 -57.080272) (xy 185.776881 -57.101412) (xy 185.821723 -57.128974) (xy 185.862353 -57.162433)
			(xy 185.880502 -57.181496) (xy 185.888022 -57.1889) (xy 185.907303 -57.197423) (xy 185.91784 -57.198006)
			(xy 185.992516 -57.198006) (xy 186.003068 -57.197497) (xy 186.022363 -57.188948) (xy 186.029854 -57.181496)
			(xy 186.047961 -57.16239) (xy 186.088588 -57.128914) (xy 186.133434 -57.101347) (xy 186.181647 -57.080214)
			(xy 186.232309 -57.065915) (xy 186.284457 -57.058723) (xy 186.310778 -57.058306) (xy 186.338033 -57.058739)
			(xy 186.391988 -57.066494) (xy 186.427256 -57.076848) (xy 187.23864 -57.076848) (xy 187.239124 -57.049478)
			(xy 187.246936 -56.9953) (xy 187.262421 -56.942796) (xy 187.285258 -56.893049) (xy 187.31498 -56.847082)
			(xy 187.33262 -56.82615) (xy 187.338716 -56.819038) (xy 187.345066 -56.80202) (xy 187.345066 -56.716676)
			(xy 187.338716 -56.699658) (xy 187.33262 -56.692546) (xy 187.314992 -56.671605) (xy 187.285278 -56.625635)
			(xy 187.262439 -56.57589) (xy 187.246946 -56.523391) (xy 187.239115 -56.469217) (xy 187.23864 -56.441848)
			(xy 187.239126 -56.414597) (xy 187.246882 -56.360649) (xy 187.262237 -56.308354) (xy 187.284879 -56.258777)
			(xy 187.314345 -56.212927) (xy 187.350036 -56.171736) (xy 187.391227 -56.136045) (xy 187.437077 -56.106579)
			(xy 187.486654 -56.083937) (xy 187.538949 -56.068582) (xy 187.592897 -56.060826) (xy 187.647399 -56.060826)
			(xy 187.701347 -56.068582) (xy 187.753642 -56.083937) (xy 187.803219 -56.106579) (xy 187.849069 -56.136045)
			(xy 187.89026 -56.171736) (xy 187.925951 -56.212927) (xy 187.955417 -56.258777) (xy 187.978059 -56.308354)
			(xy 187.993414 -56.360649) (xy 188.00117 -56.414597) (xy 188.001656 -56.441848) (xy 188.00117 -56.469218)
			(xy 187.993359 -56.523396) (xy 187.977875 -56.5759) (xy 187.955037 -56.625647) (xy 187.925316 -56.671614)
			(xy 187.907676 -56.692546) (xy 187.90158 -56.699658) (xy 187.89523 -56.716676) (xy 187.89523 -56.80202)
			(xy 187.90158 -56.819038) (xy 187.907676 -56.82615) (xy 187.925301 -56.847093) (xy 187.955016 -56.893063)
			(xy 187.977855 -56.942807) (xy 187.993349 -56.995306) (xy 188.001181 -57.04948) (xy 188.001656 -57.076848)
			(xy 188.00117 -57.104099) (xy 187.993414 -57.158047) (xy 187.978059 -57.210342) (xy 187.955417 -57.259919)
			(xy 187.925951 -57.305769) (xy 187.89026 -57.34696) (xy 187.849069 -57.382651) (xy 187.803219 -57.412117)
			(xy 187.753642 -57.434759) (xy 187.701347 -57.450114) (xy 187.647399 -57.45787) (xy 187.592897 -57.45787)
			(xy 187.538949 -57.450114) (xy 187.486654 -57.434759) (xy 187.437077 -57.412117) (xy 187.391227 -57.382651)
			(xy 187.350036 -57.34696) (xy 187.314345 -57.305769) (xy 187.284879 -57.259919) (xy 187.262237 -57.210342)
			(xy 187.246882 -57.158047) (xy 187.239126 -57.104099) (xy 187.23864 -57.076848) (xy 186.427256 -57.076848)
			(xy 186.444291 -57.081849) (xy 186.493876 -57.104491) (xy 186.539733 -57.133959) (xy 186.58093 -57.169654)
			(xy 186.616627 -57.210849) (xy 186.646099 -57.256705) (xy 186.668743 -57.306289) (xy 186.684101 -57.35859)
			(xy 186.691859 -57.412545) (xy 186.691859 -57.467055) (xy 186.684101 -57.52101) (xy 186.668743 -57.573311)
			(xy 186.646099 -57.622895) (xy 186.616627 -57.668751) (xy 186.58093 -57.709946) (xy 186.539733 -57.745641)
			(xy 186.493876 -57.775109) (xy 186.444291 -57.797751) (xy 186.391988 -57.813106) (xy 186.338033 -57.820861)
			(xy 186.310778 -57.821322) (xy 186.284463 -57.820856) (xy 186.232329 -57.813638) (xy 186.181682 -57.799327)
			(xy 186.13348 -57.778195) (xy 186.088637 -57.750642) (xy 186.048005 -57.717191) (xy 186.029854 -57.698132)
			(xy 186.022347 -57.690713) (xy 186.003056 -57.682197) (xy 185.992516 -57.681622) (xy 185.91784 -57.681622)
			(xy 185.90729 -57.682152) (xy 185.887994 -57.690686) (xy 185.880502 -57.698132) (xy 185.862353 -57.717197)
			(xy 185.821737 -57.750679) (xy 185.7769 -57.778253) (xy 185.728695 -57.799395) (xy 185.67804 -57.813701)
			(xy 185.625897 -57.820901) (xy 185.599578 -57.821322) (xy 185.572329 -57.820806) (xy 185.518386 -57.813047)
			(xy 185.466095 -57.797691) (xy 185.416523 -57.77505) (xy 185.370677 -57.745584) (xy 185.329491 -57.709894)
			(xy 185.293803 -57.668705) (xy 185.26434 -57.622858) (xy 185.241701 -57.573284) (xy 185.226348 -57.520993)
			(xy 185.218592 -57.467049) (xy 185.035255 -57.467049) (xy 185.039085 -57.494776) (xy 185.039508 -57.521094)
			(xy 185.039036 -57.548464) (xy 185.03122 -57.602643) (xy 185.015732 -57.655146) (xy 184.992891 -57.704893)
			(xy 184.963168 -57.75086) (xy 184.945528 -57.771792) (xy 184.939432 -57.778904) (xy 184.933082 -57.795922)
			(xy 184.933082 -57.881266) (xy 184.939432 -57.898284) (xy 184.945528 -57.905396) (xy 184.963165 -57.926333)
			(xy 184.992893 -57.972299) (xy 185.015742 -58.022044) (xy 185.03124 -58.074546) (xy 185.03907 -58.128725)
			(xy 185.039071 -58.183466) (xy 185.031242 -58.237645) (xy 185.015745 -58.290148) (xy 184.992898 -58.339893)
			(xy 184.96317 -58.38586) (xy 184.945528 -58.406792) (xy 184.939432 -58.413904) (xy 184.933082 -58.430922)
			(xy 184.933082 -58.516266) (xy 184.939432 -58.533284) (xy 184.945528 -58.540396) (xy 184.963183 -58.561315)
			(xy 184.992892 -58.607292) (xy 185.015724 -58.657043) (xy 185.031211 -58.709546) (xy 185.039036 -58.763724)
			(xy 185.039508 -58.791094) (xy 185.039022 -58.818345) (xy 185.031266 -58.872293) (xy 185.030869 -58.873644)
			(xy 186.300618 -58.873644) (xy 186.301105 -58.846274) (xy 186.308917 -58.792096) (xy 186.324401 -58.739593)
			(xy 186.347238 -58.689846) (xy 186.376959 -58.643878) (xy 186.394598 -58.622946) (xy 186.400694 -58.615834)
			(xy 186.407044 -58.598816) (xy 186.407044 -58.513472) (xy 186.400694 -58.496454) (xy 186.394598 -58.489342)
			(xy 186.376965 -58.468405) (xy 186.347252 -58.422434) (xy 186.324415 -58.372687) (xy 186.308923 -58.320188)
			(xy 186.301093 -58.266013) (xy 186.300618 -58.238644) (xy 186.301104 -58.211393) (xy 186.30886 -58.157445)
			(xy 186.324215 -58.10515) (xy 186.346857 -58.055573) (xy 186.376323 -58.009723) (xy 186.412014 -57.968532)
			(xy 186.453205 -57.932841) (xy 186.499055 -57.903375) (xy 186.548632 -57.880733) (xy 186.600927 -57.865378)
			(xy 186.654875 -57.857622) (xy 186.709377 -57.857622) (xy 186.763325 -57.865378) (xy 186.81562 -57.880733)
			(xy 186.865197 -57.903375) (xy 186.911047 -57.932841) (xy 186.952238 -57.968532) (xy 186.987929 -58.009723)
			(xy 187.017395 -58.055573) (xy 187.040037 -58.10515) (xy 187.055392 -58.157445) (xy 187.063148 -58.211393)
			(xy 187.063634 -58.238644) (xy 187.063151 -58.266014) (xy 187.05534 -58.320193) (xy 187.039856 -58.372696)
			(xy 187.017017 -58.422444) (xy 186.987295 -58.46841) (xy 186.969654 -58.489342) (xy 186.963558 -58.496454)
			(xy 186.957208 -58.513472) (xy 186.957208 -58.598816) (xy 186.963558 -58.615834) (xy 186.969654 -58.622946)
			(xy 186.987274 -58.643894) (xy 187.01699 -58.689861) (xy 187.039831 -58.739605) (xy 187.055326 -58.792102)
			(xy 187.063158 -58.846276) (xy 187.063634 -58.873644) (xy 187.063148 -58.900895) (xy 187.055392 -58.954843)
			(xy 187.040037 -59.007138) (xy 187.017395 -59.056715) (xy 186.987929 -59.102565) (xy 186.952238 -59.143756)
			(xy 186.911047 -59.179447) (xy 186.865197 -59.208913) (xy 186.81562 -59.231555) (xy 186.763325 -59.24691)
			(xy 186.709377 -59.254666) (xy 186.654875 -59.254666) (xy 186.600927 -59.24691) (xy 186.548632 -59.231555)
			(xy 186.499055 -59.208913) (xy 186.453205 -59.179447) (xy 186.412014 -59.143756) (xy 186.376323 -59.102565)
			(xy 186.346857 -59.056715) (xy 186.324215 -59.007138) (xy 186.30886 -58.954843) (xy 186.301104 -58.900895)
			(xy 186.300618 -58.873644) (xy 185.030869 -58.873644) (xy 185.015911 -58.924588) (xy 184.993269 -58.974165)
			(xy 184.963803 -59.020015) (xy 184.928112 -59.061206) (xy 184.886921 -59.096897) (xy 184.841071 -59.126363)
			(xy 184.791494 -59.149005) (xy 184.739199 -59.16436) (xy 184.685251 -59.172116) (xy 184.630749 -59.172116)
			(xy 184.576801 -59.16436) (xy 184.524506 -59.149005) (xy 184.474929 -59.126363) (xy 184.429079 -59.096897)
			(xy 184.387888 -59.061206) (xy 184.352197 -59.020015) (xy 184.322731 -58.974165) (xy 184.300089 -58.924588)
			(xy 184.284734 -58.872293) (xy 184.276978 -58.818345) (xy 184.276492 -58.791094) (xy 182.378534 -58.791094)
			(xy 182.375442 -58.812603) (xy 182.360087 -58.864898) (xy 182.337445 -58.914475) (xy 182.307979 -58.960325)
			(xy 182.272288 -59.001516) (xy 182.231097 -59.037207) (xy 182.185247 -59.066673) (xy 182.13567 -59.089315)
			(xy 182.083375 -59.10467) (xy 182.029427 -59.112426) (xy 181.974925 -59.112426) (xy 181.920977 -59.10467)
			(xy 181.868682 -59.089315) (xy 181.819105 -59.066673) (xy 181.773255 -59.037207) (xy 181.732064 -59.001516)
			(xy 181.696373 -58.960325) (xy 181.666907 -58.914475) (xy 181.644265 -58.864898) (xy 181.62891 -58.812603)
			(xy 181.621154 -58.758655) (xy 181.620668 -58.731404) (xy 179.791106 -58.731404) (xy 179.791106 -60.126452)
			(xy 185.280272 -60.126452) (xy 185.280272 -60.071948) (xy 185.288028 -60.018) (xy 185.303384 -59.965704)
			(xy 185.326025 -59.916126) (xy 185.355492 -59.870275) (xy 185.391184 -59.829084) (xy 185.432375 -59.793392)
			(xy 185.478226 -59.763925) (xy 185.527804 -59.741284) (xy 185.5801 -59.725928) (xy 185.634048 -59.718172)
			(xy 185.6613 -59.717686) (xy 185.68867 -59.718155) (xy 185.742849 -59.725973) (xy 185.795352 -59.741461)
			(xy 185.845099 -59.764302) (xy 185.891066 -59.794026) (xy 185.911998 -59.811666) (xy 185.91911 -59.817762)
			(xy 185.936128 -59.824112) (xy 186.021472 -59.824112) (xy 186.03849 -59.817762) (xy 186.045602 -59.811666)
			(xy 186.066535 -59.794025) (xy 186.112503 -59.764301) (xy 186.162249 -59.741455) (xy 186.214751 -59.725959)
			(xy 186.268929 -59.71813) (xy 186.323671 -59.71813) (xy 186.377849 -59.725959) (xy 186.430351 -59.741455)
			(xy 186.480097 -59.764301) (xy 186.526065 -59.794025) (xy 186.546998 -59.811666) (xy 186.55411 -59.817762)
			(xy 186.571128 -59.824112) (xy 186.656472 -59.824112) (xy 186.67349 -59.817762) (xy 186.680602 -59.811666)
			(xy 186.701518 -59.794007) (xy 186.747496 -59.764299) (xy 186.797247 -59.741468) (xy 186.849751 -59.725981)
			(xy 186.90393 -59.718158) (xy 186.9313 -59.717686) (xy 186.958551 -59.718184) (xy 187.012498 -59.72594)
			(xy 187.064792 -59.741295) (xy 187.114368 -59.763936) (xy 187.160218 -59.793402) (xy 187.201407 -59.829093)
			(xy 187.237098 -59.870282) (xy 187.266564 -59.916132) (xy 187.289205 -59.965708) (xy 187.30456 -60.018002)
			(xy 187.312316 -60.071949) (xy 187.312316 -60.126451) (xy 187.30456 -60.180398) (xy 187.289205 -60.232692)
			(xy 187.266564 -60.282268) (xy 187.237098 -60.328118) (xy 187.201407 -60.369307) (xy 187.160218 -60.404998)
			(xy 187.114368 -60.434464) (xy 187.064792 -60.457105) (xy 187.012498 -60.47246) (xy 186.958551 -60.480216)
			(xy 186.9313 -60.480702) (xy 186.90393 -60.480235) (xy 186.849751 -60.472418) (xy 186.797248 -60.456929)
			(xy 186.747501 -60.434087) (xy 186.701534 -60.404363) (xy 186.680602 -60.386722) (xy 186.67349 -60.380626)
			(xy 186.656472 -60.374276) (xy 186.571128 -60.374276) (xy 186.55411 -60.380626) (xy 186.546998 -60.386722)
			(xy 186.526065 -60.404363) (xy 186.480097 -60.434087) (xy 186.430351 -60.456933) (xy 186.377849 -60.472429)
			(xy 186.323671 -60.480258) (xy 186.268929 -60.480258) (xy 186.214751 -60.472429) (xy 186.162249 -60.456933)
			(xy 186.112503 -60.434087) (xy 186.066535 -60.404363) (xy 186.045602 -60.386722) (xy 186.03849 -60.380626)
			(xy 186.021472 -60.374276) (xy 185.936128 -60.374276) (xy 185.91911 -60.380626) (xy 185.911998 -60.386722)
			(xy 185.89108 -60.404379) (xy 185.845103 -60.434087) (xy 185.795352 -60.456919) (xy 185.742848 -60.472406)
			(xy 185.68867 -60.48023) (xy 185.6613 -60.480702) (xy 185.634048 -60.480228) (xy 185.5801 -60.472472)
			(xy 185.527804 -60.457116) (xy 185.478226 -60.434475) (xy 185.432375 -60.405008) (xy 185.391184 -60.369316)
			(xy 185.355492 -60.328125) (xy 185.326025 -60.282274) (xy 185.303384 -60.232696) (xy 185.288028 -60.1804)
			(xy 185.280272 -60.126452) (xy 179.791106 -60.126452) (xy 179.791106 -60.999878) (xy 179.790573 -61.009867)
			(xy 179.782865 -61.028306) (xy 179.77612 -61.035692) (xy 179.700682 -61.11113) (xy 179.700174 -61.111892)
			(xy 179.696872 -61.115194) (xy 179.696618 -61.115448) (xy 179.069238 -61.742828) (xy 179.063396 -61.748416)
			(xy 179.062888 -61.748924) (xy 179.000404 -61.811408) (xy 178.993048 -61.818056) (xy 178.974747 -61.825637)
			(xy 178.964844 -61.82614) (xy 178.909218 -61.82614) (xy 178.9049 -61.826902) (xy 178.892546 -61.828867)
			(xy 178.867624 -61.831032) (xy 178.855116 -61.83122) (xy 177.179478 -61.83122) (xy 177.16785 -61.831781)
			(xy 177.146939 -61.841956) (xy 177.139346 -61.850778) (xy 177.082704 -61.923422) (xy 177.077878 -61.946028)
			(xy 177.080926 -61.957712) (xy 177.086392 -61.980757) (xy 177.092248 -62.027756) (xy 177.09261 -62.051438)
			(xy 177.092122 -62.078688) (xy 177.084361 -62.132631) (xy 177.069002 -62.184922) (xy 177.046359 -62.234494)
			(xy 177.016892 -62.28034) (xy 176.9812 -62.321526) (xy 176.940011 -62.357213) (xy 176.894162 -62.386676)
			(xy 176.844588 -62.409315) (xy 176.792296 -62.424668) (xy 176.738352 -62.432424) (xy 176.711102 -62.432946)
			(xy 176.687547 -62.432566) (xy 176.640803 -62.426712) (xy 176.617884 -62.421262) (xy 176.60366 -62.417706)
			(xy 176.576482 -62.426342) (xy 176.49825 -62.517274) (xy 176.493678 -62.545468) (xy 176.499266 -62.55893)
			(xy 176.508592 -62.582314) (xy 176.521713 -62.630918) (xy 176.528331 -62.680824) (xy 176.52873 -62.705996)
			(xy 176.528245 -62.733248) (xy 176.520489 -62.787197) (xy 176.505134 -62.839494) (xy 176.482493 -62.889073)
			(xy 176.453028 -62.934925) (xy 176.417336 -62.976118) (xy 176.376146 -63.011812) (xy 176.330296 -63.041281)
			(xy 176.280718 -63.063925) (xy 176.228423 -63.079283) (xy 176.174474 -63.087043) (xy 176.147222 -63.087504)
			(xy 176.118412 -63.086978) (xy 176.061447 -63.078312) (xy 176.006435 -63.061173) (xy 175.954628 -63.035953)
			(xy 175.907205 -63.003224) (xy 175.885856 -62.983872) (xy 175.87722 -62.975744) (xy 175.855376 -62.968886)
			(xy 175.76546 -62.981332) (xy 175.763428 -62.981586) (xy 175.752691 -62.984094) (xy 175.734652 -62.996734)
			(xy 175.72863 -63.00597) (xy 175.713812 -63.03009) (xy 175.678174 -63.074069) (xy 175.636425 -63.112297)
			(xy 175.589485 -63.143934) (xy 175.538384 -63.168285) (xy 175.484245 -63.184815) (xy 175.428257 -63.193161)
			(xy 175.399954 -63.193676) (xy 175.372707 -63.193187) (xy 175.318769 -63.185425) (xy 175.266484 -63.170068)
			(xy 175.216917 -63.147426) (xy 175.171076 -63.117961) (xy 175.129895 -63.082272) (xy 175.094212 -63.041087)
			(xy 175.064752 -62.995243) (xy 175.042116 -62.945673) (xy 175.026765 -62.893386) (xy 175.01901 -62.839447)
			(xy 175.01901 -62.784953) (xy 175.026765 -62.731014) (xy 175.042116 -62.678727) (xy 175.064752 -62.629157)
			(xy 175.094212 -62.583313) (xy 175.129895 -62.542128) (xy 175.171076 -62.506439) (xy 175.216917 -62.476974)
			(xy 175.266484 -62.454332) (xy 175.318769 -62.438975) (xy 175.372707 -62.431213) (xy 175.399954 -62.43066)
			(xy 175.428765 -62.431184) (xy 175.485732 -62.439846) (xy 175.540747 -62.456981) (xy 175.592558 -62.482198)
			(xy 175.639986 -62.514922) (xy 175.66132 -62.534292) (xy 175.669956 -62.54242) (xy 175.6918 -62.549278)
			(xy 175.7934 -62.535054) (xy 175.81245 -62.522354) (xy 175.818546 -62.512194) (xy 175.833365 -62.488075)
			(xy 175.869005 -62.444097) (xy 175.910753 -62.40587) (xy 175.957693 -62.374233) (xy 176.008793 -62.349882)
			(xy 176.062932 -62.33335) (xy 176.118919 -62.325002) (xy 176.147222 -62.324488) (xy 176.167288 -62.324996)
			(xy 176.167542 -62.324996) (xy 176.18329 -62.326012) (xy 176.191926 -62.327028) (xy 176.212754 -62.330076)
			(xy 176.213008 -62.330076) (xy 176.24044 -62.336172) (xy 176.254664 -62.339728) (xy 176.281842 -62.331092)
			(xy 176.360074 -62.24016) (xy 176.364392 -62.21222) (xy 176.358804 -62.198504) (xy 176.348985 -62.173891)
			(xy 176.335478 -62.12265) (xy 176.33188 -62.096396) (xy 176.33061 -62.082426) (xy 176.32934 -62.051438)
			(xy 176.32934 -62.05093) (xy 176.32971 -62.027312) (xy 176.335571 -61.980441) (xy 176.341024 -61.957458)
			(xy 176.344072 -61.945774) (xy 176.339246 -61.923168) (xy 176.282858 -61.850778) (xy 176.275269 -61.841945)
			(xy 176.254359 -61.831751) (xy 176.242726 -61.83122) (xy 175.264318 -61.83122) (xy 175.251555 -61.83108)
			(xy 175.226122 -61.828913) (xy 175.213518 -61.826902) (xy 175.2092 -61.82614) (xy 174.968916 -61.82614)
			(xy 174.957232 -61.829188) (xy 174.952406 -61.831474) (xy 174.951898 -61.831728) (xy 174.936992 -61.838666)
			(xy 174.906214 -61.850239) (xy 174.89043 -61.854842) (xy 174.863137 -61.862057) (xy 174.807149 -61.869288)
			(xy 174.750708 -61.86818) (xy 174.72279 -61.863986) (xy 174.696211 -61.859027) (xy 174.644705 -61.842588)
			(xy 174.620174 -61.83122) (xy 174.615094 -61.82868) (xy 174.603918 -61.82614) (xy 174.379382 -61.82614)
			(xy 174.373286 -61.826394) (xy 174.357792 -61.82995) (xy 174.346362 -61.83122) (xy 173.163992 -61.83122)
			(xy 173.153482 -61.831749) (xy 173.134212 -61.840152) (xy 173.126654 -61.847476) (xy 173.123098 -61.851286)
			(xy 173.07814 -61.920374) (xy 173.071028 -61.931296) (xy 173.070012 -61.94425) (xy 173.068996 -61.956696)
			(xy 173.072044 -61.963808) (xy 173.072044 -61.964062) (xy 173.07433 -61.969142) (xy 173.084313 -61.993204)
			(xy 173.098349 -62.043372) (xy 173.105411 -62.094986) (xy 173.105826 -62.121034) (xy 173.105826 -62.12586)
			(xy 173.105014 -62.152886) (xy 173.096704 -62.206313) (xy 173.080935 -62.258031) (xy 173.058023 -62.307004)
			(xy 173.028426 -62.352253) (xy 172.992737 -62.39287) (xy 172.951672 -62.428042) (xy 172.906053 -62.457064)
			(xy 172.856793 -62.479355) (xy 172.804879 -62.494469) (xy 172.751352 -62.502102) (xy 172.697284 -62.502102)
			(xy 172.643757 -62.494469) (xy 172.591843 -62.479355) (xy 172.542583 -62.457064) (xy 172.496964 -62.428042)
			(xy 172.455899 -62.39287) (xy 172.42021 -62.352253) (xy 172.390613 -62.307004) (xy 172.367701 -62.258031)
			(xy 172.351932 -62.206313) (xy 172.343622 -62.152886) (xy 172.34281 -62.12586) (xy 172.34281 -62.12078)
			(xy 172.343258 -62.094683) (xy 172.350411 -62.042981) (xy 172.364541 -61.992736) (xy 172.37456 -61.968634)
			(xy 172.37964 -61.95695) (xy 172.378624 -61.94425) (xy 172.377608 -61.931296) (xy 172.327316 -61.854334)
			(xy 172.320204 -61.843412) (xy 172.297852 -61.83122) (xy 169.762424 -61.83122) (xy 169.75236 -61.831657)
			(xy 169.733778 -61.839394) (xy 169.726356 -61.846206) (xy 169.32275 -62.249812) (xy 169.315384 -62.256924)
			(xy 169.307764 -62.27572) (xy 169.307764 -63.273432) (xy 171.67682 -63.273432) (xy 171.680891 -63.21781)
			(xy 171.693017 -63.163373) (xy 171.71294 -63.111282) (xy 171.740236 -63.062647) (xy 171.774322 -63.018504)
			(xy 171.814471 -62.979795) (xy 171.859829 -62.947344) (xy 171.909429 -62.921843) (xy 171.962213 -62.903836)
			(xy 172.017056 -62.893706) (xy 172.07279 -62.891669) (xy 172.128227 -62.897769) (xy 172.182184 -62.911875)
			(xy 172.233513 -62.933687) (xy 172.281119 -62.962741) (xy 172.323987 -62.998416) (xy 172.361204 -63.039953)
			(xy 172.391977 -63.086466) (xy 172.415649 -63.136963) (xy 172.431717 -63.19037) (xy 172.439837 -63.245546)
			(xy 172.439837 -63.245552) (xy 185.204569 -63.245552) (xy 185.204569 -63.191048) (xy 185.212326 -63.137098)
			(xy 185.227682 -63.084802) (xy 185.250324 -63.035223) (xy 185.279792 -62.989371) (xy 185.315485 -62.94818)
			(xy 185.356677 -62.912487) (xy 185.40253 -62.88302) (xy 185.452109 -62.860379) (xy 185.504406 -62.845025)
			(xy 185.558356 -62.837269) (xy 185.585608 -62.836806) (xy 185.612978 -62.837266) (xy 185.667158 -62.845085)
			(xy 185.719661 -62.860575) (xy 185.769408 -62.883419) (xy 185.815374 -62.913144) (xy 185.836306 -62.930786)
			(xy 185.843418 -62.936882) (xy 185.860436 -62.943232) (xy 185.94578 -62.943232) (xy 185.962798 -62.936882)
			(xy 185.96991 -62.930786) (xy 185.990843 -62.913145) (xy 186.036811 -62.883421) (xy 186.086557 -62.860575)
			(xy 186.139059 -62.845079) (xy 186.193237 -62.83725) (xy 186.247979 -62.83725) (xy 186.302157 -62.845079)
			(xy 186.354659 -62.860575) (xy 186.404405 -62.883421) (xy 186.450373 -62.913145) (xy 186.471306 -62.930786)
			(xy 186.478418 -62.936882) (xy 186.495436 -62.943232) (xy 186.58078 -62.943232) (xy 186.597798 -62.936882)
			(xy 186.60491 -62.930786) (xy 186.625826 -62.913127) (xy 186.671803 -62.883418) (xy 186.721555 -62.860586)
			(xy 186.774059 -62.8451) (xy 186.828238 -62.837277) (xy 186.855608 -62.836806) (xy 186.88286 -62.837264)
			(xy 186.936809 -62.845022) (xy 186.989104 -62.860378) (xy 187.038682 -62.883021) (xy 187.084534 -62.912488)
			(xy 187.125724 -62.948181) (xy 187.161416 -62.989373) (xy 187.190883 -63.035225) (xy 187.213524 -63.084803)
			(xy 187.22888 -63.137099) (xy 187.236636 -63.191048) (xy 187.236636 -63.245552) (xy 187.22888 -63.299501)
			(xy 187.213524 -63.351797) (xy 187.190883 -63.401375) (xy 187.161416 -63.447227) (xy 187.125724 -63.488419)
			(xy 187.084534 -63.524112) (xy 187.038682 -63.553579) (xy 186.989104 -63.576222) (xy 186.936809 -63.591578)
			(xy 186.88286 -63.599336) (xy 186.855608 -63.599822) (xy 186.828237 -63.59937) (xy 186.774057 -63.591552)
			(xy 186.721553 -63.576061) (xy 186.671806 -63.553215) (xy 186.62584 -63.523486) (xy 186.60491 -63.505842)
			(xy 186.597798 -63.499746) (xy 186.58078 -63.493396) (xy 186.495436 -63.493396) (xy 186.478418 -63.499746)
			(xy 186.471306 -63.505842) (xy 186.450373 -63.523483) (xy 186.404405 -63.553207) (xy 186.354659 -63.576053)
			(xy 186.302157 -63.591549) (xy 186.247979 -63.599378) (xy 186.193237 -63.599378) (xy 186.139059 -63.591549)
			(xy 186.086557 -63.576053) (xy 186.036811 -63.553207) (xy 185.990843 -63.523483) (xy 185.96991 -63.505842)
			(xy 185.962798 -63.499746) (xy 185.94578 -63.493396) (xy 185.860436 -63.493396) (xy 185.843418 -63.499746)
			(xy 185.836306 -63.505842) (xy 185.815388 -63.523499) (xy 185.769411 -63.553207) (xy 185.71966 -63.576039)
			(xy 185.667156 -63.591526) (xy 185.612978 -63.59935) (xy 185.585608 -63.599822) (xy 185.558356 -63.599331)
			(xy 185.504406 -63.591575) (xy 185.452109 -63.576221) (xy 185.40253 -63.55358) (xy 185.356677 -63.524113)
			(xy 185.315485 -63.48842) (xy 185.279792 -63.447229) (xy 185.250324 -63.401377) (xy 185.227682 -63.351798)
			(xy 185.212326 -63.299502) (xy 185.204569 -63.245552) (xy 172.439837 -63.245552) (xy 172.440346 -63.273432)
			(xy 172.439837 -63.301318) (xy 172.431717 -63.356494) (xy 172.415649 -63.409901) (xy 172.391977 -63.460398)
			(xy 172.361204 -63.506911) (xy 172.323987 -63.548448) (xy 172.281119 -63.584123) (xy 172.233513 -63.613177)
			(xy 172.182184 -63.634989) (xy 172.128227 -63.649095) (xy 172.07279 -63.655195) (xy 172.017056 -63.653158)
			(xy 171.962213 -63.643028) (xy 171.909429 -63.625021) (xy 171.859829 -63.59952) (xy 171.814471 -63.567069)
			(xy 171.774322 -63.52836) (xy 171.740236 -63.484217) (xy 171.71294 -63.435582) (xy 171.693017 -63.383491)
			(xy 171.680891 -63.329054) (xy 171.67682 -63.273432) (xy 169.307764 -63.273432) (xy 169.307764 -64.102234)
			(xy 169.487594 -64.102234) (xy 169.491665 -64.046612) (xy 169.503791 -63.992175) (xy 169.523714 -63.940084)
			(xy 169.55101 -63.891449) (xy 169.585096 -63.847306) (xy 169.625245 -63.808597) (xy 169.670603 -63.776146)
			(xy 169.720203 -63.750645) (xy 169.772987 -63.732638) (xy 169.82783 -63.722508) (xy 169.883564 -63.720471)
			(xy 169.939001 -63.726571) (xy 169.992958 -63.740677) (xy 170.044287 -63.762489) (xy 170.091893 -63.791543)
			(xy 170.134761 -63.827218) (xy 170.171978 -63.868755) (xy 170.202751 -63.915268) (xy 170.226423 -63.965765)
			(xy 170.242491 -64.019172) (xy 170.250611 -64.074348) (xy 170.25112 -64.102234) (xy 170.250611 -64.13012)
			(xy 170.242491 -64.185296) (xy 170.226423 -64.238703) (xy 170.202751 -64.2892) (xy 170.187473 -64.312292)
			(xy 173.166022 -64.312292) (xy 173.170093 -64.25667) (xy 173.182219 -64.202233) (xy 173.202142 -64.150142)
			(xy 173.229438 -64.101507) (xy 173.263524 -64.057364) (xy 173.303673 -64.018655) (xy 173.349031 -63.986204)
			(xy 173.398631 -63.960703) (xy 173.451415 -63.942696) (xy 173.506258 -63.932566) (xy 173.561992 -63.930529)
			(xy 173.617429 -63.936629) (xy 173.671386 -63.950735) (xy 173.722715 -63.972547) (xy 173.770321 -64.001601)
			(xy 173.813189 -64.037276) (xy 173.850406 -64.078813) (xy 173.881179 -64.125326) (xy 173.904851 -64.175823)
			(xy 173.920919 -64.22923) (xy 173.929039 -64.284406) (xy 173.929548 -64.312292) (xy 175.005998 -64.312292)
			(xy 175.010069 -64.25667) (xy 175.022195 -64.202233) (xy 175.042118 -64.150142) (xy 175.069414 -64.101507)
			(xy 175.1035 -64.057364) (xy 175.143649 -64.018655) (xy 175.189007 -63.986204) (xy 175.238607 -63.960703)
			(xy 175.291391 -63.942696) (xy 175.346234 -63.932566) (xy 175.401968 -63.930529) (xy 175.457405 -63.936629)
			(xy 175.511362 -63.950735) (xy 175.562691 -63.972547) (xy 175.610297 -64.001601) (xy 175.653165 -64.037276)
			(xy 175.690382 -64.078813) (xy 175.721155 -64.125326) (xy 175.744827 -64.175823) (xy 175.760895 -64.22923)
			(xy 175.769015 -64.284406) (xy 175.769524 -64.312292) (xy 175.769015 -64.340178) (xy 175.760895 -64.395354)
			(xy 175.744827 -64.448761) (xy 175.721155 -64.499258) (xy 175.690382 -64.545771) (xy 175.653165 -64.587308)
			(xy 175.610297 -64.622983) (xy 175.562691 -64.652037) (xy 175.511362 -64.673849) (xy 175.457405 -64.687955)
			(xy 175.401968 -64.694055) (xy 175.346234 -64.692018) (xy 175.291391 -64.681888) (xy 175.238607 -64.663881)
			(xy 175.189007 -64.63838) (xy 175.143649 -64.605929) (xy 175.1035 -64.56722) (xy 175.069414 -64.523077)
			(xy 175.042118 -64.474442) (xy 175.022195 -64.422351) (xy 175.010069 -64.367914) (xy 175.005998 -64.312292)
			(xy 173.929548 -64.312292) (xy 173.929039 -64.340178) (xy 173.920919 -64.395354) (xy 173.904851 -64.448761)
			(xy 173.881179 -64.499258) (xy 173.850406 -64.545771) (xy 173.813189 -64.587308) (xy 173.770321 -64.622983)
			(xy 173.722715 -64.652037) (xy 173.671386 -64.673849) (xy 173.617429 -64.687955) (xy 173.561992 -64.694055)
			(xy 173.506258 -64.692018) (xy 173.451415 -64.681888) (xy 173.398631 -64.663881) (xy 173.349031 -64.63838)
			(xy 173.303673 -64.605929) (xy 173.263524 -64.56722) (xy 173.229438 -64.523077) (xy 173.202142 -64.474442)
			(xy 173.182219 -64.422351) (xy 173.170093 -64.367914) (xy 173.166022 -64.312292) (xy 170.187473 -64.312292)
			(xy 170.171978 -64.335713) (xy 170.134761 -64.37725) (xy 170.091893 -64.412925) (xy 170.044287 -64.441979)
			(xy 169.992958 -64.463791) (xy 169.939001 -64.477897) (xy 169.883564 -64.483997) (xy 169.82783 -64.48196)
			(xy 169.772987 -64.47183) (xy 169.720203 -64.453823) (xy 169.670603 -64.428322) (xy 169.625245 -64.395871)
			(xy 169.585096 -64.357162) (xy 169.55101 -64.313019) (xy 169.523714 -64.264384) (xy 169.503791 -64.212293)
			(xy 169.491665 -64.157856) (xy 169.487594 -64.102234) (xy 169.307764 -64.102234) (xy 169.307764 -65.15989)
			(xy 187.21654 -65.15989) (xy 187.220611 -65.104268) (xy 187.232737 -65.049831) (xy 187.25266 -64.99774)
			(xy 187.279956 -64.949105) (xy 187.314042 -64.904962) (xy 187.354191 -64.866253) (xy 187.399549 -64.833802)
			(xy 187.449149 -64.808301) (xy 187.501933 -64.790294) (xy 187.556776 -64.780164) (xy 187.61251 -64.778127)
			(xy 187.667947 -64.784227) (xy 187.721904 -64.798333) (xy 187.773233 -64.820145) (xy 187.820839 -64.849199)
			(xy 187.863707 -64.884874) (xy 187.900924 -64.926411) (xy 187.931697 -64.972924) (xy 187.955369 -65.023421)
			(xy 187.971437 -65.076828) (xy 187.979557 -65.132004) (xy 187.980066 -65.15989) (xy 187.979557 -65.187776)
			(xy 187.971437 -65.242952) (xy 187.955369 -65.296359) (xy 187.931697 -65.346856) (xy 187.900924 -65.393369)
			(xy 187.863707 -65.434906) (xy 187.820839 -65.470581) (xy 187.773233 -65.499635) (xy 187.721904 -65.521447)
			(xy 187.667947 -65.535553) (xy 187.61251 -65.541653) (xy 187.556776 -65.539616) (xy 187.501933 -65.529486)
			(xy 187.449149 -65.511479) (xy 187.399549 -65.485978) (xy 187.354191 -65.453527) (xy 187.314042 -65.414818)
			(xy 187.279956 -65.370675) (xy 187.25266 -65.32204) (xy 187.232737 -65.269949) (xy 187.220611 -65.215512)
			(xy 187.21654 -65.15989) (xy 169.307764 -65.15989) (xy 169.307764 -65.75552) (xy 182.446674 -65.75552)
			(xy 182.450745 -65.699898) (xy 182.462871 -65.645461) (xy 182.482794 -65.59337) (xy 182.51009 -65.544735)
			(xy 182.544176 -65.500592) (xy 182.584325 -65.461883) (xy 182.629683 -65.429432) (xy 182.679283 -65.403931)
			(xy 182.732067 -65.385924) (xy 182.78691 -65.375794) (xy 182.842644 -65.373757) (xy 182.898081 -65.379857)
			(xy 182.952038 -65.393963) (xy 183.003367 -65.415775) (xy 183.050973 -65.444829) (xy 183.093841 -65.480504)
			(xy 183.131058 -65.522041) (xy 183.161831 -65.568554) (xy 183.185503 -65.619051) (xy 183.201571 -65.672458)
			(xy 183.209691 -65.727634) (xy 183.2102 -65.75552) (xy 183.209691 -65.783406) (xy 183.201571 -65.838582)
			(xy 183.185503 -65.891989) (xy 183.161831 -65.942486) (xy 183.131058 -65.988999) (xy 183.093841 -66.030536)
			(xy 183.050973 -66.066211) (xy 183.003367 -66.095265) (xy 182.952038 -66.117077) (xy 182.898081 -66.131183)
			(xy 182.842644 -66.137283) (xy 182.78691 -66.135246) (xy 182.732067 -66.125116) (xy 182.679283 -66.107109)
			(xy 182.629683 -66.081608) (xy 182.584325 -66.049157) (xy 182.544176 -66.010448) (xy 182.51009 -65.966305)
			(xy 182.482794 -65.91767) (xy 182.462871 -65.865579) (xy 182.450745 -65.811142) (xy 182.446674 -65.75552)
			(xy 169.307764 -65.75552) (xy 169.307764 -67.488054) (xy 186.879228 -67.488054) (xy 186.883299 -67.432432)
			(xy 186.895425 -67.377995) (xy 186.915348 -67.325904) (xy 186.942644 -67.277269) (xy 186.97673 -67.233126)
			(xy 187.016879 -67.194417) (xy 187.062237 -67.161966) (xy 187.111837 -67.136465) (xy 187.164621 -67.118458)
			(xy 187.219464 -67.108328) (xy 187.275198 -67.106291) (xy 187.330635 -67.112391) (xy 187.384592 -67.126497)
			(xy 187.435921 -67.148309) (xy 187.483527 -67.177363) (xy 187.526395 -67.213038) (xy 187.563612 -67.254575)
			(xy 187.594385 -67.301088) (xy 187.618057 -67.351585) (xy 187.634125 -67.404992) (xy 187.642245 -67.460168)
			(xy 187.642754 -67.488054) (xy 187.642245 -67.51594) (xy 187.634125 -67.571116) (xy 187.618057 -67.624523)
			(xy 187.594385 -67.67502) (xy 187.563612 -67.721533) (xy 187.526395 -67.76307) (xy 187.483527 -67.798745)
			(xy 187.435921 -67.827799) (xy 187.384592 -67.849611) (xy 187.330635 -67.863717) (xy 187.275198 -67.869817)
			(xy 187.219464 -67.86778) (xy 187.164621 -67.85765) (xy 187.111837 -67.839643) (xy 187.062237 -67.814142)
			(xy 187.016879 -67.781691) (xy 186.97673 -67.742982) (xy 186.942644 -67.698839) (xy 186.915348 -67.650204)
			(xy 186.895425 -67.598113) (xy 186.883299 -67.543676) (xy 186.879228 -67.488054) (xy 169.307764 -67.488054)
			(xy 169.307764 -69.9516) (xy 169.30822 -69.961479) (xy 169.315655 -69.979786) (xy 169.322242 -69.98716)
			(xy 169.322496 -69.987414) (xy 169.498772 -70.16369) (xy 169.49928 -70.164198) (xy 169.50666 -70.170782)
			(xy 169.52496 -70.178231) (xy 169.53484 -70.178676)
		)
		(stroke
			(width 0)
			(type solid)
		)
		(fill yes)
		(layer "In9.Cu")
		(net "P12V_SSD6_R")
	)
	(gr_poly
		(pts
			(xy 136.57834 -70.178676) (xy 136.588406 -70.178245) (xy 136.606998 -70.170518) (xy 136.614408 -70.16369)
			(xy 136.940544 -69.837554) (xy 136.941052 -69.837046) (xy 136.947634 -69.829665) (xy 136.955085 -69.811366)
			(xy 136.95553 -69.801486) (xy 136.95553 -67.91579) (xy 136.955133 -67.906269) (xy 136.948174 -67.888543)
			(xy 136.935222 -67.874584) (xy 136.926828 -67.87007) (xy 136.83107 -67.823842) (xy 136.802368 -67.827144)
			(xy 136.790684 -67.836288) (xy 136.770373 -67.851904) (xy 136.72636 -67.878129) (xy 136.679231 -67.898224)
			(xy 136.629836 -67.911827) (xy 136.579065 -67.918694) (xy 136.553448 -67.919092) (xy 136.526194 -67.918632)
			(xy 136.47224 -67.910881) (xy 136.419939 -67.89553) (xy 136.370355 -67.872891) (xy 136.324497 -67.843425)
			(xy 136.283301 -67.807733) (xy 136.247603 -67.766541) (xy 136.218132 -67.720687) (xy 136.195487 -67.671106)
			(xy 136.180129 -67.618807) (xy 136.172371 -67.564854) (xy 136.172371 -67.510346) (xy 136.180129 -67.456393)
			(xy 136.195487 -67.404094) (xy 136.218132 -67.354513) (xy 136.247603 -67.308659) (xy 136.283301 -67.267467)
			(xy 136.324497 -67.231775) (xy 136.370355 -67.202309) (xy 136.419939 -67.17967) (xy 136.47224 -67.164319)
			(xy 136.526194 -67.156568) (xy 136.553448 -67.156076) (xy 136.579065 -67.156488) (xy 136.62984 -67.163343)
			(xy 136.679238 -67.176937) (xy 136.726371 -67.197025) (xy 136.770388 -67.223244) (xy 136.790684 -67.23888)
			(xy 136.802368 -67.248024) (xy 136.83107 -67.251326) (xy 136.926828 -67.205098) (xy 136.935233 -67.2006)
			(xy 136.948186 -67.186631) (xy 136.955156 -67.168902) (xy 136.95553 -67.159378) (xy 136.95553 -65.506854)
			(xy 136.941814 -65.483486) (xy 136.930384 -65.476628) (xy 136.929876 -65.476628) (xy 136.856724 -65.433702)
			(xy 136.852333 -65.431316) (xy 136.842867 -65.428114) (xy 136.837928 -65.427352) (xy 136.827514 -65.426082)
			(xy 136.803892 -65.432432) (xy 136.798304 -65.43548) (xy 136.770018 -65.450255) (xy 136.709742 -65.471196)
			(xy 136.646821 -65.481817) (xy 136.614916 -65.48247) (xy 136.614662 -65.48247) (xy 136.587415 -65.481981)
			(xy 136.533477 -65.474221) (xy 136.481192 -65.458864) (xy 136.431625 -65.436223) (xy 136.385784 -65.406759)
			(xy 136.344602 -65.371071) (xy 136.308918 -65.329886) (xy 136.279459 -65.284042) (xy 136.256822 -65.234472)
			(xy 136.241471 -65.182186) (xy 136.233716 -65.128247) (xy 136.233716 -65.073753) (xy 136.241471 -65.019814)
			(xy 136.256822 -64.967528) (xy 136.279459 -64.917958) (xy 136.308918 -64.872114) (xy 136.344602 -64.830929)
			(xy 136.385784 -64.795241) (xy 136.431625 -64.765777) (xy 136.481192 -64.743136) (xy 136.533477 -64.727779)
			(xy 136.587415 -64.720019) (xy 136.614662 -64.719454) (xy 136.614916 -64.719454) (xy 136.64682 -64.720119)
			(xy 136.709735 -64.730755) (xy 136.770014 -64.75168) (xy 136.798304 -64.766444) (xy 136.803892 -64.769492)
			(xy 136.817608 -64.773302) (xy 136.822593 -64.774512) (xy 136.832831 -64.775151) (xy 136.837928 -64.774572)
			(xy 136.847834 -64.773302) (xy 136.93013 -64.725296) (xy 136.930892 -64.724788) (xy 136.938176 -64.719977)
			(xy 136.949233 -64.706486) (xy 136.955146 -64.690074) (xy 136.95553 -64.681354) (xy 136.95553 -52.63261)
			(xy 136.955022 -52.626006) (xy 136.953752 -52.615592) (xy 136.95299 -52.612798) (xy 136.947278 -52.589272)
			(xy 136.941167 -52.541247) (xy 136.940798 -52.51704) (xy 136.940798 -52.49926) (xy 136.941052 -52.49418)
			(xy 136.94283 -52.477162) (xy 136.944005 -52.466351) (xy 136.947437 -52.444875) (xy 136.949688 -52.434236)
			(xy 136.951466 -52.427378) (xy 136.95172 -52.42687) (xy 136.952736 -52.422552) (xy 136.952736 -52.421536)
			(xy 136.953752 -52.418234) (xy 136.95553 -52.41163) (xy 136.95553 -51.455828) (xy 136.955967 -51.445764)
			(xy 136.963703 -51.427182) (xy 136.970516 -51.41976) (xy 137.07745 -51.312826) (xy 137.08485 -51.305985)
			(xy 137.103448 -51.298265) (xy 137.113518 -51.29784) (xy 137.80389 -51.29784) (xy 137.812272 -51.297078)
			(xy 137.819878 -51.295566) (xy 137.833715 -51.288583) (xy 137.83945 -51.283362) (xy 137.91946 -51.203352)
			(xy 137.91946 -49.20615) (xy 137.918862 -49.193827) (xy 137.907402 -49.17201) (xy 137.897616 -49.164494)
			(xy 137.833862 -49.120044) (xy 137.827361 -49.115866) (xy 137.812628 -49.111224) (xy 137.804906 -49.1109)
			(xy 137.782808 -49.1109) (xy 137.774934 -49.113694) (xy 137.74475 -49.123452) (xy 137.68219 -49.13393)
			(xy 137.650474 -49.134522) (xy 137.64641 -49.134522) (xy 137.619352 -49.133759) (xy 137.565851 -49.125532)
			(xy 137.51405 -49.109825) (xy 137.46499 -49.086952) (xy 137.419657 -49.057374) (xy 137.37896 -49.021684)
			(xy 137.343717 -48.980598) (xy 137.314637 -48.934944) (xy 137.292303 -48.885636) (xy 137.277163 -48.833667)
			(xy 137.269523 -48.780079) (xy 137.268966 -48.753014) (xy 137.269451 -48.725761) (xy 137.277206 -48.671811)
			(xy 137.292559 -48.619513) (xy 137.315199 -48.569932) (xy 137.344665 -48.524078) (xy 137.380356 -48.482884)
			(xy 137.421546 -48.447189) (xy 137.467397 -48.417718) (xy 137.516975 -48.395073) (xy 137.569272 -48.379714)
			(xy 137.623221 -48.371954) (xy 137.650474 -48.371506) (xy 137.651236 -48.371506) (xy 137.684852 -48.37226)
			(xy 137.751028 -48.384143) (xy 137.782808 -48.395128) (xy 137.794492 -48.399446) (xy 137.81913 -48.396398)
			(xy 137.897616 -48.341534) (xy 137.907276 -48.333917) (xy 137.918669 -48.312157) (xy 137.91946 -48.299878)
			(xy 137.91946 -41.95445) (xy 137.91893 -41.944459) (xy 137.911225 -41.926018) (xy 137.904474 -41.918636)
			(xy 137.023856 -41.038018) (xy 137.016744 -41.030652) (xy 136.997948 -41.023032) (xy 135.216392 -41.023032)
			(xy 135.20769 -41.023383) (xy 135.191286 -41.029198) (xy 135.177766 -41.040156) (xy 135.172958 -41.047416)
			(xy 135.128 -41.121584) (xy 135.123936 -41.13022) (xy 135.120611 -41.140526) (xy 135.122042 -41.162115)
			(xy 135.12673 -41.171876) (xy 135.127492 -41.1734) (xy 135.13181 -41.18229) (xy 135.143889 -41.20826)
			(xy 135.161002 -41.262918) (xy 135.169773 -41.319517) (xy 135.170418 -41.348152) (xy 135.170418 -41.34866)
			(xy 135.170418 -41.35501) (xy 135.169507 -41.383073) (xy 135.160461 -41.438486) (xy 135.14339 -41.491975)
			(xy 135.118662 -41.542384) (xy 135.086812 -41.588623) (xy 135.068056 -41.609518) (xy 135.067802 -41.609772)
			(xy 135.06133 -41.617127) (xy 135.054032 -41.63529) (xy 135.053578 -41.645078) (xy 135.053578 -41.724072)
			(xy 135.060436 -41.741852) (xy 135.067294 -41.748964) (xy 135.086562 -41.770291) (xy 135.119123 -41.817654)
			(xy 135.14421 -41.869364) (xy 135.161256 -41.924253) (xy 135.169876 -41.981079) (xy 135.169873 -42.038554)
			(xy 135.161249 -42.095378) (xy 135.144198 -42.150265) (xy 135.119107 -42.201974) (xy 135.086542 -42.249334)
			(xy 135.067294 -42.27068) (xy 135.060436 -42.277792) (xy 135.053578 -42.295572) (xy 135.053578 -42.384472)
			(xy 135.060436 -42.402252) (xy 135.067294 -42.409364) (xy 135.086563 -42.430692) (xy 135.119124 -42.478055)
			(xy 135.144211 -42.529767) (xy 135.161257 -42.584658) (xy 135.169876 -42.641484) (xy 135.170418 -42.670222)
			(xy 135.169945 -42.697592) (xy 135.162119 -42.751769) (xy 135.14663 -42.804271) (xy 135.123797 -42.854021)
			(xy 135.094087 -42.899996) (xy 135.076438 -42.92092) (xy 135.070342 -42.928032) (xy 135.063992 -42.944796)
			(xy 135.063992 -43.030648) (xy 135.070342 -43.047412) (xy 135.076438 -43.054524) (xy 135.094081 -43.075455)
			(xy 135.123809 -43.12142) (xy 135.146653 -43.171167) (xy 135.162143 -43.223671) (xy 135.169959 -43.277851)
			(xy 135.170418 -43.305222) (xy 135.169932 -43.332473) (xy 135.162176 -43.386421) (xy 135.146821 -43.438716)
			(xy 135.124179 -43.488293) (xy 135.094713 -43.534143) (xy 135.059022 -43.575334) (xy 135.017831 -43.611025)
			(xy 134.971981 -43.640491) (xy 134.922404 -43.663133) (xy 134.870109 -43.678488) (xy 134.816161 -43.686244)
			(xy 134.761659 -43.686244) (xy 134.707711 -43.678488) (xy 134.655416 -43.663133) (xy 134.605839 -43.640491)
			(xy 134.559989 -43.611025) (xy 134.518798 -43.575334) (xy 134.483107 -43.534143) (xy 134.453641 -43.488293)
			(xy 134.430999 -43.438716) (xy 134.415644 -43.386421) (xy 134.407888 -43.332473) (xy 134.407402 -43.305222)
			(xy 134.407879 -43.277854) (xy 134.415713 -43.223681) (xy 134.431209 -43.171184) (xy 134.454048 -43.12144)
			(xy 134.483762 -43.075472) (xy 134.501382 -43.054524) (xy 134.507478 -43.047412) (xy 134.513828 -43.030648)
			(xy 134.513828 -42.944796) (xy 134.507478 -42.928032) (xy 134.501382 -42.92092) (xy 134.48374 -42.899989)
			(xy 134.454013 -42.854022) (xy 134.431168 -42.804276) (xy 134.415676 -42.751772) (xy 134.407855 -42.697593)
			(xy 134.407402 -42.670222) (xy 134.407921 -42.641482) (xy 134.416541 -42.584653) (xy 134.433589 -42.52976)
			(xy 134.458679 -42.478045) (xy 134.491243 -42.43068) (xy 134.510526 -42.409364) (xy 134.517384 -42.402252)
			(xy 134.524242 -42.384472) (xy 134.524242 -42.295572) (xy 134.517384 -42.277792) (xy 134.510526 -42.27068)
			(xy 134.491253 -42.249353) (xy 134.458685 -42.20199) (xy 134.43359 -42.150278) (xy 134.416537 -42.095385)
			(xy 134.407911 -42.038556) (xy 134.407909 -41.981076) (xy 134.41653 -41.924246) (xy 134.433578 -41.869352)
			(xy 134.458669 -41.817637) (xy 134.491233 -41.770272) (xy 134.510526 -41.748964) (xy 134.517384 -41.741852)
			(xy 134.524242 -41.724072) (xy 134.524242 -41.635172) (xy 134.517384 -41.617646) (xy 134.510526 -41.61028)
			(xy 134.491726 -41.589486) (xy 134.459798 -41.543413) (xy 134.434943 -41.493168) (xy 134.417697 -41.439831)
			(xy 134.408429 -41.384547) (xy 134.407402 -41.356534) (xy 134.407402 -41.354248) (xy 134.407402 -41.349422)
			(xy 134.407926 -41.32057) (xy 134.416619 -41.263525) (xy 134.433822 -41.208446) (xy 134.44601 -41.18229)
			(xy 134.453122 -41.167558) (xy 134.456433 -41.158544) (xy 134.45683 -41.139359) (xy 134.453884 -41.13022)
			(xy 134.44982 -41.121584) (xy 134.404862 -41.04767) (xy 134.398004 -41.035986) (xy 134.37489 -41.023032)
			(xy 133.454394 -41.023032) (xy 133.442776 -41.023611) (xy 133.421894 -41.033808) (xy 133.414262 -41.04259)
			(xy 133.35762 -41.11498) (xy 133.352794 -41.137586) (xy 133.355588 -41.14927) (xy 133.36091 -41.171949)
			(xy 133.36664 -41.21818) (xy 133.367018 -41.241472) (xy 133.366557 -41.268726) (xy 133.358803 -41.322681)
			(xy 133.34345 -41.374983) (xy 133.320809 -41.424567) (xy 133.291342 -41.470425) (xy 133.255648 -41.511621)
			(xy 133.214455 -41.547319) (xy 133.168601 -41.576791) (xy 133.119018 -41.599437) (xy 133.066718 -41.614795)
			(xy 133.012764 -41.622554) (xy 132.98551 -41.62298) (xy 132.956771 -41.62246) (xy 132.899943 -41.613838)
			(xy 132.845051 -41.596788) (xy 132.793339 -41.571696) (xy 132.745976 -41.53913) (xy 132.724652 -41.519856)
			(xy 132.71754 -41.512998) (xy 132.69976 -41.50614) (xy 132.61086 -41.50614) (xy 132.59308 -41.512998)
			(xy 132.585968 -41.519856) (xy 132.56464 -41.539124) (xy 132.517275 -41.571684) (xy 132.465564 -41.596771)
			(xy 132.410674 -41.613819) (xy 132.353848 -41.622441) (xy 132.32511 -41.62298) (xy 132.297857 -41.622517)
			(xy 132.243907 -41.614761) (xy 132.191609 -41.599406) (xy 132.14203 -41.576764) (xy 132.096177 -41.547295)
			(xy 132.054986 -41.511601) (xy 132.019294 -41.470408) (xy 131.989828 -41.424554) (xy 131.967188 -41.374974)
			(xy 131.951835 -41.322675) (xy 131.944081 -41.268725) (xy 131.943602 -41.241472) (xy 131.943981 -41.21818)
			(xy 131.949712 -41.171949) (xy 131.955032 -41.14927) (xy 131.957826 -41.137586) (xy 131.953 -41.11498)
			(xy 131.896358 -41.04259) (xy 131.88877 -41.033755) (xy 131.86786 -41.023559) (xy 131.856226 -41.023032)
			(xy 128.008634 -41.023032) (xy 127.99857 -41.023468) (xy 127.979986 -41.031203) (xy 127.972566 -41.038018)
			(xy 127.805942 -41.204642) (xy 127.799202 -41.212013) (xy 127.791618 -41.230475) (xy 127.79121 -41.240456)
			(xy 127.79121 -43.73626) (xy 136.313162 -43.73626) (xy 136.317233 -43.680638) (xy 136.329359 -43.626201)
			(xy 136.349282 -43.57411) (xy 136.376578 -43.525475) (xy 136.410664 -43.481332) (xy 136.450813 -43.442623)
			(xy 136.496171 -43.410172) (xy 136.545771 -43.384671) (xy 136.598555 -43.366664) (xy 136.653398 -43.356534)
			(xy 136.709132 -43.354497) (xy 136.764569 -43.360597) (xy 136.818526 -43.374703) (xy 136.869855 -43.396515)
			(xy 136.917461 -43.425569) (xy 136.960329 -43.461244) (xy 136.997546 -43.502781) (xy 137.028319 -43.549294)
			(xy 137.051991 -43.599791) (xy 137.068059 -43.653198) (xy 137.076179 -43.708374) (xy 137.076688 -43.73626)
			(xy 137.076179 -43.764146) (xy 137.068059 -43.819322) (xy 137.051991 -43.872729) (xy 137.028319 -43.923226)
			(xy 136.997546 -43.969739) (xy 136.960329 -44.011276) (xy 136.917461 -44.046951) (xy 136.869855 -44.076005)
			(xy 136.818526 -44.097817) (xy 136.764569 -44.111923) (xy 136.709132 -44.118023) (xy 136.653398 -44.115986)
			(xy 136.598555 -44.105856) (xy 136.545771 -44.087849) (xy 136.496171 -44.062348) (xy 136.450813 -44.029897)
			(xy 136.410664 -43.991188) (xy 136.376578 -43.947045) (xy 136.349282 -43.89841) (xy 136.329359 -43.846319)
			(xy 136.317233 -43.791882) (xy 136.313162 -43.73626) (xy 127.79121 -43.73626) (xy 127.79121 -45.114464)
			(xy 136.165588 -45.114464) (xy 136.169659 -45.058842) (xy 136.181785 -45.004405) (xy 136.201708 -44.952314)
			(xy 136.229004 -44.903679) (xy 136.26309 -44.859536) (xy 136.303239 -44.820827) (xy 136.348597 -44.788376)
			(xy 136.398197 -44.762875) (xy 136.450981 -44.744868) (xy 136.505824 -44.734738) (xy 136.561558 -44.732701)
			(xy 136.616995 -44.738801) (xy 136.670952 -44.752907) (xy 136.722281 -44.774719) (xy 136.769887 -44.803773)
			(xy 136.812755 -44.839448) (xy 136.849972 -44.880985) (xy 136.880745 -44.927498) (xy 136.904417 -44.977995)
			(xy 136.920485 -45.031402) (xy 136.928605 -45.086578) (xy 136.929114 -45.114464) (xy 136.928605 -45.14235)
			(xy 136.920485 -45.197526) (xy 136.904417 -45.250933) (xy 136.880745 -45.30143) (xy 136.849972 -45.347943)
			(xy 136.812755 -45.38948) (xy 136.769887 -45.425155) (xy 136.722281 -45.454209) (xy 136.670952 -45.476021)
			(xy 136.616995 -45.490127) (xy 136.561558 -45.496227) (xy 136.505824 -45.49419) (xy 136.450981 -45.48406)
			(xy 136.398197 -45.466053) (xy 136.348597 -45.440552) (xy 136.303239 -45.408101) (xy 136.26309 -45.369392)
			(xy 136.229004 -45.325249) (xy 136.201708 -45.276614) (xy 136.181785 -45.224523) (xy 136.169659 -45.170086)
			(xy 136.165588 -45.114464) (xy 127.79121 -45.114464) (xy 127.79121 -46.893226) (xy 136.437368 -46.893226)
			(xy 136.441439 -46.837604) (xy 136.453565 -46.783167) (xy 136.473488 -46.731076) (xy 136.500784 -46.682441)
			(xy 136.53487 -46.638298) (xy 136.575019 -46.599589) (xy 136.620377 -46.567138) (xy 136.669977 -46.541637)
			(xy 136.722761 -46.52363) (xy 136.777604 -46.5135) (xy 136.833338 -46.511463) (xy 136.888775 -46.517563)
			(xy 136.942732 -46.531669) (xy 136.994061 -46.553481) (xy 137.041667 -46.582535) (xy 137.084535 -46.61821)
			(xy 137.121752 -46.659747) (xy 137.152525 -46.70626) (xy 137.176197 -46.756757) (xy 137.192265 -46.810164)
			(xy 137.200385 -46.86534) (xy 137.200894 -46.893226) (xy 137.200385 -46.921112) (xy 137.192265 -46.976288)
			(xy 137.176197 -47.029695) (xy 137.152525 -47.080192) (xy 137.121752 -47.126705) (xy 137.084535 -47.168242)
			(xy 137.041667 -47.203917) (xy 136.994061 -47.232971) (xy 136.942732 -47.254783) (xy 136.888775 -47.268889)
			(xy 136.833338 -47.274989) (xy 136.777604 -47.272952) (xy 136.722761 -47.262822) (xy 136.669977 -47.244815)
			(xy 136.620377 -47.219314) (xy 136.575019 -47.186863) (xy 136.53487 -47.148154) (xy 136.500784 -47.104011)
			(xy 136.473488 -47.055376) (xy 136.453565 -47.003285) (xy 136.441439 -46.948848) (xy 136.437368 -46.893226)
			(xy 127.79121 -46.893226) (xy 127.79121 -47.936658) (xy 134.753096 -47.936658) (xy 134.753582 -47.909407)
			(xy 134.761338 -47.855459) (xy 134.776693 -47.803164) (xy 134.799335 -47.753587) (xy 134.828801 -47.707737)
			(xy 134.864492 -47.666546) (xy 134.905683 -47.630855) (xy 134.951533 -47.601389) (xy 135.00111 -47.578747)
			(xy 135.053405 -47.563392) (xy 135.107353 -47.555636) (xy 135.161855 -47.555636) (xy 135.215803 -47.563392)
			(xy 135.268098 -47.578747) (xy 135.317675 -47.601389) (xy 135.363525 -47.630855) (xy 135.404716 -47.666546)
			(xy 135.440407 -47.707737) (xy 135.469873 -47.753587) (xy 135.492515 -47.803164) (xy 135.50787 -47.855459)
			(xy 135.515626 -47.909407) (xy 135.516112 -47.936658) (xy 135.515667 -47.963) (xy 135.508416 -48.015181)
			(xy 135.49406 -48.065871) (xy 135.47287 -48.114105) (xy 135.445251 -48.158968) (xy 135.411726 -48.199607)
			(xy 135.372931 -48.235252) (xy 135.35152 -48.250602) (xy 135.339699 -48.2593) (xy 135.321266 -48.282126)
			(xy 135.310085 -48.30925) (xy 135.307078 -48.338435) (xy 135.312493 -48.367269) (xy 135.325884 -48.393374)
			(xy 135.346144 -48.414593) (xy 135.358632 -48.422306) (xy 135.383181 -48.436979) (xy 135.427937 -48.472587)
			(xy 135.466878 -48.514475) (xy 135.499131 -48.561705) (xy 135.523975 -48.61322) (xy 135.540852 -48.667865)
			(xy 135.549385 -48.724418) (xy 135.549894 -48.753014) (xy 135.549408 -48.780265) (xy 135.541652 -48.834213)
			(xy 135.526297 -48.886508) (xy 135.503655 -48.936085) (xy 135.474189 -48.981935) (xy 135.438498 -49.023126)
			(xy 135.397307 -49.058817) (xy 135.351457 -49.088283) (xy 135.30188 -49.110925) (xy 135.249585 -49.12628)
			(xy 135.195637 -49.134036) (xy 135.141135 -49.134036) (xy 135.087187 -49.12628) (xy 135.034892 -49.110925)
			(xy 134.985315 -49.088283) (xy 134.939465 -49.058817) (xy 134.898274 -49.023126) (xy 134.862583 -48.981935)
			(xy 134.833117 -48.936085) (xy 134.810475 -48.886508) (xy 134.79512 -48.834213) (xy 134.787364 -48.780265)
			(xy 134.786878 -48.753014) (xy 134.787306 -48.726672) (xy 134.794561 -48.67449) (xy 134.80892 -48.6238)
			(xy 134.830113 -48.575566) (xy 134.857735 -48.530703) (xy 134.891262 -48.490064) (xy 134.930058 -48.45442)
			(xy 134.95147 -48.43907) (xy 134.963321 -48.430408) (xy 134.981756 -48.407575) (xy 134.992937 -48.380442)
			(xy 134.995941 -48.351249) (xy 134.99052 -48.322408) (xy 134.977121 -48.296299) (xy 134.95685 -48.275078)
			(xy 134.944358 -48.267366) (xy 134.919839 -48.252646) (xy 134.875083 -48.217045) (xy 134.836142 -48.175165)
			(xy 134.803885 -48.127943) (xy 134.779037 -48.076436) (xy 134.762152 -48.021798) (xy 134.75361 -47.965252)
			(xy 134.753096 -47.936658) (xy 127.79121 -47.936658) (xy 127.79121 -58.731404) (xy 129.620772 -58.731404)
			(xy 129.621223 -58.704033) (xy 129.629042 -58.649853) (xy 129.644533 -58.597349) (xy 129.667379 -58.547602)
			(xy 129.697108 -58.501636) (xy 129.714752 -58.480706) (xy 129.720848 -58.473594) (xy 129.727198 -58.456576)
			(xy 129.727198 -58.371232) (xy 129.720848 -58.354214) (xy 129.714752 -58.347102) (xy 129.697114 -58.326167)
			(xy 129.667387 -58.2802) (xy 129.64454 -58.230454) (xy 129.629043 -58.177952) (xy 129.621213 -58.123774)
			(xy 129.621213 -58.069032) (xy 129.629041 -58.014854) (xy 129.644538 -57.962351) (xy 129.667384 -57.912605)
			(xy 129.697111 -57.866638) (xy 129.714752 -57.845706) (xy 129.720848 -57.838594) (xy 129.727198 -57.821576)
			(xy 129.727198 -57.736232) (xy 129.720848 -57.719214) (xy 129.714752 -57.712102) (xy 129.697114 -57.691167)
			(xy 129.667387 -57.6452) (xy 129.64454 -57.595454) (xy 129.629043 -57.542952) (xy 129.621213 -57.488774)
			(xy 129.621213 -57.434032) (xy 129.629041 -57.379854) (xy 129.644538 -57.327351) (xy 129.667384 -57.277605)
			(xy 129.697111 -57.231638) (xy 129.714752 -57.210706) (xy 129.720848 -57.203594) (xy 129.727198 -57.186576)
			(xy 129.727198 -57.101232) (xy 129.720848 -57.084214) (xy 129.714752 -57.077102) (xy 129.697108 -57.056173)
			(xy 129.667396 -57.0102) (xy 129.64456 -56.960452) (xy 129.62907 -56.90795) (xy 129.621244 -56.853774)
			(xy 129.620772 -56.826404) (xy 129.621258 -56.799153) (xy 129.629014 -56.745205) (xy 129.644369 -56.69291)
			(xy 129.667011 -56.643333) (xy 129.696477 -56.597483) (xy 129.732168 -56.556292) (xy 129.773359 -56.520601)
			(xy 129.819209 -56.491135) (xy 129.868786 -56.468493) (xy 129.921081 -56.453138) (xy 129.975029 -56.445382)
			(xy 130.029531 -56.445382) (xy 130.083479 -56.453138) (xy 130.135774 -56.468493) (xy 130.185351 -56.491135)
			(xy 130.231201 -56.520601) (xy 130.272392 -56.556292) (xy 130.308083 -56.597483) (xy 130.337549 -56.643333)
			(xy 130.360191 -56.69291) (xy 130.375546 -56.745205) (xy 130.383302 -56.799153) (xy 130.383788 -56.826404)
			(xy 130.383327 -56.853774) (xy 130.375509 -56.907954) (xy 130.360018 -56.960457) (xy 130.337175 -57.010204)
			(xy 130.30745 -57.056171) (xy 130.289808 -57.077102) (xy 130.283712 -57.084214) (xy 130.277362 -57.101232)
			(xy 130.277362 -57.186576) (xy 130.283712 -57.203594) (xy 130.289808 -57.210706) (xy 130.307451 -57.231636)
			(xy 130.337173 -57.277605) (xy 130.360016 -57.327352) (xy 130.375511 -57.379854) (xy 130.383338 -57.434033)
			(xy 130.383338 -57.488773) (xy 130.375509 -57.542952) (xy 130.360014 -57.595453) (xy 130.33717 -57.6452)
			(xy 130.307448 -57.691169) (xy 130.289808 -57.712102) (xy 130.283712 -57.719214) (xy 130.277362 -57.736232)
			(xy 130.277362 -57.821576) (xy 130.283712 -57.838594) (xy 130.289808 -57.845706) (xy 130.307451 -57.866636)
			(xy 130.337173 -57.912605) (xy 130.360016 -57.962352) (xy 130.375511 -58.014854) (xy 130.383338 -58.069033)
			(xy 130.383338 -58.123773) (xy 130.375509 -58.177952) (xy 130.360014 -58.230453) (xy 130.33717 -58.2802)
			(xy 130.307448 -58.326169) (xy 130.289808 -58.347102) (xy 130.283712 -58.354214) (xy 130.277362 -58.371232)
			(xy 130.277362 -58.456576) (xy 130.283712 -58.473594) (xy 130.289808 -58.480706) (xy 130.307465 -58.501624)
			(xy 130.337174 -58.547601) (xy 130.360006 -58.597352) (xy 130.375493 -58.649856) (xy 130.383316 -58.704034)
			(xy 130.383788 -58.731404) (xy 130.383302 -58.758655) (xy 130.378638 -58.791094) (xy 132.276596 -58.791094)
			(xy 132.27706 -58.763724) (xy 132.284878 -58.709545) (xy 132.300368 -58.657041) (xy 132.32321 -58.607295)
			(xy 132.352935 -58.561328) (xy 132.370576 -58.540396) (xy 132.376672 -58.533284) (xy 132.383022 -58.516266)
			(xy 132.383022 -58.430922) (xy 132.376672 -58.413904) (xy 132.370576 -58.406792) (xy 132.352927 -58.385865)
			(xy 132.323199 -58.339897) (xy 132.300351 -58.290151) (xy 132.284853 -58.237647) (xy 132.277024 -58.183467)
			(xy 132.277025 -58.128724) (xy 132.284855 -58.074544) (xy 132.300354 -58.022041) (xy 132.323203 -57.972295)
			(xy 132.352933 -57.926328) (xy 132.370576 -57.905396) (xy 132.376672 -57.898284) (xy 132.383022 -57.881266)
			(xy 132.383022 -57.795922) (xy 132.376672 -57.778904) (xy 132.370576 -57.771792) (xy 132.352916 -57.750877)
			(xy 132.323208 -57.704899) (xy 132.300377 -57.655147) (xy 132.28489 -57.602643) (xy 132.277067 -57.548464)
			(xy 132.276596 -57.521094) (xy 132.277067 -57.494779) (xy 132.284283 -57.442645) (xy 132.298593 -57.391998)
			(xy 132.319724 -57.343796) (xy 132.347276 -57.298953) (xy 132.380727 -57.258321) (xy 132.399786 -57.24017)
			(xy 132.407201 -57.23266) (xy 132.415718 -57.213371) (xy 132.416296 -57.202832) (xy 132.416296 -57.128156)
			(xy 132.415752 -57.117608) (xy 132.407227 -57.098312) (xy 132.399786 -57.090818) (xy 132.380713 -57.072677)
			(xy 132.347235 -57.032058) (xy 132.319664 -56.987219) (xy 132.298524 -56.939012) (xy 132.284218 -56.888356)
			(xy 132.277018 -56.836213) (xy 132.276596 -56.809894) (xy 132.277082 -56.782643) (xy 132.284838 -56.728695)
			(xy 132.300193 -56.6764) (xy 132.322835 -56.626823) (xy 132.352301 -56.580973) (xy 132.387992 -56.539782)
			(xy 132.429183 -56.504091) (xy 132.475033 -56.474625) (xy 132.52461 -56.451983) (xy 132.576905 -56.436628)
			(xy 132.630853 -56.428872) (xy 132.685355 -56.428872) (xy 132.739303 -56.436628) (xy 132.791598 -56.451983)
			(xy 132.841175 -56.474625) (xy 132.887025 -56.504091) (xy 132.928216 -56.539782) (xy 132.963907 -56.580973)
			(xy 132.993373 -56.626823) (xy 133.016015 -56.6764) (xy 133.03137 -56.728695) (xy 133.039126 -56.782643)
			(xy 133.039612 -56.809894) (xy 133.039198 -56.836211) (xy 133.031969 -56.888347) (xy 133.017648 -56.938996)
			(xy 132.996506 -56.987197) (xy 132.968945 -57.032038) (xy 132.935485 -57.072669) (xy 132.916422 -57.090818)
			(xy 132.909014 -57.098334) (xy 132.900492 -57.117618) (xy 132.899912 -57.128156) (xy 132.899912 -57.202832)
			(xy 132.900461 -57.213379) (xy 132.908982 -57.232675) (xy 132.916422 -57.24017) (xy 132.935472 -57.258335)
			(xy 132.968956 -57.298947) (xy 132.996532 -57.343781) (xy 133.017676 -57.391982) (xy 133.031986 -57.442636)
			(xy 133.035359 -57.467049) (xy 133.218692 -57.467049) (xy 133.218692 -57.412551) (xy 133.226448 -57.358607)
			(xy 133.241802 -57.306315) (xy 133.264441 -57.256741) (xy 133.293904 -57.210893) (xy 133.329592 -57.169705)
			(xy 133.370779 -57.134015) (xy 133.416625 -57.104549) (xy 133.466198 -57.081908) (xy 133.518489 -57.066552)
			(xy 133.572433 -57.058793) (xy 133.599682 -57.058306) (xy 133.625999 -57.058723) (xy 133.678135 -57.06595)
			(xy 133.728784 -57.08027) (xy 133.776986 -57.101411) (xy 133.821827 -57.128973) (xy 133.862457 -57.162433)
			(xy 133.880606 -57.181496) (xy 133.888124 -57.188902) (xy 133.907407 -57.197424) (xy 133.917944 -57.198006)
			(xy 133.99262 -57.198006) (xy 134.003166 -57.197445) (xy 134.022462 -57.188932) (xy 134.029958 -57.181496)
			(xy 134.048112 -57.162436) (xy 134.088729 -57.128957) (xy 134.133565 -57.101384) (xy 134.181769 -57.080242)
			(xy 134.232423 -57.065933) (xy 134.284564 -57.05873) (xy 134.310882 -57.058306) (xy 134.338137 -57.05874)
			(xy 134.392092 -57.066495) (xy 134.427356 -57.076848) (xy 135.238744 -57.076848) (xy 135.239227 -57.049478)
			(xy 135.247039 -56.9953) (xy 135.262524 -56.942796) (xy 135.285362 -56.893049) (xy 135.315084 -56.847082)
			(xy 135.332724 -56.82615) (xy 135.33882 -56.819038) (xy 135.34517 -56.80202) (xy 135.34517 -56.716676)
			(xy 135.33882 -56.699658) (xy 135.332724 -56.692546) (xy 135.315097 -56.671604) (xy 135.285382 -56.625635)
			(xy 135.262544 -56.57589) (xy 135.24705 -56.523391) (xy 135.239219 -56.469217) (xy 135.238744 -56.441848)
			(xy 135.23923 -56.414597) (xy 135.246986 -56.360649) (xy 135.262341 -56.308354) (xy 135.284983 -56.258777)
			(xy 135.314449 -56.212927) (xy 135.35014 -56.171736) (xy 135.391331 -56.136045) (xy 135.437181 -56.106579)
			(xy 135.486758 -56.083937) (xy 135.539053 -56.068582) (xy 135.593001 -56.060826) (xy 135.647503 -56.060826)
			(xy 135.701451 -56.068582) (xy 135.753746 -56.083937) (xy 135.803323 -56.106579) (xy 135.849173 -56.136045)
			(xy 135.890364 -56.171736) (xy 135.926055 -56.212927) (xy 135.955521 -56.258777) (xy 135.978163 -56.308354)
			(xy 135.993518 -56.360649) (xy 136.001274 -56.414597) (xy 136.00176 -56.441848) (xy 136.001273 -56.469218)
			(xy 135.993462 -56.523396) (xy 135.977978 -56.575899) (xy 135.955141 -56.625647) (xy 135.92542 -56.671614)
			(xy 135.90778 -56.692546) (xy 135.901684 -56.699658) (xy 135.895334 -56.716676) (xy 135.895334 -56.80202)
			(xy 135.901684 -56.819038) (xy 135.90778 -56.82615) (xy 135.925406 -56.847093) (xy 135.95512 -56.893062)
			(xy 135.977959 -56.942807) (xy 135.993453 -56.995305) (xy 136.001285 -57.04948) (xy 136.00176 -57.076848)
			(xy 136.001274 -57.104099) (xy 135.993518 -57.158047) (xy 135.978163 -57.210342) (xy 135.955521 -57.259919)
			(xy 135.926055 -57.305769) (xy 135.890364 -57.34696) (xy 135.849173 -57.382651) (xy 135.803323 -57.412117)
			(xy 135.753746 -57.434759) (xy 135.701451 -57.450114) (xy 135.647503 -57.45787) (xy 135.593001 -57.45787)
			(xy 135.539053 -57.450114) (xy 135.486758 -57.434759) (xy 135.437181 -57.412117) (xy 135.391331 -57.382651)
			(xy 135.35014 -57.34696) (xy 135.314449 -57.305769) (xy 135.284983 -57.259919) (xy 135.262341 -57.210342)
			(xy 135.246986 -57.158047) (xy 135.23923 -57.104099) (xy 135.238744 -57.076848) (xy 134.427356 -57.076848)
			(xy 134.444394 -57.08185) (xy 134.493978 -57.104492) (xy 134.539835 -57.133961) (xy 134.581031 -57.169656)
			(xy 134.616728 -57.210851) (xy 134.646199 -57.256706) (xy 134.668844 -57.306289) (xy 134.684201 -57.358591)
			(xy 134.691959 -57.412545) (xy 134.691959 -57.467055) (xy 134.684201 -57.521009) (xy 134.668844 -57.573311)
			(xy 134.646199 -57.622894) (xy 134.616728 -57.668749) (xy 134.581031 -57.709944) (xy 134.539835 -57.745639)
			(xy 134.493978 -57.775108) (xy 134.444394 -57.79775) (xy 134.392092 -57.813105) (xy 134.338137 -57.82086)
			(xy 134.310882 -57.821322) (xy 134.284567 -57.820854) (xy 134.232433 -57.813636) (xy 134.181786 -57.799325)
			(xy 134.133584 -57.778194) (xy 134.088742 -57.750641) (xy 134.048109 -57.717191) (xy 134.029958 -57.698132)
			(xy 134.02245 -57.690714) (xy 134.00316 -57.682198) (xy 133.99262 -57.681622) (xy 133.917944 -57.681622)
			(xy 133.907395 -57.682155) (xy 133.888099 -57.690687) (xy 133.880606 -57.698132) (xy 133.862455 -57.717196)
			(xy 133.82184 -57.750678) (xy 133.777003 -57.778252) (xy 133.728798 -57.799394) (xy 133.678143 -57.813701)
			(xy 133.626001 -57.820901) (xy 133.599682 -57.821322) (xy 133.572433 -57.820807) (xy 133.518489 -57.813048)
			(xy 133.466198 -57.797692) (xy 133.416625 -57.775051) (xy 133.370779 -57.745585) (xy 133.329592 -57.709895)
			(xy 133.293904 -57.668707) (xy 133.264441 -57.622859) (xy 133.241802 -57.573285) (xy 133.226448 -57.520994)
			(xy 133.218692 -57.467049) (xy 133.035359 -57.467049) (xy 133.039189 -57.494776) (xy 133.039612 -57.521094)
			(xy 133.039139 -57.548464) (xy 133.031323 -57.602643) (xy 133.015835 -57.655146) (xy 132.992995 -57.704893)
			(xy 132.963272 -57.75086) (xy 132.945632 -57.771792) (xy 132.939536 -57.778904) (xy 132.933186 -57.795922)
			(xy 132.933186 -57.881266) (xy 132.939536 -57.898284) (xy 132.945632 -57.905396) (xy 132.963269 -57.926333)
			(xy 132.992997 -57.972299) (xy 133.015845 -58.022044) (xy 133.031343 -58.074546) (xy 133.039173 -58.128725)
			(xy 133.039174 -58.183466) (xy 133.031345 -58.237645) (xy 133.015848 -58.290147) (xy 132.993001 -58.339893)
			(xy 132.963274 -58.38586) (xy 132.945632 -58.406792) (xy 132.939536 -58.413904) (xy 132.933186 -58.430922)
			(xy 132.933186 -58.516266) (xy 132.939536 -58.533284) (xy 132.945632 -58.540396) (xy 132.963288 -58.561315)
			(xy 132.992996 -58.607292) (xy 133.015828 -58.657043) (xy 133.031315 -58.709546) (xy 133.03914 -58.763724)
			(xy 133.039612 -58.791094) (xy 133.039126 -58.818345) (xy 133.03137 -58.872293) (xy 133.030973 -58.873644)
			(xy 134.300722 -58.873644) (xy 134.301208 -58.846274) (xy 134.309021 -58.792096) (xy 134.324505 -58.739593)
			(xy 134.347342 -58.689846) (xy 134.377063 -58.643878) (xy 134.394702 -58.622946) (xy 134.400798 -58.615834)
			(xy 134.407148 -58.598816) (xy 134.407148 -58.513472) (xy 134.400798 -58.496454) (xy 134.394702 -58.489342)
			(xy 134.377069 -58.468405) (xy 134.347357 -58.422433) (xy 134.324519 -58.372687) (xy 134.309027 -58.320188)
			(xy 134.301197 -58.266013) (xy 134.300722 -58.238644) (xy 134.301208 -58.211393) (xy 134.308964 -58.157445)
			(xy 134.324319 -58.10515) (xy 134.346961 -58.055573) (xy 134.376427 -58.009723) (xy 134.412118 -57.968532)
			(xy 134.453309 -57.932841) (xy 134.499159 -57.903375) (xy 134.548736 -57.880733) (xy 134.601031 -57.865378)
			(xy 134.654979 -57.857622) (xy 134.709481 -57.857622) (xy 134.763429 -57.865378) (xy 134.815724 -57.880733)
			(xy 134.865301 -57.903375) (xy 134.911151 -57.932841) (xy 134.952342 -57.968532) (xy 134.988033 -58.009723)
			(xy 135.017499 -58.055573) (xy 135.040141 -58.10515) (xy 135.055496 -58.157445) (xy 135.063252 -58.211393)
			(xy 135.063738 -58.238644) (xy 135.063254 -58.266014) (xy 135.055443 -58.320193) (xy 135.039959 -58.372696)
			(xy 135.017121 -58.422443) (xy 134.987398 -58.46841) (xy 134.969758 -58.489342) (xy 134.963662 -58.496454)
			(xy 134.957312 -58.513472) (xy 134.957312 -58.598816) (xy 134.963662 -58.615834) (xy 134.969758 -58.622946)
			(xy 134.987379 -58.643893) (xy 135.017095 -58.689861) (xy 135.039935 -58.739605) (xy 135.05543 -58.792102)
			(xy 135.063262 -58.846276) (xy 135.063738 -58.873644) (xy 135.063252 -58.900895) (xy 135.055496 -58.954843)
			(xy 135.040141 -59.007138) (xy 135.017499 -59.056715) (xy 134.988033 -59.102565) (xy 134.952342 -59.143756)
			(xy 134.911151 -59.179447) (xy 134.865301 -59.208913) (xy 134.815724 -59.231555) (xy 134.763429 -59.24691)
			(xy 134.709481 -59.254666) (xy 134.654979 -59.254666) (xy 134.601031 -59.24691) (xy 134.548736 -59.231555)
			(xy 134.499159 -59.208913) (xy 134.453309 -59.179447) (xy 134.412118 -59.143756) (xy 134.376427 -59.102565)
			(xy 134.346961 -59.056715) (xy 134.324319 -59.007138) (xy 134.308964 -58.954843) (xy 134.301208 -58.900895)
			(xy 134.300722 -58.873644) (xy 133.030973 -58.873644) (xy 133.016015 -58.924588) (xy 132.993373 -58.974165)
			(xy 132.963907 -59.020015) (xy 132.928216 -59.061206) (xy 132.887025 -59.096897) (xy 132.841175 -59.126363)
			(xy 132.791598 -59.149005) (xy 132.739303 -59.16436) (xy 132.685355 -59.172116) (xy 132.630853 -59.172116)
			(xy 132.576905 -59.16436) (xy 132.52461 -59.149005) (xy 132.475033 -59.126363) (xy 132.429183 -59.096897)
			(xy 132.387992 -59.061206) (xy 132.352301 -59.020015) (xy 132.322835 -58.974165) (xy 132.300193 -58.924588)
			(xy 132.284838 -58.872293) (xy 132.277082 -58.818345) (xy 132.276596 -58.791094) (xy 130.378638 -58.791094)
			(xy 130.375546 -58.812603) (xy 130.360191 -58.864898) (xy 130.337549 -58.914475) (xy 130.308083 -58.960325)
			(xy 130.272392 -59.001516) (xy 130.231201 -59.037207) (xy 130.185351 -59.066673) (xy 130.135774 -59.089315)
			(xy 130.083479 -59.10467) (xy 130.029531 -59.112426) (xy 129.975029 -59.112426) (xy 129.921081 -59.10467)
			(xy 129.868786 -59.089315) (xy 129.819209 -59.066673) (xy 129.773359 -59.037207) (xy 129.732168 -59.001516)
			(xy 129.696477 -58.960325) (xy 129.667011 -58.914475) (xy 129.644369 -58.864898) (xy 129.629014 -58.812603)
			(xy 129.621258 -58.758655) (xy 129.620772 -58.731404) (xy 127.79121 -58.731404) (xy 127.79121 -60.126453)
			(xy 133.280349 -60.126453) (xy 133.280349 -60.071947) (xy 133.288107 -60.017994) (xy 133.303463 -59.965695)
			(xy 133.326106 -59.916114) (xy 133.355575 -59.87026) (xy 133.39127 -59.829067) (xy 133.432463 -59.793373)
			(xy 133.478318 -59.763904) (xy 133.527899 -59.741262) (xy 133.580198 -59.725906) (xy 133.634151 -59.718149)
			(xy 133.661404 -59.717686) (xy 133.688774 -59.718153) (xy 133.742953 -59.725971) (xy 133.795456 -59.74146)
			(xy 133.845203 -59.764302) (xy 133.89117 -59.794025) (xy 133.912102 -59.811666) (xy 133.919214 -59.817762)
			(xy 133.936232 -59.824112) (xy 134.021576 -59.824112) (xy 134.038594 -59.817762) (xy 134.045706 -59.811666)
			(xy 134.066639 -59.794025) (xy 134.112607 -59.764301) (xy 134.162353 -59.741455) (xy 134.214855 -59.725959)
			(xy 134.269033 -59.71813) (xy 134.323775 -59.71813) (xy 134.377953 -59.725959) (xy 134.430455 -59.741455)
			(xy 134.480201 -59.764301) (xy 134.526169 -59.794025) (xy 134.547102 -59.811666) (xy 134.554214 -59.817762)
			(xy 134.571232 -59.824112) (xy 134.656576 -59.824112) (xy 134.673594 -59.817762) (xy 134.680706 -59.811666)
			(xy 134.701621 -59.794005) (xy 134.747599 -59.764298) (xy 134.797351 -59.741467) (xy 134.849855 -59.725981)
			(xy 134.904034 -59.718157) (xy 134.931404 -59.717686) (xy 134.958655 -59.718184) (xy 135.012601 -59.725941)
			(xy 135.064895 -59.741296) (xy 135.11447 -59.763937) (xy 135.16032 -59.793403) (xy 135.201509 -59.829094)
			(xy 135.237199 -59.870284) (xy 135.266665 -59.916133) (xy 135.289305 -59.965709) (xy 135.30466 -60.018003)
			(xy 135.312416 -60.071949) (xy 135.312416 -60.126451) (xy 135.30466 -60.180397) (xy 135.289305 -60.232691)
			(xy 135.266665 -60.282267) (xy 135.237199 -60.328116) (xy 135.201509 -60.369306) (xy 135.16032 -60.404997)
			(xy 135.11447 -60.434463) (xy 135.064895 -60.457104) (xy 135.012601 -60.472459) (xy 134.958655 -60.480216)
			(xy 134.931404 -60.480702) (xy 134.904034 -60.480233) (xy 134.849855 -60.472416) (xy 134.797352 -60.456927)
			(xy 134.747605 -60.434086) (xy 134.701638 -60.404363) (xy 134.680706 -60.386722) (xy 134.673594 -60.380626)
			(xy 134.656576 -60.374276) (xy 134.571232 -60.374276) (xy 134.554214 -60.380626) (xy 134.547102 -60.386722)
			(xy 134.526169 -60.404363) (xy 134.480201 -60.434087) (xy 134.430455 -60.456933) (xy 134.377953 -60.472429)
			(xy 134.323775 -60.480258) (xy 134.269033 -60.480258) (xy 134.214855 -60.472429) (xy 134.162353 -60.456933)
			(xy 134.112607 -60.434087) (xy 134.066639 -60.404363) (xy 134.045706 -60.386722) (xy 134.038594 -60.380626)
			(xy 134.021576 -60.374276) (xy 133.936232 -60.374276) (xy 133.919214 -60.380626) (xy 133.912102 -60.386722)
			(xy 133.891183 -60.404377) (xy 133.845206 -60.434086) (xy 133.795455 -60.456918) (xy 133.742952 -60.472406)
			(xy 133.688774 -60.48023) (xy 133.661404 -60.480702) (xy 133.634151 -60.480251) (xy 133.580198 -60.472494)
			(xy 133.527899 -60.457138) (xy 133.478318 -60.434496) (xy 133.432463 -60.405027) (xy 133.39127 -60.369333)
			(xy 133.355575 -60.32814) (xy 133.326106 -60.282286) (xy 133.303463 -60.232705) (xy 133.288107 -60.180406)
			(xy 133.280349 -60.126453) (xy 127.79121 -60.126453) (xy 127.79121 -60.999878) (xy 127.790677 -61.009867)
			(xy 127.78297 -61.028306) (xy 127.776224 -61.035692) (xy 127.000508 -61.811408) (xy 126.993152 -61.818057)
			(xy 126.974851 -61.825639) (xy 126.964948 -61.82614) (xy 125.178058 -61.82614) (xy 125.166397 -61.826721)
			(xy 125.145491 -61.837057) (xy 125.137926 -61.845952) (xy 125.089158 -61.909706) (xy 125.08348 -61.917895)
			(xy 125.078258 -61.937106) (xy 125.078998 -61.947044) (xy 125.080014 -61.953648) (xy 125.080776 -61.956696)
			(xy 125.086324 -61.979795) (xy 125.09231 -62.026923) (xy 125.092714 -62.050676) (xy 125.092714 -62.054486)
			(xy 125.092019 -62.081593) (xy 125.083908 -62.135208) (xy 125.068287 -62.187133) (xy 125.045472 -62.236324)
			(xy 125.015922 -62.28179) (xy 124.980232 -62.322613) (xy 124.939122 -62.357972) (xy 124.89342 -62.387154)
			(xy 124.844046 -62.409571) (xy 124.791996 -62.424772) (xy 124.738318 -62.43245) (xy 124.711206 -62.432946)
			(xy 124.687651 -62.432567) (xy 124.640906 -62.426712) (xy 124.617988 -62.421262) (xy 124.603764 -62.417706)
			(xy 124.576586 -62.426342) (xy 124.498354 -62.517274) (xy 124.493782 -62.545468) (xy 124.49937 -62.55893)
			(xy 124.508696 -62.582314) (xy 124.521817 -62.630918) (xy 124.528435 -62.680824) (xy 124.528834 -62.705996)
			(xy 124.528349 -62.733248) (xy 124.520593 -62.787198) (xy 124.505238 -62.839494) (xy 124.482598 -62.889074)
			(xy 124.453132 -62.934927) (xy 124.417441 -62.976119) (xy 124.376251 -63.011814) (xy 124.3304 -63.041283)
			(xy 124.280823 -63.063928) (xy 124.228527 -63.079286) (xy 124.174578 -63.087046) (xy 124.147326 -63.087504)
			(xy 124.118516 -63.086979) (xy 124.061551 -63.078313) (xy 124.006538 -63.061175) (xy 123.954731 -63.035954)
			(xy 123.907308 -63.003226) (xy 123.88596 -62.983872) (xy 123.877324 -62.975744) (xy 123.85548 -62.968886)
			(xy 123.765564 -62.981332) (xy 123.763532 -62.981586) (xy 123.752794 -62.984093) (xy 123.734754 -62.996732)
			(xy 123.728734 -63.00597) (xy 123.713917 -63.03009) (xy 123.678278 -63.07407) (xy 123.63653 -63.112298)
			(xy 123.58959 -63.143936) (xy 123.538489 -63.168287) (xy 123.484349 -63.184818) (xy 123.428362 -63.193164)
			(xy 123.400058 -63.193676) (xy 123.372811 -63.193187) (xy 123.318872 -63.185426) (xy 123.266587 -63.170069)
			(xy 123.217019 -63.147427) (xy 123.171178 -63.117962) (xy 123.129997 -63.082274) (xy 123.094313 -63.041088)
			(xy 123.064853 -62.995244) (xy 123.042217 -62.945673) (xy 123.026865 -62.893386) (xy 123.01911 -62.839447)
			(xy 123.01911 -62.784953) (xy 123.026865 -62.731014) (xy 123.042217 -62.678727) (xy 123.064853 -62.629156)
			(xy 123.094313 -62.583312) (xy 123.129997 -62.542126) (xy 123.171178 -62.506438) (xy 123.217019 -62.476973)
			(xy 123.266587 -62.454331) (xy 123.318872 -62.438974) (xy 123.372811 -62.431213) (xy 123.400058 -62.43066)
			(xy 123.428869 -62.431184) (xy 123.485836 -62.439847) (xy 123.54085 -62.456982) (xy 123.592661 -62.482199)
			(xy 123.640088 -62.514924) (xy 123.661424 -62.534292) (xy 123.67006 -62.54242) (xy 123.691904 -62.549278)
			(xy 123.78182 -62.536832) (xy 123.783852 -62.536578) (xy 123.79459 -62.534071) (xy 123.812628 -62.52143)
			(xy 123.81865 -62.512194) (xy 123.833469 -62.488075) (xy 123.869109 -62.444098) (xy 123.910857 -62.405871)
			(xy 123.957797 -62.374235) (xy 124.008898 -62.349884) (xy 124.063036 -62.333353) (xy 124.119023 -62.325005)
			(xy 124.147326 -62.324488) (xy 124.17088 -62.324869) (xy 124.217624 -62.330728) (xy 124.240544 -62.336172)
			(xy 124.254768 -62.339728) (xy 124.281946 -62.331092) (xy 124.360178 -62.24016) (xy 124.36475 -62.211966)
			(xy 124.359162 -62.198504) (xy 124.350017 -62.175595) (xy 124.337031 -62.128008) (xy 124.330276 -62.079146)
			(xy 124.329698 -62.054486) (xy 124.329698 -62.050676) (xy 124.330109 -62.026924) (xy 124.336098 -61.979797)
			(xy 124.341636 -61.956696) (xy 124.342398 -61.953648) (xy 124.343414 -61.947044) (xy 124.344183 -61.937105)
			(xy 124.338948 -61.91789) (xy 124.333254 -61.909706) (xy 124.284486 -61.845952) (xy 124.276907 -61.837076)
			(xy 124.256008 -61.826737) (xy 124.244354 -61.82614) (xy 122.96902 -61.82614) (xy 122.957336 -61.829188)
			(xy 122.95251 -61.831474) (xy 122.952002 -61.831728) (xy 122.937096 -61.838666) (xy 122.906318 -61.850239)
			(xy 122.890534 -61.854842) (xy 122.863241 -61.862057) (xy 122.807253 -61.869289) (xy 122.750812 -61.868181)
			(xy 122.722894 -61.863986) (xy 122.696315 -61.859027) (xy 122.644809 -61.842589) (xy 122.620278 -61.83122)
			(xy 122.615198 -61.82868) (xy 122.604022 -61.82614) (xy 121.167398 -61.82614) (xy 121.154669 -61.826849)
			(xy 121.132289 -61.838989) (xy 121.124726 -61.849254) (xy 121.071132 -61.931296) (xy 121.070116 -61.94425)
			(xy 121.0691 -61.956696) (xy 121.072148 -61.963808) (xy 121.072148 -61.964062) (xy 121.074434 -61.969142)
			(xy 121.084417 -61.993204) (xy 121.098453 -62.043372) (xy 121.105515 -62.094986) (xy 121.10593 -62.121034)
			(xy 121.10593 -62.12586) (xy 121.105118 -62.152886) (xy 121.096808 -62.206313) (xy 121.081039 -62.258031)
			(xy 121.058127 -62.307004) (xy 121.02853 -62.352253) (xy 120.992841 -62.39287) (xy 120.951776 -62.428042)
			(xy 120.906157 -62.457064) (xy 120.856897 -62.479355) (xy 120.804983 -62.494469) (xy 120.751456 -62.502102)
			(xy 120.697388 -62.502102) (xy 120.643861 -62.494469) (xy 120.591947 -62.479355) (xy 120.542687 -62.457064)
			(xy 120.497068 -62.428042) (xy 120.456003 -62.39287) (xy 120.420314 -62.352253) (xy 120.390717 -62.307004)
			(xy 120.367805 -62.258031) (xy 120.352036 -62.206313) (xy 120.343726 -62.152886) (xy 120.342914 -62.12586)
			(xy 120.342914 -62.12078) (xy 120.343362 -62.094683) (xy 120.350515 -62.042981) (xy 120.364645 -61.992736)
			(xy 120.374664 -61.968634) (xy 120.379744 -61.95695) (xy 120.378728 -61.94425) (xy 120.377712 -61.931296)
			(xy 120.324118 -61.849254) (xy 120.317006 -61.838332) (xy 120.294654 -61.82614) (xy 117.757448 -61.82614)
			(xy 117.738652 -61.83376) (xy 117.73154 -61.841126) (xy 117.322854 -62.249812) (xy 117.315488 -62.256924)
			(xy 117.307868 -62.27572) (xy 117.307868 -63.273432) (xy 119.676924 -63.273432) (xy 119.680995 -63.21781)
			(xy 119.693121 -63.163373) (xy 119.713044 -63.111282) (xy 119.74034 -63.062647) (xy 119.774426 -63.018504)
			(xy 119.814575 -62.979795) (xy 119.859933 -62.947344) (xy 119.909533 -62.921843) (xy 119.962317 -62.903836)
			(xy 120.01716 -62.893706) (xy 120.072894 -62.891669) (xy 120.128331 -62.897769) (xy 120.182288 -62.911875)
			(xy 120.233617 -62.933687) (xy 120.281223 -62.962741) (xy 120.324091 -62.998416) (xy 120.361308 -63.039953)
			(xy 120.392081 -63.086466) (xy 120.415753 -63.136963) (xy 120.431821 -63.19037) (xy 120.439941 -63.245546)
			(xy 120.439941 -63.245552) (xy 133.204669 -63.245552) (xy 133.204669 -63.191048) (xy 133.212426 -63.137098)
			(xy 133.227782 -63.084801) (xy 133.250425 -63.035222) (xy 133.279893 -62.98937) (xy 133.315587 -62.948178)
			(xy 133.356779 -62.912486) (xy 133.402632 -62.883019) (xy 133.452212 -62.860378) (xy 133.504509 -62.845024)
			(xy 133.55846 -62.837268) (xy 133.585712 -62.836806) (xy 133.613083 -62.837264) (xy 133.667262 -62.845083)
			(xy 133.719765 -62.860574) (xy 133.769512 -62.883418) (xy 133.815479 -62.913144) (xy 133.83641 -62.930786)
			(xy 133.843522 -62.936882) (xy 133.86054 -62.943232) (xy 133.945884 -62.943232) (xy 133.962902 -62.936882)
			(xy 133.970014 -62.930786) (xy 133.990947 -62.913145) (xy 134.036915 -62.883421) (xy 134.086661 -62.860575)
			(xy 134.139163 -62.845079) (xy 134.193341 -62.83725) (xy 134.248083 -62.83725) (xy 134.302261 -62.845079)
			(xy 134.354763 -62.860575) (xy 134.404509 -62.883421) (xy 134.450477 -62.913145) (xy 134.47141 -62.930786)
			(xy 134.478522 -62.936882) (xy 134.49554 -62.943232) (xy 134.580884 -62.943232) (xy 134.597902 -62.936882)
			(xy 134.605014 -62.930786) (xy 134.625966 -62.913172) (xy 134.671933 -62.883457) (xy 134.721676 -62.860616)
			(xy 134.774172 -62.845119) (xy 134.828344 -62.837284) (xy 134.855712 -62.836806) (xy 134.882964 -62.837265)
			(xy 134.936912 -62.845023) (xy 134.989207 -62.86038) (xy 135.038785 -62.883022) (xy 135.084635 -62.91249)
			(xy 135.125826 -62.948183) (xy 135.161517 -62.989374) (xy 135.190984 -63.035226) (xy 135.213625 -63.084804)
			(xy 135.22898 -63.1371) (xy 135.236736 -63.191048) (xy 135.236736 -63.245552) (xy 135.22898 -63.2995)
			(xy 135.213625 -63.351796) (xy 135.190984 -63.401374) (xy 135.161517 -63.447226) (xy 135.125826 -63.488417)
			(xy 135.084635 -63.52411) (xy 135.038785 -63.553578) (xy 134.989207 -63.57622) (xy 134.936912 -63.591577)
			(xy 134.882964 -63.599335) (xy 134.855712 -63.599822) (xy 134.828341 -63.599368) (xy 134.774161 -63.59155)
			(xy 134.721657 -63.576059) (xy 134.67191 -63.553214) (xy 134.625944 -63.523486) (xy 134.605014 -63.505842)
			(xy 134.597902 -63.499746) (xy 134.580884 -63.493396) (xy 134.49554 -63.493396) (xy 134.478522 -63.499746)
			(xy 134.47141 -63.505842) (xy 134.450477 -63.523483) (xy 134.404509 -63.553207) (xy 134.354763 -63.576053)
			(xy 134.302261 -63.591549) (xy 134.248083 -63.599378) (xy 134.193341 -63.599378) (xy 134.139163 -63.591549)
			(xy 134.086661 -63.576053) (xy 134.036915 -63.553207) (xy 133.990947 -63.523483) (xy 133.970014 -63.505842)
			(xy 133.962902 -63.499746) (xy 133.945884 -63.493396) (xy 133.86054 -63.493396) (xy 133.843522 -63.499746)
			(xy 133.83641 -63.505842) (xy 133.815491 -63.523497) (xy 133.769514 -63.553205) (xy 133.719763 -63.576037)
			(xy 133.66726 -63.591525) (xy 133.613082 -63.59935) (xy 133.585712 -63.599822) (xy 133.55846 -63.599332)
			(xy 133.504509 -63.591576) (xy 133.452212 -63.576222) (xy 133.402632 -63.553581) (xy 133.356779 -63.524114)
			(xy 133.315587 -63.488422) (xy 133.279893 -63.44723) (xy 133.250425 -63.401378) (xy 133.227782 -63.351799)
			(xy 133.212426 -63.299502) (xy 133.204669 -63.245552) (xy 120.439941 -63.245552) (xy 120.44045 -63.273432)
			(xy 120.439941 -63.301318) (xy 120.431821 -63.356494) (xy 120.415753 -63.409901) (xy 120.392081 -63.460398)
			(xy 120.361308 -63.506911) (xy 120.324091 -63.548448) (xy 120.281223 -63.584123) (xy 120.233617 -63.613177)
			(xy 120.182288 -63.634989) (xy 120.128331 -63.649095) (xy 120.072894 -63.655195) (xy 120.01716 -63.653158)
			(xy 119.962317 -63.643028) (xy 119.909533 -63.625021) (xy 119.859933 -63.59952) (xy 119.814575 -63.567069)
			(xy 119.774426 -63.52836) (xy 119.74034 -63.484217) (xy 119.713044 -63.435582) (xy 119.693121 -63.383491)
			(xy 119.680995 -63.329054) (xy 119.676924 -63.273432) (xy 117.307868 -63.273432) (xy 117.307868 -64.102234)
			(xy 117.487698 -64.102234) (xy 117.491769 -64.046612) (xy 117.503895 -63.992175) (xy 117.523818 -63.940084)
			(xy 117.551114 -63.891449) (xy 117.5852 -63.847306) (xy 117.625349 -63.808597) (xy 117.670707 -63.776146)
			(xy 117.720307 -63.750645) (xy 117.773091 -63.732638) (xy 117.827934 -63.722508) (xy 117.883668 -63.720471)
			(xy 117.939105 -63.726571) (xy 117.993062 -63.740677) (xy 118.044391 -63.762489) (xy 118.091997 -63.791543)
			(xy 118.134865 -63.827218) (xy 118.172082 -63.868755) (xy 118.202855 -63.915268) (xy 118.226527 -63.965765)
			(xy 118.242595 -64.019172) (xy 118.250715 -64.074348) (xy 118.251224 -64.102234) (xy 118.250715 -64.13012)
			(xy 118.242595 -64.185296) (xy 118.226527 -64.238703) (xy 118.202855 -64.2892) (xy 118.187577 -64.312292)
			(xy 121.166126 -64.312292) (xy 121.170197 -64.25667) (xy 121.182323 -64.202233) (xy 121.202246 -64.150142)
			(xy 121.229542 -64.101507) (xy 121.263628 -64.057364) (xy 121.303777 -64.018655) (xy 121.349135 -63.986204)
			(xy 121.398735 -63.960703) (xy 121.451519 -63.942696) (xy 121.506362 -63.932566) (xy 121.562096 -63.930529)
			(xy 121.617533 -63.936629) (xy 121.67149 -63.950735) (xy 121.722819 -63.972547) (xy 121.770425 -64.001601)
			(xy 121.813293 -64.037276) (xy 121.85051 -64.078813) (xy 121.881283 -64.125326) (xy 121.904955 -64.175823)
			(xy 121.921023 -64.22923) (xy 121.929143 -64.284406) (xy 121.929652 -64.312292) (xy 121.929143 -64.340178)
			(xy 121.921023 -64.395354) (xy 121.904955 -64.448761) (xy 121.881283 -64.499258) (xy 121.85051 -64.545771)
			(xy 121.813293 -64.587308) (xy 121.770425 -64.622983) (xy 121.722819 -64.652037) (xy 121.67149 -64.673849)
			(xy 121.617533 -64.687955) (xy 121.562096 -64.694055) (xy 121.506362 -64.692018) (xy 121.451519 -64.681888)
			(xy 121.398735 -64.663881) (xy 121.349135 -64.63838) (xy 121.303777 -64.605929) (xy 121.263628 -64.56722)
			(xy 121.229542 -64.523077) (xy 121.202246 -64.474442) (xy 121.182323 -64.422351) (xy 121.170197 -64.367914)
			(xy 121.166126 -64.312292) (xy 118.187577 -64.312292) (xy 118.172082 -64.335713) (xy 118.134865 -64.37725)
			(xy 118.091997 -64.412925) (xy 118.044391 -64.441979) (xy 117.993062 -64.463791) (xy 117.939105 -64.477897)
			(xy 117.883668 -64.483997) (xy 117.827934 -64.48196) (xy 117.773091 -64.47183) (xy 117.720307 -64.453823)
			(xy 117.670707 -64.428322) (xy 117.625349 -64.395871) (xy 117.5852 -64.357162) (xy 117.551114 -64.313019)
			(xy 117.523818 -64.264384) (xy 117.503895 -64.212293) (xy 117.491769 -64.157856) (xy 117.487698 -64.102234)
			(xy 117.307868 -64.102234) (xy 117.307868 -65.124076) (xy 122.207526 -65.124076) (xy 122.211597 -65.068454)
			(xy 122.223723 -65.014017) (xy 122.243646 -64.961926) (xy 122.270942 -64.913291) (xy 122.305028 -64.869148)
			(xy 122.345177 -64.830439) (xy 122.390535 -64.797988) (xy 122.440135 -64.772487) (xy 122.492919 -64.75448)
			(xy 122.547762 -64.74435) (xy 122.603496 -64.742313) (xy 122.658933 -64.748413) (xy 122.71289 -64.762519)
			(xy 122.764219 -64.784331) (xy 122.811825 -64.813385) (xy 122.854693 -64.84906) (xy 122.89191 -64.890597)
			(xy 122.922683 -64.93711) (xy 122.946355 -64.987607) (xy 122.962423 -65.041014) (xy 122.970543 -65.09619)
			(xy 122.971052 -65.124076) (xy 122.970543 -65.151962) (xy 122.969376 -65.15989) (xy 135.216644 -65.15989)
			(xy 135.220715 -65.104268) (xy 135.232841 -65.049831) (xy 135.252764 -64.99774) (xy 135.28006 -64.949105)
			(xy 135.314146 -64.904962) (xy 135.354295 -64.866253) (xy 135.399653 -64.833802) (xy 135.449253 -64.808301)
			(xy 135.502037 -64.790294) (xy 135.55688 -64.780164) (xy 135.612614 -64.778127) (xy 135.668051 -64.784227)
			(xy 135.722008 -64.798333) (xy 135.773337 -64.820145) (xy 135.820943 -64.849199) (xy 135.863811 -64.884874)
			(xy 135.901028 -64.926411) (xy 135.931801 -64.972924) (xy 135.955473 -65.023421) (xy 135.971541 -65.076828)
			(xy 135.979661 -65.132004) (xy 135.98017 -65.15989) (xy 135.979661 -65.187776) (xy 135.971541 -65.242952)
			(xy 135.955473 -65.296359) (xy 135.931801 -65.346856) (xy 135.901028 -65.393369) (xy 135.863811 -65.434906)
			(xy 135.820943 -65.470581) (xy 135.773337 -65.499635) (xy 135.722008 -65.521447) (xy 135.668051 -65.535553)
			(xy 135.612614 -65.541653) (xy 135.55688 -65.539616) (xy 135.502037 -65.529486) (xy 135.449253 -65.511479)
			(xy 135.399653 -65.485978) (xy 135.354295 -65.453527) (xy 135.314146 -65.414818) (xy 135.28006 -65.370675)
			(xy 135.252764 -65.32204) (xy 135.232841 -65.269949) (xy 135.220715 -65.215512) (xy 135.216644 -65.15989)
			(xy 122.969376 -65.15989) (xy 122.962423 -65.207138) (xy 122.946355 -65.260545) (xy 122.922683 -65.311042)
			(xy 122.89191 -65.357555) (xy 122.854693 -65.399092) (xy 122.811825 -65.434767) (xy 122.764219 -65.463821)
			(xy 122.71289 -65.485633) (xy 122.658933 -65.499739) (xy 122.603496 -65.505839) (xy 122.547762 -65.503802)
			(xy 122.492919 -65.493672) (xy 122.440135 -65.475665) (xy 122.390535 -65.450164) (xy 122.345177 -65.417713)
			(xy 122.305028 -65.379004) (xy 122.270942 -65.334861) (xy 122.243646 -65.286226) (xy 122.223723 -65.234135)
			(xy 122.211597 -65.179698) (xy 122.207526 -65.124076) (xy 117.307868 -65.124076) (xy 117.307868 -65.75552)
			(xy 130.446778 -65.75552) (xy 130.450849 -65.699898) (xy 130.462975 -65.645461) (xy 130.482898 -65.59337)
			(xy 130.510194 -65.544735) (xy 130.54428 -65.500592) (xy 130.584429 -65.461883) (xy 130.629787 -65.429432)
			(xy 130.679387 -65.403931) (xy 130.732171 -65.385924) (xy 130.787014 -65.375794) (xy 130.842748 -65.373757)
			(xy 130.898185 -65.379857) (xy 130.952142 -65.393963) (xy 131.003471 -65.415775) (xy 131.051077 -65.444829)
			(xy 131.093945 -65.480504) (xy 131.131162 -65.522041) (xy 131.161935 -65.568554) (xy 131.185607 -65.619051)
			(xy 131.201675 -65.672458) (xy 131.209795 -65.727634) (xy 131.210304 -65.75552) (xy 131.209795 -65.783406)
			(xy 131.201675 -65.838582) (xy 131.185607 -65.891989) (xy 131.161935 -65.942486) (xy 131.131162 -65.988999)
			(xy 131.093945 -66.030536) (xy 131.051077 -66.066211) (xy 131.003471 -66.095265) (xy 130.952142 -66.117077)
			(xy 130.898185 -66.131183) (xy 130.842748 -66.137283) (xy 130.787014 -66.135246) (xy 130.732171 -66.125116)
			(xy 130.679387 -66.107109) (xy 130.629787 -66.081608) (xy 130.584429 -66.049157) (xy 130.54428 -66.010448)
			(xy 130.510194 -65.966305) (xy 130.482898 -65.91767) (xy 130.462975 -65.865579) (xy 130.450849 -65.811142)
			(xy 130.446778 -65.75552) (xy 117.307868 -65.75552) (xy 117.307868 -67.3481) (xy 117.307954 -67.352044)
			(xy 117.309225 -67.35983) (xy 117.310408 -67.363594) (xy 117.310408 -67.363848) (xy 117.312531 -67.369873)
			(xy 117.319343 -67.380676) (xy 117.32387 -67.385184) (xy 117.385084 -67.442842) (xy 117.404388 -67.449954)
			(xy 117.415056 -67.449446) (xy 117.50548 -67.445382) (xy 117.554166 -67.44364) (xy 117.651581 -67.441734)
			(xy 117.700298 -67.441572) (xy 117.803759 -67.442076) (xy 118.010521 -67.450216) (xy 118.216803 -67.466483)
			(xy 118.3987 -67.488054) (xy 134.879332 -67.488054) (xy 134.883403 -67.432432) (xy 134.895529 -67.377995)
			(xy 134.915452 -67.325904) (xy 134.942748 -67.277269) (xy 134.976834 -67.233126) (xy 135.016983 -67.194417)
			(xy 135.062341 -67.161966) (xy 135.111941 -67.136465) (xy 135.164725 -67.118458) (xy 135.219568 -67.108328)
			(xy 135.275302 -67.106291) (xy 135.330739 -67.112391) (xy 135.384696 -67.126497) (xy 135.436025 -67.148309)
			(xy 135.483631 -67.177363) (xy 135.526499 -67.213038) (xy 135.563716 -67.254575) (xy 135.594489 -67.301088)
			(xy 135.618161 -67.351585) (xy 135.634229 -67.404992) (xy 135.642349 -67.460168) (xy 135.642858 -67.488054)
			(xy 135.642349 -67.51594) (xy 135.634229 -67.571116) (xy 135.618161 -67.624523) (xy 135.594489 -67.67502)
			(xy 135.563716 -67.721533) (xy 135.526499 -67.76307) (xy 135.483631 -67.798745) (xy 135.436025 -67.827799)
			(xy 135.384696 -67.849611) (xy 135.330739 -67.863717) (xy 135.275302 -67.869817) (xy 135.219568 -67.86778)
			(xy 135.164725 -67.85765) (xy 135.111941 -67.839643) (xy 135.062341 -67.814142) (xy 135.016983 -67.781691)
			(xy 134.976834 -67.742982) (xy 134.942748 -67.698839) (xy 134.915452 -67.650204) (xy 134.895529 -67.598113)
			(xy 134.883403 -67.543676) (xy 134.879332 -67.488054) (xy 118.3987 -67.488054) (xy 118.422286 -67.490851)
			(xy 118.626651 -67.523284) (xy 118.829582 -67.563731) (xy 119.030764 -67.612129) (xy 119.229888 -67.668403)
			(xy 119.426643 -67.732467) (xy 119.620726 -67.804221) (xy 119.811836 -67.883555) (xy 119.999678 -67.970344)
			(xy 120.18396 -68.064456) (xy 120.364398 -68.165743) (xy 120.540711 -68.27405) (xy 120.712628 -68.389209)
			(xy 120.879881 -68.511042) (xy 121.042213 -68.639359) (xy 121.199371 -68.773963) (xy 121.351113 -68.914644)
			(xy 121.497203 -69.061186) (xy 121.637416 -69.213361) (xy 121.771534 -69.370934) (xy 121.89935 -69.533661)
			(xy 122.020665 -69.70129) (xy 122.135293 -69.873561) (xy 122.243056 -70.050208) (xy 122.293888 -70.140322)
			(xy 122.293888 -70.140576) (xy 122.294142 -70.14083) (xy 122.297599 -70.146564) (xy 122.306998 -70.156091)
			(xy 122.312684 -70.159626) (xy 122.333004 -70.171818) (xy 122.338939 -70.174992) (xy 122.351932 -70.178478)
			(xy 122.358658 -70.178676)
		)
		(stroke
			(width 0)
			(type solid)
		)
		(fill yes)
		(layer "In9.Cu")
		(net "P12V_SSD4_R")
	)
	(gr_poly
		(pts
			(xy 368.778282 -70.178676) (xy 368.788154 -70.178204) (xy 368.806434 -70.170742) (xy 368.813842 -70.164198)
			(xy 368.814096 -70.163944) (xy 369.140486 -69.837554) (xy 369.140994 -69.837046) (xy 369.147572 -69.829663)
			(xy 369.155015 -69.811364) (xy 369.155472 -69.801486) (xy 369.155472 -67.91579) (xy 369.155075 -67.906267)
			(xy 369.14812 -67.888537) (xy 369.135173 -67.874569) (xy 369.12677 -67.87007) (xy 369.031012 -67.823842)
			(xy 369.00231 -67.827144) (xy 368.990626 -67.836288) (xy 368.970314 -67.851901) (xy 368.9263 -67.878119)
			(xy 368.87917 -67.898207) (xy 368.829776 -67.911803) (xy 368.779006 -67.918662) (xy 368.75339 -67.919092)
			(xy 368.72614 -67.918605) (xy 368.672196 -67.910848) (xy 368.619905 -67.895492) (xy 368.570331 -67.872852)
			(xy 368.524484 -67.843386) (xy 368.483297 -67.807696) (xy 368.447608 -67.766508) (xy 368.418144 -67.72066)
			(xy 368.395504 -67.671086) (xy 368.38015 -67.618794) (xy 368.372394 -67.56485) (xy 368.372394 -67.51035)
			(xy 368.38015 -67.456406) (xy 368.395504 -67.404114) (xy 368.418144 -67.35454) (xy 368.447608 -67.308692)
			(xy 368.483297 -67.267504) (xy 368.524484 -67.231814) (xy 368.570331 -67.202348) (xy 368.619905 -67.179708)
			(xy 368.672196 -67.164352) (xy 368.72614 -67.156595) (xy 368.75339 -67.156076) (xy 368.779006 -67.15649)
			(xy 368.829778 -67.163351) (xy 368.879173 -67.176949) (xy 368.926302 -67.197041) (xy 368.970316 -67.223263)
			(xy 368.990626 -67.23888) (xy 369.00231 -67.248024) (xy 369.031012 -67.251326) (xy 369.12677 -67.205098)
			(xy 369.13517 -67.200597) (xy 369.148112 -67.186625) (xy 369.155076 -67.1689) (xy 369.155472 -67.159378)
			(xy 369.155472 -65.52057) (xy 369.155472 -65.51803) (xy 369.154395 -65.507417) (xy 369.144816 -65.488384)
			(xy 369.13693 -65.4812) (xy 369.130072 -65.476628) (xy 369.056412 -65.433956) (xy 369.047567 -65.429334)
			(xy 369.027823 -65.426569) (xy 369.018058 -65.428622) (xy 369.003834 -65.432432) (xy 368.998246 -65.43548)
			(xy 368.969961 -65.450258) (xy 368.909685 -65.471206) (xy 368.846764 -65.481833) (xy 368.814858 -65.48247)
			(xy 368.814604 -65.48247) (xy 368.787354 -65.482007) (xy 368.733408 -65.474251) (xy 368.681115 -65.458897)
			(xy 368.631539 -65.436257) (xy 368.58569 -65.406792) (xy 368.544501 -65.371102) (xy 368.50881 -65.329913)
			(xy 368.479345 -65.284065) (xy 368.456704 -65.234489) (xy 368.44135 -65.182196) (xy 368.433593 -65.12825)
			(xy 368.433593 -65.07375) (xy 368.44135 -65.019804) (xy 368.456704 -64.967511) (xy 368.479345 -64.917935)
			(xy 368.50881 -64.872087) (xy 368.544501 -64.830898) (xy 368.58569 -64.795208) (xy 368.631539 -64.765743)
			(xy 368.681115 -64.743103) (xy 368.733408 -64.727749) (xy 368.787354 -64.719993) (xy 368.814604 -64.719454)
			(xy 368.814858 -64.719454) (xy 368.846761 -64.720122) (xy 368.909673 -64.730765) (xy 368.969949 -64.751695)
			(xy 368.998246 -64.766444) (xy 369.003834 -64.769492) (xy 369.018058 -64.773302) (xy 369.027884 -64.775458)
			(xy 369.047795 -64.772711) (xy 369.056666 -64.767968) (xy 369.125246 -64.72809) (xy 369.131342 -64.724534)
			(xy 369.132612 -64.723772) (xy 369.142797 -64.716252) (xy 369.154795 -64.693996) (xy 369.155472 -64.681354)
			(xy 369.155472 -52.623212) (xy 369.153694 -52.616862) (xy 369.147631 -52.592612) (xy 369.141128 -52.54305)
			(xy 369.14074 -52.518056) (xy 369.14074 -52.51577) (xy 369.141205 -52.491159) (xy 369.147702 -52.442363)
			(xy 369.153694 -52.418488) (xy 369.155472 -52.411884) (xy 369.155472 -51.455828) (xy 369.155976 -51.445777)
			(xy 369.163695 -51.427214) (xy 369.170458 -51.41976) (xy 369.277392 -51.312826) (xy 369.284789 -51.305976)
			(xy 369.303387 -51.298234) (xy 369.31346 -51.29784) (xy 370.003832 -51.29784) (xy 370.013709 -51.297379)
			(xy 370.032007 -51.289936) (xy 370.039392 -51.283362) (xy 370.039646 -51.283108) (xy 370.119402 -51.203352)
			(xy 370.119148 -51.198526) (xy 370.119148 -49.205896) (xy 370.118563 -49.193564) (xy 370.107126 -49.171716)
			(xy 370.097304 -49.16424) (xy 370.065808 -49.142396) (xy 370.029486 -49.116996) (xy 370.021009 -49.11156)
			(xy 370.001359 -49.107227) (xy 369.991386 -49.108614) (xy 369.98656 -49.109376) (xy 369.982496 -49.1109)
			(xy 369.95059 -49.121904) (xy 369.884158 -49.133784) (xy 369.850416 -49.134522) (xy 369.846352 -49.134522)
			(xy 369.819289 -49.133762) (xy 369.765776 -49.125541) (xy 369.713964 -49.109837) (xy 369.664891 -49.086967)
			(xy 369.619545 -49.05739) (xy 369.578834 -49.0217) (xy 369.543578 -48.980613) (xy 369.514483 -48.934955)
			(xy 369.492135 -48.885643) (xy 369.476983 -48.833666) (xy 369.469329 -48.78007) (xy 369.469329 -48.72593)
			(xy 369.476982 -48.672334) (xy 369.492135 -48.620358) (xy 369.514483 -48.571045) (xy 369.543578 -48.525387)
			(xy 369.578834 -48.4843) (xy 369.619544 -48.44861) (xy 369.664891 -48.419033) (xy 369.713964 -48.396163)
			(xy 369.765776 -48.380459) (xy 369.819288 -48.372238) (xy 369.846352 -48.371506) (xy 369.85067 -48.371506)
			(xy 369.883265 -48.372189) (xy 369.947504 -48.383292) (xy 369.978432 -48.393604) (xy 369.98275 -48.395128)
			(xy 369.992148 -48.396906) (xy 370.001886 -48.398172) (xy 370.02108 -48.39411) (xy 370.029486 -48.389032)
			(xy 370.030248 -48.388524) (xy 370.065808 -48.363632) (xy 370.097304 -48.341788) (xy 370.106975 -48.334176)
			(xy 370.118394 -48.312416) (xy 370.119148 -48.300132) (xy 370.119148 -41.95445) (xy 370.118714 -41.944385)
			(xy 370.110981 -41.925799) (xy 370.104162 -41.918382) (xy 369.223798 -41.038018) (xy 369.216686 -41.030652)
			(xy 369.19789 -41.023032) (xy 367.416334 -41.023032) (xy 367.407637 -41.023392) (xy 367.391248 -41.029219)
			(xy 367.377743 -41.040183) (xy 367.3729 -41.047416) (xy 367.327942 -41.121584) (xy 367.32372 -41.129309)
			(xy 367.320262 -41.146558) (xy 367.322816 -41.163964) (xy 367.326672 -41.171876) (xy 367.327434 -41.1734)
			(xy 367.331752 -41.18229) (xy 367.343721 -41.207986) (xy 367.360767 -41.262046) (xy 367.369606 -41.318037)
			(xy 367.37036 -41.346374) (xy 367.37036 -41.347898) (xy 367.37036 -41.349422) (xy 367.37036 -41.35501)
			(xy 367.369446 -41.383181) (xy 367.360341 -41.438805) (xy 367.343146 -41.492481) (xy 367.318234 -41.543041)
			(xy 367.286148 -41.589381) (xy 367.267236 -41.61028) (xy 367.260378 -41.617646) (xy 367.25352 -41.635172)
			(xy 367.25352 -41.724072) (xy 367.260378 -41.741852) (xy 367.267236 -41.748964) (xy 367.286507 -41.77029)
			(xy 367.319072 -41.817651) (xy 367.344163 -41.869361) (xy 367.361212 -41.924251) (xy 367.369833 -41.981078)
			(xy 367.369831 -42.038554) (xy 367.361205 -42.09538) (xy 367.344152 -42.150268) (xy 367.319056 -42.201977)
			(xy 367.286487 -42.249335) (xy 367.267236 -42.27068) (xy 367.260378 -42.277792) (xy 367.25352 -42.295572)
			(xy 367.25352 -42.384472) (xy 367.260378 -42.402252) (xy 367.267236 -42.409364) (xy 367.286503 -42.430693)
			(xy 367.31906 -42.478057) (xy 367.344145 -42.529769) (xy 367.361189 -42.584659) (xy 367.369807 -42.641484)
			(xy 367.37036 -42.670222) (xy 367.369887 -42.697591) (xy 367.362059 -42.751767) (xy 367.346569 -42.804268)
			(xy 367.323732 -42.854016) (xy 367.29402 -42.899989) (xy 367.27638 -42.92092) (xy 367.270284 -42.928032)
			(xy 367.263934 -42.944796) (xy 367.263934 -43.030648) (xy 367.270284 -43.047412) (xy 367.27638 -43.054524)
			(xy 367.294021 -43.075455) (xy 367.323746 -43.121422) (xy 367.346587 -43.171169) (xy 367.362075 -43.223672)
			(xy 367.369891 -43.277852) (xy 367.37036 -43.305222) (xy 367.369874 -43.332473) (xy 367.362118 -43.386421)
			(xy 367.346763 -43.438716) (xy 367.324121 -43.488293) (xy 367.294655 -43.534143) (xy 367.258964 -43.575334)
			(xy 367.217773 -43.611025) (xy 367.171923 -43.640491) (xy 367.122346 -43.663133) (xy 367.070051 -43.678488)
			(xy 367.016103 -43.686244) (xy 366.961601 -43.686244) (xy 366.907653 -43.678488) (xy 366.855358 -43.663133)
			(xy 366.805781 -43.640491) (xy 366.759931 -43.611025) (xy 366.71874 -43.575334) (xy 366.683049 -43.534143)
			(xy 366.653583 -43.488293) (xy 366.630941 -43.438716) (xy 366.615586 -43.386421) (xy 366.60783 -43.332473)
			(xy 366.607344 -43.305222) (xy 366.607821 -43.277854) (xy 366.615656 -43.223682) (xy 366.631153 -43.171186)
			(xy 366.653994 -43.121444) (xy 366.683711 -43.075477) (xy 366.701324 -43.054524) (xy 366.70742 -43.047412)
			(xy 366.71377 -43.030648) (xy 366.71377 -42.944796) (xy 366.70742 -42.928032) (xy 366.701324 -42.92092)
			(xy 366.68368 -42.899989) (xy 366.65395 -42.854024) (xy 366.631102 -42.804278) (xy 366.615608 -42.751774)
			(xy 366.607786 -42.697593) (xy 366.607344 -42.670222) (xy 366.607863 -42.641483) (xy 366.616484 -42.584654)
			(xy 366.633533 -42.529762) (xy 366.658625 -42.478049) (xy 366.691192 -42.430686) (xy 366.710468 -42.409364)
			(xy 366.717326 -42.402252) (xy 366.724184 -42.384472) (xy 366.724184 -42.295572) (xy 366.717326 -42.277792)
			(xy 366.710468 -42.27068) (xy 366.691198 -42.249352) (xy 366.658634 -42.201988) (xy 366.633543 -42.150275)
			(xy 366.616493 -42.095383) (xy 366.607869 -42.038555) (xy 366.607867 -41.981077) (xy 366.616486 -41.924248)
			(xy 366.633531 -41.869355) (xy 366.658618 -41.81764) (xy 366.691178 -41.770273) (xy 366.710468 -41.748964)
			(xy 366.717326 -41.741852) (xy 366.724184 -41.724072) (xy 366.724184 -41.635172) (xy 366.717326 -41.617646)
			(xy 366.710468 -41.61028) (xy 366.691667 -41.589487) (xy 366.659734 -41.543415) (xy 366.634877 -41.49317)
			(xy 366.617629 -41.439833) (xy 366.60836 -41.384548) (xy 366.607344 -41.356534) (xy 366.607344 -41.35374)
			(xy 366.607344 -41.349168) (xy 366.607932 -41.319467) (xy 366.617167 -41.260785) (xy 366.635365 -41.204237)
			(xy 366.648238 -41.177464) (xy 366.648492 -41.176956) (xy 366.651032 -41.171876) (xy 366.654334 -41.158668)
			(xy 366.656251 -41.148796) (xy 366.653227 -41.128935) (xy 366.648492 -41.12006) (xy 366.640364 -41.106598)
			(xy 366.640364 -41.10609) (xy 366.604296 -41.047162) (xy 366.599433 -41.039972) (xy 366.585907 -41.029115)
			(xy 366.569536 -41.023382) (xy 366.560862 -41.023032) (xy 365.654336 -41.023032) (xy 365.642713 -41.023603)
			(xy 365.621818 -41.033789) (xy 365.614204 -41.04259) (xy 365.557562 -41.11498) (xy 365.552736 -41.137586)
			(xy 365.55553 -41.14927) (xy 365.560851 -41.171949) (xy 365.566581 -41.21818) (xy 365.56696 -41.241472)
			(xy 365.566499 -41.268725) (xy 365.558745 -41.322676) (xy 365.54339 -41.374975) (xy 365.520749 -41.424555)
			(xy 365.491281 -41.470409) (xy 365.455586 -41.511601) (xy 365.414393 -41.547293) (xy 365.368538 -41.576758)
			(xy 365.318956 -41.599397) (xy 365.266657 -41.614749) (xy 365.212705 -41.6225) (xy 365.185452 -41.62298)
			(xy 365.156712 -41.622463) (xy 365.09988 -41.613847) (xy 365.044985 -41.596802) (xy 364.993268 -41.571714)
			(xy 364.945901 -41.53915) (xy 364.924594 -41.519856) (xy 364.917482 -41.512998) (xy 364.899702 -41.50614)
			(xy 364.810802 -41.50614) (xy 364.793022 -41.512998) (xy 364.78591 -41.519856) (xy 364.764582 -41.539126)
			(xy 364.717219 -41.571691) (xy 364.665508 -41.596784) (xy 364.610618 -41.613838) (xy 364.553791 -41.622467)
			(xy 364.525052 -41.62298) (xy 364.497804 -41.62249) (xy 364.443863 -41.614728) (xy 364.391575 -41.599369)
			(xy 364.342006 -41.576724) (xy 364.296164 -41.547256) (xy 364.254982 -41.511565) (xy 364.219298 -41.470375)
			(xy 364.189839 -41.424527) (xy 364.167205 -41.374953) (xy 364.151856 -41.322663) (xy 364.144104 -41.26872)
			(xy 364.143544 -41.241472) (xy 364.143923 -41.21818) (xy 364.149653 -41.171949) (xy 364.154974 -41.14927)
			(xy 364.157768 -41.137586) (xy 364.152942 -41.11498) (xy 364.0963 -41.04259) (xy 364.088708 -41.033765)
			(xy 364.067797 -41.023593) (xy 364.056168 -41.023032) (xy 360.208576 -41.023032) (xy 360.198508 -41.02346)
			(xy 360.179913 -41.031184) (xy 360.172508 -41.038018) (xy 360.005884 -41.204642) (xy 359.999208 -41.212054)
			(xy 359.991643 -41.230491) (xy 359.991152 -41.240456) (xy 359.991152 -43.73626) (xy 368.513104 -43.73626)
			(xy 368.517175 -43.680638) (xy 368.529301 -43.626201) (xy 368.549224 -43.57411) (xy 368.57652 -43.525475)
			(xy 368.610606 -43.481332) (xy 368.650755 -43.442623) (xy 368.696113 -43.410172) (xy 368.745713 -43.384671)
			(xy 368.798497 -43.366664) (xy 368.85334 -43.356534) (xy 368.909074 -43.354497) (xy 368.964511 -43.360597)
			(xy 369.018468 -43.374703) (xy 369.069797 -43.396515) (xy 369.117403 -43.425569) (xy 369.160271 -43.461244)
			(xy 369.197488 -43.502781) (xy 369.228261 -43.549294) (xy 369.251933 -43.599791) (xy 369.268001 -43.653198)
			(xy 369.276121 -43.708374) (xy 369.27663 -43.73626) (xy 369.276121 -43.764146) (xy 369.268001 -43.819322)
			(xy 369.251933 -43.872729) (xy 369.228261 -43.923226) (xy 369.197488 -43.969739) (xy 369.160271 -44.011276)
			(xy 369.117403 -44.046951) (xy 369.069797 -44.076005) (xy 369.018468 -44.097817) (xy 368.964511 -44.111923)
			(xy 368.909074 -44.118023) (xy 368.85334 -44.115986) (xy 368.798497 -44.105856) (xy 368.745713 -44.087849)
			(xy 368.696113 -44.062348) (xy 368.650755 -44.029897) (xy 368.610606 -43.991188) (xy 368.57652 -43.947045)
			(xy 368.549224 -43.89841) (xy 368.529301 -43.846319) (xy 368.517175 -43.791882) (xy 368.513104 -43.73626)
			(xy 359.991152 -43.73626) (xy 359.991152 -45.114464) (xy 368.36553 -45.114464) (xy 368.369601 -45.058842)
			(xy 368.381727 -45.004405) (xy 368.40165 -44.952314) (xy 368.428946 -44.903679) (xy 368.463032 -44.859536)
			(xy 368.503181 -44.820827) (xy 368.548539 -44.788376) (xy 368.598139 -44.762875) (xy 368.650923 -44.744868)
			(xy 368.705766 -44.734738) (xy 368.7615 -44.732701) (xy 368.816937 -44.738801) (xy 368.870894 -44.752907)
			(xy 368.922223 -44.774719) (xy 368.969829 -44.803773) (xy 369.012697 -44.839448) (xy 369.049914 -44.880985)
			(xy 369.080687 -44.927498) (xy 369.104359 -44.977995) (xy 369.120427 -45.031402) (xy 369.128547 -45.086578)
			(xy 369.129056 -45.114464) (xy 369.128547 -45.14235) (xy 369.120427 -45.197526) (xy 369.104359 -45.250933)
			(xy 369.080687 -45.30143) (xy 369.049914 -45.347943) (xy 369.012697 -45.38948) (xy 368.969829 -45.425155)
			(xy 368.922223 -45.454209) (xy 368.870894 -45.476021) (xy 368.816937 -45.490127) (xy 368.7615 -45.496227)
			(xy 368.705766 -45.49419) (xy 368.650923 -45.48406) (xy 368.598139 -45.466053) (xy 368.548539 -45.440552)
			(xy 368.503181 -45.408101) (xy 368.463032 -45.369392) (xy 368.428946 -45.325249) (xy 368.40165 -45.276614)
			(xy 368.381727 -45.224523) (xy 368.369601 -45.170086) (xy 368.36553 -45.114464) (xy 359.991152 -45.114464)
			(xy 359.991152 -46.893226) (xy 368.63731 -46.893226) (xy 368.641381 -46.837604) (xy 368.653507 -46.783167)
			(xy 368.67343 -46.731076) (xy 368.700726 -46.682441) (xy 368.734812 -46.638298) (xy 368.774961 -46.599589)
			(xy 368.820319 -46.567138) (xy 368.869919 -46.541637) (xy 368.922703 -46.52363) (xy 368.977546 -46.5135)
			(xy 369.03328 -46.511463) (xy 369.088717 -46.517563) (xy 369.142674 -46.531669) (xy 369.194003 -46.553481)
			(xy 369.241609 -46.582535) (xy 369.284477 -46.61821) (xy 369.321694 -46.659747) (xy 369.352467 -46.70626)
			(xy 369.376139 -46.756757) (xy 369.392207 -46.810164) (xy 369.400327 -46.86534) (xy 369.400836 -46.893226)
			(xy 369.400327 -46.921112) (xy 369.392207 -46.976288) (xy 369.376139 -47.029695) (xy 369.352467 -47.080192)
			(xy 369.321694 -47.126705) (xy 369.284477 -47.168242) (xy 369.241609 -47.203917) (xy 369.194003 -47.232971)
			(xy 369.142674 -47.254783) (xy 369.088717 -47.268889) (xy 369.03328 -47.274989) (xy 368.977546 -47.272952)
			(xy 368.922703 -47.262822) (xy 368.869919 -47.244815) (xy 368.820319 -47.219314) (xy 368.774961 -47.186863)
			(xy 368.734812 -47.148154) (xy 368.700726 -47.104011) (xy 368.67343 -47.055376) (xy 368.653507 -47.003285)
			(xy 368.641381 -46.948848) (xy 368.63731 -46.893226) (xy 359.991152 -46.893226) (xy 359.991152 -47.936658)
			(xy 366.953038 -47.936658) (xy 366.953524 -47.909407) (xy 366.96128 -47.855459) (xy 366.976635 -47.803164)
			(xy 366.999277 -47.753587) (xy 367.028743 -47.707737) (xy 367.064434 -47.666546) (xy 367.105625 -47.630855)
			(xy 367.151475 -47.601389) (xy 367.201052 -47.578747) (xy 367.253347 -47.563392) (xy 367.307295 -47.555636)
			(xy 367.361797 -47.555636) (xy 367.415745 -47.563392) (xy 367.46804 -47.578747) (xy 367.517617 -47.601389)
			(xy 367.563467 -47.630855) (xy 367.604658 -47.666546) (xy 367.640349 -47.707737) (xy 367.669815 -47.753587)
			(xy 367.692457 -47.803164) (xy 367.707812 -47.855459) (xy 367.715568 -47.909407) (xy 367.716054 -47.936658)
			(xy 367.715591 -47.962999) (xy 367.708341 -48.015179) (xy 367.693986 -48.065867) (xy 367.6728 -48.114101)
			(xy 367.645183 -48.158964) (xy 367.611662 -48.199604) (xy 367.572871 -48.23525) (xy 367.551462 -48.250602)
			(xy 367.539635 -48.259295) (xy 367.521194 -48.28212) (xy 367.510007 -48.309246) (xy 367.506999 -48.338435)
			(xy 367.512416 -48.367273) (xy 367.525813 -48.393379) (xy 367.546082 -48.414596) (xy 367.558574 -48.422306)
			(xy 367.58311 -48.437001) (xy 367.627868 -48.472603) (xy 367.666812 -48.514486) (xy 367.699068 -48.561712)
			(xy 367.723914 -48.613224) (xy 367.740793 -48.667868) (xy 367.749327 -48.724419) (xy 367.749836 -48.753014)
			(xy 367.74935 -48.780265) (xy 367.741594 -48.834213) (xy 367.726239 -48.886508) (xy 367.703597 -48.936085)
			(xy 367.674131 -48.981935) (xy 367.63844 -49.023126) (xy 367.597249 -49.058817) (xy 367.551399 -49.088283)
			(xy 367.501822 -49.110925) (xy 367.449527 -49.12628) (xy 367.395579 -49.134036) (xy 367.341077 -49.134036)
			(xy 367.287129 -49.12628) (xy 367.234834 -49.110925) (xy 367.185257 -49.088283) (xy 367.139407 -49.058817)
			(xy 367.098216 -49.023126) (xy 367.062525 -48.981935) (xy 367.033059 -48.936085) (xy 367.010417 -48.886508)
			(xy 366.995062 -48.834213) (xy 366.987306 -48.780265) (xy 366.98682 -48.753014) (xy 366.987273 -48.726673)
			(xy 366.994526 -48.674493) (xy 367.008884 -48.623805) (xy 367.030072 -48.575572) (xy 367.05769 -48.530709)
			(xy 367.091212 -48.490069) (xy 367.130003 -48.454422) (xy 367.151412 -48.43907) (xy 367.163257 -48.430403)
			(xy 367.181684 -48.407569) (xy 367.19286 -48.380438) (xy 367.195862 -48.35125) (xy 367.190443 -48.322412)
			(xy 367.17705 -48.296304) (xy 367.156788 -48.275081) (xy 367.1443 -48.267366) (xy 367.11979 -48.25263)
			(xy 367.075033 -48.217034) (xy 367.036089 -48.175157) (xy 367.003831 -48.127938) (xy 366.978981 -48.076433)
			(xy 366.962095 -48.021796) (xy 366.953552 -47.965251) (xy 366.953038 -47.936658) (xy 359.991152 -47.936658)
			(xy 359.991152 -58.731404) (xy 361.820714 -58.731404) (xy 361.821179 -58.704034) (xy 361.828997 -58.649854)
			(xy 361.844486 -58.597351) (xy 361.867328 -58.547604) (xy 361.897053 -58.501638) (xy 361.914694 -58.480706)
			(xy 361.92079 -58.473594) (xy 361.92714 -58.456576) (xy 361.92714 -58.371232) (xy 361.92079 -58.354214)
			(xy 361.914694 -58.347102) (xy 361.897059 -58.326165) (xy 361.867336 -58.280197) (xy 361.844493 -58.230452)
			(xy 361.828997 -58.17795) (xy 361.821169 -58.123773) (xy 361.821169 -58.069033) (xy 361.828996 -58.014855)
			(xy 361.84449 -57.962354) (xy 361.867333 -57.912608) (xy 361.897055 -57.866639) (xy 361.914694 -57.845706)
			(xy 361.92079 -57.838594) (xy 361.92714 -57.821576) (xy 361.92714 -57.736232) (xy 361.92079 -57.719214)
			(xy 361.914694 -57.712102) (xy 361.897059 -57.691165) (xy 361.867336 -57.645197) (xy 361.844493 -57.595452)
			(xy 361.828997 -57.54295) (xy 361.821169 -57.488773) (xy 361.821169 -57.434033) (xy 361.828996 -57.379855)
			(xy 361.84449 -57.327354) (xy 361.867333 -57.277608) (xy 361.897055 -57.231639) (xy 361.914694 -57.210706)
			(xy 361.92079 -57.203594) (xy 361.92714 -57.186576) (xy 361.92714 -57.101232) (xy 361.92079 -57.084214)
			(xy 361.914694 -57.077102) (xy 361.897041 -57.056181) (xy 361.867332 -57.010205) (xy 361.844499 -56.960455)
			(xy 361.829011 -56.907952) (xy 361.821186 -56.853774) (xy 361.820714 -56.826404) (xy 361.8212 -56.799153)
			(xy 361.828956 -56.745205) (xy 361.844311 -56.69291) (xy 361.866953 -56.643333) (xy 361.896419 -56.597483)
			(xy 361.93211 -56.556292) (xy 361.973301 -56.520601) (xy 362.019151 -56.491135) (xy 362.068728 -56.468493)
			(xy 362.121023 -56.453138) (xy 362.174971 -56.445382) (xy 362.229473 -56.445382) (xy 362.283421 -56.453138)
			(xy 362.335716 -56.468493) (xy 362.385293 -56.491135) (xy 362.431143 -56.520601) (xy 362.472334 -56.556292)
			(xy 362.508025 -56.597483) (xy 362.537491 -56.643333) (xy 362.560133 -56.69291) (xy 362.575488 -56.745205)
			(xy 362.583244 -56.799153) (xy 362.58373 -56.826404) (xy 362.583283 -56.853775) (xy 362.575463 -56.907956)
			(xy 362.559971 -56.96046) (xy 362.537124 -57.010206) (xy 362.507394 -57.056172) (xy 362.48975 -57.077102)
			(xy 362.483654 -57.084214) (xy 362.477304 -57.101232) (xy 362.477304 -57.186576) (xy 362.483654 -57.203594)
			(xy 362.48975 -57.210706) (xy 362.507396 -57.231635) (xy 362.537122 -57.277603) (xy 362.559968 -57.32735)
			(xy 362.575465 -57.379853) (xy 362.583294 -57.434032) (xy 362.583294 -57.488774) (xy 362.575464 -57.542953)
			(xy 362.559966 -57.595456) (xy 362.537119 -57.645202) (xy 362.507392 -57.69117) (xy 362.48975 -57.712102)
			(xy 362.483654 -57.719214) (xy 362.477304 -57.736232) (xy 362.477304 -57.821576) (xy 362.483654 -57.838594)
			(xy 362.48975 -57.845706) (xy 362.507396 -57.866635) (xy 362.537122 -57.912603) (xy 362.559968 -57.96235)
			(xy 362.575465 -58.014853) (xy 362.583294 -58.069032) (xy 362.583294 -58.123774) (xy 362.575464 -58.177953)
			(xy 362.559966 -58.230456) (xy 362.537119 -58.280202) (xy 362.507392 -58.32617) (xy 362.48975 -58.347102)
			(xy 362.483654 -58.354214) (xy 362.477304 -58.371232) (xy 362.477304 -58.456576) (xy 362.483654 -58.473594)
			(xy 362.48975 -58.480706) (xy 362.507398 -58.501631) (xy 362.53711 -58.547605) (xy 362.559945 -58.597354)
			(xy 362.575434 -58.649857) (xy 362.583258 -58.704034) (xy 362.58373 -58.731404) (xy 362.583244 -58.758655)
			(xy 362.57858 -58.791094) (xy 364.476538 -58.791094) (xy 364.476991 -58.763723) (xy 364.484811 -58.709543)
			(xy 364.500302 -58.65704) (xy 364.523147 -58.607293) (xy 364.552875 -58.561327) (xy 364.570518 -58.540396)
			(xy 364.576614 -58.533284) (xy 364.582964 -58.516266) (xy 364.582964 -58.430922) (xy 364.576614 -58.413904)
			(xy 364.570518 -58.406792) (xy 364.552872 -58.385864) (xy 364.523148 -58.339895) (xy 364.500303 -58.290148)
			(xy 364.484808 -58.237645) (xy 364.47698 -58.183466) (xy 364.476981 -58.128725) (xy 364.48481 -58.074546)
			(xy 364.500307 -58.022044) (xy 364.523152 -57.972297) (xy 364.552877 -57.926329) (xy 364.570518 -57.905396)
			(xy 364.576614 -57.898284) (xy 364.582964 -57.881266) (xy 364.582964 -57.795922) (xy 364.576614 -57.778904)
			(xy 364.570518 -57.771792) (xy 364.552864 -57.750871) (xy 364.523154 -57.704896) (xy 364.500321 -57.655145)
			(xy 364.484833 -57.602642) (xy 364.477009 -57.548464) (xy 364.476538 -57.521094) (xy 364.476995 -57.494778)
			(xy 364.484213 -57.442644) (xy 364.498524 -57.391995) (xy 364.519658 -57.343793) (xy 364.547213 -57.298951)
			(xy 364.580667 -57.25832) (xy 364.599728 -57.24017) (xy 364.607134 -57.232652) (xy 364.615659 -57.21337)
			(xy 364.616238 -57.202832) (xy 364.616238 -57.128156) (xy 364.615681 -57.11761) (xy 364.607164 -57.098315)
			(xy 364.599728 -57.090818) (xy 364.580663 -57.072669) (xy 364.547182 -57.032052) (xy 364.519609 -56.987215)
			(xy 364.498468 -56.93901) (xy 364.484161 -56.888355) (xy 364.47696 -56.836213) (xy 364.476538 -56.809894)
			(xy 364.477024 -56.782643) (xy 364.48478 -56.728695) (xy 364.500135 -56.6764) (xy 364.522777 -56.626823)
			(xy 364.552243 -56.580973) (xy 364.587934 -56.539782) (xy 364.629125 -56.504091) (xy 364.674975 -56.474625)
			(xy 364.724552 -56.451983) (xy 364.776847 -56.436628) (xy 364.830795 -56.428872) (xy 364.885297 -56.428872)
			(xy 364.939245 -56.436628) (xy 364.99154 -56.451983) (xy 365.041117 -56.474625) (xy 365.086967 -56.504091)
			(xy 365.128158 -56.539782) (xy 365.163849 -56.580973) (xy 365.193315 -56.626823) (xy 365.215957 -56.6764)
			(xy 365.231312 -56.728695) (xy 365.239068 -56.782643) (xy 365.239554 -56.809894) (xy 365.239158 -56.836212)
			(xy 365.231928 -56.888349) (xy 365.217605 -56.938999) (xy 365.19646 -56.987201) (xy 365.168894 -57.032042)
			(xy 365.135429 -57.07267) (xy 365.116364 -57.090818) (xy 365.108962 -57.09834) (xy 365.100436 -57.117619)
			(xy 365.099854 -57.128156) (xy 365.099854 -57.202832) (xy 365.10042 -57.213377) (xy 365.108931 -57.232672)
			(xy 365.116364 -57.24017) (xy 365.135422 -57.258326) (xy 365.168903 -57.298941) (xy 365.196478 -57.343777)
			(xy 365.21762 -57.39198) (xy 365.231929 -57.442634) (xy 365.235302 -57.467053) (xy 365.418569 -57.467053)
			(xy 365.418569 -57.412547) (xy 365.426327 -57.358596) (xy 365.441683 -57.306298) (xy 365.464327 -57.256718)
			(xy 365.493796 -57.210866) (xy 365.529491 -57.169674) (xy 365.570685 -57.133982) (xy 365.616539 -57.104515)
			(xy 365.666121 -57.081875) (xy 365.718419 -57.066522) (xy 365.772371 -57.058768) (xy 365.799624 -57.058306)
			(xy 365.82594 -57.058761) (xy 365.878074 -57.065981) (xy 365.928722 -57.080293) (xy 365.976924 -57.101427)
			(xy 366.021766 -57.128982) (xy 366.062398 -57.162436) (xy 366.080548 -57.181496) (xy 366.08805 -57.18892)
			(xy 366.107345 -57.197432) (xy 366.117886 -57.198006) (xy 366.192562 -57.198006) (xy 366.203111 -57.197468)
			(xy 366.222406 -57.188939) (xy 366.2299 -57.181496) (xy 366.248034 -57.162416) (xy 366.288655 -57.128938)
			(xy 366.333495 -57.101368) (xy 366.381703 -57.080229) (xy 366.43236 -57.065925) (xy 366.484504 -57.058727)
			(xy 366.510824 -57.058306) (xy 366.538075 -57.058765) (xy 366.592022 -57.066525) (xy 366.627172 -57.076848)
			(xy 367.438686 -57.076848) (xy 367.439184 -57.049479) (xy 367.446994 -56.995301) (xy 367.462476 -56.942799)
			(xy 367.485311 -56.893051) (xy 367.515028 -56.847083) (xy 367.532666 -56.82615) (xy 367.538762 -56.819038)
			(xy 367.545112 -56.80202) (xy 367.545112 -56.716676) (xy 367.538762 -56.699658) (xy 367.532666 -56.692546)
			(xy 367.51503 -56.671612) (xy 367.485319 -56.625639) (xy 367.462483 -56.575892) (xy 367.446991 -56.523392)
			(xy 367.439161 -56.469217) (xy 367.438686 -56.441848) (xy 367.439172 -56.414597) (xy 367.446928 -56.360649)
			(xy 367.462283 -56.308354) (xy 367.484925 -56.258777) (xy 367.514391 -56.212927) (xy 367.550082 -56.171736)
			(xy 367.591273 -56.136045) (xy 367.637123 -56.106579) (xy 367.6867 -56.083937) (xy 367.738995 -56.068582)
			(xy 367.792943 -56.060826) (xy 367.847445 -56.060826) (xy 367.901393 -56.068582) (xy 367.953688 -56.083937)
			(xy 368.003265 -56.106579) (xy 368.049115 -56.136045) (xy 368.090306 -56.171736) (xy 368.125997 -56.212927)
			(xy 368.155463 -56.258777) (xy 368.178105 -56.308354) (xy 368.19346 -56.360649) (xy 368.201216 -56.414597)
			(xy 368.201702 -56.441848) (xy 368.201205 -56.469217) (xy 368.193395 -56.523395) (xy 368.177913 -56.575898)
			(xy 368.155078 -56.625645) (xy 368.12536 -56.671613) (xy 368.107722 -56.692546) (xy 368.101626 -56.699658)
			(xy 368.095276 -56.716676) (xy 368.095276 -56.80202) (xy 368.101626 -56.819038) (xy 368.107722 -56.82615)
			(xy 368.125355 -56.847087) (xy 368.155067 -56.893059) (xy 368.177903 -56.942805) (xy 368.193396 -56.995305)
			(xy 368.201227 -57.049479) (xy 368.201702 -57.076848) (xy 368.201216 -57.104099) (xy 368.19346 -57.158047)
			(xy 368.178105 -57.210342) (xy 368.155463 -57.259919) (xy 368.125997 -57.305769) (xy 368.090306 -57.34696)
			(xy 368.049115 -57.382651) (xy 368.003265 -57.412117) (xy 367.953688 -57.434759) (xy 367.901393 -57.450114)
			(xy 367.847445 -57.45787) (xy 367.792943 -57.45787) (xy 367.738995 -57.450114) (xy 367.6867 -57.434759)
			(xy 367.637123 -57.412117) (xy 367.591273 -57.382651) (xy 367.550082 -57.34696) (xy 367.514391 -57.305769)
			(xy 367.484925 -57.259919) (xy 367.462283 -57.210342) (xy 367.446928 -57.158047) (xy 367.439172 -57.104099)
			(xy 367.438686 -57.076848) (xy 366.627172 -57.076848) (xy 366.644316 -57.081883) (xy 366.693892 -57.104526)
			(xy 366.739741 -57.133994) (xy 366.78093 -57.169687) (xy 366.81662 -57.210878) (xy 366.846085 -57.256729)
			(xy 366.868726 -57.306306) (xy 366.88408 -57.358601) (xy 366.891836 -57.412549) (xy 366.891836 -57.467051)
			(xy 366.88408 -57.520999) (xy 366.868726 -57.573294) (xy 366.846085 -57.622871) (xy 366.81662 -57.668722)
			(xy 366.78093 -57.709913) (xy 366.739741 -57.745606) (xy 366.693892 -57.775074) (xy 366.644316 -57.797717)
			(xy 366.592022 -57.813075) (xy 366.538075 -57.820835) (xy 366.510824 -57.821322) (xy 366.484507 -57.820892)
			(xy 366.432372 -57.813666) (xy 366.381724 -57.799348) (xy 366.333522 -57.778209) (xy 366.288681 -57.75065)
			(xy 366.24805 -57.717194) (xy 366.2299 -57.698132) (xy 366.222376 -57.690733) (xy 366.203098 -57.682206)
			(xy 366.192562 -57.681622) (xy 366.117886 -57.681622) (xy 366.107333 -57.682124) (xy 366.088038 -57.690678)
			(xy 366.080548 -57.698132) (xy 366.062425 -57.717224) (xy 366.021804 -57.750703) (xy 365.976961 -57.778274)
			(xy 365.928751 -57.799411) (xy 365.878091 -57.813712) (xy 365.825944 -57.820905) (xy 365.799624 -57.821322)
			(xy 365.772371 -57.820832) (xy 365.718419 -57.813078) (xy 365.666121 -57.797725) (xy 365.616539 -57.775085)
			(xy 365.570685 -57.745618) (xy 365.529491 -57.709926) (xy 365.493796 -57.668734) (xy 365.464327 -57.622882)
			(xy 365.441683 -57.573302) (xy 365.426327 -57.521004) (xy 365.418569 -57.467053) (xy 365.235302 -57.467053)
			(xy 365.239131 -57.494776) (xy 365.239554 -57.521094) (xy 365.239096 -57.548465) (xy 365.231278 -57.602645)
			(xy 365.215787 -57.655148) (xy 365.192944 -57.704895) (xy 365.163217 -57.750861) (xy 365.145574 -57.771792)
			(xy 365.139478 -57.778904) (xy 365.133128 -57.795922) (xy 365.133128 -57.881266) (xy 365.139478 -57.898284)
			(xy 365.145574 -57.905396) (xy 365.163209 -57.926334) (xy 365.192934 -57.9723) (xy 365.215779 -58.022046)
			(xy 365.231276 -58.074547) (xy 365.239105 -58.128725) (xy 365.239106 -58.183466) (xy 365.231278 -58.237644)
			(xy 365.215783 -58.290146) (xy 365.192938 -58.339892) (xy 365.163214 -58.385859) (xy 365.145574 -58.406792)
			(xy 365.139478 -58.413904) (xy 365.133128 -58.430922) (xy 365.133128 -58.516266) (xy 365.139478 -58.533284)
			(xy 365.145574 -58.540396) (xy 365.163221 -58.561322) (xy 365.192932 -58.607296) (xy 365.215767 -58.657045)
			(xy 365.231256 -58.709547) (xy 365.239082 -58.763724) (xy 365.239554 -58.791094) (xy 365.239068 -58.818345)
			(xy 365.231312 -58.872293) (xy 365.230915 -58.873644) (xy 366.500664 -58.873644) (xy 366.50114 -58.846274)
			(xy 366.508953 -58.792095) (xy 366.524439 -58.739591) (xy 366.547279 -58.689844) (xy 366.577003 -58.643877)
			(xy 366.594644 -58.622946) (xy 366.60074 -58.615834) (xy 366.60709 -58.598816) (xy 366.60709 -58.513472)
			(xy 366.60074 -58.496454) (xy 366.594644 -58.489342) (xy 366.577018 -58.468399) (xy 366.547303 -58.42243)
			(xy 366.524464 -58.372685) (xy 366.50897 -58.320187) (xy 366.501139 -58.266013) (xy 366.500664 -58.238644)
			(xy 366.50115 -58.211393) (xy 366.508906 -58.157445) (xy 366.524261 -58.10515) (xy 366.546903 -58.055573)
			(xy 366.576369 -58.009723) (xy 366.61206 -57.968532) (xy 366.653251 -57.932841) (xy 366.699101 -57.903375)
			(xy 366.748678 -57.880733) (xy 366.800973 -57.865378) (xy 366.854921 -57.857622) (xy 366.909423 -57.857622)
			(xy 366.963371 -57.865378) (xy 367.015666 -57.880733) (xy 367.065243 -57.903375) (xy 367.111093 -57.932841)
			(xy 367.152284 -57.968532) (xy 367.187975 -58.009723) (xy 367.217441 -58.055573) (xy 367.240083 -58.10515)
			(xy 367.255438 -58.157445) (xy 367.263194 -58.211393) (xy 367.26368 -58.238644) (xy 367.263186 -58.266013)
			(xy 367.255376 -58.320191) (xy 367.239893 -58.372694) (xy 367.217058 -58.422442) (xy 367.187339 -58.46841)
			(xy 367.1697 -58.489342) (xy 367.163604 -58.496454) (xy 367.157254 -58.513472) (xy 367.157254 -58.598816)
			(xy 367.163604 -58.615834) (xy 367.1697 -58.622946) (xy 367.187327 -58.643888) (xy 367.217041 -58.689858)
			(xy 367.239879 -58.739603) (xy 367.255373 -58.792101) (xy 367.263204 -58.846275) (xy 367.26368 -58.873644)
			(xy 367.263194 -58.900895) (xy 367.255438 -58.954843) (xy 367.240083 -59.007138) (xy 367.217441 -59.056715)
			(xy 367.187975 -59.102565) (xy 367.152284 -59.143756) (xy 367.111093 -59.179447) (xy 367.065243 -59.208913)
			(xy 367.015666 -59.231555) (xy 366.963371 -59.24691) (xy 366.909423 -59.254666) (xy 366.854921 -59.254666)
			(xy 366.800973 -59.24691) (xy 366.748678 -59.231555) (xy 366.699101 -59.208913) (xy 366.653251 -59.179447)
			(xy 366.61206 -59.143756) (xy 366.576369 -59.102565) (xy 366.546903 -59.056715) (xy 366.524261 -59.007138)
			(xy 366.508906 -58.954843) (xy 366.50115 -58.900895) (xy 366.500664 -58.873644) (xy 365.230915 -58.873644)
			(xy 365.215957 -58.924588) (xy 365.193315 -58.974165) (xy 365.163849 -59.020015) (xy 365.128158 -59.061206)
			(xy 365.086967 -59.096897) (xy 365.041117 -59.126363) (xy 364.99154 -59.149005) (xy 364.939245 -59.16436)
			(xy 364.885297 -59.172116) (xy 364.830795 -59.172116) (xy 364.776847 -59.16436) (xy 364.724552 -59.149005)
			(xy 364.674975 -59.126363) (xy 364.629125 -59.096897) (xy 364.587934 -59.061206) (xy 364.552243 -59.020015)
			(xy 364.522777 -58.974165) (xy 364.500135 -58.924588) (xy 364.48478 -58.872293) (xy 364.477024 -58.818345)
			(xy 364.476538 -58.791094) (xy 362.57858 -58.791094) (xy 362.575488 -58.812603) (xy 362.560133 -58.864898)
			(xy 362.537491 -58.914475) (xy 362.508025 -58.960325) (xy 362.472334 -59.001516) (xy 362.431143 -59.037207)
			(xy 362.385293 -59.066673) (xy 362.335716 -59.089315) (xy 362.283421 -59.10467) (xy 362.229473 -59.112426)
			(xy 362.174971 -59.112426) (xy 362.121023 -59.10467) (xy 362.068728 -59.089315) (xy 362.019151 -59.066673)
			(xy 361.973301 -59.037207) (xy 361.93211 -59.001516) (xy 361.896419 -58.960325) (xy 361.866953 -58.914475)
			(xy 361.844311 -58.864898) (xy 361.828956 -58.812603) (xy 361.8212 -58.758655) (xy 361.820714 -58.731404)
			(xy 359.991152 -58.731404) (xy 359.991152 -60.071945) (xy 365.480249 -60.071945) (xy 365.488008 -60.017989)
			(xy 365.503366 -59.965686) (xy 365.526013 -59.916103) (xy 365.555485 -59.870246) (xy 365.591185 -59.829052)
			(xy 365.632383 -59.793358) (xy 365.678243 -59.763891) (xy 365.72783 -59.74125) (xy 365.780134 -59.725898)
			(xy 365.834091 -59.718146) (xy 365.861346 -59.717686) (xy 365.888715 -59.718187) (xy 365.942892 -59.725997)
			(xy 365.995395 -59.741478) (xy 366.045142 -59.764312) (xy 366.091111 -59.794029) (xy 366.112044 -59.811666)
			(xy 366.119156 -59.817762) (xy 366.136174 -59.824112) (xy 366.221518 -59.824112) (xy 366.238536 -59.817762)
			(xy 366.245648 -59.811666) (xy 366.266581 -59.794025) (xy 366.312549 -59.764301) (xy 366.362295 -59.741455)
			(xy 366.414797 -59.725959) (xy 366.468975 -59.71813) (xy 366.523717 -59.71813) (xy 366.577895 -59.725959)
			(xy 366.630397 -59.741455) (xy 366.680143 -59.764301) (xy 366.726111 -59.794025) (xy 366.747044 -59.811666)
			(xy 366.754156 -59.817762) (xy 366.771174 -59.824112) (xy 366.856518 -59.824112) (xy 366.873536 -59.817762)
			(xy 366.880648 -59.811666) (xy 366.901584 -59.794033) (xy 366.947557 -59.764321) (xy 366.997303 -59.741485)
			(xy 367.049803 -59.725992) (xy 367.103977 -59.718162) (xy 367.131346 -59.717686) (xy 367.158595 -59.718187)
			(xy 367.212537 -59.725949) (xy 367.264825 -59.741307) (xy 367.314396 -59.763951) (xy 367.36024 -59.793418)
			(xy 367.401424 -59.829109) (xy 367.43711 -59.870297) (xy 367.466571 -59.916145) (xy 367.489209 -59.965718)
			(xy 367.504561 -60.018008) (xy 367.512316 -60.071951) (xy 367.512316 -60.126449) (xy 367.504561 -60.180392)
			(xy 367.489209 -60.232682) (xy 367.466571 -60.282255) (xy 367.43711 -60.328103) (xy 367.401424 -60.369291)
			(xy 367.36024 -60.404982) (xy 367.314396 -60.434449) (xy 367.264825 -60.457093) (xy 367.212537 -60.472451)
			(xy 367.158595 -60.480213) (xy 367.131346 -60.480702) (xy 367.103977 -60.480208) (xy 367.049799 -60.472397)
			(xy 366.997296 -60.456915) (xy 366.947549 -60.434079) (xy 366.901581 -60.40436) (xy 366.880648 -60.386722)
			(xy 366.873536 -60.380626) (xy 366.856518 -60.374276) (xy 366.771174 -60.374276) (xy 366.754156 -60.380626)
			(xy 366.747044 -60.386722) (xy 366.726111 -60.404363) (xy 366.680143 -60.434087) (xy 366.630397 -60.456933)
			(xy 366.577895 -60.472429) (xy 366.523717 -60.480258) (xy 366.468975 -60.480258) (xy 366.414797 -60.472429)
			(xy 366.362295 -60.456933) (xy 366.312549 -60.434087) (xy 366.266581 -60.404363) (xy 366.245648 -60.386722)
			(xy 366.238536 -60.380626) (xy 366.221518 -60.374276) (xy 366.136174 -60.374276) (xy 366.119156 -60.380626)
			(xy 366.112044 -60.386722) (xy 366.091109 -60.404357) (xy 366.045137 -60.434069) (xy 365.99539 -60.456905)
			(xy 365.94289 -60.472397) (xy 365.888715 -60.480227) (xy 365.861346 -60.480702) (xy 365.834091 -60.480254)
			(xy 365.780134 -60.472502) (xy 365.72783 -60.45715) (xy 365.678243 -60.434509) (xy 365.632383 -60.405042)
			(xy 365.591185 -60.369348) (xy 365.555485 -60.328154) (xy 365.526013 -60.282297) (xy 365.503366 -60.232714)
			(xy 365.488008 -60.180411) (xy 365.48025 -60.126455) (xy 365.480249 -60.071945) (xy 359.991152 -60.071945)
			(xy 359.991152 -60.999878) (xy 359.990617 -61.009866) (xy 359.982904 -61.028299) (xy 359.976166 -61.035692)
			(xy 359.269538 -61.74232) (xy 359.266236 -61.745622) (xy 359.20045 -61.811408) (xy 359.193096 -61.818064)
			(xy 359.174796 -61.825661) (xy 359.16489 -61.82614) (xy 359.109518 -61.82614) (xy 359.1052 -61.826902)
			(xy 359.101644 -61.82741) (xy 359.09758 -61.827918) (xy 359.094786 -61.82868) (xy 359.09377 -61.82868)
			(xy 359.090976 -61.828934) (xy 359.082121 -61.829961) (xy 359.06433 -61.831107) (xy 359.055416 -61.83122)
			(xy 359.0544 -61.83122) (xy 359.053638 -61.83122) (xy 357.379524 -61.83122) (xy 357.367902 -61.831792)
			(xy 357.347009 -61.841981) (xy 357.339392 -61.850778) (xy 357.28275 -61.923422) (xy 357.277924 -61.946028)
			(xy 357.280972 -61.957712) (xy 357.286438 -61.980757) (xy 357.292292 -62.027757) (xy 357.292656 -62.051438)
			(xy 357.292168 -62.078689) (xy 357.284407 -62.132635) (xy 357.269049 -62.184928) (xy 357.246406 -62.234503)
			(xy 357.21694 -62.280352) (xy 357.181249 -62.321542) (xy 357.14006 -62.357234) (xy 357.094212 -62.386702)
			(xy 357.044637 -62.409346) (xy 356.992345 -62.424705) (xy 356.938399 -62.432467) (xy 356.911148 -62.432946)
			(xy 356.887594 -62.432563) (xy 356.840851 -62.426702) (xy 356.81793 -62.421262) (xy 356.803706 -62.417706)
			(xy 356.776528 -62.426342) (xy 356.698296 -62.517274) (xy 356.693724 -62.545468) (xy 356.699312 -62.55893)
			(xy 356.708637 -62.582314) (xy 356.721756 -62.630918) (xy 356.728373 -62.680824) (xy 356.728776 -62.705996)
			(xy 356.728313 -62.733248) (xy 356.720556 -62.787198) (xy 356.7052 -62.839494) (xy 356.682558 -62.889073)
			(xy 356.653089 -62.934924) (xy 356.617395 -62.976115) (xy 356.576202 -63.011806) (xy 356.530348 -63.041271)
			(xy 356.480768 -63.06391) (xy 356.42847 -63.079262) (xy 356.37452 -63.087015) (xy 356.347268 -63.087504)
			(xy 356.318457 -63.086982) (xy 356.261489 -63.078322) (xy 356.206472 -63.061188) (xy 356.15466 -63.035972)
			(xy 356.107232 -63.003246) (xy 356.085902 -62.983872) (xy 356.077266 -62.975744) (xy 356.055422 -62.968886)
			(xy 355.967792 -62.981332) (xy 355.959747 -62.982777) (xy 355.945107 -62.990024) (xy 355.93909 -62.995556)
			(xy 355.929184 -63.005462) (xy 355.926136 -63.010542) (xy 355.911178 -63.034138) (xy 355.875456 -63.077093)
			(xy 355.833859 -63.114388) (xy 355.787276 -63.145228) (xy 355.736698 -63.168957) (xy 355.683203 -63.185067)
			(xy 355.627934 -63.193217) (xy 355.6 -63.193676) (xy 355.572751 -63.19319) (xy 355.518808 -63.185434)
			(xy 355.466518 -63.17008) (xy 355.416945 -63.147441) (xy 355.371098 -63.117977) (xy 355.329911 -63.082289)
			(xy 355.294223 -63.041102) (xy 355.264759 -62.995255) (xy 355.24212 -62.945682) (xy 355.226766 -62.893392)
			(xy 355.21901 -62.839449) (xy 355.21901 -62.784951) (xy 355.226766 -62.731008) (xy 355.24212 -62.678718)
			(xy 355.264759 -62.629145) (xy 355.294223 -62.583298) (xy 355.329911 -62.542111) (xy 355.371098 -62.506423)
			(xy 355.416945 -62.476959) (xy 355.466518 -62.45432) (xy 355.518808 -62.438966) (xy 355.572751 -62.43121)
			(xy 355.6 -62.43066) (xy 355.62881 -62.431187) (xy 355.685773 -62.439856) (xy 355.740784 -62.456996)
			(xy 355.792591 -62.482216) (xy 355.840013 -62.514944) (xy 355.861366 -62.534292) (xy 355.870002 -62.54242)
			(xy 355.891846 -62.549278) (xy 355.982016 -62.536578) (xy 355.993151 -62.534402) (xy 356.012031 -62.521877)
			(xy 356.018338 -62.512448) (xy 356.018592 -62.512194) (xy 356.018592 -62.51194) (xy 356.03341 -62.48782)
			(xy 356.069049 -62.443842) (xy 356.110797 -62.405616) (xy 356.157737 -62.373981) (xy 356.208838 -62.349632)
			(xy 356.262978 -62.333104) (xy 356.318965 -62.324761) (xy 356.347268 -62.324234) (xy 356.383082 -62.326012)
			(xy 356.391972 -62.327028) (xy 356.407974 -62.329314) (xy 356.41534 -62.330584) (xy 356.415594 -62.330584)
			(xy 356.440486 -62.336172) (xy 356.45471 -62.339728) (xy 356.481888 -62.331092) (xy 356.550468 -62.251336)
			(xy 356.556264 -62.244015) (xy 356.562608 -62.22647) (xy 356.562215 -62.207818) (xy 356.559104 -62.199012)
			(xy 356.55885 -62.198504) (xy 356.55885 -62.19825) (xy 356.549044 -62.173698) (xy 356.535532 -62.122587)
			(xy 356.531926 -62.096396) (xy 356.530656 -62.082426) (xy 356.529386 -62.051438) (xy 356.529386 -62.05093)
			(xy 356.529756 -62.027312) (xy 356.535616 -61.980441) (xy 356.54107 -61.957458) (xy 356.543864 -61.946028)
			(xy 356.539292 -61.923422) (xy 356.483412 -61.851032) (xy 356.47757 -61.844682) (xy 356.470656 -61.838791)
			(xy 356.453863 -61.831902) (xy 356.444804 -61.83122) (xy 355.46411 -61.83122) (xy 355.451411 -61.831074)
			(xy 355.426104 -61.828915) (xy 355.413564 -61.826902) (xy 355.409246 -61.82614) (xy 355.168962 -61.82614)
			(xy 355.157278 -61.829188) (xy 355.152452 -61.831474) (xy 355.151944 -61.831728) (xy 355.122101 -61.845328)
			(xy 355.05901 -61.863215) (xy 355.026468 -61.867288) (xy 355.014784 -61.868304) (xy 354.992392 -61.869652)
			(xy 354.947572 -61.867742) (xy 354.925376 -61.864494) (xy 354.898345 -61.859631) (xy 354.845947 -61.843178)
			(xy 354.820982 -61.831728) (xy 354.816156 -61.829188) (xy 354.804218 -61.82614) (xy 354.553774 -61.82614)
			(xy 354.549456 -61.826902) (xy 354.536914 -61.828896) (xy 354.511608 -61.831059) (xy 354.49891 -61.83122)
			(xy 353.364038 -61.83122) (xy 353.355556 -61.831536) (xy 353.339531 -61.837102) (xy 353.326227 -61.847628)
			(xy 353.321366 -61.854588) (xy 353.317048 -61.861192) (xy 353.27844 -61.92012) (xy 353.273444 -61.928484)
			(xy 353.269509 -61.947551) (xy 353.27082 -61.957204) (xy 353.27209 -61.963808) (xy 353.274376 -61.969396)
			(xy 353.284347 -61.993418) (xy 353.298376 -62.043501) (xy 353.305454 -62.095028) (xy 353.305872 -62.121034)
			(xy 353.305872 -62.12586) (xy 353.30506 -62.152886) (xy 353.29675 -62.206313) (xy 353.280981 -62.258031)
			(xy 353.258069 -62.307004) (xy 353.228472 -62.352253) (xy 353.192783 -62.39287) (xy 353.151718 -62.428042)
			(xy 353.106099 -62.457064) (xy 353.056839 -62.479355) (xy 353.004925 -62.494469) (xy 352.951398 -62.502102)
			(xy 352.89733 -62.502102) (xy 352.843803 -62.494469) (xy 352.791889 -62.479355) (xy 352.742629 -62.457064)
			(xy 352.69701 -62.428042) (xy 352.655945 -62.39287) (xy 352.620256 -62.352253) (xy 352.590659 -62.307004)
			(xy 352.567747 -62.258031) (xy 352.551978 -62.206313) (xy 352.543668 -62.152886) (xy 352.542856 -62.12586)
			(xy 352.542856 -62.121034) (xy 352.543283 -62.094894) (xy 352.550417 -62.043102) (xy 352.564555 -61.992769)
			(xy 352.574606 -61.968634) (xy 352.578416 -61.959744) (xy 352.578924 -61.947044) (xy 352.57867 -61.943996)
			(xy 352.577991 -61.937794) (xy 352.574014 -61.925973) (xy 352.570796 -61.920628) (xy 352.56724 -61.91504)
			(xy 352.526854 -61.85408) (xy 352.519341 -61.843884) (xy 352.497082 -61.831871) (xy 352.484436 -61.83122)
			(xy 349.96247 -61.83122) (xy 349.952403 -61.831649) (xy 349.933808 -61.839373) (xy 349.926402 -61.846206)
			(xy 349.522796 -62.249812) (xy 349.51543 -62.256924) (xy 349.50781 -62.27572) (xy 349.50781 -63.273432)
			(xy 351.876866 -63.273432) (xy 351.880937 -63.21781) (xy 351.893063 -63.163373) (xy 351.912986 -63.111282)
			(xy 351.940282 -63.062647) (xy 351.974368 -63.018504) (xy 352.014517 -62.979795) (xy 352.059875 -62.947344)
			(xy 352.109475 -62.921843) (xy 352.162259 -62.903836) (xy 352.217102 -62.893706) (xy 352.272836 -62.891669)
			(xy 352.328273 -62.897769) (xy 352.38223 -62.911875) (xy 352.433559 -62.933687) (xy 352.481165 -62.962741)
			(xy 352.524033 -62.998416) (xy 352.56125 -63.039953) (xy 352.592023 -63.086466) (xy 352.615695 -63.136963)
			(xy 352.631763 -63.19037) (xy 352.639883 -63.245546) (xy 352.639883 -63.245548) (xy 365.404692 -63.245548)
			(xy 365.404692 -63.191052) (xy 365.412447 -63.13711) (xy 365.427799 -63.084821) (xy 365.450436 -63.035249)
			(xy 365.479897 -62.989402) (xy 365.515582 -62.948215) (xy 365.556766 -62.912525) (xy 365.602608 -62.883058)
			(xy 365.652178 -62.860415) (xy 365.704465 -62.845057) (xy 365.758406 -62.837295) (xy 365.785654 -62.836806)
			(xy 365.813023 -62.837298) (xy 365.867201 -62.845109) (xy 365.919704 -62.860592) (xy 365.969452 -62.883428)
			(xy 366.015419 -62.913147) (xy 366.036352 -62.930786) (xy 366.043464 -62.936882) (xy 366.060482 -62.943232)
			(xy 366.145826 -62.943232) (xy 366.162844 -62.936882) (xy 366.169956 -62.930786) (xy 366.190889 -62.913145)
			(xy 366.236857 -62.883421) (xy 366.286603 -62.860575) (xy 366.339105 -62.845079) (xy 366.393283 -62.83725)
			(xy 366.448025 -62.83725) (xy 366.502203 -62.845079) (xy 366.554705 -62.860575) (xy 366.604451 -62.883421)
			(xy 366.650419 -62.913145) (xy 366.671352 -62.930786) (xy 366.678464 -62.936882) (xy 366.695482 -62.943232)
			(xy 366.780826 -62.943232) (xy 366.797844 -62.936882) (xy 366.804956 -62.930786) (xy 366.825892 -62.913152)
			(xy 366.871864 -62.88344) (xy 366.921611 -62.860603) (xy 366.97411 -62.845111) (xy 367.028285 -62.837281)
			(xy 367.055654 -62.836806) (xy 367.08291 -62.837238) (xy 367.136868 -62.84499) (xy 367.189173 -62.860342)
			(xy 367.238761 -62.882983) (xy 367.284622 -62.912451) (xy 367.325821 -62.948146) (xy 367.361521 -62.989341)
			(xy 367.390995 -63.035198) (xy 367.413642 -63.084784) (xy 367.429001 -63.137087) (xy 367.436759 -63.191044)
			(xy 367.436759 -63.245556) (xy 367.429001 -63.299513) (xy 367.413642 -63.351816) (xy 367.390995 -63.401402)
			(xy 367.361521 -63.447259) (xy 367.325821 -63.488454) (xy 367.284622 -63.524149) (xy 367.238761 -63.553617)
			(xy 367.189173 -63.576258) (xy 367.136868 -63.59161) (xy 367.08291 -63.599362) (xy 367.055654 -63.599822)
			(xy 367.028284 -63.599343) (xy 366.974105 -63.591531) (xy 366.921601 -63.576046) (xy 366.871854 -63.553207)
			(xy 366.825887 -63.523483) (xy 366.804956 -63.505842) (xy 366.797844 -63.499746) (xy 366.780826 -63.493396)
			(xy 366.695482 -63.493396) (xy 366.678464 -63.499746) (xy 366.671352 -63.505842) (xy 366.650419 -63.523483)
			(xy 366.604451 -63.553207) (xy 366.554705 -63.576053) (xy 366.502203 -63.591549) (xy 366.448025 -63.599378)
			(xy 366.393283 -63.599378) (xy 366.339105 -63.591549) (xy 366.286603 -63.576053) (xy 366.236857 -63.553207)
			(xy 366.190889 -63.523483) (xy 366.169956 -63.505842) (xy 366.162844 -63.499746) (xy 366.145826 -63.493396)
			(xy 366.060482 -63.493396) (xy 366.043464 -63.499746) (xy 366.036352 -63.505842) (xy 366.015417 -63.523477)
			(xy 365.969444 -63.553188) (xy 365.919697 -63.576024) (xy 365.867198 -63.591517) (xy 365.813023 -63.599347)
			(xy 365.785654 -63.599822) (xy 365.758406 -63.599305) (xy 365.704465 -63.591543) (xy 365.652178 -63.576185)
			(xy 365.602608 -63.553542) (xy 365.556766 -63.524075) (xy 365.515582 -63.488385) (xy 365.479897 -63.447198)
			(xy 365.450436 -63.401351) (xy 365.427799 -63.351779) (xy 365.412447 -63.29949) (xy 365.404692 -63.245548)
			(xy 352.639883 -63.245548) (xy 352.640392 -63.273432) (xy 352.639883 -63.301318) (xy 352.631763 -63.356494)
			(xy 352.615695 -63.409901) (xy 352.592023 -63.460398) (xy 352.56125 -63.506911) (xy 352.524033 -63.548448)
			(xy 352.481165 -63.584123) (xy 352.433559 -63.613177) (xy 352.38223 -63.634989) (xy 352.328273 -63.649095)
			(xy 352.272836 -63.655195) (xy 352.217102 -63.653158) (xy 352.162259 -63.643028) (xy 352.109475 -63.625021)
			(xy 352.059875 -63.59952) (xy 352.014517 -63.567069) (xy 351.974368 -63.52836) (xy 351.940282 -63.484217)
			(xy 351.912986 -63.435582) (xy 351.893063 -63.383491) (xy 351.880937 -63.329054) (xy 351.876866 -63.273432)
			(xy 349.50781 -63.273432) (xy 349.50781 -64.102234) (xy 349.68764 -64.102234) (xy 349.691711 -64.046612)
			(xy 349.703837 -63.992175) (xy 349.72376 -63.940084) (xy 349.751056 -63.891449) (xy 349.785142 -63.847306)
			(xy 349.825291 -63.808597) (xy 349.870649 -63.776146) (xy 349.920249 -63.750645) (xy 349.973033 -63.732638)
			(xy 350.027876 -63.722508) (xy 350.08361 -63.720471) (xy 350.139047 -63.726571) (xy 350.193004 -63.740677)
			(xy 350.244333 -63.762489) (xy 350.291939 -63.791543) (xy 350.334807 -63.827218) (xy 350.372024 -63.868755)
			(xy 350.402797 -63.915268) (xy 350.426469 -63.965765) (xy 350.442537 -64.019172) (xy 350.450657 -64.074348)
			(xy 350.451166 -64.102234) (xy 350.450657 -64.13012) (xy 350.442537 -64.185296) (xy 350.426469 -64.238703)
			(xy 350.402797 -64.2892) (xy 350.387519 -64.312292) (xy 353.366068 -64.312292) (xy 353.370139 -64.25667)
			(xy 353.382265 -64.202233) (xy 353.402188 -64.150142) (xy 353.429484 -64.101507) (xy 353.46357 -64.057364)
			(xy 353.503719 -64.018655) (xy 353.549077 -63.986204) (xy 353.598677 -63.960703) (xy 353.651461 -63.942696)
			(xy 353.706304 -63.932566) (xy 353.762038 -63.930529) (xy 353.817475 -63.936629) (xy 353.871432 -63.950735)
			(xy 353.922761 -63.972547) (xy 353.970367 -64.001601) (xy 354.013235 -64.037276) (xy 354.050452 -64.078813)
			(xy 354.081225 -64.125326) (xy 354.104897 -64.175823) (xy 354.120965 -64.22923) (xy 354.129085 -64.284406)
			(xy 354.129594 -64.312292) (xy 354.129085 -64.340178) (xy 354.120965 -64.395354) (xy 354.104897 -64.448761)
			(xy 354.081225 -64.499258) (xy 354.050452 -64.545771) (xy 354.013235 -64.587308) (xy 353.970367 -64.622983)
			(xy 353.922761 -64.652037) (xy 353.871432 -64.673849) (xy 353.817475 -64.687955) (xy 353.762038 -64.694055)
			(xy 353.706304 -64.692018) (xy 353.651461 -64.681888) (xy 353.598677 -64.663881) (xy 353.549077 -64.63838)
			(xy 353.503719 -64.605929) (xy 353.46357 -64.56722) (xy 353.429484 -64.523077) (xy 353.402188 -64.474442)
			(xy 353.382265 -64.422351) (xy 353.370139 -64.367914) (xy 353.366068 -64.312292) (xy 350.387519 -64.312292)
			(xy 350.372024 -64.335713) (xy 350.334807 -64.37725) (xy 350.291939 -64.412925) (xy 350.244333 -64.441979)
			(xy 350.193004 -64.463791) (xy 350.139047 -64.477897) (xy 350.08361 -64.483997) (xy 350.027876 -64.48196)
			(xy 349.973033 -64.47183) (xy 349.920249 -64.453823) (xy 349.870649 -64.428322) (xy 349.825291 -64.395871)
			(xy 349.785142 -64.357162) (xy 349.751056 -64.313019) (xy 349.72376 -64.264384) (xy 349.703837 -64.212293)
			(xy 349.691711 -64.157856) (xy 349.68764 -64.102234) (xy 349.50781 -64.102234) (xy 349.50781 -65.124076)
			(xy 354.407468 -65.124076) (xy 354.411539 -65.068454) (xy 354.423665 -65.014017) (xy 354.443588 -64.961926)
			(xy 354.470884 -64.913291) (xy 354.50497 -64.869148) (xy 354.545119 -64.830439) (xy 354.590477 -64.797988)
			(xy 354.640077 -64.772487) (xy 354.692861 -64.75448) (xy 354.747704 -64.74435) (xy 354.803438 -64.742313)
			(xy 354.858875 -64.748413) (xy 354.912832 -64.762519) (xy 354.964161 -64.784331) (xy 355.011767 -64.813385)
			(xy 355.054635 -64.84906) (xy 355.091852 -64.890597) (xy 355.122625 -64.93711) (xy 355.146297 -64.987607)
			(xy 355.162365 -65.041014) (xy 355.170485 -65.09619) (xy 355.170994 -65.124076) (xy 355.170485 -65.151962)
			(xy 355.169318 -65.15989) (xy 367.416586 -65.15989) (xy 367.420657 -65.104268) (xy 367.432783 -65.049831)
			(xy 367.452706 -64.99774) (xy 367.480002 -64.949105) (xy 367.514088 -64.904962) (xy 367.554237 -64.866253)
			(xy 367.599595 -64.833802) (xy 367.649195 -64.808301) (xy 367.701979 -64.790294) (xy 367.756822 -64.780164)
			(xy 367.812556 -64.778127) (xy 367.867993 -64.784227) (xy 367.92195 -64.798333) (xy 367.973279 -64.820145)
			(xy 368.020885 -64.849199) (xy 368.063753 -64.884874) (xy 368.10097 -64.926411) (xy 368.131743 -64.972924)
			(xy 368.155415 -65.023421) (xy 368.171483 -65.076828) (xy 368.179603 -65.132004) (xy 368.180112 -65.15989)
			(xy 368.179603 -65.187776) (xy 368.171483 -65.242952) (xy 368.155415 -65.296359) (xy 368.131743 -65.346856)
			(xy 368.10097 -65.393369) (xy 368.063753 -65.434906) (xy 368.020885 -65.470581) (xy 367.973279 -65.499635)
			(xy 367.92195 -65.521447) (xy 367.867993 -65.535553) (xy 367.812556 -65.541653) (xy 367.756822 -65.539616)
			(xy 367.701979 -65.529486) (xy 367.649195 -65.511479) (xy 367.599595 -65.485978) (xy 367.554237 -65.453527)
			(xy 367.514088 -65.414818) (xy 367.480002 -65.370675) (xy 367.452706 -65.32204) (xy 367.432783 -65.269949)
			(xy 367.420657 -65.215512) (xy 367.416586 -65.15989) (xy 355.169318 -65.15989) (xy 355.162365 -65.207138)
			(xy 355.146297 -65.260545) (xy 355.122625 -65.311042) (xy 355.091852 -65.357555) (xy 355.054635 -65.399092)
			(xy 355.011767 -65.434767) (xy 354.964161 -65.463821) (xy 354.912832 -65.485633) (xy 354.858875 -65.499739)
			(xy 354.803438 -65.505839) (xy 354.747704 -65.503802) (xy 354.692861 -65.493672) (xy 354.640077 -65.475665)
			(xy 354.590477 -65.450164) (xy 354.545119 -65.417713) (xy 354.50497 -65.379004) (xy 354.470884 -65.334861)
			(xy 354.443588 -65.286226) (xy 354.423665 -65.234135) (xy 354.411539 -65.179698) (xy 354.407468 -65.124076)
			(xy 349.50781 -65.124076) (xy 349.50781 -65.75552) (xy 362.64672 -65.75552) (xy 362.650791 -65.699898)
			(xy 362.662917 -65.645461) (xy 362.68284 -65.59337) (xy 362.710136 -65.544735) (xy 362.744222 -65.500592)
			(xy 362.784371 -65.461883) (xy 362.829729 -65.429432) (xy 362.879329 -65.403931) (xy 362.932113 -65.385924)
			(xy 362.986956 -65.375794) (xy 363.04269 -65.373757) (xy 363.098127 -65.379857) (xy 363.152084 -65.393963)
			(xy 363.203413 -65.415775) (xy 363.251019 -65.444829) (xy 363.293887 -65.480504) (xy 363.331104 -65.522041)
			(xy 363.361877 -65.568554) (xy 363.385549 -65.619051) (xy 363.401617 -65.672458) (xy 363.409737 -65.727634)
			(xy 363.410246 -65.75552) (xy 363.409737 -65.783406) (xy 363.401617 -65.838582) (xy 363.385549 -65.891989)
			(xy 363.361877 -65.942486) (xy 363.331104 -65.988999) (xy 363.293887 -66.030536) (xy 363.251019 -66.066211)
			(xy 363.203413 -66.095265) (xy 363.152084 -66.117077) (xy 363.098127 -66.131183) (xy 363.04269 -66.137283)
			(xy 362.986956 -66.135246) (xy 362.932113 -66.125116) (xy 362.879329 -66.107109) (xy 362.829729 -66.081608)
			(xy 362.784371 -66.049157) (xy 362.744222 -66.010448) (xy 362.710136 -65.966305) (xy 362.68284 -65.91767)
			(xy 362.662917 -65.865579) (xy 362.650791 -65.811142) (xy 362.64672 -65.75552) (xy 349.50781 -65.75552)
			(xy 349.50781 -67.347846) (xy 349.508312 -67.35827) (xy 349.516571 -67.377415) (xy 349.523812 -67.38493)
			(xy 349.585026 -67.442588) (xy 349.60433 -67.4497) (xy 349.614998 -67.449192) (xy 349.68619 -67.445596)
			(xy 349.828704 -67.441787) (xy 349.899986 -67.441572) (xy 349.899986 -67.441318) (xy 350.003489 -67.441823)
			(xy 350.210334 -67.449969) (xy 350.416699 -67.466249) (xy 350.600491 -67.488054) (xy 367.079274 -67.488054)
			(xy 367.083345 -67.432432) (xy 367.095471 -67.377995) (xy 367.115394 -67.325904) (xy 367.14269 -67.277269)
			(xy 367.176776 -67.233126) (xy 367.216925 -67.194417) (xy 367.262283 -67.161966) (xy 367.311883 -67.136465)
			(xy 367.364667 -67.118458) (xy 367.41951 -67.108328) (xy 367.475244 -67.106291) (xy 367.530681 -67.112391)
			(xy 367.584638 -67.126497) (xy 367.635967 -67.148309) (xy 367.683573 -67.177363) (xy 367.726441 -67.213038)
			(xy 367.763658 -67.254575) (xy 367.794431 -67.301088) (xy 367.818103 -67.351585) (xy 367.834171 -67.404992)
			(xy 367.842291 -67.460168) (xy 367.8428 -67.488054) (xy 367.842291 -67.51594) (xy 367.834171 -67.571116)
			(xy 367.818103 -67.624523) (xy 367.794431 -67.67502) (xy 367.763658 -67.721533) (xy 367.726441 -67.76307)
			(xy 367.683573 -67.798745) (xy 367.635967 -67.827799) (xy 367.584638 -67.849611) (xy 367.530681 -67.863717)
			(xy 367.475244 -67.869817) (xy 367.41951 -67.86778) (xy 367.364667 -67.85765) (xy 367.311883 -67.839643)
			(xy 367.262283 -67.814142) (xy 367.216925 -67.781691) (xy 367.176776 -67.742982) (xy 367.14269 -67.698839)
			(xy 367.115394 -67.650204) (xy 367.095471 -67.598113) (xy 367.083345 -67.543676) (xy 367.079274 -67.488054)
			(xy 350.600491 -67.488054) (xy 350.622263 -67.490637) (xy 350.826708 -67.523096) (xy 351.029717 -67.563576)
			(xy 351.230976 -67.612013) (xy 351.430172 -67.668334) (xy 351.626998 -67.73245) (xy 351.821149 -67.804262)
			(xy 352.012323 -67.883659) (xy 352.200224 -67.970518) (xy 352.384561 -68.064704) (xy 352.565049 -68.166072)
			(xy 352.741408 -68.274464) (xy 352.913365 -68.389713) (xy 353.080653 -68.511639) (xy 353.243013 -68.640054)
			(xy 353.400194 -68.77476) (xy 353.551952 -68.915546) (xy 353.698052 -69.062196) (xy 353.838267 -69.214482)
			(xy 353.972381 -69.372168) (xy 354.100185 -69.53501) (xy 354.221482 -69.702755) (xy 354.336083 -69.875144)
			(xy 354.443812 -70.051909) (xy 354.494592 -70.1421) (xy 354.494592 -70.142354) (xy 354.498303 -70.148363)
			(xy 354.508346 -70.158283) (xy 354.514404 -70.161912) (xy 354.5332 -70.172326) (xy 354.538924 -70.175284)
			(xy 354.551397 -70.178496) (xy 354.557838 -70.178676)
		)
		(stroke
			(width 0)
			(type solid)
		)
		(fill yes)
		(layer "In9.Cu")
		(net "P12V_SSD12_R")
	)
	(gr_poly
		(pts
			(xy 162.586416 -70.177914) (xy 162.586924 -70.177914) (xy 162.594443 -70.176314) (xy 162.608134 -70.169341)
			(xy 162.613848 -70.164198) (xy 162.941 -69.837046) (xy 162.945985 -69.831546) (xy 162.952821 -69.818378)
			(xy 162.954462 -69.811138) (xy 162.955478 -69.801486) (xy 162.955478 -67.91579) (xy 162.955478 -67.914774)
			(xy 162.954918 -67.905912) (xy 162.948537 -67.889356) (xy 162.936895 -67.875966) (xy 162.929316 -67.87134)
			(xy 162.844226 -67.830192) (xy 162.837635 -67.827316) (xy 162.82345 -67.824989) (xy 162.816286 -67.82562)
			(xy 162.809428 -67.826382) (xy 162.796728 -67.831462) (xy 162.790632 -67.836288) (xy 162.77032 -67.851901)
			(xy 162.726306 -67.87812) (xy 162.679177 -67.898208) (xy 162.629782 -67.911805) (xy 162.579012 -67.918665)
			(xy 162.553396 -67.919092) (xy 162.526146 -67.918605) (xy 162.472201 -67.910849) (xy 162.419909 -67.895494)
			(xy 162.370335 -67.872854) (xy 162.324487 -67.843389) (xy 162.283299 -67.807699) (xy 162.247609 -67.76651)
			(xy 162.218144 -67.720662) (xy 162.195505 -67.671087) (xy 162.18015 -67.618795) (xy 162.172394 -67.56485)
			(xy 162.172394 -67.51035) (xy 162.18015 -67.456405) (xy 162.195505 -67.404113) (xy 162.218144 -67.354538)
			(xy 162.247609 -67.30869) (xy 162.283299 -67.267501) (xy 162.324487 -67.231811) (xy 162.370335 -67.202346)
			(xy 162.419909 -67.179706) (xy 162.472201 -67.164351) (xy 162.526146 -67.156595) (xy 162.553396 -67.156076)
			(xy 162.578986 -67.156509) (xy 162.6297 -67.163396) (xy 162.679037 -67.177006) (xy 162.72611 -67.197095)
			(xy 162.770071 -67.223301) (xy 162.790378 -67.23888) (xy 162.790886 -67.23888) (xy 162.79114 -67.239134)
			(xy 162.796755 -67.243261) (xy 162.809643 -67.248549) (xy 162.81654 -67.249548) (xy 162.823652 -67.250564)
			(xy 162.837622 -67.248024) (xy 162.929316 -67.203828) (xy 162.936891 -67.199194) (xy 162.948543 -67.185812)
			(xy 162.954926 -67.169257) (xy 162.955478 -67.160394) (xy 162.955478 -65.520316) (xy 162.955255 -65.513713)
			(xy 162.951779 -65.500972) (xy 162.94862 -65.49517) (xy 162.945318 -65.489328) (xy 162.936174 -65.480184)
			(xy 162.930078 -65.476628) (xy 162.856672 -65.433956) (xy 162.844226 -65.428622) (xy 162.839146 -65.427606)
			(xy 162.83559 -65.427098) (xy 162.831699 -65.426809) (xy 162.823914 -65.427314) (xy 162.820096 -65.428114)
			(xy 162.80384 -65.432432) (xy 162.798252 -65.43548) (xy 162.769967 -65.450258) (xy 162.709691 -65.471208)
			(xy 162.64677 -65.481836) (xy 162.614864 -65.48247) (xy 162.61461 -65.48247) (xy 162.587359 -65.482007)
			(xy 162.533413 -65.474252) (xy 162.481119 -65.458899) (xy 162.431542 -65.436259) (xy 162.385693 -65.406794)
			(xy 162.344503 -65.371104) (xy 162.308812 -65.329915) (xy 162.279346 -65.284066) (xy 162.256705 -65.23449)
			(xy 162.24135 -65.182197) (xy 162.233593 -65.128251) (xy 162.233593 -65.073749) (xy 162.24135 -65.019803)
			(xy 162.256705 -64.96751) (xy 162.279346 -64.917934) (xy 162.308812 -64.872085) (xy 162.344503 -64.830896)
			(xy 162.385693 -64.795206) (xy 162.431542 -64.765741) (xy 162.481119 -64.743101) (xy 162.533413 -64.727748)
			(xy 162.587359 -64.719993) (xy 162.61461 -64.719454) (xy 162.614864 -64.719454) (xy 162.646766 -64.720123)
			(xy 162.709679 -64.730766) (xy 162.769954 -64.751698) (xy 162.798252 -64.766444) (xy 162.80384 -64.769492)
			(xy 162.820096 -64.77381) (xy 162.82392 -64.77457) (xy 162.831699 -64.775077) (xy 162.83559 -64.774826)
			(xy 162.839146 -64.774318) (xy 162.844226 -64.773302) (xy 162.856672 -64.767968) (xy 162.930078 -64.725296)
			(xy 162.931856 -64.72428) (xy 162.9389 -64.719431) (xy 162.94952 -64.706041) (xy 162.955136 -64.6899)
			(xy 162.955478 -64.681354) (xy 162.955478 -52.63261) (xy 162.95497 -52.626006) (xy 162.9537 -52.615846)
			(xy 162.947638 -52.591596) (xy 162.941136 -52.542033) (xy 162.940746 -52.51704) (xy 162.940746 -52.515262)
			(xy 162.940746 -52.49926) (xy 162.941 -52.49418) (xy 162.94227 -52.481988) (xy 162.943456 -52.469958)
			(xy 162.947143 -52.446065) (xy 162.949636 -52.434236) (xy 162.951414 -52.427378) (xy 162.952684 -52.422552)
			(xy 162.952684 -52.421536) (xy 162.9537 -52.418234) (xy 162.955478 -52.41163) (xy 162.955478 -51.455828)
			(xy 162.955914 -51.445763) (xy 162.963644 -51.427176) (xy 162.970464 -51.41976) (xy 163.077398 -51.312826)
			(xy 163.084795 -51.305977) (xy 163.103393 -51.298237) (xy 163.113466 -51.29784) (xy 163.803838 -51.29784)
			(xy 163.81222 -51.297078) (xy 163.819823 -51.29556) (xy 163.833651 -51.288567) (xy 163.839398 -51.283362)
			(xy 163.904422 -51.218338) (xy 163.911267 -51.21094) (xy 163.918991 -51.192341) (xy 163.919408 -51.18227)
			(xy 163.919408 -49.20615) (xy 163.919154 -49.202594) (xy 163.917745 -49.191295) (xy 163.906527 -49.171517)
			(xy 163.897564 -49.164494) (xy 163.829492 -49.116996) (xy 163.817808 -49.1109) (xy 163.782756 -49.1109)
			(xy 163.774882 -49.113694) (xy 163.744698 -49.123448) (xy 163.682138 -49.133917) (xy 163.650422 -49.134522)
			(xy 163.646358 -49.134522) (xy 163.619298 -49.133762) (xy 163.565791 -49.125541) (xy 163.513985 -49.109838)
			(xy 163.464919 -49.086968) (xy 163.41958 -49.057391) (xy 163.378877 -49.0217) (xy 163.343629 -48.980614)
			(xy 163.314544 -48.934957) (xy 163.292207 -48.885646) (xy 163.277065 -48.833673) (xy 163.269424 -48.780081)
			(xy 163.268914 -48.753014) (xy 163.269376 -48.725761) (xy 163.277132 -48.67181) (xy 163.292487 -48.619512)
			(xy 163.315129 -48.569931) (xy 163.344597 -48.524078) (xy 163.380291 -48.482885) (xy 163.421484 -48.447192)
			(xy 163.467338 -48.417725) (xy 163.516919 -48.395084) (xy 163.569218 -48.37973) (xy 163.623169 -48.371976)
			(xy 163.650422 -48.371506) (xy 163.651184 -48.371506) (xy 163.684801 -48.372256) (xy 163.75098 -48.38413)
			(xy 163.782756 -48.395128) (xy 163.794418 -48.398663) (xy 163.818555 -48.395594) (xy 163.828984 -48.389286)
			(xy 163.863528 -48.365156) (xy 163.897564 -48.341534) (xy 163.897818 -48.34128) (xy 163.90668 -48.334285)
			(xy 163.917745 -48.314637) (xy 163.919154 -48.303434) (xy 163.919408 -48.299878) (xy 163.919408 -41.954704)
			(xy 163.9189 -41.946576) (xy 163.917713 -41.940684) (xy 163.912967 -41.929644) (xy 163.909502 -41.924732)
			(xy 163.904422 -41.918636) (xy 163.02355 -41.037764) (xy 163.020702 -41.035055) (xy 163.014327 -41.030454)
			(xy 163.01085 -41.02862) (xy 163.005423 -41.026037) (xy 162.993744 -41.023213) (xy 162.987736 -41.023032)
			(xy 161.216086 -41.023032) (xy 161.209568 -41.023261) (xy 161.196963 -41.026594) (xy 161.191194 -41.029636)
			(xy 161.186114 -41.03243) (xy 161.176716 -41.04132) (xy 161.128202 -41.121584) (xy 161.123376 -41.131998)
			(xy 161.120594 -41.141946) (xy 161.122314 -41.162512) (xy 161.126678 -41.171876) (xy 161.129218 -41.176956)
			(xy 161.142113 -41.203638) (xy 161.160397 -41.260005) (xy 161.169726 -41.318524) (xy 161.170366 -41.348152)
			(xy 161.170366 -41.35501) (xy 161.169455 -41.383073) (xy 161.16041 -41.438488) (xy 161.14334 -41.491978)
			(xy 161.118615 -41.542388) (xy 161.086768 -41.58863) (xy 161.068004 -41.609518) (xy 161.067496 -41.610026)
			(xy 161.064058 -41.613783) (xy 161.058558 -41.622353) (xy 161.056574 -41.627044) (xy 161.053526 -41.635172)
			(xy 161.053526 -41.714674) (xy 161.053623 -41.719287) (xy 161.055278 -41.728363) (xy 161.056828 -41.732708)
			(xy 161.06013 -41.741344) (xy 161.067242 -41.748964) (xy 161.086513 -41.77029) (xy 161.119077 -41.817651)
			(xy 161.144168 -41.869362) (xy 161.161217 -41.924252) (xy 161.169838 -41.981078) (xy 161.169835 -42.038554)
			(xy 161.16121 -42.09538) (xy 161.144156 -42.150268) (xy 161.119061 -42.201977) (xy 161.086493 -42.249335)
			(xy 161.067242 -42.27068) (xy 161.06013 -42.2783) (xy 161.056828 -42.286936) (xy 161.055288 -42.291284)
			(xy 161.053631 -42.300358) (xy 161.053526 -42.30497) (xy 161.053526 -42.375074) (xy 161.053623 -42.379687)
			(xy 161.055278 -42.388763) (xy 161.056828 -42.393108) (xy 161.06013 -42.401744) (xy 161.067242 -42.409364)
			(xy 161.086509 -42.430693) (xy 161.119066 -42.478057) (xy 161.14415 -42.52977) (xy 161.161194 -42.584659)
			(xy 161.169811 -42.641484) (xy 161.170366 -42.670222) (xy 161.169893 -42.697591) (xy 161.162065 -42.751767)
			(xy 161.146575 -42.804269) (xy 161.123739 -42.854016) (xy 161.094027 -42.899989) (xy 161.076386 -42.92092)
			(xy 161.07029 -42.928032) (xy 161.067242 -42.93616) (xy 161.065703 -42.940508) (xy 161.064051 -42.949582)
			(xy 161.06394 -42.954194) (xy 161.06394 -43.02125) (xy 161.064044 -43.025861) (xy 161.065712 -43.034932)
			(xy 161.067242 -43.039284) (xy 161.07029 -43.047412) (xy 161.076386 -43.054524) (xy 161.094027 -43.075456)
			(xy 161.123751 -43.121422) (xy 161.146592 -43.171169) (xy 161.16208 -43.223673) (xy 161.169895 -43.277852)
			(xy 161.170366 -43.305222) (xy 161.16988 -43.332473) (xy 161.162124 -43.386421) (xy 161.146769 -43.438716)
			(xy 161.124127 -43.488293) (xy 161.094661 -43.534143) (xy 161.05897 -43.575334) (xy 161.017779 -43.611025)
			(xy 160.971929 -43.640491) (xy 160.922352 -43.663133) (xy 160.870057 -43.678488) (xy 160.816109 -43.686244)
			(xy 160.761607 -43.686244) (xy 160.707659 -43.678488) (xy 160.655364 -43.663133) (xy 160.605787 -43.640491)
			(xy 160.559937 -43.611025) (xy 160.518746 -43.575334) (xy 160.483055 -43.534143) (xy 160.453589 -43.488293)
			(xy 160.430947 -43.438716) (xy 160.415592 -43.386421) (xy 160.407836 -43.332473) (xy 160.40735 -43.305222)
			(xy 160.407827 -43.277854) (xy 160.415662 -43.223682) (xy 160.431159 -43.171186) (xy 160.454001 -43.121444)
			(xy 160.483718 -43.075478) (xy 160.50133 -43.054524) (xy 160.507426 -43.047412) (xy 160.510474 -43.039284)
			(xy 160.512016 -43.034936) (xy 160.513676 -43.025862) (xy 160.513776 -43.02125) (xy 160.513776 -42.954194)
			(xy 160.513676 -42.949582) (xy 160.512016 -42.940508) (xy 160.510474 -42.93616) (xy 160.507426 -42.928032)
			(xy 160.50133 -42.92092) (xy 160.483686 -42.89999) (xy 160.453955 -42.854024) (xy 160.431107 -42.804278)
			(xy 160.415613 -42.751774) (xy 160.407791 -42.697593) (xy 160.40735 -42.670222) (xy 160.407869 -42.641483)
			(xy 160.41649 -42.584654) (xy 160.43354 -42.529762) (xy 160.458632 -42.47805) (xy 160.491199 -42.430687)
			(xy 160.510474 -42.409364) (xy 160.517586 -42.401744) (xy 160.520888 -42.393108) (xy 160.522432 -42.38876)
			(xy 160.524095 -42.379687) (xy 160.52419 -42.375074) (xy 160.52419 -42.30497) (xy 160.524088 -42.300358)
			(xy 160.522424 -42.291286) (xy 160.520888 -42.286936) (xy 160.517586 -42.2783) (xy 160.510474 -42.27068)
			(xy 160.491204 -42.249352) (xy 160.458639 -42.201988) (xy 160.433548 -42.150275) (xy 160.416497 -42.095383)
			(xy 160.407873 -42.038555) (xy 160.407871 -41.981077) (xy 160.41649 -41.924248) (xy 160.433536 -41.869355)
			(xy 160.458623 -41.81764) (xy 160.491184 -41.770273) (xy 160.510474 -41.748964) (xy 160.517586 -41.741344)
			(xy 160.520888 -41.732708) (xy 160.522432 -41.72836) (xy 160.524095 -41.719287) (xy 160.52419 -41.714674)
			(xy 160.52419 -41.64457) (xy 160.524088 -41.639958) (xy 160.522424 -41.630886) (xy 160.520888 -41.626536)
			(xy 160.517586 -41.6179) (xy 160.510474 -41.61028) (xy 160.491672 -41.589487) (xy 160.45974 -41.543415)
			(xy 160.434882 -41.493171) (xy 160.417634 -41.439833) (xy 160.408365 -41.384548) (xy 160.40735 -41.356534)
			(xy 160.40735 -41.349422) (xy 160.407941 -41.319721) (xy 160.417184 -41.261043) (xy 160.435387 -41.204498)
			(xy 160.448244 -41.177718) (xy 160.45307 -41.167558) (xy 160.456268 -41.158796) (xy 160.456781 -41.140167)
			(xy 160.454086 -41.131236) (xy 160.449514 -41.121584) (xy 160.40481 -41.04767) (xy 160.399998 -41.040388)
			(xy 160.386505 -41.029333) (xy 160.370096 -41.023419) (xy 160.361376 -41.023032) (xy 159.454088 -41.023032)
			(xy 159.4483 -41.02316) (xy 159.437013 -41.025729) (xy 159.431736 -41.028112) (xy 159.42691 -41.030652)
			(xy 159.41802 -41.037764) (xy 159.41421 -41.04259) (xy 159.36468 -41.105836) (xy 159.361287 -41.110462)
			(xy 159.356412 -41.120843) (xy 159.355028 -41.12641) (xy 159.352742 -41.137586) (xy 159.355536 -41.14927)
			(xy 159.360857 -41.171949) (xy 159.366587 -41.21818) (xy 159.366966 -41.241472) (xy 159.366505 -41.268725)
			(xy 159.358751 -41.322677) (xy 159.343397 -41.374976) (xy 159.320755 -41.424557) (xy 159.291287 -41.47041)
			(xy 159.255593 -41.511603) (xy 159.214399 -41.547296) (xy 159.168544 -41.576762) (xy 159.118962 -41.599401)
			(xy 159.066663 -41.614754) (xy 159.012711 -41.622506) (xy 158.985458 -41.62298) (xy 158.956717 -41.622463)
			(xy 158.899886 -41.613848) (xy 158.84499 -41.596804) (xy 158.793272 -41.571716) (xy 158.745904 -41.539153)
			(xy 158.7246 -41.519856) (xy 158.71698 -41.512744) (xy 158.708344 -41.509442) (xy 158.703996 -41.507903)
			(xy 158.694922 -41.50625) (xy 158.69031 -41.50614) (xy 158.620206 -41.50614) (xy 158.615594 -41.506239)
			(xy 158.606519 -41.507898) (xy 158.602172 -41.509442) (xy 158.593536 -41.512744) (xy 158.585916 -41.519856)
			(xy 158.564589 -41.539126) (xy 158.517226 -41.571691) (xy 158.465515 -41.596782) (xy 158.410624 -41.613832)
			(xy 158.353797 -41.622454) (xy 158.296319 -41.622454) (xy 158.239492 -41.613832) (xy 158.184601 -41.596782)
			(xy 158.13289 -41.571691) (xy 158.085527 -41.539126) (xy 158.0642 -41.519856) (xy 158.05658 -41.512744)
			(xy 158.047944 -41.509442) (xy 158.043596 -41.507903) (xy 158.034522 -41.50625) (xy 158.02991 -41.50614)
			(xy 157.959806 -41.50614) (xy 157.955194 -41.506239) (xy 157.946119 -41.507898) (xy 157.941772 -41.509442)
			(xy 157.933136 -41.512744) (xy 157.925516 -41.519856) (xy 157.904189 -41.539127) (xy 157.856826 -41.571692)
			(xy 157.805114 -41.596786) (xy 157.750224 -41.613841) (xy 157.693397 -41.62247) (xy 157.664658 -41.62298)
			(xy 157.637409 -41.622491) (xy 157.583468 -41.614729) (xy 157.53118 -41.59937) (xy 157.48161 -41.576726)
			(xy 157.435767 -41.547259) (xy 157.394584 -41.511567) (xy 157.358899 -41.470377) (xy 157.32944 -41.424529)
			(xy 157.306805 -41.374955) (xy 157.291456 -41.322664) (xy 157.283704 -41.268721) (xy 157.28315 -41.241472)
			(xy 157.283529 -41.21818) (xy 157.289259 -41.171949) (xy 157.29458 -41.14927) (xy 157.297374 -41.137586)
			(xy 157.295088 -41.12641) (xy 157.293746 -41.120827) (xy 157.288879 -41.11043) (xy 157.285436 -41.105836)
			(xy 157.235906 -41.04259) (xy 157.228364 -41.033805) (xy 157.207592 -41.023633) (xy 157.196028 -41.023032)
			(xy 154.008328 -41.023032) (xy 154.003451 -41.02313) (xy 153.993863 -41.024921) (xy 153.989278 -41.026588)
			(xy 153.980134 -41.030398) (xy 153.80589 -41.204642) (xy 153.799214 -41.212054) (xy 153.791648 -41.23049)
			(xy 153.791158 -41.240456) (xy 153.791158 -43.73626) (xy 162.31311 -43.73626) (xy 162.317181 -43.680638)
			(xy 162.329307 -43.626201) (xy 162.34923 -43.57411) (xy 162.376526 -43.525475) (xy 162.410612 -43.481332)
			(xy 162.450761 -43.442623) (xy 162.496119 -43.410172) (xy 162.545719 -43.384671) (xy 162.598503 -43.366664)
			(xy 162.653346 -43.356534) (xy 162.70908 -43.354497) (xy 162.764517 -43.360597) (xy 162.818474 -43.374703)
			(xy 162.869803 -43.396515) (xy 162.917409 -43.425569) (xy 162.960277 -43.461244) (xy 162.997494 -43.502781)
			(xy 163.028267 -43.549294) (xy 163.051939 -43.599791) (xy 163.068007 -43.653198) (xy 163.076127 -43.708374)
			(xy 163.076636 -43.73626) (xy 163.076127 -43.764146) (xy 163.068007 -43.819322) (xy 163.051939 -43.872729)
			(xy 163.028267 -43.923226) (xy 162.997494 -43.969739) (xy 162.960277 -44.011276) (xy 162.917409 -44.046951)
			(xy 162.869803 -44.076005) (xy 162.818474 -44.097817) (xy 162.764517 -44.111923) (xy 162.70908 -44.118023)
			(xy 162.653346 -44.115986) (xy 162.598503 -44.105856) (xy 162.545719 -44.087849) (xy 162.496119 -44.062348)
			(xy 162.450761 -44.029897) (xy 162.410612 -43.991188) (xy 162.376526 -43.947045) (xy 162.34923 -43.89841)
			(xy 162.329307 -43.846319) (xy 162.317181 -43.791882) (xy 162.31311 -43.73626) (xy 153.791158 -43.73626)
			(xy 153.791158 -45.114464) (xy 162.165536 -45.114464) (xy 162.169607 -45.058842) (xy 162.181733 -45.004405)
			(xy 162.201656 -44.952314) (xy 162.228952 -44.903679) (xy 162.263038 -44.859536) (xy 162.303187 -44.820827)
			(xy 162.348545 -44.788376) (xy 162.398145 -44.762875) (xy 162.450929 -44.744868) (xy 162.505772 -44.734738)
			(xy 162.561506 -44.732701) (xy 162.616943 -44.738801) (xy 162.6709 -44.752907) (xy 162.722229 -44.774719)
			(xy 162.769835 -44.803773) (xy 162.812703 -44.839448) (xy 162.84992 -44.880985) (xy 162.880693 -44.927498)
			(xy 162.904365 -44.977995) (xy 162.920433 -45.031402) (xy 162.928553 -45.086578) (xy 162.929062 -45.114464)
			(xy 162.928553 -45.14235) (xy 162.920433 -45.197526) (xy 162.904365 -45.250933) (xy 162.880693 -45.30143)
			(xy 162.84992 -45.347943) (xy 162.812703 -45.38948) (xy 162.769835 -45.425155) (xy 162.722229 -45.454209)
			(xy 162.6709 -45.476021) (xy 162.616943 -45.490127) (xy 162.561506 -45.496227) (xy 162.505772 -45.49419)
			(xy 162.450929 -45.48406) (xy 162.398145 -45.466053) (xy 162.348545 -45.440552) (xy 162.303187 -45.408101)
			(xy 162.263038 -45.369392) (xy 162.228952 -45.325249) (xy 162.201656 -45.276614) (xy 162.181733 -45.224523)
			(xy 162.169607 -45.170086) (xy 162.165536 -45.114464) (xy 153.791158 -45.114464) (xy 153.791158 -46.893226)
			(xy 162.437316 -46.893226) (xy 162.441387 -46.837604) (xy 162.453513 -46.783167) (xy 162.473436 -46.731076)
			(xy 162.500732 -46.682441) (xy 162.534818 -46.638298) (xy 162.574967 -46.599589) (xy 162.620325 -46.567138)
			(xy 162.669925 -46.541637) (xy 162.722709 -46.52363) (xy 162.777552 -46.5135) (xy 162.833286 -46.511463)
			(xy 162.888723 -46.517563) (xy 162.94268 -46.531669) (xy 162.994009 -46.553481) (xy 163.041615 -46.582535)
			(xy 163.084483 -46.61821) (xy 163.1217 -46.659747) (xy 163.152473 -46.70626) (xy 163.176145 -46.756757)
			(xy 163.192213 -46.810164) (xy 163.200333 -46.86534) (xy 163.200842 -46.893226) (xy 163.200333 -46.921112)
			(xy 163.192213 -46.976288) (xy 163.176145 -47.029695) (xy 163.152473 -47.080192) (xy 163.1217 -47.126705)
			(xy 163.084483 -47.168242) (xy 163.041615 -47.203917) (xy 162.994009 -47.232971) (xy 162.94268 -47.254783)
			(xy 162.888723 -47.268889) (xy 162.833286 -47.274989) (xy 162.777552 -47.272952) (xy 162.722709 -47.262822)
			(xy 162.669925 -47.244815) (xy 162.620325 -47.219314) (xy 162.574967 -47.186863) (xy 162.534818 -47.148154)
			(xy 162.500732 -47.104011) (xy 162.473436 -47.055376) (xy 162.453513 -47.003285) (xy 162.441387 -46.948848)
			(xy 162.437316 -46.893226) (xy 153.791158 -46.893226) (xy 153.791158 -47.936658) (xy 160.753044 -47.936658)
			(xy 160.75353 -47.909407) (xy 160.761286 -47.855459) (xy 160.776641 -47.803164) (xy 160.799283 -47.753587)
			(xy 160.828749 -47.707737) (xy 160.86444 -47.666546) (xy 160.905631 -47.630855) (xy 160.951481 -47.601389)
			(xy 161.001058 -47.578747) (xy 161.053353 -47.563392) (xy 161.107301 -47.555636) (xy 161.161803 -47.555636)
			(xy 161.215751 -47.563392) (xy 161.268046 -47.578747) (xy 161.317623 -47.601389) (xy 161.363473 -47.630855)
			(xy 161.404664 -47.666546) (xy 161.440355 -47.707737) (xy 161.469821 -47.753587) (xy 161.492463 -47.803164)
			(xy 161.507818 -47.855459) (xy 161.515574 -47.909407) (xy 161.51606 -47.936658) (xy 161.515595 -47.962999)
			(xy 161.508345 -48.015179) (xy 161.49399 -48.065867) (xy 161.472804 -48.1141) (xy 161.445188 -48.158963)
			(xy 161.411667 -48.199604) (xy 161.372877 -48.23525) (xy 161.351468 -48.250602) (xy 161.33964 -48.259295)
			(xy 161.321198 -48.282119) (xy 161.310011 -48.309246) (xy 161.307002 -48.338435) (xy 161.31242 -48.367273)
			(xy 161.325817 -48.39338) (xy 161.346088 -48.414597) (xy 161.35858 -48.422306) (xy 161.383117 -48.436999)
			(xy 161.427876 -48.472601) (xy 161.466819 -48.514485) (xy 161.499075 -48.561712) (xy 161.52392 -48.613224)
			(xy 161.540799 -48.667868) (xy 161.549333 -48.724418) (xy 161.549842 -48.753014) (xy 161.549356 -48.780265)
			(xy 161.5416 -48.834213) (xy 161.526245 -48.886508) (xy 161.503603 -48.936085) (xy 161.474137 -48.981935)
			(xy 161.438446 -49.023126) (xy 161.397255 -49.058817) (xy 161.351405 -49.088283) (xy 161.301828 -49.110925)
			(xy 161.249533 -49.12628) (xy 161.195585 -49.134036) (xy 161.141083 -49.134036) (xy 161.087135 -49.12628)
			(xy 161.03484 -49.110925) (xy 160.985263 -49.088283) (xy 160.939413 -49.058817) (xy 160.898222 -49.023126)
			(xy 160.862531 -48.981935) (xy 160.833065 -48.936085) (xy 160.810423 -48.886508) (xy 160.795068 -48.834213)
			(xy 160.787312 -48.780265) (xy 160.786826 -48.753014) (xy 160.787276 -48.726673) (xy 160.79453 -48.674493)
			(xy 160.808887 -48.623804) (xy 160.830076 -48.575571) (xy 160.857694 -48.530709) (xy 160.891217 -48.490068)
			(xy 160.930008 -48.454422) (xy 160.951418 -48.43907) (xy 160.963262 -48.430402) (xy 160.981688 -48.407568)
			(xy 160.992863 -48.380437) (xy 160.995865 -48.35125) (xy 160.990446 -48.322412) (xy 160.977054 -48.296305)
			(xy 160.956794 -48.275082) (xy 160.944306 -48.267366) (xy 160.919798 -48.252628) (xy 160.87504 -48.217032)
			(xy 160.836096 -48.175156) (xy 160.803837 -48.127937) (xy 160.778987 -48.076432) (xy 160.762101 -48.021796)
			(xy 160.753558 -47.965251) (xy 160.753044 -47.936658) (xy 153.791158 -47.936658) (xy 153.791158 -58.731404)
			(xy 155.62072 -58.731404) (xy 155.621184 -58.704034) (xy 155.629001 -58.649854) (xy 155.644491 -58.597351)
			(xy 155.667333 -58.547604) (xy 155.697058 -58.501637) (xy 155.7147 -58.480706) (xy 155.714954 -58.480452)
			(xy 155.720531 -58.473359) (xy 155.726782 -58.456447) (xy 155.727146 -58.447432) (xy 155.727146 -58.380376)
			(xy 155.726812 -58.371356) (xy 155.72055 -58.354439) (xy 155.714954 -58.347356) (xy 155.7147 -58.347356)
			(xy 155.7147 -58.347102) (xy 155.697064 -58.326166) (xy 155.667341 -58.280198) (xy 155.644498 -58.230452)
			(xy 155.629002 -58.177951) (xy 155.621174 -58.123773) (xy 155.621173 -58.069033) (xy 155.629001 -58.014855)
			(xy 155.644495 -57.962354) (xy 155.667339 -57.912608) (xy 155.697061 -57.866639) (xy 155.7147 -57.845706)
			(xy 155.714954 -57.845452) (xy 155.720531 -57.838359) (xy 155.726782 -57.821447) (xy 155.727146 -57.812432)
			(xy 155.727146 -57.745376) (xy 155.726812 -57.736356) (xy 155.72055 -57.719439) (xy 155.714954 -57.712356)
			(xy 155.7147 -57.712356) (xy 155.7147 -57.712102) (xy 155.697064 -57.691166) (xy 155.667341 -57.645198)
			(xy 155.644498 -57.595452) (xy 155.629002 -57.542951) (xy 155.621174 -57.488773) (xy 155.621173 -57.434033)
			(xy 155.629001 -57.379855) (xy 155.644495 -57.327354) (xy 155.667339 -57.277608) (xy 155.697061 -57.231639)
			(xy 155.7147 -57.210706) (xy 155.714954 -57.210452) (xy 155.720531 -57.203359) (xy 155.726782 -57.186447)
			(xy 155.727146 -57.177432) (xy 155.727146 -57.110376) (xy 155.726812 -57.101356) (xy 155.72055 -57.084439)
			(xy 155.714954 -57.077356) (xy 155.7147 -57.077356) (xy 155.7147 -57.077102) (xy 155.697048 -57.05618)
			(xy 155.667338 -57.010204) (xy 155.644505 -56.960454) (xy 155.629017 -56.907951) (xy 155.621192 -56.853774)
			(xy 155.62072 -56.826404) (xy 155.621206 -56.799153) (xy 155.628962 -56.745205) (xy 155.644317 -56.69291)
			(xy 155.666959 -56.643333) (xy 155.696425 -56.597483) (xy 155.732116 -56.556292) (xy 155.773307 -56.520601)
			(xy 155.819157 -56.491135) (xy 155.868734 -56.468493) (xy 155.921029 -56.453138) (xy 155.974977 -56.445382)
			(xy 156.029479 -56.445382) (xy 156.083427 -56.453138) (xy 156.135722 -56.468493) (xy 156.185299 -56.491135)
			(xy 156.231149 -56.520601) (xy 156.27234 -56.556292) (xy 156.308031 -56.597483) (xy 156.337497 -56.643333)
			(xy 156.360139 -56.69291) (xy 156.375494 -56.745205) (xy 156.38325 -56.799153) (xy 156.383736 -56.826404)
			(xy 156.383288 -56.853775) (xy 156.375468 -56.907956) (xy 156.359976 -56.960459) (xy 156.33713 -57.010206)
			(xy 156.3074 -57.056172) (xy 156.289756 -57.077102) (xy 156.289502 -57.077356) (xy 156.283928 -57.084451)
			(xy 156.277674 -57.101361) (xy 156.27731 -57.110376) (xy 156.27731 -57.177432) (xy 156.27765 -57.186451)
			(xy 156.283909 -57.203368) (xy 156.289502 -57.210452) (xy 156.289756 -57.210452) (xy 156.289756 -57.210706)
			(xy 156.307401 -57.231635) (xy 156.337127 -57.277603) (xy 156.359973 -57.32735) (xy 156.37547 -57.379853)
			(xy 156.383299 -57.434032) (xy 156.383298 -57.488774) (xy 156.375469 -57.542953) (xy 156.359971 -57.595456)
			(xy 156.337124 -57.645202) (xy 156.307398 -57.69117) (xy 156.289756 -57.712102) (xy 156.289502 -57.712356)
			(xy 156.283928 -57.719451) (xy 156.277674 -57.736361) (xy 156.27731 -57.745376) (xy 156.27731 -57.812432)
			(xy 156.27765 -57.821451) (xy 156.283909 -57.838368) (xy 156.289502 -57.845452) (xy 156.289756 -57.845452)
			(xy 156.289756 -57.845706) (xy 156.307401 -57.866635) (xy 156.337127 -57.912603) (xy 156.359973 -57.96235)
			(xy 156.37547 -58.014853) (xy 156.383299 -58.069032) (xy 156.383298 -58.123774) (xy 156.375469 -58.177953)
			(xy 156.359971 -58.230456) (xy 156.337124 -58.280202) (xy 156.307398 -58.32617) (xy 156.289756 -58.347102)
			(xy 156.289502 -58.347356) (xy 156.283928 -58.354451) (xy 156.277674 -58.371361) (xy 156.27731 -58.380376)
			(xy 156.27731 -58.447432) (xy 156.27765 -58.456451) (xy 156.283909 -58.473368) (xy 156.289502 -58.480452)
			(xy 156.289756 -58.480452) (xy 156.289756 -58.480706) (xy 156.307405 -58.501631) (xy 156.337116 -58.547605)
			(xy 156.359951 -58.597354) (xy 156.37544 -58.649857) (xy 156.383264 -58.704034) (xy 156.383736 -58.731404)
			(xy 156.38325 -58.758655) (xy 156.378586 -58.791094) (xy 158.276544 -58.791094) (xy 158.276996 -58.763723)
			(xy 158.284815 -58.709543) (xy 158.300307 -58.657039) (xy 158.323152 -58.607293) (xy 158.352881 -58.561327)
			(xy 158.370524 -58.540396) (xy 158.370778 -58.540142) (xy 158.376362 -58.533054) (xy 158.382608 -58.516138)
			(xy 158.38297 -58.507122) (xy 158.38297 -58.440066) (xy 158.382636 -58.431047) (xy 158.376373 -58.41413)
			(xy 158.370778 -58.407046) (xy 158.370524 -58.407046) (xy 158.370524 -58.406792) (xy 158.352878 -58.385864)
			(xy 158.323153 -58.339895) (xy 158.300308 -58.290148) (xy 158.284813 -58.237645) (xy 158.276985 -58.183466)
			(xy 158.276985 -58.128725) (xy 158.284815 -58.074546) (xy 158.300312 -58.022043) (xy 158.323158 -57.972297)
			(xy 158.352883 -57.926329) (xy 158.370524 -57.905396) (xy 158.370778 -57.905142) (xy 158.376362 -57.898054)
			(xy 158.382608 -57.881138) (xy 158.38297 -57.872122) (xy 158.38297 -57.805066) (xy 158.382636 -57.796047)
			(xy 158.376373 -57.77913) (xy 158.370778 -57.772046) (xy 158.370524 -57.772046) (xy 158.370524 -57.771792)
			(xy 158.352871 -57.750871) (xy 158.323161 -57.704895) (xy 158.300327 -57.655145) (xy 158.284839 -57.602642)
			(xy 158.277015 -57.548464) (xy 158.276544 -57.521094) (xy 158.276993 -57.494779) (xy 158.28423 -57.442649)
			(xy 158.298552 -57.392006) (xy 158.319687 -57.343807) (xy 158.347237 -57.298964) (xy 158.38068 -57.258325)
			(xy 158.399734 -57.24017) (xy 158.407141 -57.232653) (xy 158.415665 -57.21337) (xy 158.416244 -57.202832)
			(xy 158.416244 -57.128156) (xy 158.415685 -57.11761) (xy 158.407169 -57.098315) (xy 158.399734 -57.090818)
			(xy 158.380682 -57.07266) (xy 158.347227 -57.032029) (xy 158.319669 -56.987189) (xy 158.29853 -56.938989)
			(xy 158.284212 -56.888343) (xy 158.276984 -56.83621) (xy 158.276544 -56.809894) (xy 158.27703 -56.782643)
			(xy 158.284786 -56.728695) (xy 158.300141 -56.6764) (xy 158.322783 -56.626823) (xy 158.352249 -56.580973)
			(xy 158.38794 -56.539782) (xy 158.429131 -56.504091) (xy 158.474981 -56.474625) (xy 158.524558 -56.451983)
			(xy 158.576853 -56.436628) (xy 158.630801 -56.428872) (xy 158.685303 -56.428872) (xy 158.739251 -56.436628)
			(xy 158.791546 -56.451983) (xy 158.841123 -56.474625) (xy 158.886973 -56.504091) (xy 158.928164 -56.539782)
			(xy 158.963855 -56.580973) (xy 158.993321 -56.626823) (xy 159.015963 -56.6764) (xy 159.031318 -56.728695)
			(xy 159.039074 -56.782643) (xy 159.03956 -56.809894) (xy 159.039101 -56.836208) (xy 159.031866 -56.888338)
			(xy 159.017547 -56.938981) (xy 158.996413 -56.98718) (xy 158.968864 -57.032024) (xy 158.935423 -57.072662)
			(xy 158.91637 -57.090818) (xy 158.908969 -57.09834) (xy 158.900442 -57.117619) (xy 158.89986 -57.128156)
			(xy 158.89986 -57.202832) (xy 158.900424 -57.213377) (xy 158.908936 -57.232672) (xy 158.91637 -57.24017)
			(xy 158.935398 -57.258353) (xy 158.968859 -57.298976) (xy 158.996422 -57.34381) (xy 159.017566 -57.392006)
			(xy 159.031888 -57.442649) (xy 159.035273 -57.467053) (xy 159.218569 -57.467053) (xy 159.218569 -57.412547)
			(xy 159.226327 -57.358595) (xy 159.241684 -57.306297) (xy 159.264328 -57.256717) (xy 159.293797 -57.210864)
			(xy 159.329493 -57.169672) (xy 159.370688 -57.133979) (xy 159.416543 -57.104513) (xy 159.466125 -57.081873)
			(xy 159.518425 -57.06652) (xy 159.572377 -57.058767) (xy 159.59963 -57.058306) (xy 159.625945 -57.058752)
			(xy 159.678074 -57.065991) (xy 159.728717 -57.080314) (xy 159.776916 -57.10145) (xy 159.821759 -57.129)
			(xy 159.862398 -57.162443) (xy 159.880554 -57.181496) (xy 159.888054 -57.188923) (xy 159.907351 -57.197433)
			(xy 159.917892 -57.198006) (xy 159.992568 -57.198006) (xy 160.003117 -57.197471) (xy 160.022412 -57.18894)
			(xy 160.029906 -57.181496) (xy 160.048065 -57.162444) (xy 160.088694 -57.128986) (xy 160.133534 -57.101427)
			(xy 160.181734 -57.080288) (xy 160.232381 -57.06597) (xy 160.284514 -57.058745) (xy 160.31083 -57.058306)
			(xy 160.338081 -57.058766) (xy 160.392027 -57.066526) (xy 160.427173 -57.076848) (xy 161.238692 -57.076848)
			(xy 161.239188 -57.049479) (xy 161.246999 -56.995301) (xy 161.262481 -56.942798) (xy 161.285316 -56.893051)
			(xy 161.315034 -56.847083) (xy 161.332672 -56.82615) (xy 161.332926 -56.825896) (xy 161.338523 -56.818817)
			(xy 161.344763 -56.801894) (xy 161.345118 -56.792876) (xy 161.345118 -56.72582) (xy 161.344748 -56.716805)
			(xy 161.338509 -56.699888) (xy 161.332926 -56.6928) (xy 161.332672 -56.6928) (xy 161.332672 -56.692546)
			(xy 161.315037 -56.671611) (xy 161.285325 -56.625639) (xy 161.262489 -56.575892) (xy 161.246997 -56.523392)
			(xy 161.239167 -56.469217) (xy 161.238692 -56.441848) (xy 161.239178 -56.414597) (xy 161.246934 -56.360649)
			(xy 161.262289 -56.308354) (xy 161.284931 -56.258777) (xy 161.314397 -56.212927) (xy 161.350088 -56.171736)
			(xy 161.391279 -56.136045) (xy 161.437129 -56.106579) (xy 161.486706 -56.083937) (xy 161.539001 -56.068582)
			(xy 161.592949 -56.060826) (xy 161.647451 -56.060826) (xy 161.701399 -56.068582) (xy 161.753694 -56.083937)
			(xy 161.803271 -56.106579) (xy 161.849121 -56.136045) (xy 161.890312 -56.171736) (xy 161.926003 -56.212927)
			(xy 161.955469 -56.258777) (xy 161.978111 -56.308354) (xy 161.993466 -56.360649) (xy 162.001222 -56.414597)
			(xy 162.001708 -56.441848) (xy 162.001209 -56.469217) (xy 161.993399 -56.523395) (xy 161.977918 -56.575897)
			(xy 161.955083 -56.625645) (xy 161.925366 -56.671613) (xy 161.907728 -56.692546) (xy 161.907474 -56.6928)
			(xy 161.901878 -56.69988) (xy 161.895638 -56.716802) (xy 161.895282 -56.72582) (xy 161.895282 -56.792876)
			(xy 161.895654 -56.801891) (xy 161.901892 -56.818808) (xy 161.907474 -56.825896) (xy 161.907728 -56.825896)
			(xy 161.907728 -56.82615) (xy 161.925361 -56.847087) (xy 161.955073 -56.893059) (xy 161.97791 -56.942805)
			(xy 161.993402 -56.995304) (xy 162.001233 -57.049479) (xy 162.001708 -57.076848) (xy 162.001222 -57.104099)
			(xy 161.993466 -57.158047) (xy 161.978111 -57.210342) (xy 161.955469 -57.259919) (xy 161.926003 -57.305769)
			(xy 161.890312 -57.34696) (xy 161.849121 -57.382651) (xy 161.803271 -57.412117) (xy 161.753694 -57.434759)
			(xy 161.701399 -57.450114) (xy 161.647451 -57.45787) (xy 161.592949 -57.45787) (xy 161.539001 -57.450114)
			(xy 161.486706 -57.434759) (xy 161.437129 -57.412117) (xy 161.391279 -57.382651) (xy 161.350088 -57.34696)
			(xy 161.314397 -57.305769) (xy 161.284931 -57.259919) (xy 161.262289 -57.210342) (xy 161.246934 -57.158047)
			(xy 161.239178 -57.104099) (xy 161.238692 -57.076848) (xy 160.427173 -57.076848) (xy 160.44432 -57.081884)
			(xy 160.493896 -57.104528) (xy 160.539744 -57.133996) (xy 160.580932 -57.169689) (xy 160.616622 -57.21088)
			(xy 160.646086 -57.256731) (xy 160.668726 -57.306308) (xy 160.68408 -57.358602) (xy 160.691836 -57.412549)
			(xy 160.691836 -57.467051) (xy 160.68408 -57.520998) (xy 160.668726 -57.573292) (xy 160.646086 -57.622869)
			(xy 160.616622 -57.66872) (xy 160.580932 -57.709911) (xy 160.539744 -57.745604) (xy 160.493896 -57.775072)
			(xy 160.44432 -57.797716) (xy 160.392027 -57.813074) (xy 160.338081 -57.820834) (xy 160.31083 -57.821322)
			(xy 160.284515 -57.820894) (xy 160.232385 -57.81365) (xy 160.181742 -57.799323) (xy 160.133543 -57.778183)
			(xy 160.0887 -57.75063) (xy 160.048062 -57.717186) (xy 160.029906 -57.698132) (xy 160.02238 -57.690736)
			(xy 160.003103 -57.682207) (xy 159.992568 -57.681622) (xy 159.917892 -57.681622) (xy 159.907339 -57.682127)
			(xy 159.888044 -57.690679) (xy 159.880554 -57.698132) (xy 159.86242 -57.717209) (xy 159.821785 -57.750663)
			(xy 159.77694 -57.778218) (xy 159.728735 -57.799353) (xy 159.678084 -57.813666) (xy 159.625947 -57.820886)
			(xy 159.59963 -57.821322) (xy 159.572377 -57.820833) (xy 159.518425 -57.81308) (xy 159.466125 -57.797727)
			(xy 159.416543 -57.775087) (xy 159.370688 -57.745621) (xy 159.329493 -57.709928) (xy 159.293797 -57.668736)
			(xy 159.264328 -57.622883) (xy 159.241684 -57.573303) (xy 159.226327 -57.521005) (xy 159.218569 -57.467053)
			(xy 159.035273 -57.467053) (xy 159.039119 -57.494779) (xy 159.03956 -57.521094) (xy 159.0391 -57.548465)
			(xy 159.031282 -57.602644) (xy 159.015792 -57.655148) (xy 158.992949 -57.704895) (xy 158.963222 -57.750861)
			(xy 158.94558 -57.771792) (xy 158.945326 -57.772046) (xy 158.939747 -57.779138) (xy 158.933498 -57.796051)
			(xy 158.933134 -57.805066) (xy 158.933134 -57.872122) (xy 158.933473 -57.881141) (xy 158.939732 -57.898058)
			(xy 158.945326 -57.905142) (xy 158.94558 -57.905142) (xy 158.94558 -57.905396) (xy 158.963215 -57.926334)
			(xy 158.992939 -57.972301) (xy 159.015784 -58.022046) (xy 159.031281 -58.074547) (xy 159.03911 -58.128725)
			(xy 159.03911 -58.183466) (xy 159.031283 -58.237644) (xy 159.015787 -58.290145) (xy 158.992943 -58.339891)
			(xy 158.96322 -58.385859) (xy 158.94558 -58.406792) (xy 158.945326 -58.407046) (xy 158.939747 -58.414138)
			(xy 158.933498 -58.431051) (xy 158.933134 -58.440066) (xy 158.933134 -58.507122) (xy 158.933473 -58.516141)
			(xy 158.939732 -58.533058) (xy 158.945326 -58.540142) (xy 158.94558 -58.540142) (xy 158.94558 -58.540396)
			(xy 158.963228 -58.561321) (xy 158.992939 -58.607296) (xy 159.015773 -58.657045) (xy 159.031262 -58.709547)
			(xy 159.039088 -58.763724) (xy 159.03956 -58.791094) (xy 159.039074 -58.818345) (xy 159.031318 -58.872293)
			(xy 159.030921 -58.873644) (xy 160.30067 -58.873644) (xy 160.301145 -58.846274) (xy 160.308958 -58.792094)
			(xy 160.324444 -58.739591) (xy 160.347284 -58.689844) (xy 160.377009 -58.643877) (xy 160.39465 -58.622946)
			(xy 160.394904 -58.622692) (xy 160.400501 -58.615612) (xy 160.406741 -58.59869) (xy 160.407096 -58.589672)
			(xy 160.407096 -58.522616) (xy 160.406732 -58.5136) (xy 160.40049 -58.496683) (xy 160.394904 -58.489596)
			(xy 160.39465 -58.489596) (xy 160.39465 -58.489342) (xy 160.377025 -58.468398) (xy 160.347309 -58.42243)
			(xy 160.32447 -58.372685) (xy 160.308976 -58.320187) (xy 160.301145 -58.266013) (xy 160.30067 -58.238644)
			(xy 160.301156 -58.211393) (xy 160.308912 -58.157445) (xy 160.324267 -58.10515) (xy 160.346909 -58.055573)
			(xy 160.376375 -58.009723) (xy 160.412066 -57.968532) (xy 160.453257 -57.932841) (xy 160.499107 -57.903375)
			(xy 160.548684 -57.880733) (xy 160.600979 -57.865378) (xy 160.654927 -57.857622) (xy 160.709429 -57.857622)
			(xy 160.763377 -57.865378) (xy 160.815672 -57.880733) (xy 160.865249 -57.903375) (xy 160.911099 -57.932841)
			(xy 160.95229 -57.968532) (xy 160.987981 -58.009723) (xy 161.017447 -58.055573) (xy 161.040089 -58.10515)
			(xy 161.055444 -58.157445) (xy 161.0632 -58.211393) (xy 161.063686 -58.238644) (xy 161.063191 -58.266013)
			(xy 161.05538 -58.320191) (xy 161.039898 -58.372694) (xy 161.017063 -58.422441) (xy 160.987344 -58.468409)
			(xy 160.969706 -58.489342) (xy 160.969452 -58.489596) (xy 160.963855 -58.496675) (xy 160.957616 -58.513598)
			(xy 160.95726 -58.522616) (xy 160.95726 -58.589672) (xy 160.957617 -58.598689) (xy 160.963863 -58.615607)
			(xy 160.969452 -58.622692) (xy 160.969706 -58.622692) (xy 160.969706 -58.622946) (xy 160.987334 -58.643887)
			(xy 161.017047 -58.689857) (xy 161.039885 -58.739603) (xy 161.055379 -58.792101) (xy 161.06321 -58.846275)
			(xy 161.063686 -58.873644) (xy 161.0632 -58.900895) (xy 161.055444 -58.954843) (xy 161.040089 -59.007138)
			(xy 161.017447 -59.056715) (xy 160.987981 -59.102565) (xy 160.95229 -59.143756) (xy 160.911099 -59.179447)
			(xy 160.865249 -59.208913) (xy 160.815672 -59.231555) (xy 160.763377 -59.24691) (xy 160.709429 -59.254666)
			(xy 160.654927 -59.254666) (xy 160.600979 -59.24691) (xy 160.548684 -59.231555) (xy 160.499107 -59.208913)
			(xy 160.453257 -59.179447) (xy 160.412066 -59.143756) (xy 160.376375 -59.102565) (xy 160.346909 -59.056715)
			(xy 160.324267 -59.007138) (xy 160.308912 -58.954843) (xy 160.301156 -58.900895) (xy 160.30067 -58.873644)
			(xy 159.030921 -58.873644) (xy 159.015963 -58.924588) (xy 158.993321 -58.974165) (xy 158.963855 -59.020015)
			(xy 158.928164 -59.061206) (xy 158.886973 -59.096897) (xy 158.841123 -59.126363) (xy 158.791546 -59.149005)
			(xy 158.739251 -59.16436) (xy 158.685303 -59.172116) (xy 158.630801 -59.172116) (xy 158.576853 -59.16436)
			(xy 158.524558 -59.149005) (xy 158.474981 -59.126363) (xy 158.429131 -59.096897) (xy 158.38794 -59.061206)
			(xy 158.352249 -59.020015) (xy 158.322783 -58.974165) (xy 158.300141 -58.924588) (xy 158.284786 -58.872293)
			(xy 158.27703 -58.818345) (xy 158.276544 -58.791094) (xy 156.378586 -58.791094) (xy 156.375494 -58.812603)
			(xy 156.360139 -58.864898) (xy 156.337497 -58.914475) (xy 156.308031 -58.960325) (xy 156.27234 -59.001516)
			(xy 156.231149 -59.037207) (xy 156.185299 -59.066673) (xy 156.135722 -59.089315) (xy 156.083427 -59.10467)
			(xy 156.029479 -59.112426) (xy 155.974977 -59.112426) (xy 155.921029 -59.10467) (xy 155.868734 -59.089315)
			(xy 155.819157 -59.066673) (xy 155.773307 -59.037207) (xy 155.732116 -59.001516) (xy 155.696425 -58.960325)
			(xy 155.666959 -58.914475) (xy 155.644317 -58.864898) (xy 155.628962 -58.812603) (xy 155.621206 -58.758655)
			(xy 155.62072 -58.731404) (xy 153.791158 -58.731404) (xy 153.791158 -60.126449) (xy 159.280372 -60.126449)
			(xy 159.280372 -60.071951) (xy 159.288127 -60.018006) (xy 159.30348 -59.965714) (xy 159.326118 -59.91614)
			(xy 159.35558 -59.870291) (xy 159.391267 -59.829101) (xy 159.432452 -59.793409) (xy 159.478297 -59.763941)
			(xy 159.527869 -59.741297) (xy 159.580159 -59.725937) (xy 159.634103 -59.718175) (xy 159.661352 -59.717686)
			(xy 159.688721 -59.718184) (xy 159.742899 -59.725994) (xy 159.795401 -59.741476) (xy 159.845149 -59.764311)
			(xy 159.891117 -59.794028) (xy 159.91205 -59.811666) (xy 159.912304 -59.81192) (xy 159.919384 -59.817517)
			(xy 159.936306 -59.823757) (xy 159.945324 -59.824112) (xy 160.01238 -59.824112) (xy 160.021396 -59.823743)
			(xy 160.038313 -59.817503) (xy 160.0454 -59.81192) (xy 160.0454 -59.811666) (xy 160.045654 -59.811666)
			(xy 160.066587 -59.794025) (xy 160.112555 -59.764301) (xy 160.162301 -59.741455) (xy 160.214803 -59.725959)
			(xy 160.268981 -59.71813) (xy 160.323723 -59.71813) (xy 160.377901 -59.725959) (xy 160.430403 -59.741455)
			(xy 160.480149 -59.764301) (xy 160.526117 -59.794025) (xy 160.54705 -59.811666) (xy 160.547304 -59.81192)
			(xy 160.554384 -59.817517) (xy 160.571306 -59.823757) (xy 160.580324 -59.824112) (xy 160.64738 -59.824112)
			(xy 160.656396 -59.823743) (xy 160.673313 -59.817503) (xy 160.6804 -59.81192) (xy 160.6804 -59.811666)
			(xy 160.680654 -59.811666) (xy 160.701588 -59.79403) (xy 160.747561 -59.764319) (xy 160.797308 -59.741483)
			(xy 160.849808 -59.725991) (xy 160.903983 -59.718161) (xy 160.931352 -59.717686) (xy 160.958607 -59.718158)
			(xy 161.012562 -59.725909) (xy 161.064865 -59.741261) (xy 161.11445 -59.7639) (xy 161.160309 -59.793367)
			(xy 161.201506 -59.82906) (xy 161.237205 -59.870253) (xy 161.266677 -59.916108) (xy 161.289322 -59.96569)
			(xy 161.30468 -60.017991) (xy 161.312439 -60.071945) (xy 161.312439 -60.126455) (xy 161.30468 -60.180409)
			(xy 161.289322 -60.23271) (xy 161.266677 -60.282292) (xy 161.237205 -60.328147) (xy 161.201506 -60.36934)
			(xy 161.160309 -60.405033) (xy 161.11445 -60.4345) (xy 161.064865 -60.457139) (xy 161.012562 -60.472491)
			(xy 160.958607 -60.480242) (xy 160.931352 -60.480702) (xy 160.903983 -60.480205) (xy 160.849805 -60.472395)
			(xy 160.797302 -60.456913) (xy 160.747555 -60.434078) (xy 160.701587 -60.40436) (xy 160.680654 -60.386722)
			(xy 160.6804 -60.386468) (xy 160.67332 -60.380872) (xy 160.656398 -60.374632) (xy 160.64738 -60.374276)
			(xy 160.580324 -60.374276) (xy 160.571309 -60.37465) (xy 160.554392 -60.380886) (xy 160.547304 -60.386468)
			(xy 160.54705 -60.386722) (xy 160.526117 -60.404363) (xy 160.480149 -60.434087) (xy 160.430403 -60.456933)
			(xy 160.377901 -60.472429) (xy 160.323723 -60.480258) (xy 160.268981 -60.480258) (xy 160.214803 -60.472429)
			(xy 160.162301 -60.456933) (xy 160.112555 -60.434087) (xy 160.066587 -60.404363) (xy 160.045654 -60.386722)
			(xy 160.0454 -60.386468) (xy 160.03832 -60.380872) (xy 160.021398 -60.374632) (xy 160.01238 -60.374276)
			(xy 159.945324 -60.374276) (xy 159.936309 -60.37465) (xy 159.919392 -60.380886) (xy 159.912304 -60.386468)
			(xy 159.912304 -60.386722) (xy 159.91205 -60.386722) (xy 159.891113 -60.404355) (xy 159.845141 -60.434067)
			(xy 159.795395 -60.456903) (xy 159.742895 -60.472396) (xy 159.688721 -60.480227) (xy 159.661352 -60.480702)
			(xy 159.634103 -60.480225) (xy 159.580159 -60.472463) (xy 159.527869 -60.457103) (xy 159.478297 -60.434459)
			(xy 159.432452 -60.404991) (xy 159.391267 -60.369299) (xy 159.35558 -60.328109) (xy 159.326118 -60.28226)
			(xy 159.30348 -60.232686) (xy 159.288127 -60.180394) (xy 159.280372 -60.126449) (xy 153.791158 -60.126449)
			(xy 153.791158 -60.999878) (xy 153.790623 -61.009866) (xy 153.782911 -61.0283) (xy 153.776172 -61.035692)
			(xy 153.728166 -61.083698) (xy 153.724102 -61.08827) (xy 153.718092 -61.095857) (xy 153.705254 -61.110344)
			(xy 153.698448 -61.117226) (xy 153.071576 -61.744352) (xy 153.064807 -61.751016) (xy 153.050572 -61.763597)
			(xy 153.043128 -61.769498) (xy 153.038302 -61.773562) (xy 153.000456 -61.811408) (xy 152.993102 -61.818065)
			(xy 152.974802 -61.825664) (xy 152.964896 -61.82614) (xy 152.927812 -61.82614) (xy 152.917144 -61.827156)
			(xy 152.907492 -61.829188) (xy 151.160734 -61.829188) (xy 151.154685 -61.831612) (xy 151.144003 -61.839069)
			(xy 151.139652 -61.84392) (xy 151.087836 -61.91123) (xy 151.083453 -61.917802) (xy 151.078527 -61.932803)
			(xy 151.078184 -61.940694) (xy 151.079962 -61.953648) (xy 151.080724 -61.956696) (xy 151.086175 -61.979361)
			(xy 151.092162 -62.025592) (xy 151.092662 -62.048898) (xy 151.092662 -62.054486) (xy 151.091966 -62.081592)
			(xy 151.083855 -62.135204) (xy 151.068234 -62.187126) (xy 151.045418 -62.236314) (xy 151.015867 -62.281775)
			(xy 150.980177 -62.322594) (xy 150.939066 -62.357948) (xy 150.893364 -62.387125) (xy 150.84399 -62.409536)
			(xy 150.791941 -62.42473) (xy 150.738265 -62.432401) (xy 150.711154 -62.432946) (xy 150.6876 -62.432564)
			(xy 150.640856 -62.426703) (xy 150.617936 -62.421262) (xy 150.617682 -62.421262) (xy 150.610815 -62.419761)
			(xy 150.59677 -62.420149) (xy 150.589996 -62.422024) (xy 150.583392 -62.42431) (xy 150.571962 -62.431676)
			(xy 150.5077 -62.506352) (xy 150.503263 -62.511817) (xy 150.497348 -62.524584) (xy 150.496016 -62.531498)
			(xy 150.494746 -62.538356) (xy 150.496524 -62.552072) (xy 150.499318 -62.55893) (xy 150.508643 -62.582314)
			(xy 150.521762 -62.630918) (xy 150.528379 -62.680824) (xy 150.528782 -62.705996) (xy 150.528319 -62.733248)
			(xy 150.520562 -62.787198) (xy 150.505206 -62.839495) (xy 150.482564 -62.889074) (xy 150.453095 -62.934926)
			(xy 150.417401 -62.976117) (xy 150.376208 -63.011809) (xy 150.330355 -63.041274) (xy 150.280775 -63.063914)
			(xy 150.228477 -63.079267) (xy 150.174526 -63.08702) (xy 150.147274 -63.087504) (xy 150.118462 -63.086982)
			(xy 150.061494 -63.078323) (xy 150.006477 -63.06119) (xy 149.954664 -63.035974) (xy 149.907236 -63.003249)
			(xy 149.885908 -62.983872) (xy 149.885654 -62.983618) (xy 149.88138 -62.979816) (xy 149.871504 -62.974052)
			(xy 149.866096 -62.972188) (xy 149.855428 -62.968886) (xy 149.765512 -62.981332) (xy 149.76348 -62.981586)
			(xy 149.752749 -62.984102) (xy 149.734725 -62.99675) (xy 149.728682 -63.00597) (xy 149.713865 -63.030092)
			(xy 149.678228 -63.074077) (xy 149.636481 -63.11231) (xy 149.589542 -63.143954) (xy 149.538441 -63.168311)
			(xy 149.4843 -63.184849) (xy 149.428311 -63.193202) (xy 149.400006 -63.193676) (xy 149.372755 -63.193213)
			(xy 149.318808 -63.185458) (xy 149.266514 -63.170103) (xy 149.216937 -63.147463) (xy 149.171087 -63.117998)
			(xy 149.129897 -63.082307) (xy 149.094206 -63.041118) (xy 149.06474 -62.995268) (xy 149.042099 -62.945692)
			(xy 149.026744 -62.893398) (xy 149.018987 -62.839451) (xy 149.018987 -62.784949) (xy 149.026744 -62.731002)
			(xy 149.042099 -62.678708) (xy 149.06474 -62.629132) (xy 149.094206 -62.583282) (xy 149.129897 -62.542093)
			(xy 149.171087 -62.506402) (xy 149.216937 -62.476937) (xy 149.266514 -62.454297) (xy 149.318808 -62.438942)
			(xy 149.372755 -62.431187) (xy 149.400006 -62.43066) (xy 149.428815 -62.431188) (xy 149.485779 -62.439857)
			(xy 149.540789 -62.456997) (xy 149.592595 -62.482219) (xy 149.640016 -62.514947) (xy 149.661372 -62.534292)
			(xy 149.661626 -62.534546) (xy 149.665897 -62.538351) (xy 149.675772 -62.544123) (xy 149.681184 -62.545976)
			(xy 149.691852 -62.549278) (xy 149.781768 -62.536578) (xy 149.787461 -62.535649) (xy 149.798237 -62.531545)
			(xy 149.803104 -62.52845) (xy 149.80793 -62.525402) (xy 149.815804 -62.51702) (xy 149.818598 -62.512194)
			(xy 149.833417 -62.488077) (xy 149.869059 -62.444105) (xy 149.910809 -62.405883) (xy 149.957749 -62.374253)
			(xy 150.00885 -62.349908) (xy 150.062987 -62.333383) (xy 150.118972 -62.325043) (xy 150.147274 -62.324488)
			(xy 150.183342 -62.326012) (xy 150.191978 -62.327028) (xy 150.212806 -62.330076) (xy 150.213314 -62.330076)
			(xy 150.240238 -62.336172) (xy 150.240746 -62.336172) (xy 150.247858 -62.33795) (xy 150.261574 -62.337696)
			(xy 150.268178 -62.33541) (xy 150.274819 -62.333099) (xy 150.286557 -62.325368) (xy 150.291292 -62.32017)
			(xy 150.350728 -62.251082) (xy 150.355174 -62.245621) (xy 150.361106 -62.232856) (xy 150.362412 -62.225936)
			(xy 150.363682 -62.219078) (xy 150.361904 -62.205362) (xy 150.35911 -62.198504) (xy 150.349964 -62.175595)
			(xy 150.336976 -62.128009) (xy 150.33022 -62.079146) (xy 150.329646 -62.054486) (xy 150.329646 -62.050676)
			(xy 150.330057 -62.026924) (xy 150.336045 -61.979797) (xy 150.341584 -61.956696) (xy 150.342346 -61.953648)
			(xy 150.344124 -61.940694) (xy 150.343786 -61.932801) (xy 150.338862 -61.917799) (xy 150.334472 -61.91123)
			(xy 150.282656 -61.84392) (xy 150.278259 -61.839121) (xy 150.26759 -61.831674) (xy 150.261574 -61.829188)
			(xy 149.259036 -61.829188) (xy 149.249229 -61.829105) (xy 149.229656 -61.827832) (xy 149.21992 -61.826648)
			(xy 149.213316 -61.82614) (xy 148.968968 -61.82614) (xy 148.957284 -61.829188) (xy 148.952458 -61.831474)
			(xy 148.95195 -61.831728) (xy 148.942001 -61.836358) (xy 148.921668 -61.844615) (xy 148.91131 -61.848238)
			(xy 148.883125 -61.857443) (xy 148.824783 -61.868002) (xy 148.765509 -61.869382) (xy 148.73605 -61.866018)
			(xy 148.706366 -61.861525) (xy 148.648818 -61.844425) (xy 148.621496 -61.831982) (xy 148.620988 -61.831474)
			(xy 148.620226 -61.83122) (xy 148.61794 -61.82995) (xy 148.615908 -61.829188) (xy 148.604224 -61.82614)
			(xy 148.349716 -61.82614) (xy 148.343112 -61.826648) (xy 148.333375 -61.827821) (xy 148.313803 -61.829095)
			(xy 148.303996 -61.829188) (xy 147.167092 -61.829188) (xy 147.15998 -61.829696) (xy 147.141946 -61.832998)
			(xy 147.137009 -61.835979) (xy 147.12854 -61.843803) (xy 147.125182 -61.848492) (xy 147.124674 -61.849254)
			(xy 147.07743 -61.921644) (xy 147.074412 -61.926844) (xy 147.070686 -61.93827) (xy 147.070064 -61.94425)
			(xy 147.069048 -61.956696) (xy 147.072096 -61.963808) (xy 147.07362 -61.967618) (xy 147.074382 -61.969142)
			(xy 147.084002 -61.9923) (xy 147.097772 -62.04052) (xy 147.105109 -62.090127) (xy 147.105878 -62.115192)
			(xy 147.105878 -62.12586) (xy 147.105066 -62.152886) (xy 147.096756 -62.206313) (xy 147.080987 -62.258031)
			(xy 147.058075 -62.307004) (xy 147.028478 -62.352253) (xy 146.992789 -62.39287) (xy 146.951724 -62.428042)
			(xy 146.906105 -62.457064) (xy 146.856845 -62.479355) (xy 146.804931 -62.494469) (xy 146.751404 -62.502102)
			(xy 146.697336 -62.502102) (xy 146.643809 -62.494469) (xy 146.591895 -62.479355) (xy 146.542635 -62.457064)
			(xy 146.497016 -62.428042) (xy 146.455951 -62.39287) (xy 146.420262 -62.352253) (xy 146.390665 -62.307004)
			(xy 146.367753 -62.258031) (xy 146.351984 -62.206313) (xy 146.343674 -62.152886) (xy 146.342862 -62.12586)
			(xy 146.342862 -62.12078) (xy 146.34331 -62.094683) (xy 146.350464 -62.042982) (xy 146.364596 -61.992737)
			(xy 146.374612 -61.968634) (xy 146.377152 -61.962792) (xy 146.379184 -61.9506) (xy 146.378676 -61.94425)
			(xy 146.378007 -61.93828) (xy 146.374284 -61.926863) (xy 146.37131 -61.921644) (xy 146.324066 -61.849254)
			(xy 146.323558 -61.848492) (xy 146.320161 -61.843839) (xy 146.311695 -61.836028) (xy 146.306794 -61.832998)
			(xy 146.28876 -61.829696) (xy 146.281648 -61.829188) (xy 143.750284 -61.829188) (xy 143.746083 -61.830783)
			(xy 143.738291 -61.83526) (xy 143.73479 -61.838078) (xy 143.32204 -62.250574) (xy 143.316655 -62.256567)
			(xy 143.309672 -62.271077) (xy 143.308324 -62.279022) (xy 143.307816 -62.28588) (xy 143.307816 -63.273432)
			(xy 145.676872 -63.273432) (xy 145.680943 -63.21781) (xy 145.693069 -63.163373) (xy 145.712992 -63.111282)
			(xy 145.740288 -63.062647) (xy 145.774374 -63.018504) (xy 145.814523 -62.979795) (xy 145.859881 -62.947344)
			(xy 145.909481 -62.921843) (xy 145.962265 -62.903836) (xy 146.017108 -62.893706) (xy 146.072842 -62.891669)
			(xy 146.128279 -62.897769) (xy 146.182236 -62.911875) (xy 146.233565 -62.933687) (xy 146.281171 -62.962741)
			(xy 146.324039 -62.998416) (xy 146.361256 -63.039953) (xy 146.392029 -63.086466) (xy 146.415701 -63.136963)
			(xy 146.431769 -63.19037) (xy 146.439889 -63.245546) (xy 146.439889 -63.245548) (xy 159.204692 -63.245548)
			(xy 159.204692 -63.191052) (xy 159.212447 -63.137109) (xy 159.2278 -63.08482) (xy 159.250437 -63.035247)
			(xy 159.279899 -62.9894) (xy 159.315584 -62.948213) (xy 159.356768 -62.912523) (xy 159.402612 -62.883056)
			(xy 159.452182 -62.860414) (xy 159.50447 -62.845056) (xy 159.558412 -62.837295) (xy 159.58566 -62.836806)
			(xy 159.613029 -62.837294) (xy 159.667208 -62.845106) (xy 159.719711 -62.86059) (xy 159.769458 -62.883427)
			(xy 159.815426 -62.913147) (xy 159.836358 -62.930786) (xy 159.836612 -62.93104) (xy 159.843687 -62.936643)
			(xy 159.860613 -62.942879) (xy 159.869632 -62.943232) (xy 159.936688 -62.943232) (xy 159.945703 -62.942862)
			(xy 159.96262 -62.936623) (xy 159.969708 -62.93104) (xy 159.969708 -62.930786) (xy 159.969962 -62.930786)
			(xy 159.990895 -62.913145) (xy 160.036863 -62.883421) (xy 160.086609 -62.860575) (xy 160.139111 -62.845079)
			(xy 160.193289 -62.83725) (xy 160.248031 -62.83725) (xy 160.302209 -62.845079) (xy 160.354711 -62.860575)
			(xy 160.404457 -62.883421) (xy 160.450425 -62.913145) (xy 160.471358 -62.930786) (xy 160.471612 -62.93104)
			(xy 160.478687 -62.936643) (xy 160.495613 -62.942879) (xy 160.504632 -62.943232) (xy 160.571688 -62.943232)
			(xy 160.580703 -62.942862) (xy 160.59762 -62.936623) (xy 160.604708 -62.93104) (xy 160.604708 -62.930786)
			(xy 160.604962 -62.930786) (xy 160.625896 -62.913149) (xy 160.671868 -62.883437) (xy 160.721615 -62.860601)
			(xy 160.774116 -62.84511) (xy 160.828291 -62.837281) (xy 160.85566 -62.836806) (xy 160.882916 -62.837238)
			(xy 160.936873 -62.844991) (xy 160.989178 -62.860344) (xy 161.038765 -62.882985) (xy 161.084625 -62.912453)
			(xy 161.125824 -62.948148) (xy 161.161523 -62.989343) (xy 161.190996 -63.0352) (xy 161.213642 -63.084785)
			(xy 161.229001 -63.137088) (xy 161.236759 -63.191044) (xy 161.236759 -63.245556) (xy 161.229001 -63.299512)
			(xy 161.213642 -63.351815) (xy 161.190996 -63.4014) (xy 161.161523 -63.447257) (xy 161.125824 -63.488452)
			(xy 161.084625 -63.524147) (xy 161.038765 -63.553615) (xy 160.989178 -63.576256) (xy 160.936873 -63.591609)
			(xy 160.882916 -63.599362) (xy 160.85566 -63.599822) (xy 160.82829 -63.59934) (xy 160.774111 -63.591529)
			(xy 160.721607 -63.576045) (xy 160.67186 -63.553206) (xy 160.625893 -63.523483) (xy 160.604962 -63.505842)
			(xy 160.604708 -63.505588) (xy 160.597624 -63.499997) (xy 160.580705 -63.493753) (xy 160.571688 -63.493396)
			(xy 160.504632 -63.493396) (xy 160.495617 -63.493769) (xy 160.4787 -63.500006) (xy 160.471612 -63.505588)
			(xy 160.471358 -63.505842) (xy 160.450425 -63.523483) (xy 160.404457 -63.553207) (xy 160.354711 -63.576053)
			(xy 160.302209 -63.591549) (xy 160.248031 -63.599378) (xy 160.193289 -63.599378) (xy 160.139111 -63.591549)
			(xy 160.086609 -63.576053) (xy 160.036863 -63.553207) (xy 159.990895 -63.523483) (xy 159.969962 -63.505842)
			(xy 159.969708 -63.505588) (xy 159.962624 -63.499997) (xy 159.945705 -63.493753) (xy 159.936688 -63.493396)
			(xy 159.869632 -63.493396) (xy 159.860617 -63.493769) (xy 159.8437 -63.500006) (xy 159.836612 -63.505588)
			(xy 159.836612 -63.505842) (xy 159.836358 -63.505842) (xy 159.815421 -63.523474) (xy 159.769449 -63.553186)
			(xy 159.719702 -63.576022) (xy 159.667203 -63.591515) (xy 159.613029 -63.599347) (xy 159.58566 -63.599822)
			(xy 159.558412 -63.599305) (xy 159.50447 -63.591544) (xy 159.452182 -63.576186) (xy 159.402612 -63.553544)
			(xy 159.356768 -63.524077) (xy 159.315584 -63.488387) (xy 159.279899 -63.4472) (xy 159.250437 -63.401353)
			(xy 159.2278 -63.35178) (xy 159.212447 -63.299491) (xy 159.204692 -63.245548) (xy 146.439889 -63.245548)
			(xy 146.440398 -63.273432) (xy 146.439889 -63.301318) (xy 146.431769 -63.356494) (xy 146.415701 -63.409901)
			(xy 146.392029 -63.460398) (xy 146.361256 -63.506911) (xy 146.324039 -63.548448) (xy 146.281171 -63.584123)
			(xy 146.233565 -63.613177) (xy 146.182236 -63.634989) (xy 146.128279 -63.649095) (xy 146.072842 -63.655195)
			(xy 146.017108 -63.653158) (xy 145.962265 -63.643028) (xy 145.909481 -63.625021) (xy 145.859881 -63.59952)
			(xy 145.814523 -63.567069) (xy 145.774374 -63.52836) (xy 145.740288 -63.484217) (xy 145.712992 -63.435582)
			(xy 145.693069 -63.383491) (xy 145.680943 -63.329054) (xy 145.676872 -63.273432) (xy 143.307816 -63.273432)
			(xy 143.307816 -64.102234) (xy 143.487646 -64.102234) (xy 143.491717 -64.046612) (xy 143.503843 -63.992175)
			(xy 143.523766 -63.940084) (xy 143.551062 -63.891449) (xy 143.585148 -63.847306) (xy 143.625297 -63.808597)
			(xy 143.670655 -63.776146) (xy 143.720255 -63.750645) (xy 143.773039 -63.732638) (xy 143.827882 -63.722508)
			(xy 143.883616 -63.720471) (xy 143.939053 -63.726571) (xy 143.99301 -63.740677) (xy 144.044339 -63.762489)
			(xy 144.091945 -63.791543) (xy 144.134813 -63.827218) (xy 144.17203 -63.868755) (xy 144.202803 -63.915268)
			(xy 144.226475 -63.965765) (xy 144.242543 -64.019172) (xy 144.250663 -64.074348) (xy 144.251172 -64.102234)
			(xy 144.250663 -64.13012) (xy 144.242543 -64.185296) (xy 144.226475 -64.238703) (xy 144.202803 -64.2892)
			(xy 144.187525 -64.312292) (xy 147.166074 -64.312292) (xy 147.170145 -64.25667) (xy 147.182271 -64.202233)
			(xy 147.202194 -64.150142) (xy 147.22949 -64.101507) (xy 147.263576 -64.057364) (xy 147.303725 -64.018655)
			(xy 147.349083 -63.986204) (xy 147.398683 -63.960703) (xy 147.451467 -63.942696) (xy 147.50631 -63.932566)
			(xy 147.562044 -63.930529) (xy 147.617481 -63.936629) (xy 147.671438 -63.950735) (xy 147.722767 -63.972547)
			(xy 147.770373 -64.001601) (xy 147.813241 -64.037276) (xy 147.850458 -64.078813) (xy 147.881231 -64.125326)
			(xy 147.904903 -64.175823) (xy 147.920971 -64.22923) (xy 147.929091 -64.284406) (xy 147.9296 -64.312292)
			(xy 147.929091 -64.340178) (xy 147.920971 -64.395354) (xy 147.904903 -64.448761) (xy 147.881231 -64.499258)
			(xy 147.850458 -64.545771) (xy 147.813241 -64.587308) (xy 147.770373 -64.622983) (xy 147.722767 -64.652037)
			(xy 147.671438 -64.673849) (xy 147.617481 -64.687955) (xy 147.562044 -64.694055) (xy 147.50631 -64.692018)
			(xy 147.451467 -64.681888) (xy 147.398683 -64.663881) (xy 147.349083 -64.63838) (xy 147.303725 -64.605929)
			(xy 147.263576 -64.56722) (xy 147.22949 -64.523077) (xy 147.202194 -64.474442) (xy 147.182271 -64.422351)
			(xy 147.170145 -64.367914) (xy 147.166074 -64.312292) (xy 144.187525 -64.312292) (xy 144.17203 -64.335713)
			(xy 144.134813 -64.37725) (xy 144.091945 -64.412925) (xy 144.044339 -64.441979) (xy 143.99301 -64.463791)
			(xy 143.939053 -64.477897) (xy 143.883616 -64.483997) (xy 143.827882 -64.48196) (xy 143.773039 -64.47183)
			(xy 143.720255 -64.453823) (xy 143.670655 -64.428322) (xy 143.625297 -64.395871) (xy 143.585148 -64.357162)
			(xy 143.551062 -64.313019) (xy 143.523766 -64.264384) (xy 143.503843 -64.212293) (xy 143.491717 -64.157856)
			(xy 143.487646 -64.102234) (xy 143.307816 -64.102234) (xy 143.307816 -65.124076) (xy 148.207474 -65.124076)
			(xy 148.211545 -65.068454) (xy 148.223671 -65.014017) (xy 148.243594 -64.961926) (xy 148.27089 -64.913291)
			(xy 148.304976 -64.869148) (xy 148.345125 -64.830439) (xy 148.390483 -64.797988) (xy 148.440083 -64.772487)
			(xy 148.492867 -64.75448) (xy 148.54771 -64.74435) (xy 148.603444 -64.742313) (xy 148.658881 -64.748413)
			(xy 148.712838 -64.762519) (xy 148.764167 -64.784331) (xy 148.811773 -64.813385) (xy 148.854641 -64.84906)
			(xy 148.891858 -64.890597) (xy 148.922631 -64.93711) (xy 148.946303 -64.987607) (xy 148.962371 -65.041014)
			(xy 148.970491 -65.09619) (xy 148.971 -65.124076) (xy 148.970491 -65.151962) (xy 148.969324 -65.15989)
			(xy 161.216592 -65.15989) (xy 161.220663 -65.104268) (xy 161.232789 -65.049831) (xy 161.252712 -64.99774)
			(xy 161.280008 -64.949105) (xy 161.314094 -64.904962) (xy 161.354243 -64.866253) (xy 161.399601 -64.833802)
			(xy 161.449201 -64.808301) (xy 161.501985 -64.790294) (xy 161.556828 -64.780164) (xy 161.612562 -64.778127)
			(xy 161.667999 -64.784227) (xy 161.721956 -64.798333) (xy 161.773285 -64.820145) (xy 161.820891 -64.849199)
			(xy 161.863759 -64.884874) (xy 161.900976 -64.926411) (xy 161.931749 -64.972924) (xy 161.955421 -65.023421)
			(xy 161.971489 -65.076828) (xy 161.979609 -65.132004) (xy 161.980118 -65.15989) (xy 161.979609 -65.187776)
			(xy 161.971489 -65.242952) (xy 161.955421 -65.296359) (xy 161.931749 -65.346856) (xy 161.900976 -65.393369)
			(xy 161.863759 -65.434906) (xy 161.820891 -65.470581) (xy 161.773285 -65.499635) (xy 161.721956 -65.521447)
			(xy 161.667999 -65.535553) (xy 161.612562 -65.541653) (xy 161.556828 -65.539616) (xy 161.501985 -65.529486)
			(xy 161.449201 -65.511479) (xy 161.399601 -65.485978) (xy 161.354243 -65.453527) (xy 161.314094 -65.414818)
			(xy 161.280008 -65.370675) (xy 161.252712 -65.32204) (xy 161.232789 -65.269949) (xy 161.220663 -65.215512)
			(xy 161.216592 -65.15989) (xy 148.969324 -65.15989) (xy 148.962371 -65.207138) (xy 148.946303 -65.260545)
			(xy 148.922631 -65.311042) (xy 148.891858 -65.357555) (xy 148.854641 -65.399092) (xy 148.811773 -65.434767)
			(xy 148.764167 -65.463821) (xy 148.712838 -65.485633) (xy 148.658881 -65.499739) (xy 148.603444 -65.505839)
			(xy 148.54771 -65.503802) (xy 148.492867 -65.493672) (xy 148.440083 -65.475665) (xy 148.390483 -65.450164)
			(xy 148.345125 -65.417713) (xy 148.304976 -65.379004) (xy 148.27089 -65.334861) (xy 148.243594 -65.286226)
			(xy 148.223671 -65.234135) (xy 148.211545 -65.179698) (xy 148.207474 -65.124076) (xy 143.307816 -65.124076)
			(xy 143.307816 -65.75552) (xy 156.446726 -65.75552) (xy 156.450797 -65.699898) (xy 156.462923 -65.645461)
			(xy 156.482846 -65.59337) (xy 156.510142 -65.544735) (xy 156.544228 -65.500592) (xy 156.584377 -65.461883)
			(xy 156.629735 -65.429432) (xy 156.679335 -65.403931) (xy 156.732119 -65.385924) (xy 156.786962 -65.375794)
			(xy 156.842696 -65.373757) (xy 156.898133 -65.379857) (xy 156.95209 -65.393963) (xy 157.003419 -65.415775)
			(xy 157.051025 -65.444829) (xy 157.093893 -65.480504) (xy 157.13111 -65.522041) (xy 157.161883 -65.568554)
			(xy 157.185555 -65.619051) (xy 157.201623 -65.672458) (xy 157.209743 -65.727634) (xy 157.210252 -65.75552)
			(xy 157.209743 -65.783406) (xy 157.201623 -65.838582) (xy 157.185555 -65.891989) (xy 157.161883 -65.942486)
			(xy 157.13111 -65.988999) (xy 157.093893 -66.030536) (xy 157.051025 -66.066211) (xy 157.003419 -66.095265)
			(xy 156.95209 -66.117077) (xy 156.898133 -66.131183) (xy 156.842696 -66.137283) (xy 156.786962 -66.135246)
			(xy 156.732119 -66.125116) (xy 156.679335 -66.107109) (xy 156.629735 -66.081608) (xy 156.584377 -66.049157)
			(xy 156.544228 -66.010448) (xy 156.510142 -65.966305) (xy 156.482846 -65.91767) (xy 156.462923 -65.865579)
			(xy 156.450797 -65.811142) (xy 156.446726 -65.75552) (xy 143.307816 -65.75552) (xy 143.307816 -67.488054)
			(xy 160.87928 -67.488054) (xy 160.883351 -67.432432) (xy 160.895477 -67.377995) (xy 160.9154 -67.325904)
			(xy 160.942696 -67.277269) (xy 160.976782 -67.233126) (xy 161.016931 -67.194417) (xy 161.062289 -67.161966)
			(xy 161.111889 -67.136465) (xy 161.164673 -67.118458) (xy 161.219516 -67.108328) (xy 161.27525 -67.106291)
			(xy 161.330687 -67.112391) (xy 161.384644 -67.126497) (xy 161.435973 -67.148309) (xy 161.483579 -67.177363)
			(xy 161.526447 -67.213038) (xy 161.563664 -67.254575) (xy 161.594437 -67.301088) (xy 161.618109 -67.351585)
			(xy 161.634177 -67.404992) (xy 161.642297 -67.460168) (xy 161.642806 -67.488054) (xy 161.642297 -67.51594)
			(xy 161.634177 -67.571116) (xy 161.618109 -67.624523) (xy 161.594437 -67.67502) (xy 161.563664 -67.721533)
			(xy 161.526447 -67.76307) (xy 161.483579 -67.798745) (xy 161.435973 -67.827799) (xy 161.384644 -67.849611)
			(xy 161.330687 -67.863717) (xy 161.27525 -67.869817) (xy 161.219516 -67.86778) (xy 161.164673 -67.85765)
			(xy 161.111889 -67.839643) (xy 161.062289 -67.814142) (xy 161.016931 -67.781691) (xy 160.976782 -67.742982)
			(xy 160.942696 -67.698839) (xy 160.9154 -67.650204) (xy 160.895477 -67.598113) (xy 160.883351 -67.543676)
			(xy 160.87928 -67.488054) (xy 143.307816 -67.488054) (xy 143.307816 -69.9516) (xy 143.308832 -69.961252)
			(xy 143.31046 -69.968496) (xy 143.317301 -69.981665) (xy 143.322294 -69.98716) (xy 143.499332 -70.164198)
			(xy 143.504831 -70.169185) (xy 143.517998 -70.176028) (xy 143.52524 -70.17766) (xy 143.534892 -70.178676)
			(xy 162.578288 -70.178676)
		)
		(stroke
			(width 0)
			(type solid)
		)
		(fill yes)
		(layer "In9.Cu")
		(net "P12V_SSD5_R")
	)
	(gr_poly
		(pts
			(xy 339.985604 -228.524562)
			(arc
				(start 339.989922 -228.507544)
				(mid 340.36 -228.218548)
				(end 340.730078 -228.507544)
			)
			(xy 340.734396 -228.524562) (xy 340.761828 -228.545898) (xy 342.881966 -228.545898) (xy 342.909398 -228.524562)
			(arc
				(start 342.913716 -228.507544)
				(mid 343.283794 -228.218548)
				(end 343.653872 -228.507544)
			)
			(xy 343.65819 -228.524562) (xy 343.685622 -228.545898)
			(arc
				(start 345.824048 -228.545898)
				(mid 345.836767 -228.54428)
				(end 345.848686 -228.539548)
			)
			(xy 345.87434 -228.525324) (xy 345.882976 -228.51745)
			(arc
				(start 345.886278 -228.51237)
				(mid 346.202 -228.345344)
				(end 346.517722 -228.51237)
			)
			(xy 346.521024 -228.51745) (xy 346.52966 -228.525324)
			(arc
				(start 346.555314 -228.539548)
				(mid 346.567228 -228.544301)
				(end 346.579952 -228.545898)
			)
			(arc
				(start 346.840048 -228.545898)
				(mid 346.852767 -228.54428)
				(end 346.864686 -228.539548)
			)
			(xy 346.89034 -228.525324) (xy 346.898976 -228.51745)
			(arc
				(start 346.902278 -228.51237)
				(mid 347.218 -228.345344)
				(end 347.533722 -228.51237)
			)
			(xy 347.537024 -228.51745) (xy 347.54566 -228.525324)
			(arc
				(start 347.571314 -228.539548)
				(mid 347.583228 -228.544301)
				(end 347.595952 -228.545898)
			)
			(arc
				(start 349.442786 -228.545898)
				(mid 349.457642 -228.543677)
				(end 349.471234 -228.537262)
			)
			(arc
				(start 349.471234 -228.537262)
				(mid 349.683832 -228.472485)
				(end 349.89643 -228.537262)
			)
			(arc
				(start 349.89643 -228.537262)
				(mid 349.910004 -228.543738)
				(end 349.924878 -228.545898)
			)
			(arc
				(start 350.839532 -228.545898)
				(mid 350.860458 -228.541388)
				(end 350.877632 -228.528626)
			)
			(xy 350.93529 -228.463348) (xy 350.94164 -228.44252)
			(arc
				(start 350.94037 -228.431598)
				(mid 350.938282 -228.409417)
				(end 350.937576 -228.387148)
			)
			(arc
				(start 350.937576 -228.386894)
				(mid 351.293684 -228.030786)
				(end 351.649792 -228.386894)
			)
			(arc
				(start 351.649792 -228.387148)
				(mid 351.649095 -228.409417)
				(end 351.646998 -228.431598)
			)
			(xy 351.645728 -228.44252) (xy 351.652078 -228.463348)
			(arc
				(start 351.709736 -228.528626)
				(mid 351.72693 -228.541344)
				(end 351.747836 -228.545898)
			)
			(xy 352.020632 -228.545898) (xy 352.048318 -228.523292)
			(arc
				(start 352.052128 -228.505258)
				(mid 352.184899 -228.286472)
				(end 352.426016 -228.200712)
			)
			(arc
				(start 352.426016 -228.200712)
				(mid 352.605101 -228.245357)
				(end 352.742246 -228.36886)
			)
			(arc
				(start 352.742246 -228.36886)
				(mid 352.821413 -228.41356)
				(end 352.904552 -228.376988)
			)
			(arc
				(start 352.904552 -228.376988)
				(mid 353.035778 -228.276017)
				(end 353.197414 -228.240082)
			)
			(arc
				(start 353.197414 -228.240082)
				(mid 353.42443 -228.314914)
				(end 353.562412 -228.510084)
			)
			(xy 353.567492 -228.52634) (xy 353.593908 -228.545898)
			(arc
				(start 354.260912 -228.545898)
				(mid 354.280435 -228.541997)
				(end 354.29698 -228.530912)
			)
			(arc
				(start 354.54082 -228.287072)
				(mid 354.551931 -228.270538)
				(end 354.555806 -228.251004)
			)
			(arc
				(start 354.555806 -223.03867)
				(mid 354.552109 -223.019645)
				(end 354.541582 -223.003364)
			)
			(xy 354.485702 -222.945452) (xy 354.467922 -222.937324)
			(arc
				(start 354.458016 -222.93707)
				(mid 354.090965 -222.555816)
				(end 354.458016 -222.174562)
			)
			(xy 354.467922 -222.174308) (xy 354.485702 -222.16618)
			(arc
				(start 354.541582 -222.108268)
				(mid 354.552143 -222.092001)
				(end 354.555806 -222.072962)
			)
			(arc
				(start 354.555806 -221.450916)
				(mid 354.551905 -221.431393)
				(end 354.54082 -221.414848)
			)
			(xy 354.078032 -220.95206) (xy 354.07092 -220.944694) (xy 354.052124 -220.937074)
			(arc
				(start 351.726754 -220.937074)
				(mid 351.703469 -220.942725)
				(end 351.685352 -220.95841)
			)
			(xy 351.630234 -221.035626) (xy 351.626678 -221.059756)
			(arc
				(start 351.630742 -221.07144)
				(mid 351.644951 -221.127937)
				(end 351.649792 -221.185994)
			)
			(arc
				(start 351.649792 -221.186756)
				(mid 351.600607 -221.367273)
				(end 351.466658 -221.497906)
			)
			(arc
				(start 351.466658 -221.497906)
				(mid 351.447571 -221.516452)
				(end 351.440496 -221.542102)
			)
			(xy 351.440496 -221.542356) (xy 351.440496 -221.631256)
			(arc
				(start 351.440496 -221.63151)
				(mid 351.44759 -221.657149)
				(end 351.466658 -221.675706)
			)
			(arc
				(start 351.466658 -221.675706)
				(mid 351.649812 -221.986856)
				(end 351.466658 -222.298006)
			)
			(arc
				(start 351.466658 -222.298006)
				(mid 351.447571 -222.316552)
				(end 351.440496 -222.342202)
			)
			(xy 351.440496 -222.342456) (xy 351.440496 -222.431356)
			(arc
				(start 351.440496 -222.43161)
				(mid 351.44759 -222.457249)
				(end 351.466658 -222.475806)
			)
			(arc
				(start 351.466658 -222.475806)
				(mid 351.600624 -222.606429)
				(end 351.649792 -222.786956)
			)
			(arc
				(start 351.649792 -222.786956)
				(mid 351.600684 -222.96741)
				(end 351.466912 -223.098106)
			)
			(arc
				(start 351.466912 -223.098106)
				(mid 351.447761 -223.116762)
				(end 351.44075 -223.142556)
			)
			(arc
				(start 351.44075 -223.231202)
				(mid 351.447779 -223.256985)
				(end 351.466912 -223.275652)
			)
			(arc
				(start 351.466912 -223.275652)
				(mid 351.600696 -223.406341)
				(end 351.649792 -223.586802)
			)
			(arc
				(start 351.649792 -223.586802)
				(mid 351.600607 -223.767319)
				(end 351.466658 -223.897952)
			)
			(arc
				(start 351.466658 -223.897952)
				(mid 351.447571 -223.916498)
				(end 351.440496 -223.942148)
			)
			(xy 351.440496 -223.942402) (xy 351.440496 -224.031302)
			(arc
				(start 351.440496 -224.031556)
				(mid 351.44759 -224.057195)
				(end 351.466658 -224.075752)
			)
			(arc
				(start 351.466658 -224.075752)
				(mid 351.600624 -224.206375)
				(end 351.649792 -224.386902)
			)
			(arc
				(start 351.649792 -224.386902)
				(mid 351.600684 -224.567356)
				(end 351.466912 -224.698052)
			)
			(arc
				(start 351.466912 -224.698052)
				(mid 351.447761 -224.716708)
				(end 351.44075 -224.742502)
			)
			(arc
				(start 351.44075 -224.831148)
				(mid 351.447779 -224.856931)
				(end 351.466912 -224.875598)
			)
			(arc
				(start 351.466912 -224.875598)
				(mid 351.600696 -225.006287)
				(end 351.649792 -225.186748)
			)
			(arc
				(start 351.649792 -225.186748)
				(mid 351.600607 -225.367265)
				(end 351.466658 -225.497898)
			)
			(arc
				(start 351.466658 -225.497898)
				(mid 351.447571 -225.516444)
				(end 351.440496 -225.542094)
			)
			(xy 351.440496 -225.542348) (xy 351.440496 -225.631248)
			(arc
				(start 351.440496 -225.631502)
				(mid 351.44759 -225.657141)
				(end 351.466658 -225.675698)
			)
			(arc
				(start 351.466658 -225.675698)
				(mid 351.649812 -225.986848)
				(end 351.466658 -226.297998)
			)
			(arc
				(start 351.466658 -226.297998)
				(mid 351.447571 -226.316544)
				(end 351.440496 -226.342194)
			)
			(xy 351.440496 -226.342448) (xy 351.440496 -226.431348)
			(arc
				(start 351.440496 -226.431602)
				(mid 351.44759 -226.457241)
				(end 351.466658 -226.475798)
			)
			(arc
				(start 351.466658 -226.475798)
				(mid 351.525881 -226.517004)
				(end 351.575624 -226.56927)
			)
			(xy 351.575624 -226.569524)
			(arc
				(start 351.575878 -226.569778)
				(mid 351.593561 -226.584172)
				(end 351.615756 -226.589336)
			)
			(arc
				(start 351.696528 -226.589336)
				(mid 351.718697 -226.58412)
				(end 351.736406 -226.569778)
			)
			(xy 351.73666 -226.569524)
			(arc
				(start 351.73666 -226.56927)
				(mid 351.87042 -226.460013)
				(end 352.038666 -226.420934)
			)
			(arc
				(start 352.038666 -226.420934)
				(mid 352.172372 -226.445131)
				(end 352.28911 -226.51466)
			)
			(arc
				(start 352.289618 -226.515168)
				(mid 352.305038 -226.524216)
				(end 352.322638 -226.52736)
			)
			(arc
				(start 352.389694 -226.52736)
				(mid 352.407293 -226.524214)
				(end 352.422714 -226.515168)
			)
			(arc
				(start 352.422968 -226.514914)
				(mid 352.673487 -226.420906)
				(end 352.92411 -226.51466)
			)
			(arc
				(start 352.924618 -226.515168)
				(mid 352.940038 -226.524216)
				(end 352.957638 -226.52736)
			)
			(arc
				(start 353.024694 -226.52736)
				(mid 353.042293 -226.524214)
				(end 353.057714 -226.515168)
			)
			(arc
				(start 353.057968 -226.514914)
				(mid 353.308487 -226.420906)
				(end 353.55911 -226.51466)
			)
			(arc
				(start 353.559618 -226.515168)
				(mid 353.575038 -226.524216)
				(end 353.592638 -226.52736)
			)
			(arc
				(start 353.659694 -226.52736)
				(mid 353.677293 -226.524214)
				(end 353.692714 -226.515168)
			)
			(arc
				(start 353.692968 -226.514914)
				(mid 353.809794 -226.445181)
				(end 353.943666 -226.420934)
			)
			(arc
				(start 353.943666 -226.420934)
				(mid 354.325174 -226.802442)
				(end 353.943666 -227.18395)
			)
			(arc
				(start 353.943666 -227.18395)
				(mid 353.80996 -227.159753)
				(end 353.693222 -227.090224)
			)
			(arc
				(start 353.692714 -227.089716)
				(mid 353.677294 -227.080668)
				(end 353.659694 -227.077524)
			)
			(arc
				(start 353.592638 -227.077524)
				(mid 353.575039 -227.08067)
				(end 353.559618 -227.089716)
			)
			(arc
				(start 353.559364 -227.08997)
				(mid 353.308845 -227.183978)
				(end 353.058222 -227.090224)
			)
			(arc
				(start 353.057714 -227.089716)
				(mid 353.042294 -227.080668)
				(end 353.024694 -227.077524)
			)
			(arc
				(start 352.957638 -227.077524)
				(mid 352.940039 -227.08067)
				(end 352.924618 -227.089716)
			)
			(arc
				(start 352.924364 -227.08997)
				(mid 352.673845 -227.183978)
				(end 352.423222 -227.090224)
			)
			(arc
				(start 352.422714 -227.089716)
				(mid 352.407294 -227.080668)
				(end 352.389694 -227.077524)
			)
			(arc
				(start 352.322638 -227.077524)
				(mid 352.305039 -227.08067)
				(end 352.289618 -227.089716)
			)
			(arc
				(start 352.289364 -227.08997)
				(mid 352.172538 -227.159703)
				(end 352.038666 -227.18395)
			)
			(arc
				(start 352.038666 -227.18395)
				(mid 351.863205 -227.141239)
				(end 351.727008 -227.02266)
			)
			(xy 351.72015 -227.013008) (xy 351.69983 -227.001832) (xy 351.59569 -226.99726) (xy 351.574354 -227.006658)
			(arc
				(start 351.566734 -227.015802)
				(mid 351.44444 -227.109657)
				(end 351.293938 -227.143056)
			)
			(arc
				(start 351.293684 -227.143056)
				(mid 351.113167 -227.093871)
				(end 350.982534 -226.959922)
			)
			(arc
				(start 350.982534 -226.959922)
				(mid 350.963988 -226.940835)
				(end 350.938338 -226.93376)
			)
			(xy 350.938084 -226.93376) (xy 350.849184 -226.93376)
			(arc
				(start 350.84893 -226.93376)
				(mid 350.823291 -226.940854)
				(end 350.804734 -226.959922)
			)
			(arc
				(start 350.804734 -226.959922)
				(mid 350.674111 -227.093888)
				(end 350.493584 -227.143056)
			)
			(arc
				(start 350.493584 -227.143056)
				(mid 350.31313 -227.093948)
				(end 350.182434 -226.960176)
			)
			(arc
				(start 350.182434 -226.960176)
				(mid 350.163778 -226.941025)
				(end 350.137984 -226.934014)
			)
			(arc
				(start 350.049338 -226.934014)
				(mid 350.023555 -226.941043)
				(end 350.004888 -226.960176)
			)
			(arc
				(start 350.004888 -226.960176)
				(mid 349.874199 -227.09396)
				(end 349.693738 -227.143056)
			)
			(arc
				(start 349.693738 -227.143056)
				(mid 349.513221 -227.093871)
				(end 349.382588 -226.959922)
			)
			(arc
				(start 349.382588 -226.959922)
				(mid 349.364042 -226.940835)
				(end 349.338392 -226.93376)
			)
			(xy 349.338138 -226.93376) (xy 349.249238 -226.93376)
			(arc
				(start 349.248984 -226.93376)
				(mid 349.223345 -226.940854)
				(end 349.204788 -226.959922)
			)
			(arc
				(start 349.204788 -226.959922)
				(mid 348.893638 -227.143076)
				(end 348.582488 -226.959922)
			)
			(arc
				(start 348.582488 -226.959922)
				(mid 348.563942 -226.940835)
				(end 348.538292 -226.93376)
			)
			(xy 348.538038 -226.93376) (xy 348.449138 -226.93376)
			(arc
				(start 348.448884 -226.93376)
				(mid 348.423245 -226.940854)
				(end 348.404688 -226.959922)
			)
			(arc
				(start 348.404688 -226.959922)
				(mid 348.274065 -227.093888)
				(end 348.093538 -227.143056)
			)
			(arc
				(start 348.093538 -227.143056)
				(mid 347.913084 -227.093948)
				(end 347.782388 -226.960176)
			)
			(arc
				(start 347.782388 -226.960176)
				(mid 347.763732 -226.941025)
				(end 347.737938 -226.934014)
			)
			(arc
				(start 347.649292 -226.934014)
				(mid 347.623509 -226.941043)
				(end 347.604842 -226.960176)
			)
			(arc
				(start 347.604842 -226.960176)
				(mid 347.474153 -227.09396)
				(end 347.293692 -227.143056)
			)
			(arc
				(start 347.293692 -227.143056)
				(mid 347.113175 -227.093871)
				(end 346.982542 -226.959922)
			)
			(arc
				(start 346.982542 -226.959922)
				(mid 346.963996 -226.940835)
				(end 346.938346 -226.93376)
			)
			(xy 346.938092 -226.93376) (xy 346.849192 -226.93376)
			(arc
				(start 346.848938 -226.93376)
				(mid 346.823299 -226.940854)
				(end 346.804742 -226.959922)
			)
			(arc
				(start 346.804742 -226.959922)
				(mid 346.745459 -227.038677)
				(end 346.66682 -227.098098)
			)
			(arc
				(start 346.66682 -227.098098)
				(mid 346.647669 -227.116754)
				(end 346.640658 -227.142548)
			)
			(arc
				(start 346.640658 -227.231194)
				(mid 346.647687 -227.256977)
				(end 346.66682 -227.275644)
			)
			(arc
				(start 346.66682 -227.275644)
				(mid 346.800604 -227.406333)
				(end 346.8497 -227.586794)
			)
			(arc
				(start 346.8497 -227.586794)
				(mid 346.493592 -227.942902)
				(end 346.137484 -227.586794)
			)
			(arc
				(start 346.137484 -227.586794)
				(mid 346.186592 -227.40634)
				(end 346.320364 -227.275644)
			)
			(arc
				(start 346.320364 -227.275644)
				(mid 346.339515 -227.256988)
				(end 346.346526 -227.231194)
			)
			(arc
				(start 346.346526 -227.142548)
				(mid 346.339497 -227.116765)
				(end 346.320364 -227.098098)
			)
			(arc
				(start 346.320364 -227.098098)
				(mid 346.241776 -227.038764)
				(end 346.182442 -226.960176)
			)
			(arc
				(start 346.182442 -226.960176)
				(mid 346.163786 -226.941025)
				(end 346.137992 -226.934014)
			)
			(arc
				(start 346.049346 -226.934014)
				(mid 346.023563 -226.941043)
				(end 346.004896 -226.960176)
			)
			(arc
				(start 346.004896 -226.960176)
				(mid 345.874207 -227.09396)
				(end 345.693746 -227.143056)
			)
			(arc
				(start 345.693746 -227.143056)
				(mid 345.513229 -227.093871)
				(end 345.382596 -226.959922)
			)
			(arc
				(start 345.382596 -226.959922)
				(mid 345.36405 -226.940835)
				(end 345.3384 -226.93376)
			)
			(xy 345.338146 -226.93376) (xy 345.249246 -226.93376)
			(arc
				(start 345.248992 -226.93376)
				(mid 345.223353 -226.940854)
				(end 345.204796 -226.959922)
			)
			(arc
				(start 345.204796 -226.959922)
				(mid 344.893646 -227.143076)
				(end 344.582496 -226.959922)
			)
			(arc
				(start 344.582496 -226.959922)
				(mid 344.56395 -226.940835)
				(end 344.5383 -226.93376)
			)
			(xy 344.538046 -226.93376) (xy 344.449146 -226.93376)
			(arc
				(start 344.448892 -226.93376)
				(mid 344.423253 -226.940854)
				(end 344.404696 -226.959922)
			)
			(arc
				(start 344.404696 -226.959922)
				(mid 344.274073 -227.093888)
				(end 344.093546 -227.143056)
			)
			(arc
				(start 344.093546 -227.143056)
				(mid 343.913092 -227.093948)
				(end 343.782396 -226.960176)
			)
			(arc
				(start 343.782396 -226.960176)
				(mid 343.76374 -226.941025)
				(end 343.737946 -226.934014)
			)
			(arc
				(start 343.6493 -226.934014)
				(mid 343.623517 -226.941043)
				(end 343.60485 -226.960176)
			)
			(arc
				(start 343.60485 -226.960176)
				(mid 343.474161 -227.09396)
				(end 343.2937 -227.143056)
			)
			(arc
				(start 343.2937 -227.143056)
				(mid 343.041894 -227.038754)
				(end 342.937592 -226.786948)
			)
			(arc
				(start 342.937592 -226.786948)
				(mid 342.986777 -226.606431)
				(end 343.120726 -226.475798)
			)
			(arc
				(start 343.120726 -226.475798)
				(mid 343.139813 -226.457252)
				(end 343.146888 -226.431602)
			)
			(xy 343.146888 -226.431348) (xy 343.146888 -226.342448)
			(arc
				(start 343.146888 -226.342194)
				(mid 343.139794 -226.316555)
				(end 343.120726 -226.297998)
			)
			(arc
				(start 343.120726 -226.297998)
				(mid 342.937572 -225.986848)
				(end 343.120726 -225.675698)
			)
			(arc
				(start 343.120726 -225.675698)
				(mid 343.139813 -225.657152)
				(end 343.146888 -225.631502)
			)
			(xy 343.146888 -225.631248) (xy 343.146888 -225.542348)
			(arc
				(start 343.146888 -225.542094)
				(mid 343.139794 -225.516455)
				(end 343.120726 -225.497898)
			)
			(arc
				(start 343.120726 -225.497898)
				(mid 342.98676 -225.367275)
				(end 342.937592 -225.186748)
			)
			(arc
				(start 342.937592 -225.186748)
				(mid 342.9867 -225.006294)
				(end 343.120472 -224.875598)
			)
			(arc
				(start 343.120472 -224.875598)
				(mid 343.139623 -224.856942)
				(end 343.146634 -224.831148)
			)
			(arc
				(start 343.146634 -224.742502)
				(mid 343.139605 -224.716719)
				(end 343.120472 -224.698052)
			)
			(arc
				(start 343.120472 -224.698052)
				(mid 342.986688 -224.567363)
				(end 342.937592 -224.386902)
			)
			(arc
				(start 342.937592 -224.386902)
				(mid 342.986777 -224.206385)
				(end 343.120726 -224.075752)
			)
			(arc
				(start 343.120726 -224.075752)
				(mid 343.139813 -224.057206)
				(end 343.146888 -224.031556)
			)
			(xy 343.146888 -224.031302) (xy 343.146888 -223.942402)
			(arc
				(start 343.146888 -223.942148)
				(mid 343.139794 -223.916509)
				(end 343.120726 -223.897952)
			)
			(arc
				(start 343.120726 -223.897952)
				(mid 342.98676 -223.767329)
				(end 342.937592 -223.586802)
			)
			(arc
				(start 342.937592 -223.586802)
				(mid 342.9867 -223.406348)
				(end 343.120472 -223.275652)
			)
			(arc
				(start 343.120472 -223.275652)
				(mid 343.139623 -223.256996)
				(end 343.146634 -223.231202)
			)
			(arc
				(start 343.146634 -223.142556)
				(mid 343.139605 -223.116773)
				(end 343.120472 -223.098106)
			)
			(arc
				(start 343.120472 -223.098106)
				(mid 342.986688 -222.967417)
				(end 342.937592 -222.786956)
			)
			(arc
				(start 342.937592 -222.786956)
				(mid 342.986777 -222.606439)
				(end 343.120726 -222.475806)
			)
			(arc
				(start 343.120726 -222.475806)
				(mid 343.139813 -222.45726)
				(end 343.146888 -222.43161)
			)
			(xy 343.146888 -222.431356) (xy 343.146888 -222.342456)
			(arc
				(start 343.146888 -222.342202)
				(mid 343.139794 -222.316563)
				(end 343.120726 -222.298006)
			)
			(arc
				(start 343.120726 -222.298006)
				(mid 342.98676 -222.167383)
				(end 342.937592 -221.986856)
			)
			(arc
				(start 342.937592 -221.986856)
				(mid 343.041894 -221.73505)
				(end 343.2937 -221.630748)
			)
			(arc
				(start 343.2937 -221.630748)
				(mid 343.474154 -221.679856)
				(end 343.60485 -221.813628)
			)
			(arc
				(start 343.60485 -221.813628)
				(mid 343.623506 -221.832779)
				(end 343.6493 -221.83979)
			)
			(arc
				(start 343.737946 -221.83979)
				(mid 343.763729 -221.832761)
				(end 343.782396 -221.813628)
			)
			(arc
				(start 343.782396 -221.813628)
				(mid 343.913085 -221.679844)
				(end 344.093546 -221.630748)
			)
			(arc
				(start 344.093546 -221.630748)
				(mid 344.274245 -221.679999)
				(end 344.40495 -221.814136)
			)
			(arc
				(start 344.405204 -221.81439)
				(mid 344.423804 -221.83329)
				(end 344.4494 -221.840298)
			)
			(arc
				(start 344.538046 -221.840298)
				(mid 344.563829 -221.833269)
				(end 344.582496 -221.814136)
			)
			(arc
				(start 344.582496 -221.814136)
				(mid 344.642015 -221.735225)
				(end 344.720926 -221.675706)
			)
			(arc
				(start 344.720926 -221.675706)
				(mid 344.740077 -221.65705)
				(end 344.747088 -221.631256)
			)
			(arc
				(start 344.747088 -221.54261)
				(mid 344.740146 -221.516976)
				(end 344.72118 -221.498414)
			)
			(arc
				(start 344.720926 -221.49816)
				(mid 344.586799 -221.367449)
				(end 344.537538 -221.186756)
			)
			(arc
				(start 344.537538 -221.186756)
				(mid 344.586646 -221.006302)
				(end 344.720418 -220.875606)
			)
			(arc
				(start 344.720418 -220.875606)
				(mid 344.739569 -220.85695)
				(end 344.74658 -220.831156)
			)
			(arc
				(start 344.74658 -220.74251)
				(mid 344.739551 -220.716727)
				(end 344.720418 -220.69806)
			)
			(arc
				(start 344.720418 -220.69806)
				(mid 344.641831 -220.638587)
				(end 344.582496 -220.559884)
			)
			(arc
				(start 344.582496 -220.559884)
				(mid 344.56395 -220.540797)
				(end 344.5383 -220.533722)
			)
			(xy 344.538046 -220.533722) (xy 344.449146 -220.533722)
			(arc
				(start 344.448892 -220.533722)
				(mid 344.423253 -220.540816)
				(end 344.404696 -220.559884)
			)
			(arc
				(start 344.404696 -220.559884)
				(mid 344.274073 -220.69385)
				(end 344.093546 -220.743018)
			)
			(arc
				(start 344.093546 -220.743018)
				(mid 343.737438 -220.38691)
				(end 344.093546 -220.030802)
			)
			(arc
				(start 344.093546 -220.030802)
				(mid 344.274063 -220.079987)
				(end 344.404696 -220.213936)
			)
			(arc
				(start 344.404696 -220.213936)
				(mid 344.423242 -220.233023)
				(end 344.448892 -220.240098)
			)
			(xy 344.449146 -220.240098) (xy 344.538046 -220.240098)
			(arc
				(start 344.5383 -220.240098)
				(mid 344.563939 -220.233004)
				(end 344.582496 -220.213936)
			)
			(arc
				(start 344.582496 -220.213936)
				(mid 344.893646 -220.030782)
				(end 345.204796 -220.213936)
			)
			(arc
				(start 345.204796 -220.213936)
				(mid 345.223342 -220.233023)
				(end 345.248992 -220.240098)
			)
			(xy 345.249246 -220.240098) (xy 345.338146 -220.240098)
			(arc
				(start 345.3384 -220.240098)
				(mid 345.364039 -220.233004)
				(end 345.382596 -220.213936)
			)
			(arc
				(start 345.382596 -220.213936)
				(mid 345.453217 -220.124546)
				(end 345.548458 -220.062044)
			)
			(xy 345.548712 -220.06179)
			(arc
				(start 345.54922 -220.061536)
				(mid 345.561056 -220.053882)
				(end 345.570302 -220.043248)
			)
			(arc
				(start 345.570302 -220.043248)
				(mid 345.576538 -220.029892)
				(end 345.578684 -220.015308)
			)
			(arc
				(start 345.578684 -219.15882)
				(mid 345.576545 -219.144234)
				(end 345.570302 -219.13088)
			)
			(arc
				(start 345.570302 -219.13088)
				(mid 345.561037 -219.120269)
				(end 345.54922 -219.112592)
			)
			(xy 345.548712 -219.112338)
			(arc
				(start 345.548458 -219.112084)
				(mid 345.453227 -219.049571)
				(end 345.382596 -218.960192)
			)
			(arc
				(start 345.382596 -218.960192)
				(mid 345.36405 -218.941105)
				(end 345.3384 -218.93403)
			)
			(xy 345.338146 -218.93403) (xy 345.249246 -218.93403)
			(arc
				(start 345.248992 -218.93403)
				(mid 345.223353 -218.941124)
				(end 345.204796 -218.960192)
			)
			(arc
				(start 345.204796 -218.960192)
				(mid 344.893646 -219.143346)
				(end 344.582496 -218.960192)
			)
			(arc
				(start 344.582496 -218.960192)
				(mid 344.56395 -218.941105)
				(end 344.5383 -218.93403)
			)
			(xy 344.538046 -218.93403) (xy 344.449146 -218.93403)
			(arc
				(start 344.448892 -218.93403)
				(mid 344.423253 -218.941124)
				(end 344.404696 -218.960192)
			)
			(arc
				(start 344.404696 -218.960192)
				(mid 344.274073 -219.094158)
				(end 344.093546 -219.143326)
			)
			(arc
				(start 344.093546 -219.143326)
				(mid 343.737438 -218.787218)
				(end 344.093546 -218.43111)
			)
			(arc
				(start 344.093546 -218.43111)
				(mid 344.274063 -218.480295)
				(end 344.404696 -218.614244)
			)
			(arc
				(start 344.404696 -218.614244)
				(mid 344.423242 -218.633331)
				(end 344.448892 -218.640406)
			)
			(xy 344.449146 -218.640406) (xy 344.538046 -218.640406)
			(arc
				(start 344.5383 -218.640406)
				(mid 344.563939 -218.633312)
				(end 344.582496 -218.614244)
			)
			(arc
				(start 344.582496 -218.614244)
				(mid 344.641779 -218.535489)
				(end 344.720418 -218.476068)
			)
			(arc
				(start 344.720418 -218.476068)
				(mid 344.739569 -218.457412)
				(end 344.74658 -218.431618)
			)
			(arc
				(start 344.74658 -218.342972)
				(mid 344.739551 -218.317189)
				(end 344.720418 -218.298522)
			)
			(arc
				(start 344.720418 -218.298522)
				(mid 344.586634 -218.167833)
				(end 344.537538 -217.987372)
			)
			(arc
				(start 344.537538 -217.987372)
				(mid 344.586789 -217.806673)
				(end 344.720926 -217.675968)
			)
			(xy 344.72118 -217.675968)
			(arc
				(start 344.72118 -217.675714)
				(mid 344.74008 -217.657114)
				(end 344.747088 -217.631518)
			)
			(arc
				(start 344.747088 -217.542872)
				(mid 344.740059 -217.517089)
				(end 344.720926 -217.498422)
			)
			(arc
				(start 344.720926 -217.498422)
				(mid 344.648575 -217.445173)
				(end 344.591894 -217.375486)
			)
			(arc
				(start 344.589608 -217.372184)
				(mid 344.572965 -217.357713)
				(end 344.551762 -217.35161)
			)
			(xy 344.548714 -217.35161)
			(arc
				(start 344.438986 -217.35161)
				(mid 344.414336 -217.357991)
				(end 344.395806 -217.375486)
			)
			(arc
				(start 344.395806 -217.375486)
				(mid 344.093546 -217.543342)
				(end 343.791286 -217.375486)
			)
			(arc
				(start 343.791286 -217.375486)
				(mid 343.772798 -217.357916)
				(end 343.748106 -217.35161)
			)
			(arc
				(start 343.63914 -217.35161)
				(mid 343.61449 -217.357991)
				(end 343.59596 -217.375486)
			)
			(arc
				(start 343.59596 -217.375486)
				(mid 343.2937 -217.543342)
				(end 342.99144 -217.375486)
			)
			(arc
				(start 342.99144 -217.375486)
				(mid 342.972952 -217.357916)
				(end 342.94826 -217.35161)
			)
			(arc
				(start 342.039448 -217.35161)
				(mid 342.014798 -217.357991)
				(end 341.996268 -217.375486)
			)
			(arc
				(start 341.996268 -217.375486)
				(mid 341.694008 -217.543342)
				(end 341.391748 -217.375486)
			)
			(arc
				(start 341.391748 -217.375486)
				(mid 341.37326 -217.357916)
				(end 341.348568 -217.35161)
			)
			(arc
				(start 341.239602 -217.35161)
				(mid 341.214952 -217.357991)
				(end 341.196422 -217.375486)
			)
			(arc
				(start 341.196422 -217.375486)
				(mid 340.894162 -217.543342)
				(end 340.591902 -217.375486)
			)
			(arc
				(start 340.591902 -217.375486)
				(mid 340.573414 -217.357916)
				(end 340.548722 -217.35161)
			)
			(xy 340.438994 -217.35161)
			(arc
				(start 340.435946 -217.35161)
				(mid 340.414725 -217.357678)
				(end 340.3981 -217.372184)
			)
			(arc
				(start 340.395814 -217.375486)
				(mid 340.339098 -217.445136)
				(end 340.266782 -217.498422)
			)
			(arc
				(start 340.266782 -217.498422)
				(mid 340.247631 -217.517078)
				(end 340.24062 -217.542872)
			)
			(arc
				(start 340.24062 -217.631518)
				(mid 340.247562 -217.657152)
				(end 340.266528 -217.675714)
			)
			(arc
				(start 340.266782 -217.675968)
				(mid 340.400909 -217.806679)
				(end 340.45017 -217.987372)
			)
			(arc
				(start 340.45017 -217.987372)
				(mid 340.401062 -218.167826)
				(end 340.26729 -218.298522)
			)
			(arc
				(start 340.26729 -218.298522)
				(mid 340.248139 -218.317178)
				(end 340.241128 -218.342972)
			)
			(arc
				(start 340.241128 -218.431618)
				(mid 340.248157 -218.457401)
				(end 340.26729 -218.476068)
			)
			(arc
				(start 340.26729 -218.476068)
				(mid 340.345877 -218.535541)
				(end 340.405212 -218.614244)
			)
			(arc
				(start 340.405212 -218.614244)
				(mid 340.423758 -218.633331)
				(end 340.449408 -218.640406)
			)
			(xy 340.449662 -218.640406) (xy 340.538562 -218.640406)
			(arc
				(start 340.538816 -218.640406)
				(mid 340.564455 -218.633312)
				(end 340.583012 -218.614244)
			)
			(arc
				(start 340.583012 -218.614244)
				(mid 340.713635 -218.480278)
				(end 340.894162 -218.43111)
			)
			(arc
				(start 340.894162 -218.43111)
				(mid 341.25027 -218.787218)
				(end 340.894162 -219.143326)
			)
			(arc
				(start 340.894162 -219.143326)
				(mid 340.713645 -219.094141)
				(end 340.583012 -218.960192)
			)
			(arc
				(start 340.583012 -218.960192)
				(mid 340.564466 -218.941105)
				(end 340.538816 -218.93403)
			)
			(xy 340.538562 -218.93403) (xy 340.449662 -218.93403)
			(arc
				(start 340.449408 -218.93403)
				(mid 340.423769 -218.941124)
				(end 340.405212 -218.960192)
			)
			(arc
				(start 340.405212 -218.960192)
				(mid 340.094062 -219.143346)
				(end 339.782912 -218.960192)
			)
			(arc
				(start 339.782912 -218.960192)
				(mid 339.764366 -218.941105)
				(end 339.738716 -218.93403)
			)
			(xy 339.738462 -218.93403) (xy 339.649562 -218.93403)
			(arc
				(start 339.649308 -218.93403)
				(mid 339.623669 -218.941124)
				(end 339.605112 -218.960192)
			)
			(arc
				(start 339.605112 -218.960192)
				(mid 339.474489 -219.094158)
				(end 339.293962 -219.143326)
			)
			(arc
				(start 339.293962 -219.143326)
				(mid 339.113508 -219.094218)
				(end 338.982812 -218.960446)
			)
			(arc
				(start 338.982812 -218.960446)
				(mid 338.964156 -218.941295)
				(end 338.938362 -218.934284)
			)
			(arc
				(start 338.849716 -218.934284)
				(mid 338.823933 -218.941313)
				(end 338.805266 -218.960446)
			)
			(arc
				(start 338.805266 -218.960446)
				(mid 338.721486 -219.061308)
				(end 338.606892 -219.125038)
			)
			(arc
				(start 338.606638 -219.125038)
				(mid 338.581535 -219.143587)
				(end 338.572094 -219.173298)
			)
			(arc
				(start 338.572094 -220.00083)
				(mid 338.581636 -220.030468)
				(end 338.606638 -220.04909)
			)
			(arc
				(start 338.606892 -220.04909)
				(mid 338.721503 -220.1128)
				(end 338.805266 -220.213682)
			)
			(arc
				(start 338.805266 -220.213682)
				(mid 338.823922 -220.232833)
				(end 338.849716 -220.239844)
			)
			(arc
				(start 338.938362 -220.239844)
				(mid 338.964145 -220.232815)
				(end 338.982812 -220.213682)
			)
			(arc
				(start 338.982812 -220.213682)
				(mid 339.113501 -220.079898)
				(end 339.293962 -220.030802)
			)
			(arc
				(start 339.293962 -220.030802)
				(mid 339.474479 -220.079987)
				(end 339.605112 -220.213936)
			)
			(arc
				(start 339.605112 -220.213936)
				(mid 339.623658 -220.233023)
				(end 339.649308 -220.240098)
			)
			(xy 339.649562 -220.240098) (xy 339.738462 -220.240098)
			(arc
				(start 339.738716 -220.240098)
				(mid 339.764355 -220.233004)
				(end 339.782912 -220.213936)
			)
			(arc
				(start 339.782912 -220.213936)
				(mid 340.094062 -220.030782)
				(end 340.405212 -220.213936)
			)
			(arc
				(start 340.405212 -220.213936)
				(mid 340.423758 -220.233023)
				(end 340.449408 -220.240098)
			)
			(xy 340.449662 -220.240098) (xy 340.538562 -220.240098)
			(arc
				(start 340.538816 -220.240098)
				(mid 340.564455 -220.233004)
				(end 340.583012 -220.213936)
			)
			(arc
				(start 340.583012 -220.213936)
				(mid 340.713635 -220.07997)
				(end 340.894162 -220.030802)
			)
			(arc
				(start 340.894162 -220.030802)
				(mid 341.25027 -220.38691)
				(end 340.894162 -220.743018)
			)
			(arc
				(start 340.894162 -220.743018)
				(mid 340.713645 -220.693833)
				(end 340.583012 -220.559884)
			)
			(arc
				(start 340.583012 -220.559884)
				(mid 340.564466 -220.540797)
				(end 340.538816 -220.533722)
			)
			(xy 340.538562 -220.533722) (xy 340.449662 -220.533722)
			(arc
				(start 340.449408 -220.533722)
				(mid 340.423769 -220.540816)
				(end 340.405212 -220.559884)
			)
			(arc
				(start 340.405212 -220.559884)
				(mid 340.345929 -220.638639)
				(end 340.26729 -220.69806)
			)
			(arc
				(start 340.26729 -220.69806)
				(mid 340.248139 -220.716716)
				(end 340.241128 -220.74251)
			)
			(arc
				(start 340.241128 -220.831156)
				(mid 340.248157 -220.856939)
				(end 340.26729 -220.875606)
			)
			(arc
				(start 340.26729 -220.875606)
				(mid 340.401074 -221.006295)
				(end 340.45017 -221.186756)
			)
			(arc
				(start 340.45017 -221.186756)
				(mid 340.400919 -221.367455)
				(end 340.266782 -221.49816)
			)
			(xy 340.266528 -221.49816)
			(arc
				(start 340.266528 -221.498414)
				(mid 340.247628 -221.517014)
				(end 340.24062 -221.54261)
			)
			(arc
				(start 340.24062 -221.631256)
				(mid 340.247649 -221.657039)
				(end 340.266782 -221.675706)
			)
			(arc
				(start 340.266782 -221.675706)
				(mid 340.345693 -221.735225)
				(end 340.405212 -221.814136)
			)
			(arc
				(start 340.405212 -221.814136)
				(mid 340.423868 -221.833287)
				(end 340.449662 -221.840298)
			)
			(arc
				(start 340.538308 -221.840298)
				(mid 340.563942 -221.833356)
				(end 340.582504 -221.81439)
			)
			(arc
				(start 340.582758 -221.814136)
				(mid 340.713469 -221.680009)
				(end 340.894162 -221.630748)
			)
			(arc
				(start 340.894162 -221.630748)
				(mid 341.074616 -221.679856)
				(end 341.205312 -221.813628)
			)
			(arc
				(start 341.205312 -221.813628)
				(mid 341.223968 -221.832779)
				(end 341.249762 -221.83979)
			)
			(arc
				(start 341.338408 -221.83979)
				(mid 341.364191 -221.832761)
				(end 341.382858 -221.813628)
			)
			(arc
				(start 341.382858 -221.813628)
				(mid 341.513547 -221.679844)
				(end 341.694008 -221.630748)
			)
			(arc
				(start 341.694008 -221.630748)
				(mid 341.945814 -221.73505)
				(end 342.050116 -221.986856)
			)
			(arc
				(start 342.050116 -221.986856)
				(mid 342.000931 -222.167373)
				(end 341.866982 -222.298006)
			)
			(arc
				(start 341.866982 -222.298006)
				(mid 341.847895 -222.316552)
				(end 341.84082 -222.342202)
			)
			(xy 341.84082 -222.342456) (xy 341.84082 -222.431356)
			(arc
				(start 341.84082 -222.43161)
				(mid 341.847914 -222.457249)
				(end 341.866982 -222.475806)
			)
			(arc
				(start 341.866982 -222.475806)
				(mid 342.000948 -222.606429)
				(end 342.050116 -222.786956)
			)
			(arc
				(start 342.050116 -222.786956)
				(mid 342.001008 -222.96741)
				(end 341.867236 -223.098106)
			)
			(arc
				(start 341.867236 -223.098106)
				(mid 341.848085 -223.116762)
				(end 341.841074 -223.142556)
			)
			(arc
				(start 341.841074 -223.231202)
				(mid 341.848103 -223.256985)
				(end 341.867236 -223.275652)
			)
			(arc
				(start 341.867236 -223.275652)
				(mid 342.00102 -223.406341)
				(end 342.050116 -223.586802)
			)
			(arc
				(start 342.050116 -223.586802)
				(mid 342.000931 -223.767319)
				(end 341.866982 -223.897952)
			)
			(arc
				(start 341.866982 -223.897952)
				(mid 341.847895 -223.916498)
				(end 341.84082 -223.942148)
			)
			(xy 341.84082 -223.942402) (xy 341.84082 -224.031302)
			(arc
				(start 341.84082 -224.031556)
				(mid 341.847914 -224.057195)
				(end 341.866982 -224.075752)
			)
			(arc
				(start 341.866982 -224.075752)
				(mid 342.000948 -224.206375)
				(end 342.050116 -224.386902)
			)
			(arc
				(start 342.050116 -224.386902)
				(mid 342.001008 -224.567356)
				(end 341.867236 -224.698052)
			)
			(arc
				(start 341.867236 -224.698052)
				(mid 341.848085 -224.716708)
				(end 341.841074 -224.742502)
			)
			(arc
				(start 341.841074 -224.831148)
				(mid 341.848103 -224.856931)
				(end 341.867236 -224.875598)
			)
			(arc
				(start 341.867236 -224.875598)
				(mid 342.00102 -225.006287)
				(end 342.050116 -225.186748)
			)
			(arc
				(start 342.050116 -225.186748)
				(mid 342.000931 -225.367265)
				(end 341.866982 -225.497898)
			)
			(arc
				(start 341.866982 -225.497898)
				(mid 341.847895 -225.516444)
				(end 341.84082 -225.542094)
			)
			(xy 341.84082 -225.542348) (xy 341.84082 -225.631248)
			(arc
				(start 341.84082 -225.631502)
				(mid 341.847914 -225.657141)
				(end 341.866982 -225.675698)
			)
			(arc
				(start 341.866982 -225.675698)
				(mid 342.050136 -225.986848)
				(end 341.866982 -226.297998)
			)
			(arc
				(start 341.866982 -226.297998)
				(mid 341.847895 -226.316544)
				(end 341.84082 -226.342194)
			)
			(xy 341.84082 -226.342448) (xy 341.84082 -226.431348)
			(arc
				(start 341.84082 -226.431602)
				(mid 341.847914 -226.457241)
				(end 341.866982 -226.475798)
			)
			(arc
				(start 341.866982 -226.475798)
				(mid 342.000948 -226.606421)
				(end 342.050116 -226.786948)
			)
			(arc
				(start 342.050116 -226.786948)
				(mid 341.945814 -227.038754)
				(end 341.694008 -227.143056)
			)
			(arc
				(start 341.694008 -227.143056)
				(mid 341.513554 -227.093948)
				(end 341.382858 -226.960176)
			)
			(arc
				(start 341.382858 -226.960176)
				(mid 341.364202 -226.941025)
				(end 341.338408 -226.934014)
			)
			(arc
				(start 341.249762 -226.934014)
				(mid 341.223979 -226.941043)
				(end 341.205312 -226.960176)
			)
			(arc
				(start 341.205312 -226.960176)
				(mid 341.074623 -227.09396)
				(end 340.894162 -227.143056)
			)
			(arc
				(start 340.894162 -227.143056)
				(mid 340.713645 -227.093871)
				(end 340.583012 -226.959922)
			)
			(arc
				(start 340.583012 -226.959922)
				(mid 340.564466 -226.940835)
				(end 340.538816 -226.93376)
			)
			(xy 340.538562 -226.93376) (xy 340.449662 -226.93376)
			(arc
				(start 340.449408 -226.93376)
				(mid 340.423769 -226.940854)
				(end 340.405212 -226.959922)
			)
			(arc
				(start 340.405212 -226.959922)
				(mid 340.094062 -227.143076)
				(end 339.782912 -226.959922)
			)
			(arc
				(start 339.782912 -226.959922)
				(mid 339.764366 -226.940835)
				(end 339.738716 -226.93376)
			)
			(xy 339.738462 -226.93376) (xy 339.649562 -226.93376)
			(arc
				(start 339.649308 -226.93376)
				(mid 339.623669 -226.940854)
				(end 339.605112 -226.959922)
			)
			(arc
				(start 339.605112 -226.959922)
				(mid 339.545778 -227.03851)
				(end 339.46719 -227.097844)
			)
			(arc
				(start 339.466682 -227.098352)
				(mid 339.456234 -227.106161)
				(end 339.44814 -227.116386)
			)
			(arc
				(start 339.44814 -227.11664)
				(mid 339.442844 -227.129116)
				(end 339.441028 -227.142548)
			)
			(arc
				(start 339.441028 -227.231448)
				(mid 339.448122 -227.257087)
				(end 339.46719 -227.275644)
			)
			(arc
				(start 339.46719 -227.275644)
				(mid 339.600791 -227.406399)
				(end 339.649816 -227.586794)
			)
			(arc
				(start 339.649816 -227.586794)
				(mid 339.293708 -227.942902)
				(end 338.9376 -227.586794)
			)
			(arc
				(start 338.9376 -227.586794)
				(mid 338.986719 -227.406459)
				(end 339.12048 -227.275898)
			)
			(arc
				(start 339.12048 -227.275898)
				(mid 339.131251 -227.267904)
				(end 339.13953 -227.257356)
			)
			(arc
				(start 339.13953 -227.257102)
				(mid 339.144826 -227.244626)
				(end 339.146642 -227.231194)
			)
			(arc
				(start 339.146642 -227.142294)
				(mid 339.139548 -227.116655)
				(end 339.12048 -227.098098)
			)
			(arc
				(start 339.12048 -227.098098)
				(mid 339.04206 -227.038713)
				(end 338.982812 -226.960176)
			)
			(arc
				(start 338.982812 -226.960176)
				(mid 338.964156 -226.941025)
				(end 338.938362 -226.934014)
			)
			(arc
				(start 338.849716 -226.934014)
				(mid 338.823933 -226.941043)
				(end 338.805266 -226.960176)
			)
			(arc
				(start 338.805266 -226.960176)
				(mid 338.726212 -227.057048)
				(end 338.618576 -227.120704)
			)
			(xy 338.60359 -227.126292) (xy 338.585556 -227.152454)
			(arc
				(start 338.585556 -227.908866)
				(mid 338.589457 -227.928389)
				(end 338.600542 -227.944934)
			)
			(arc
				(start 339.062568 -228.40696)
				(mid 339.093958 -228.421759)
				(end 339.127592 -228.413056)
			)
			(arc
				(start 339.127592 -228.413056)
				(mid 339.230652 -228.36279)
				(end 339.344 -228.345492)
			)
			(arc
				(start 339.344 -228.345492)
				(mid 339.522547 -228.389784)
				(end 339.659722 -228.51237)
			)
			(xy 339.663024 -228.51745) (xy 339.67166 -228.525324)
			(arc
				(start 339.697314 -228.539548)
				(mid 339.709228 -228.544301)
				(end 339.721952 -228.545898)
			)
			(xy 339.958172 -228.545898)
		)
		(stroke
			(width 0)
			(type solid)
		)
		(fill yes)
		(layer "In9.Cu")
		(net "P3V3_VCC_FPGA_CORE")
	)
	(gr_poly
		(pts
			(xy 234.116118 -70.178676) (xy 234.123071 -70.178443) (xy 234.13647 -70.174719) (xy 234.142534 -70.17131)
			(xy 234.177359 -70.150631) (xy 234.250655 -70.116163) (xy 234.32729 -70.089942) (xy 234.406338 -70.072285)
			(xy 234.486846 -70.063406) (xy 234.527344 -70.062852) (xy 234.56784 -70.06342) (xy 234.648342 -70.072325)
			(xy 234.727385 -70.089988) (xy 234.80402 -70.116199) (xy 234.877324 -70.150643) (xy 234.912154 -70.17131)
			(xy 234.918209 -70.174745) (xy 234.931612 -70.178488) (xy 234.93857 -70.178676) (xy 239.553242 -70.178676)
			(xy 239.562011 -70.178266) (xy 239.578507 -70.172298) (xy 239.5855 -70.166992) (xy 239.638332 -70.118224)
			(xy 239.64164 -70.115006) (xy 239.647137 -70.107593) (xy 239.649254 -70.103492) (xy 239.653572 -70.09511)
			(xy 239.654334 -70.08495) (xy 239.657069 -70.058056) (xy 239.66916 -70.005369) (xy 239.688565 -69.954915)
			(xy 239.714897 -69.907705) (xy 239.747628 -69.864684) (xy 239.786103 -69.826713) (xy 239.829551 -69.794552)
			(xy 239.877104 -69.768844) (xy 239.927809 -69.750105) (xy 239.980651 -69.738709) (xy 240.034572 -69.734885)
			(xy 240.088493 -69.738709) (xy 240.141335 -69.750105) (xy 240.19204 -69.768844) (xy 240.239593 -69.794552)
			(xy 240.283041 -69.826713) (xy 240.321516 -69.864684) (xy 240.354247 -69.907705) (xy 240.380579 -69.954915)
			(xy 240.399984 -70.005369) (xy 240.412075 -70.058056) (xy 240.41481 -70.08495) (xy 240.415572 -70.09511)
			(xy 240.41989 -70.103492) (xy 240.422015 -70.107588) (xy 240.427507 -70.115003) (xy 240.430812 -70.118224)
			(xy 240.483644 -70.166992) (xy 240.490625 -70.172322) (xy 240.507127 -70.178298) (xy 240.515902 -70.178676)
			(xy 252.574044 -70.178676) (xy 252.584379 -70.178193) (xy 252.603388 -70.17007) (xy 252.610874 -70.162928)
			(xy 252.668786 -70.101968) (xy 252.675898 -70.082156) (xy 252.67539 -70.071742) (xy 252.674628 -70.035928)
			(xy 252.674628 -67.988942) (xy 252.674218 -67.979331) (xy 252.667179 -67.961442) (xy 252.660912 -67.954144)
			(xy 252.640338 -67.9323) (xy 252.633974 -67.925943) (xy 252.617973 -67.917749) (xy 252.609096 -67.916298)
			(xy 252.581599 -67.912586) (xy 252.528003 -67.898233) (xy 252.477053 -67.876263) (xy 252.429826 -67.847139)
			(xy 252.387319 -67.811478) (xy 252.35043 -67.770033) (xy 252.319938 -67.723678) (xy 252.296487 -67.673393)
			(xy 252.280572 -67.620239) (xy 252.27253 -67.56534) (xy 252.27253 -67.509856) (xy 252.280573 -67.454957)
			(xy 252.296488 -67.401804) (xy 252.31994 -67.351519) (xy 252.350432 -67.305164) (xy 252.387322 -67.263719)
			(xy 252.429829 -67.228058) (xy 252.477056 -67.198936) (xy 252.528006 -67.176966) (xy 252.581602 -67.162614)
			(xy 252.609096 -67.15887) (xy 252.617981 -67.157444) (xy 252.633984 -67.149241) (xy 252.640338 -67.142868)
			(xy 252.660912 -67.121024) (xy 252.667205 -67.113737) (xy 252.674275 -67.095846) (xy 252.674628 -67.086226)
			(xy 252.674628 -65.505584) (xy 252.652022 -65.477644) (xy 252.644656 -65.47612) (xy 252.617369 -65.470519)
			(xy 252.564674 -65.45246) (xy 252.515164 -65.426933) (xy 252.46989 -65.39448) (xy 252.429815 -65.355791)
			(xy 252.395789 -65.311688) (xy 252.368535 -65.263107) (xy 252.348632 -65.211081) (xy 252.336503 -65.156714)
			(xy 252.332406 -65.101161) (xy 252.336427 -65.045603) (xy 252.348482 -64.99122) (xy 252.368313 -64.939166)
			(xy 252.395501 -64.890548) (xy 252.429466 -64.846398) (xy 252.469489 -64.807655) (xy 252.514718 -64.77514)
			(xy 252.564193 -64.749546) (xy 252.616863 -64.731414) (xy 252.644148 -64.725804) (xy 252.645164 -64.725804)
			(xy 252.652022 -64.72428) (xy 252.674628 -64.69634) (xy 252.674628 -52.999386) (xy 252.675087 -52.964394)
			(xy 252.682258 -52.894777) (xy 252.696484 -52.826254) (xy 252.717615 -52.759536) (xy 252.745434 -52.695317)
			(xy 252.779649 -52.634266) (xy 252.819905 -52.577019) (xy 252.842522 -52.550314) (xy 252.848213 -52.543195)
			(xy 252.854596 -52.526137) (xy 252.854607 -52.507923) (xy 252.848244 -52.490858) (xy 252.842522 -52.483766)
			(xy 252.819901 -52.45702) (xy 252.779625 -52.399702) (xy 252.745398 -52.338579) (xy 252.717574 -52.274287)
			(xy 252.696445 -52.207496) (xy 252.682229 -52.1389) (xy 252.675074 -52.069213) (xy 252.674628 -52.034186)
			(xy 252.674628 -51.73853) (xy 252.675179 -51.700101) (xy 252.683796 -51.623727) (xy 252.700893 -51.548795)
			(xy 252.726255 -51.476242) (xy 252.759564 -51.406976) (xy 252.800404 -51.341867) (xy 252.848263 -51.281728)
			(xy 252.875034 -51.254152) (xy 252.911356 -51.21783) (xy 252.911864 -51.217322) (xy 253.001018 -51.12512)
			(xy 253.00475 -51.121363) (xy 253.013454 -51.115337) (xy 253.01829 -51.113182) (xy 253.257558 -51.016154)
			(xy 253.262124 -51.014395) (xy 253.271717 -51.012467) (xy 253.276608 -51.012344) (xy 253.968504 -51.012344)
			(xy 253.978514 -51.011856) (xy 253.997012 -51.004197) (xy 254.011175 -50.990046) (xy 254.018848 -50.971554)
			(xy 254.019304 -50.961544) (xy 254.019304 -49.204118) (xy 254.018425 -49.194387) (xy 254.010318 -49.176628)
			(xy 254.003556 -49.169574) (xy 254.000508 -49.16678) (xy 253.929388 -49.116996) (xy 253.924287 -49.113567)
			(xy 253.912852 -49.109069) (xy 253.906782 -49.108106) (xy 253.898908 -49.10709) (xy 253.88697 -49.109376)
			(xy 253.882652 -49.1109) (xy 253.882398 -49.1109) (xy 253.850492 -49.121904) (xy 253.78406 -49.133784)
			(xy 253.750318 -49.134522) (xy 253.746254 -49.134522) (xy 253.71919 -49.133762) (xy 253.665678 -49.125541)
			(xy 253.613865 -49.109838) (xy 253.564793 -49.086968) (xy 253.519446 -49.057391) (xy 253.478735 -49.021701)
			(xy 253.443478 -48.980614) (xy 253.414384 -48.934956) (xy 253.392036 -48.885643) (xy 253.376883 -48.833667)
			(xy 253.369229 -48.78007) (xy 253.369229 -48.72593) (xy 253.376883 -48.672334) (xy 253.392035 -48.620357)
			(xy 253.414384 -48.571045) (xy 253.443478 -48.525386) (xy 253.478735 -48.4843) (xy 253.519445 -48.448609)
			(xy 253.564792 -48.419032) (xy 253.613865 -48.396162) (xy 253.665678 -48.380459) (xy 253.71919 -48.372238)
			(xy 253.746254 -48.371506) (xy 253.750826 -48.371506) (xy 253.78342 -48.372194) (xy 253.847656 -48.383306)
			(xy 253.878588 -48.393604) (xy 253.882652 -48.395128) (xy 253.89205 -48.396906) (xy 253.902019 -48.398166)
			(xy 253.921622 -48.393842) (xy 253.93015 -48.388524) (xy 253.999238 -48.340264) (xy 254.00127 -48.338486)
			(xy 254.004318 -48.335692) (xy 254.010787 -48.328731) (xy 254.018501 -48.311378) (xy 254.019304 -48.30191)
			(xy 254.019304 -41.953942) (xy 254.01905 -41.952418) (xy 254.018452 -41.944426) (xy 254.012884 -41.929405)
			(xy 254.008128 -41.922954) (xy 254.006096 -41.920414) (xy 253.123446 -41.037764) (xy 253.120597 -41.035055)
			(xy 253.114223 -41.030454) (xy 253.110746 -41.02862) (xy 253.105319 -41.026037) (xy 253.093639 -41.023215)
			(xy 253.087632 -41.023032) (xy 251.315982 -41.023032) (xy 251.309464 -41.023262) (xy 251.296859 -41.026596)
			(xy 251.29109 -41.029636) (xy 251.28601 -41.03243) (xy 251.276612 -41.04132) (xy 251.250196 -41.0845)
			(xy 251.250196 -41.085008) (xy 251.227844 -41.121838) (xy 251.225558 -41.126156) (xy 251.221017 -41.1372)
			(xy 251.221548 -41.161044) (xy 251.226574 -41.171876) (xy 251.229114 -41.176956) (xy 251.2419 -41.203363)
			(xy 251.260098 -41.259138) (xy 251.269527 -41.317044) (xy 251.270262 -41.346374) (xy 251.270262 -41.35501)
			(xy 251.269348 -41.383182) (xy 251.260243 -41.438805) (xy 251.243048 -41.492481) (xy 251.218136 -41.543041)
			(xy 251.186051 -41.589381) (xy 251.167138 -41.61028) (xy 251.16028 -41.617646) (xy 251.156978 -41.626282)
			(xy 251.155353 -41.630746) (xy 251.153567 -41.640075) (xy 251.153422 -41.644824) (xy 251.153422 -41.714674)
			(xy 251.153519 -41.719287) (xy 251.155174 -41.728363) (xy 251.156724 -41.732708) (xy 251.160026 -41.741344)
			(xy 251.167138 -41.748964) (xy 251.186409 -41.77029) (xy 251.218974 -41.817651) (xy 251.244065 -41.869362)
			(xy 251.261114 -41.924251) (xy 251.269735 -41.981078) (xy 251.269732 -42.038554) (xy 251.261107 -42.09538)
			(xy 251.244053 -42.150268) (xy 251.218958 -42.201977) (xy 251.186389 -42.249335) (xy 251.167138 -42.27068)
			(xy 251.160026 -42.2783) (xy 251.156724 -42.286936) (xy 251.155184 -42.291284) (xy 251.153528 -42.300358)
			(xy 251.153422 -42.30497) (xy 251.153422 -42.375074) (xy 251.153519 -42.379687) (xy 251.155174 -42.388763)
			(xy 251.156724 -42.393108) (xy 251.160026 -42.401744) (xy 251.167138 -42.409364) (xy 251.186405 -42.430693)
			(xy 251.218962 -42.478057) (xy 251.244047 -42.529769) (xy 251.26109 -42.584659) (xy 251.269708 -42.641484)
			(xy 251.270262 -42.670222) (xy 251.269789 -42.697591) (xy 251.261961 -42.751767) (xy 251.246471 -42.804268)
			(xy 251.223635 -42.854016) (xy 251.193922 -42.899989) (xy 251.176282 -42.92092) (xy 251.170186 -42.928032)
			(xy 251.167138 -42.93616) (xy 251.165599 -42.940508) (xy 251.163947 -42.949582) (xy 251.163836 -42.954194)
			(xy 251.163836 -43.02125) (xy 251.16394 -43.025861) (xy 251.165608 -43.034932) (xy 251.167138 -43.039284)
			(xy 251.170186 -43.047412) (xy 251.176282 -43.054524) (xy 251.193923 -43.075455) (xy 251.223648 -43.121422)
			(xy 251.246489 -43.171169) (xy 251.261977 -43.223672) (xy 251.269792 -43.277852) (xy 251.270262 -43.305222)
			(xy 251.269776 -43.332473) (xy 251.26202 -43.386421) (xy 251.246665 -43.438716) (xy 251.224023 -43.488293)
			(xy 251.194557 -43.534143) (xy 251.158866 -43.575334) (xy 251.117675 -43.611025) (xy 251.071825 -43.640491)
			(xy 251.022248 -43.663133) (xy 250.969953 -43.678488) (xy 250.916005 -43.686244) (xy 250.861503 -43.686244)
			(xy 250.807555 -43.678488) (xy 250.75526 -43.663133) (xy 250.705683 -43.640491) (xy 250.659833 -43.611025)
			(xy 250.618642 -43.575334) (xy 250.582951 -43.534143) (xy 250.553485 -43.488293) (xy 250.530843 -43.438716)
			(xy 250.515488 -43.386421) (xy 250.507732 -43.332473) (xy 250.507246 -43.305222) (xy 250.507723 -43.277854)
			(xy 250.515558 -43.223682) (xy 250.531055 -43.171186) (xy 250.553896 -43.121444) (xy 250.583613 -43.075477)
			(xy 250.601226 -43.054524) (xy 250.607322 -43.047412) (xy 250.61037 -43.039284) (xy 250.611912 -43.034936)
			(xy 250.613572 -43.025862) (xy 250.613672 -43.02125) (xy 250.613672 -42.954194) (xy 250.613572 -42.949582)
			(xy 250.611912 -42.940508) (xy 250.61037 -42.93616) (xy 250.607322 -42.928032) (xy 250.601226 -42.92092)
			(xy 250.583582 -42.89999) (xy 250.553851 -42.854024) (xy 250.531004 -42.804278) (xy 250.51551 -42.751774)
			(xy 250.507688 -42.697593) (xy 250.507246 -42.670222) (xy 250.507765 -42.641483) (xy 250.516386 -42.584654)
			(xy 250.533435 -42.529762) (xy 250.558527 -42.478049) (xy 250.591094 -42.430687) (xy 250.61037 -42.409364)
			(xy 250.617482 -42.401744) (xy 250.620784 -42.393108) (xy 250.622328 -42.38876) (xy 250.623992 -42.379687)
			(xy 250.624086 -42.375074) (xy 250.624086 -42.30497) (xy 250.623984 -42.300358) (xy 250.62232 -42.291286)
			(xy 250.620784 -42.286936) (xy 250.617482 -42.2783) (xy 250.61037 -42.27068) (xy 250.5911 -42.249352)
			(xy 250.558536 -42.201988) (xy 250.533445 -42.150275) (xy 250.516394 -42.095383) (xy 250.50777 -42.038555)
			(xy 250.507768 -41.981077) (xy 250.516387 -41.924248) (xy 250.533433 -41.869355) (xy 250.55852 -41.81764)
			(xy 250.59108 -41.770273) (xy 250.61037 -41.748964) (xy 250.617482 -41.741344) (xy 250.620784 -41.732708)
			(xy 250.622328 -41.72836) (xy 250.623992 -41.719287) (xy 250.624086 -41.714674) (xy 250.624086 -41.644824)
			(xy 250.623989 -41.64007) (xy 250.622199 -41.630734) (xy 250.62053 -41.626282) (xy 250.617228 -41.617646)
			(xy 250.61037 -41.61028) (xy 250.591568 -41.589487) (xy 250.559636 -41.543415) (xy 250.534779 -41.49317)
			(xy 250.517531 -41.439833) (xy 250.508262 -41.384548) (xy 250.507246 -41.356534) (xy 250.507246 -41.349168)
			(xy 250.507834 -41.319467) (xy 250.517069 -41.260785) (xy 250.535267 -41.204237) (xy 250.54814 -41.177464)
			(xy 250.550934 -41.171876) (xy 250.55449 -41.157144) (xy 250.556164 -41.147617) (xy 250.553036 -41.128545)
			(xy 250.548394 -41.12006) (xy 250.540266 -41.106598) (xy 250.540266 -41.10609) (xy 250.504198 -41.047416)
			(xy 250.499406 -41.040195) (xy 250.485985 -41.029248) (xy 250.469677 -41.023418) (xy 250.461018 -41.023032)
			(xy 249.553984 -41.023032) (xy 249.548196 -41.02316) (xy 249.53691 -41.02573) (xy 249.531632 -41.028112)
			(xy 249.526806 -41.030652) (xy 249.517916 -41.037764) (xy 249.514106 -41.04259) (xy 249.464576 -41.105836)
			(xy 249.461183 -41.110462) (xy 249.456309 -41.120843) (xy 249.454924 -41.12641) (xy 249.452638 -41.137586)
			(xy 249.455432 -41.149016) (xy 249.460764 -41.171758) (xy 249.466489 -41.218117) (xy 249.466862 -41.241472)
			(xy 249.466401 -41.268725) (xy 249.458647 -41.322676) (xy 249.443292 -41.374975) (xy 249.420651 -41.424556)
			(xy 249.391183 -41.470409) (xy 249.355489 -41.511601) (xy 249.314295 -41.547294) (xy 249.26844 -41.57676)
			(xy 249.218858 -41.599399) (xy 249.166559 -41.61475) (xy 249.112607 -41.622502) (xy 249.085354 -41.62298)
			(xy 249.056613 -41.622463) (xy 248.999782 -41.613847) (xy 248.944886 -41.596802) (xy 248.893169 -41.571714)
			(xy 248.845802 -41.539151) (xy 248.824496 -41.519856) (xy 248.816876 -41.512744) (xy 248.80824 -41.509442)
			(xy 248.803892 -41.507903) (xy 248.794818 -41.506251) (xy 248.790206 -41.50614) (xy 248.720102 -41.50614)
			(xy 248.71549 -41.50624) (xy 248.706415 -41.507899) (xy 248.702068 -41.509442) (xy 248.693432 -41.512744)
			(xy 248.685812 -41.519856) (xy 248.664484 -41.539126) (xy 248.617121 -41.571692) (xy 248.56541 -41.596785)
			(xy 248.51052 -41.613839) (xy 248.453693 -41.622468) (xy 248.424954 -41.62298) (xy 248.397706 -41.622491)
			(xy 248.343764 -41.614729) (xy 248.291477 -41.599369) (xy 248.241907 -41.576725) (xy 248.196065 -41.547257)
			(xy 248.154882 -41.511565) (xy 248.119198 -41.470376) (xy 248.089739 -41.424528) (xy 248.067105 -41.374954)
			(xy 248.051756 -41.322663) (xy 248.044004 -41.26872) (xy 248.043446 -41.241472) (xy 248.043811 -41.218116)
			(xy 248.049537 -41.171756) (xy 248.054876 -41.149016) (xy 248.05767 -41.137586) (xy 248.055384 -41.12641)
			(xy 248.054042 -41.120827) (xy 248.049175 -41.110431) (xy 248.045732 -41.105836) (xy 247.996202 -41.04259)
			(xy 247.995948 -41.042336) (xy 247.992311 -41.037948) (xy 247.983468 -41.030762) (xy 247.978422 -41.028112)
			(xy 247.973342 -41.025572) (xy 247.962166 -41.023032) (xy 244.108478 -41.023032) (xy 244.102468 -41.023196)
			(xy 244.090783 -41.026016) (xy 244.085364 -41.02862) (xy 244.081891 -41.030461) (xy 244.075515 -41.035058)
			(xy 244.072664 -41.037764) (xy 243.905786 -41.204642) (xy 243.89911 -41.212055) (xy 243.891545 -41.230491)
			(xy 243.891054 -41.240456) (xy 243.891054 -43.73626) (xy 252.413006 -43.73626) (xy 252.417077 -43.680638)
			(xy 252.429203 -43.626201) (xy 252.449126 -43.57411) (xy 252.476422 -43.525475) (xy 252.510508 -43.481332)
			(xy 252.550657 -43.442623) (xy 252.596015 -43.410172) (xy 252.645615 -43.384671) (xy 252.698399 -43.366664)
			(xy 252.753242 -43.356534) (xy 252.808976 -43.354497) (xy 252.864413 -43.360597) (xy 252.91837 -43.374703)
			(xy 252.969699 -43.396515) (xy 253.017305 -43.425569) (xy 253.060173 -43.461244) (xy 253.09739 -43.502781)
			(xy 253.128163 -43.549294) (xy 253.151835 -43.599791) (xy 253.167903 -43.653198) (xy 253.176023 -43.708374)
			(xy 253.176532 -43.73626) (xy 253.176023 -43.764146) (xy 253.167903 -43.819322) (xy 253.151835 -43.872729)
			(xy 253.128163 -43.923226) (xy 253.09739 -43.969739) (xy 253.060173 -44.011276) (xy 253.017305 -44.046951)
			(xy 252.969699 -44.076005) (xy 252.91837 -44.097817) (xy 252.864413 -44.111923) (xy 252.808976 -44.118023)
			(xy 252.753242 -44.115986) (xy 252.698399 -44.105856) (xy 252.645615 -44.087849) (xy 252.596015 -44.062348)
			(xy 252.550657 -44.029897) (xy 252.510508 -43.991188) (xy 252.476422 -43.947045) (xy 252.449126 -43.89841)
			(xy 252.429203 -43.846319) (xy 252.417077 -43.791882) (xy 252.413006 -43.73626) (xy 243.891054 -43.73626)
			(xy 243.891054 -45.114464) (xy 252.265432 -45.114464) (xy 252.269503 -45.058842) (xy 252.281629 -45.004405)
			(xy 252.301552 -44.952314) (xy 252.328848 -44.903679) (xy 252.362934 -44.859536) (xy 252.403083 -44.820827)
			(xy 252.448441 -44.788376) (xy 252.498041 -44.762875) (xy 252.550825 -44.744868) (xy 252.605668 -44.734738)
			(xy 252.661402 -44.732701) (xy 252.716839 -44.738801) (xy 252.770796 -44.752907) (xy 252.822125 -44.774719)
			(xy 252.869731 -44.803773) (xy 252.912599 -44.839448) (xy 252.949816 -44.880985) (xy 252.980589 -44.927498)
			(xy 253.004261 -44.977995) (xy 253.020329 -45.031402) (xy 253.028449 -45.086578) (xy 253.028958 -45.114464)
			(xy 253.028449 -45.14235) (xy 253.020329 -45.197526) (xy 253.004261 -45.250933) (xy 252.980589 -45.30143)
			(xy 252.949816 -45.347943) (xy 252.912599 -45.38948) (xy 252.869731 -45.425155) (xy 252.822125 -45.454209)
			(xy 252.770796 -45.476021) (xy 252.716839 -45.490127) (xy 252.661402 -45.496227) (xy 252.605668 -45.49419)
			(xy 252.550825 -45.48406) (xy 252.498041 -45.466053) (xy 252.448441 -45.440552) (xy 252.403083 -45.408101)
			(xy 252.362934 -45.369392) (xy 252.328848 -45.325249) (xy 252.301552 -45.276614) (xy 252.281629 -45.224523)
			(xy 252.269503 -45.170086) (xy 252.265432 -45.114464) (xy 243.891054 -45.114464) (xy 243.891054 -46.893226)
			(xy 252.537212 -46.893226) (xy 252.541283 -46.837604) (xy 252.553409 -46.783167) (xy 252.573332 -46.731076)
			(xy 252.600628 -46.682441) (xy 252.634714 -46.638298) (xy 252.674863 -46.599589) (xy 252.720221 -46.567138)
			(xy 252.769821 -46.541637) (xy 252.822605 -46.52363) (xy 252.877448 -46.5135) (xy 252.933182 -46.511463)
			(xy 252.988619 -46.517563) (xy 253.042576 -46.531669) (xy 253.093905 -46.553481) (xy 253.141511 -46.582535)
			(xy 253.184379 -46.61821) (xy 253.221596 -46.659747) (xy 253.252369 -46.70626) (xy 253.276041 -46.756757)
			(xy 253.292109 -46.810164) (xy 253.300229 -46.86534) (xy 253.300738 -46.893226) (xy 253.300229 -46.921112)
			(xy 253.292109 -46.976288) (xy 253.276041 -47.029695) (xy 253.252369 -47.080192) (xy 253.221596 -47.126705)
			(xy 253.184379 -47.168242) (xy 253.141511 -47.203917) (xy 253.093905 -47.232971) (xy 253.042576 -47.254783)
			(xy 252.988619 -47.268889) (xy 252.933182 -47.274989) (xy 252.877448 -47.272952) (xy 252.822605 -47.262822)
			(xy 252.769821 -47.244815) (xy 252.720221 -47.219314) (xy 252.674863 -47.186863) (xy 252.634714 -47.148154)
			(xy 252.600628 -47.104011) (xy 252.573332 -47.055376) (xy 252.553409 -47.003285) (xy 252.541283 -46.948848)
			(xy 252.537212 -46.893226) (xy 243.891054 -46.893226) (xy 243.891054 -47.936658) (xy 250.85294 -47.936658)
			(xy 250.853426 -47.909407) (xy 250.861182 -47.855459) (xy 250.876537 -47.803164) (xy 250.899179 -47.753587)
			(xy 250.928645 -47.707737) (xy 250.964336 -47.666546) (xy 251.005527 -47.630855) (xy 251.051377 -47.601389)
			(xy 251.100954 -47.578747) (xy 251.153249 -47.563392) (xy 251.207197 -47.555636) (xy 251.261699 -47.555636)
			(xy 251.315647 -47.563392) (xy 251.367942 -47.578747) (xy 251.417519 -47.601389) (xy 251.463369 -47.630855)
			(xy 251.50456 -47.666546) (xy 251.540251 -47.707737) (xy 251.569717 -47.753587) (xy 251.592359 -47.803164)
			(xy 251.607714 -47.855459) (xy 251.61547 -47.909407) (xy 251.615956 -47.936658) (xy 251.615492 -47.962999)
			(xy 251.608242 -48.015179) (xy 251.593888 -48.065867) (xy 251.572701 -48.1141) (xy 251.545085 -48.158963)
			(xy 251.511563 -48.199604) (xy 251.472773 -48.23525) (xy 251.451364 -48.250602) (xy 251.439537 -48.259295)
			(xy 251.421096 -48.282119) (xy 251.409908 -48.309246) (xy 251.4069 -48.338435) (xy 251.412317 -48.367273)
			(xy 251.425715 -48.393379) (xy 251.445984 -48.414596) (xy 251.458476 -48.422306) (xy 251.483012 -48.437)
			(xy 251.527771 -48.472602) (xy 251.566714 -48.514485) (xy 251.59897 -48.561712) (xy 251.623816 -48.613224)
			(xy 251.640695 -48.667868) (xy 251.649229 -48.724418) (xy 251.649738 -48.753014) (xy 251.649252 -48.780265)
			(xy 251.641496 -48.834213) (xy 251.626141 -48.886508) (xy 251.603499 -48.936085) (xy 251.574033 -48.981935)
			(xy 251.538342 -49.023126) (xy 251.497151 -49.058817) (xy 251.451301 -49.088283) (xy 251.401724 -49.110925)
			(xy 251.349429 -49.12628) (xy 251.295481 -49.134036) (xy 251.240979 -49.134036) (xy 251.187031 -49.12628)
			(xy 251.134736 -49.110925) (xy 251.085159 -49.088283) (xy 251.039309 -49.058817) (xy 250.998118 -49.023126)
			(xy 250.962427 -48.981935) (xy 250.932961 -48.936085) (xy 250.910319 -48.886508) (xy 250.894964 -48.834213)
			(xy 250.887208 -48.780265) (xy 250.886722 -48.753014) (xy 250.887174 -48.726673) (xy 250.894427 -48.674493)
			(xy 250.908785 -48.623805) (xy 250.929974 -48.575572) (xy 250.957591 -48.530709) (xy 250.991114 -48.490068)
			(xy 251.029905 -48.454422) (xy 251.051314 -48.43907) (xy 251.063158 -48.430403) (xy 251.081585 -48.407568)
			(xy 251.092761 -48.380438) (xy 251.095763 -48.35125) (xy 251.090344 -48.322412) (xy 251.076951 -48.296305)
			(xy 251.05669 -48.275081) (xy 251.044202 -48.267366) (xy 251.019693 -48.252629) (xy 250.974935 -48.217034)
			(xy 250.935991 -48.175157) (xy 250.903733 -48.127937) (xy 250.878883 -48.076433) (xy 250.861997 -48.021796)
			(xy 250.853454 -47.965251) (xy 250.85294 -47.936658) (xy 243.891054 -47.936658) (xy 243.891054 -58.731404)
			(xy 245.720616 -58.731404) (xy 245.721081 -58.704034) (xy 245.728898 -58.649854) (xy 245.744387 -58.597351)
			(xy 245.76723 -58.547604) (xy 245.796955 -58.501638) (xy 245.814596 -58.480706) (xy 245.81485 -58.480452)
			(xy 245.820427 -58.473359) (xy 245.826678 -58.456447) (xy 245.827042 -58.447432) (xy 245.827042 -58.380376)
			(xy 245.826709 -58.371356) (xy 245.820446 -58.354439) (xy 245.81485 -58.347356) (xy 245.814596 -58.347356)
			(xy 245.814596 -58.347102) (xy 245.796961 -58.326165) (xy 245.767238 -58.280198) (xy 245.744394 -58.230452)
			(xy 245.728899 -58.177951) (xy 245.721071 -58.123773) (xy 245.72107 -58.069033) (xy 245.728898 -58.014855)
			(xy 245.744392 -57.962354) (xy 245.767235 -57.912608) (xy 245.796957 -57.866639) (xy 245.814596 -57.845706)
			(xy 245.81485 -57.845452) (xy 245.820427 -57.838359) (xy 245.826678 -57.821447) (xy 245.827042 -57.812432)
			(xy 245.827042 -57.745376) (xy 245.826709 -57.736356) (xy 245.820446 -57.719439) (xy 245.81485 -57.712356)
			(xy 245.814596 -57.712356) (xy 245.814596 -57.712102) (xy 245.796961 -57.691165) (xy 245.767238 -57.645198)
			(xy 245.744394 -57.595452) (xy 245.728899 -57.542951) (xy 245.721071 -57.488773) (xy 245.72107 -57.434033)
			(xy 245.728898 -57.379855) (xy 245.744392 -57.327354) (xy 245.767235 -57.277608) (xy 245.796957 -57.231639)
			(xy 245.814596 -57.210706) (xy 245.81485 -57.210452) (xy 245.820427 -57.203359) (xy 245.826678 -57.186447)
			(xy 245.827042 -57.177432) (xy 245.827042 -57.110376) (xy 245.826709 -57.101356) (xy 245.820446 -57.084439)
			(xy 245.81485 -57.077356) (xy 245.814596 -57.077356) (xy 245.814596 -57.077102) (xy 245.796944 -57.056181)
			(xy 245.767234 -57.010205) (xy 245.744401 -56.960455) (xy 245.728913 -56.907952) (xy 245.721088 -56.853774)
			(xy 245.720616 -56.826404) (xy 245.721102 -56.799153) (xy 245.728858 -56.745205) (xy 245.744213 -56.69291)
			(xy 245.766855 -56.643333) (xy 245.796321 -56.597483) (xy 245.832012 -56.556292) (xy 245.873203 -56.520601)
			(xy 245.919053 -56.491135) (xy 245.96863 -56.468493) (xy 246.020925 -56.453138) (xy 246.074873 -56.445382)
			(xy 246.129375 -56.445382) (xy 246.183323 -56.453138) (xy 246.235618 -56.468493) (xy 246.285195 -56.491135)
			(xy 246.331045 -56.520601) (xy 246.372236 -56.556292) (xy 246.407927 -56.597483) (xy 246.437393 -56.643333)
			(xy 246.460035 -56.69291) (xy 246.47539 -56.745205) (xy 246.483146 -56.799153) (xy 246.483632 -56.826404)
			(xy 246.483185 -56.853775) (xy 246.475365 -56.907956) (xy 246.459872 -56.96046) (xy 246.437026 -57.010206)
			(xy 246.407296 -57.056172) (xy 246.389652 -57.077102) (xy 246.389398 -57.077356) (xy 246.383823 -57.084451)
			(xy 246.37757 -57.101361) (xy 246.377206 -57.110376) (xy 246.377206 -57.177432) (xy 246.377547 -57.186451)
			(xy 246.383805 -57.203367) (xy 246.389398 -57.210452) (xy 246.389652 -57.210452) (xy 246.389652 -57.210706)
			(xy 246.407297 -57.231635) (xy 246.437024 -57.277603) (xy 246.45987 -57.32735) (xy 246.475367 -57.379853)
			(xy 246.483196 -57.434032) (xy 246.483195 -57.488774) (xy 246.475366 -57.542953) (xy 246.459868 -57.595456)
			(xy 246.437021 -57.645202) (xy 246.407294 -57.69117) (xy 246.389652 -57.712102) (xy 246.389398 -57.712356)
			(xy 246.383823 -57.719451) (xy 246.37757 -57.736361) (xy 246.377206 -57.745376) (xy 246.377206 -57.812432)
			(xy 246.377547 -57.821451) (xy 246.383805 -57.838367) (xy 246.389398 -57.845452) (xy 246.389652 -57.845452)
			(xy 246.389652 -57.845706) (xy 246.407297 -57.866635) (xy 246.437024 -57.912603) (xy 246.45987 -57.96235)
			(xy 246.475367 -58.014853) (xy 246.483196 -58.069032) (xy 246.483195 -58.123774) (xy 246.475366 -58.177953)
			(xy 246.459868 -58.230456) (xy 246.437021 -58.280202) (xy 246.407294 -58.32617) (xy 246.389652 -58.347102)
			(xy 246.389398 -58.347356) (xy 246.383823 -58.354451) (xy 246.37757 -58.371361) (xy 246.377206 -58.380376)
			(xy 246.377206 -58.447432) (xy 246.377547 -58.456451) (xy 246.383805 -58.473367) (xy 246.389398 -58.480452)
			(xy 246.389652 -58.480452) (xy 246.389652 -58.480706) (xy 246.4073 -58.501631) (xy 246.437012 -58.547605)
			(xy 246.459847 -58.597354) (xy 246.475336 -58.649857) (xy 246.48316 -58.704034) (xy 246.483632 -58.731404)
			(xy 246.483146 -58.758655) (xy 246.478482 -58.791094) (xy 248.37644 -58.791094) (xy 248.376893 -58.763723)
			(xy 248.384712 -58.709543) (xy 248.400204 -58.657039) (xy 248.423049 -58.607293) (xy 248.452777 -58.561327)
			(xy 248.47042 -58.540396) (xy 248.470674 -58.540142) (xy 248.476258 -58.533054) (xy 248.482504 -58.516138)
			(xy 248.482866 -58.507122) (xy 248.482866 -58.440066) (xy 248.482533 -58.431047) (xy 248.476269 -58.414129)
			(xy 248.470674 -58.407046) (xy 248.47042 -58.407046) (xy 248.47042 -58.406792) (xy 248.452774 -58.385864)
			(xy 248.42305 -58.339895) (xy 248.400205 -58.290148) (xy 248.38471 -58.237645) (xy 248.376882 -58.183466)
			(xy 248.376882 -58.128725) (xy 248.384712 -58.074546) (xy 248.400208 -58.022043) (xy 248.423054 -57.972297)
			(xy 248.452779 -57.926329) (xy 248.47042 -57.905396) (xy 248.470674 -57.905142) (xy 248.476258 -57.898054)
			(xy 248.482504 -57.881138) (xy 248.482866 -57.872122) (xy 248.482866 -57.805066) (xy 248.482533 -57.796047)
			(xy 248.476269 -57.779129) (xy 248.470674 -57.772046) (xy 248.47042 -57.772046) (xy 248.47042 -57.771792)
			(xy 248.452767 -57.750871) (xy 248.423056 -57.704896) (xy 248.400223 -57.655145) (xy 248.384735 -57.602642)
			(xy 248.376911 -57.548464) (xy 248.37644 -57.521094) (xy 248.376891 -57.494779) (xy 248.384127 -57.44265)
			(xy 248.398449 -57.392006) (xy 248.419584 -57.343807) (xy 248.447134 -57.298964) (xy 248.480576 -57.258326)
			(xy 248.49963 -57.24017) (xy 248.507037 -57.232652) (xy 248.515561 -57.21337) (xy 248.51614 -57.202832)
			(xy 248.51614 -57.128156) (xy 248.515582 -57.11761) (xy 248.507066 -57.098315) (xy 248.49963 -57.090818)
			(xy 248.480596 -57.072641) (xy 248.447136 -57.032016) (xy 248.419573 -56.987181) (xy 248.398431 -56.938984)
			(xy 248.384109 -56.88834) (xy 248.376881 -56.836209) (xy 248.37644 -56.809894) (xy 248.376926 -56.782643)
			(xy 248.384682 -56.728695) (xy 248.400037 -56.6764) (xy 248.422679 -56.626823) (xy 248.452145 -56.580973)
			(xy 248.487836 -56.539782) (xy 248.529027 -56.504091) (xy 248.574877 -56.474625) (xy 248.624454 -56.451983)
			(xy 248.676749 -56.436628) (xy 248.730697 -56.428872) (xy 248.785199 -56.428872) (xy 248.839147 -56.436628)
			(xy 248.891442 -56.451983) (xy 248.941019 -56.474625) (xy 248.986869 -56.504091) (xy 249.02806 -56.539782)
			(xy 249.063751 -56.580973) (xy 249.093217 -56.626823) (xy 249.115859 -56.6764) (xy 249.131214 -56.728695)
			(xy 249.13897 -56.782643) (xy 249.139456 -56.809894) (xy 249.138999 -56.836208) (xy 249.131764 -56.888338)
			(xy 249.117444 -56.938981) (xy 249.096309 -56.987181) (xy 249.068761 -57.032024) (xy 249.035319 -57.072662)
			(xy 249.016266 -57.090818) (xy 249.008864 -57.09834) (xy 249.000338 -57.117619) (xy 248.999756 -57.128156)
			(xy 248.999756 -57.202832) (xy 249.000321 -57.213377) (xy 249.008833 -57.232672) (xy 249.016266 -57.24017)
			(xy 249.035313 -57.258334) (xy 249.068768 -57.298964) (xy 249.096327 -57.343802) (xy 249.117466 -57.392001)
			(xy 249.131786 -57.442647) (xy 249.13517 -57.467053) (xy 249.318469 -57.467053) (xy 249.318469 -57.412547)
			(xy 249.326227 -57.358596) (xy 249.341584 -57.306298) (xy 249.364227 -57.256718) (xy 249.393696 -57.210865)
			(xy 249.429392 -57.169673) (xy 249.470586 -57.133981) (xy 249.516441 -57.104515) (xy 249.566022 -57.081874)
			(xy 249.618321 -57.066521) (xy 249.672273 -57.058768) (xy 249.699526 -57.058306) (xy 249.725841 -57.058754)
			(xy 249.77797 -57.065993) (xy 249.828613 -57.080315) (xy 249.876812 -57.101451) (xy 249.921655 -57.129001)
			(xy 249.962294 -57.162443) (xy 249.98045 -57.181496) (xy 249.987952 -57.188921) (xy 250.007247 -57.197432)
			(xy 250.017788 -57.198006) (xy 250.092464 -57.198006) (xy 250.103013 -57.197469) (xy 250.122308 -57.188939)
			(xy 250.129802 -57.181496) (xy 250.147963 -57.162446) (xy 250.188591 -57.128988) (xy 250.233431 -57.101429)
			(xy 250.28163 -57.080289) (xy 250.332277 -57.065971) (xy 250.38441 -57.058745) (xy 250.410726 -57.058306)
			(xy 250.437977 -57.058766) (xy 250.491924 -57.066525) (xy 250.527073 -57.076848) (xy 251.338588 -57.076848)
			(xy 251.339085 -57.049479) (xy 251.346896 -56.995301) (xy 251.362378 -56.942799) (xy 251.385213 -56.893051)
			(xy 251.41493 -56.847083) (xy 251.432568 -56.82615) (xy 251.432822 -56.825896) (xy 251.438419 -56.818817)
			(xy 251.444659 -56.801894) (xy 251.445014 -56.792876) (xy 251.445014 -56.72582) (xy 251.444644 -56.716804)
			(xy 251.438405 -56.699888) (xy 251.432822 -56.6928) (xy 251.432568 -56.6928) (xy 251.432568 -56.692546)
			(xy 251.414932 -56.671612) (xy 251.385221 -56.625639) (xy 251.362385 -56.575892) (xy 251.346893 -56.523392)
			(xy 251.339063 -56.469217) (xy 251.338588 -56.441848) (xy 251.339074 -56.414597) (xy 251.34683 -56.360649)
			(xy 251.362185 -56.308354) (xy 251.384827 -56.258777) (xy 251.414293 -56.212927) (xy 251.449984 -56.171736)
			(xy 251.491175 -56.136045) (xy 251.537025 -56.106579) (xy 251.586602 -56.083937) (xy 251.638897 -56.068582)
			(xy 251.692845 -56.060826) (xy 251.747347 -56.060826) (xy 251.801295 -56.068582) (xy 251.85359 -56.083937)
			(xy 251.903167 -56.106579) (xy 251.949017 -56.136045) (xy 251.990208 -56.171736) (xy 252.025899 -56.212927)
			(xy 252.055365 -56.258777) (xy 252.078007 -56.308354) (xy 252.093362 -56.360649) (xy 252.101118 -56.414597)
			(xy 252.101604 -56.441848) (xy 252.101106 -56.469217) (xy 252.093296 -56.523395) (xy 252.077814 -56.575898)
			(xy 252.05498 -56.625645) (xy 252.025262 -56.671613) (xy 252.007624 -56.692546) (xy 252.00737 -56.6928)
			(xy 252.001774 -56.69988) (xy 251.995534 -56.716802) (xy 251.995178 -56.72582) (xy 251.995178 -56.792876)
			(xy 251.995551 -56.801891) (xy 252.001788 -56.818808) (xy 252.00737 -56.825896) (xy 252.007624 -56.825896)
			(xy 252.007624 -56.82615) (xy 252.025257 -56.847087) (xy 252.054969 -56.893059) (xy 252.077806 -56.942805)
			(xy 252.093298 -56.995305) (xy 252.101129 -57.049479) (xy 252.101604 -57.076848) (xy 252.101118 -57.104099)
			(xy 252.093362 -57.158047) (xy 252.078007 -57.210342) (xy 252.055365 -57.259919) (xy 252.025899 -57.305769)
			(xy 251.990208 -57.34696) (xy 251.949017 -57.382651) (xy 251.903167 -57.412117) (xy 251.85359 -57.434759)
			(xy 251.801295 -57.450114) (xy 251.747347 -57.45787) (xy 251.692845 -57.45787) (xy 251.638897 -57.450114)
			(xy 251.586602 -57.434759) (xy 251.537025 -57.412117) (xy 251.491175 -57.382651) (xy 251.449984 -57.34696)
			(xy 251.414293 -57.305769) (xy 251.384827 -57.259919) (xy 251.362185 -57.210342) (xy 251.34683 -57.158047)
			(xy 251.339074 -57.104099) (xy 251.338588 -57.076848) (xy 250.527073 -57.076848) (xy 250.544217 -57.081883)
			(xy 250.593793 -57.104527) (xy 250.639642 -57.133995) (xy 250.680831 -57.169688) (xy 250.716521 -57.210879)
			(xy 250.745986 -57.25673) (xy 250.768626 -57.306307) (xy 250.78398 -57.358602) (xy 250.791736 -57.412549)
			(xy 250.791736 -57.467051) (xy 250.78398 -57.520998) (xy 250.768626 -57.573293) (xy 250.745986 -57.62287)
			(xy 250.716521 -57.668721) (xy 250.680831 -57.709912) (xy 250.639642 -57.745605) (xy 250.593793 -57.775073)
			(xy 250.544217 -57.797717) (xy 250.491924 -57.813075) (xy 250.437977 -57.820834) (xy 250.410726 -57.821322)
			(xy 250.384413 -57.82083) (xy 250.332286 -57.813599) (xy 250.281644 -57.799285) (xy 250.233445 -57.778157)
			(xy 250.188601 -57.750615) (xy 250.14796 -57.717181) (xy 250.129802 -57.698132) (xy 250.122277 -57.690734)
			(xy 250.103 -57.682206) (xy 250.092464 -57.681622) (xy 250.017788 -57.681622) (xy 250.007235 -57.682125)
			(xy 249.98794 -57.690678) (xy 249.98045 -57.698132) (xy 249.962318 -57.717211) (xy 249.921683 -57.750665)
			(xy 249.876837 -57.77822) (xy 249.828632 -57.799354) (xy 249.777981 -57.813667) (xy 249.725843 -57.820886)
			(xy 249.699526 -57.821322) (xy 249.672273 -57.820832) (xy 249.618321 -57.813079) (xy 249.566022 -57.797726)
			(xy 249.516441 -57.775085) (xy 249.470586 -57.745619) (xy 249.429392 -57.709927) (xy 249.393696 -57.668735)
			(xy 249.364227 -57.622882) (xy 249.341584 -57.573302) (xy 249.326227 -57.521004) (xy 249.318469 -57.467053)
			(xy 249.13517 -57.467053) (xy 249.139015 -57.494779) (xy 249.139456 -57.521094) (xy 249.138997 -57.548465)
			(xy 249.131179 -57.602644) (xy 249.115689 -57.655148) (xy 249.092845 -57.704895) (xy 249.063119 -57.750861)
			(xy 249.045476 -57.771792) (xy 249.045222 -57.772046) (xy 249.039643 -57.779137) (xy 249.033394 -57.796051)
			(xy 249.03303 -57.805066) (xy 249.03303 -57.872122) (xy 249.03337 -57.881141) (xy 249.039629 -57.898058)
			(xy 249.045222 -57.905142) (xy 249.045476 -57.905142) (xy 249.045476 -57.905396) (xy 249.063111 -57.926334)
			(xy 249.092835 -57.972301) (xy 249.115681 -58.022046) (xy 249.131178 -58.074547) (xy 249.139007 -58.128725)
			(xy 249.139007 -58.183466) (xy 249.13118 -58.237644) (xy 249.115684 -58.290145) (xy 249.09284 -58.339891)
			(xy 249.063116 -58.385859) (xy 249.045476 -58.406792) (xy 249.045222 -58.407046) (xy 249.039643 -58.414137)
			(xy 249.033394 -58.431051) (xy 249.03303 -58.440066) (xy 249.03303 -58.507122) (xy 249.03337 -58.516141)
			(xy 249.039629 -58.533058) (xy 249.045222 -58.540142) (xy 249.045476 -58.540142) (xy 249.045476 -58.540396)
			(xy 249.063123 -58.561322) (xy 249.092834 -58.607296) (xy 249.115669 -58.657045) (xy 249.131158 -58.709547)
			(xy 249.138984 -58.763724) (xy 249.139456 -58.791094) (xy 249.13897 -58.818345) (xy 249.131214 -58.872293)
			(xy 249.130817 -58.873644) (xy 250.400566 -58.873644) (xy 250.401042 -58.846274) (xy 250.408855 -58.792095)
			(xy 250.424341 -58.739591) (xy 250.447181 -58.689844) (xy 250.476905 -58.643877) (xy 250.494546 -58.622946)
			(xy 250.4948 -58.622692) (xy 250.500396 -58.615612) (xy 250.506637 -58.59869) (xy 250.506992 -58.589672)
			(xy 250.506992 -58.522616) (xy 250.506629 -58.5136) (xy 250.500386 -58.496683) (xy 250.4948 -58.489596)
			(xy 250.494546 -58.489596) (xy 250.494546 -58.489342) (xy 250.47692 -58.468399) (xy 250.447205 -58.42243)
			(xy 250.424366 -58.372685) (xy 250.408872 -58.320187) (xy 250.401041 -58.266013) (xy 250.400566 -58.238644)
			(xy 250.401052 -58.211393) (xy 250.408808 -58.157445) (xy 250.424163 -58.10515) (xy 250.446805 -58.055573)
			(xy 250.476271 -58.009723) (xy 250.511962 -57.968532) (xy 250.553153 -57.932841) (xy 250.599003 -57.903375)
			(xy 250.64858 -57.880733) (xy 250.700875 -57.865378) (xy 250.754823 -57.857622) (xy 250.809325 -57.857622)
			(xy 250.863273 -57.865378) (xy 250.915568 -57.880733) (xy 250.965145 -57.903375) (xy 251.010995 -57.932841)
			(xy 251.052186 -57.968532) (xy 251.087877 -58.009723) (xy 251.117343 -58.055573) (xy 251.139985 -58.10515)
			(xy 251.15534 -58.157445) (xy 251.163096 -58.211393) (xy 251.163582 -58.238644) (xy 251.163087 -58.266013)
			(xy 251.155277 -58.320191) (xy 251.139795 -58.372694) (xy 251.116959 -58.422442) (xy 251.087241 -58.46841)
			(xy 251.069602 -58.489342) (xy 251.069348 -58.489596) (xy 251.063751 -58.496675) (xy 251.057512 -58.513598)
			(xy 251.057156 -58.522616) (xy 251.057156 -58.589672) (xy 251.057514 -58.598689) (xy 251.06376 -58.615607)
			(xy 251.069348 -58.622692) (xy 251.069602 -58.622692) (xy 251.069602 -58.622946) (xy 251.08723 -58.643887)
			(xy 251.116943 -58.689858) (xy 251.139781 -58.739603) (xy 251.155275 -58.792101) (xy 251.163106 -58.846275)
			(xy 251.163582 -58.873644) (xy 251.163096 -58.900895) (xy 251.15534 -58.954843) (xy 251.139985 -59.007138)
			(xy 251.117343 -59.056715) (xy 251.087877 -59.102565) (xy 251.052186 -59.143756) (xy 251.010995 -59.179447)
			(xy 250.965145 -59.208913) (xy 250.915568 -59.231555) (xy 250.863273 -59.24691) (xy 250.809325 -59.254666)
			(xy 250.754823 -59.254666) (xy 250.700875 -59.24691) (xy 250.64858 -59.231555) (xy 250.599003 -59.208913)
			(xy 250.553153 -59.179447) (xy 250.511962 -59.143756) (xy 250.476271 -59.102565) (xy 250.446805 -59.056715)
			(xy 250.424163 -59.007138) (xy 250.408808 -58.954843) (xy 250.401052 -58.900895) (xy 250.400566 -58.873644)
			(xy 249.130817 -58.873644) (xy 249.115859 -58.924588) (xy 249.093217 -58.974165) (xy 249.063751 -59.020015)
			(xy 249.02806 -59.061206) (xy 248.986869 -59.096897) (xy 248.941019 -59.126363) (xy 248.891442 -59.149005)
			(xy 248.839147 -59.16436) (xy 248.785199 -59.172116) (xy 248.730697 -59.172116) (xy 248.676749 -59.16436)
			(xy 248.624454 -59.149005) (xy 248.574877 -59.126363) (xy 248.529027 -59.096897) (xy 248.487836 -59.061206)
			(xy 248.452145 -59.020015) (xy 248.422679 -58.974165) (xy 248.400037 -58.924588) (xy 248.384682 -58.872293)
			(xy 248.376926 -58.818345) (xy 248.37644 -58.791094) (xy 246.478482 -58.791094) (xy 246.47539 -58.812603)
			(xy 246.460035 -58.864898) (xy 246.437393 -58.914475) (xy 246.407927 -58.960325) (xy 246.372236 -59.001516)
			(xy 246.331045 -59.037207) (xy 246.285195 -59.066673) (xy 246.235618 -59.089315) (xy 246.183323 -59.10467)
			(xy 246.129375 -59.112426) (xy 246.074873 -59.112426) (xy 246.020925 -59.10467) (xy 245.96863 -59.089315)
			(xy 245.919053 -59.066673) (xy 245.873203 -59.037207) (xy 245.832012 -59.001516) (xy 245.796321 -58.960325)
			(xy 245.766855 -58.914475) (xy 245.744213 -58.864898) (xy 245.728858 -58.812603) (xy 245.721102 -58.758655)
			(xy 245.720616 -58.731404) (xy 243.891054 -58.731404) (xy 243.891054 -60.126455) (xy 249.38015 -60.126455)
			(xy 249.38015 -60.071945) (xy 249.387908 -60.017989) (xy 249.403267 -59.965686) (xy 249.425913 -59.916102)
			(xy 249.455386 -59.870246) (xy 249.491085 -59.829051) (xy 249.532284 -59.793357) (xy 249.578144 -59.76389)
			(xy 249.627731 -59.74125) (xy 249.680036 -59.725898) (xy 249.733992 -59.718146) (xy 249.761248 -59.717686)
			(xy 249.788617 -59.718186) (xy 249.842794 -59.725996) (xy 249.895297 -59.741477) (xy 249.945044 -59.764312)
			(xy 249.991013 -59.794028) (xy 250.011946 -59.811666) (xy 250.0122 -59.81192) (xy 250.019281 -59.817515)
			(xy 250.036202 -59.823756) (xy 250.04522 -59.824112) (xy 250.112276 -59.824112) (xy 250.121291 -59.823741)
			(xy 250.138208 -59.817503) (xy 250.145296 -59.81192) (xy 250.145296 -59.811666) (xy 250.14555 -59.811666)
			(xy 250.166483 -59.794025) (xy 250.212451 -59.764301) (xy 250.262197 -59.741455) (xy 250.314699 -59.725959)
			(xy 250.368877 -59.71813) (xy 250.423619 -59.71813) (xy 250.477797 -59.725959) (xy 250.530299 -59.741455)
			(xy 250.580045 -59.764301) (xy 250.626013 -59.794025) (xy 250.646946 -59.811666) (xy 250.6472 -59.81192)
			(xy 250.654281 -59.817515) (xy 250.671202 -59.823756) (xy 250.68022 -59.824112) (xy 250.747276 -59.824112)
			(xy 250.756291 -59.823741) (xy 250.773208 -59.817503) (xy 250.780296 -59.81192) (xy 250.780296 -59.811666)
			(xy 250.78055 -59.811666) (xy 250.801486 -59.794032) (xy 250.847458 -59.76432) (xy 250.897205 -59.741484)
			(xy 250.949704 -59.725992) (xy 251.003879 -59.718161) (xy 251.031248 -59.717686) (xy 251.058497 -59.718187)
			(xy 251.112438 -59.725949) (xy 251.164726 -59.741308) (xy 251.214297 -59.763952) (xy 251.260141 -59.793419)
			(xy 251.301324 -59.82911) (xy 251.33701 -59.870298) (xy 251.366471 -59.916145) (xy 251.389109 -59.965719)
			(xy 251.404461 -60.018009) (xy 251.412216 -60.071951) (xy 251.412216 -60.126449) (xy 251.404461 -60.180391)
			(xy 251.389109 -60.232681) (xy 251.366471 -60.282255) (xy 251.33701 -60.328102) (xy 251.301324 -60.36929)
			(xy 251.260141 -60.404981) (xy 251.214297 -60.434448) (xy 251.164726 -60.457092) (xy 251.112438 -60.472451)
			(xy 251.058497 -60.480213) (xy 251.031248 -60.480702) (xy 251.003879 -60.480207) (xy 250.949701 -60.472396)
			(xy 250.897198 -60.456914) (xy 250.847451 -60.434079) (xy 250.801483 -60.40436) (xy 250.78055 -60.386722)
			(xy 250.780296 -60.386468) (xy 250.773217 -60.38087) (xy 250.756294 -60.374631) (xy 250.747276 -60.374276)
			(xy 250.68022 -60.374276) (xy 250.671205 -60.374648) (xy 250.654288 -60.380886) (xy 250.6472 -60.386468)
			(xy 250.646946 -60.386722) (xy 250.626013 -60.404363) (xy 250.580045 -60.434087) (xy 250.530299 -60.456933)
			(xy 250.477797 -60.472429) (xy 250.423619 -60.480258) (xy 250.368877 -60.480258) (xy 250.314699 -60.472429)
			(xy 250.262197 -60.456933) (xy 250.212451 -60.434087) (xy 250.166483 -60.404363) (xy 250.14555 -60.386722)
			(xy 250.145296 -60.386468) (xy 250.138217 -60.38087) (xy 250.121294 -60.374631) (xy 250.112276 -60.374276)
			(xy 250.04522 -60.374276) (xy 250.036205 -60.374648) (xy 250.019288 -60.380886) (xy 250.0122 -60.386468)
			(xy 250.0122 -60.386722) (xy 250.011946 -60.386722) (xy 249.99101 -60.404356) (xy 249.945038 -60.434068)
			(xy 249.895291 -60.456905) (xy 249.842792 -60.472397) (xy 249.788617 -60.480227) (xy 249.761248 -60.480702)
			(xy 249.733992 -60.480254) (xy 249.680036 -60.472502) (xy 249.627731 -60.45715) (xy 249.578144 -60.43451)
			(xy 249.532284 -60.405043) (xy 249.491085 -60.369349) (xy 249.455386 -60.328154) (xy 249.425913 -60.282298)
			(xy 249.403267 -60.232714) (xy 249.387908 -60.180411) (xy 249.38015 -60.126455) (xy 243.891054 -60.126455)
			(xy 243.891054 -60.999878) (xy 243.890519 -61.009866) (xy 243.882806 -61.0283) (xy 243.876068 -61.035692)
			(xy 243.16944 -61.74232) (xy 243.166392 -61.745368) (xy 243.100352 -61.811408) (xy 243.092998 -61.818064)
			(xy 243.074698 -61.825662) (xy 243.064792 -61.82614) (xy 243.009674 -61.82614) (xy 243.005356 -61.826902)
			(xy 242.992688 -61.82891) (xy 242.967127 -61.831068) (xy 242.954302 -61.83122) (xy 242.95354 -61.83122)
			(xy 241.317272 -61.83122) (xy 241.313337 -61.831249) (xy 241.305554 -61.8324) (xy 241.301778 -61.833506)
			(xy 241.298476 -61.834776) (xy 241.26952 -61.847222) (xy 241.262662 -61.854334) (xy 241.241009 -61.87537)
			(xy 241.192295 -61.911022) (xy 241.138577 -61.938561) (xy 241.081192 -61.9573) (xy 241.021574 -61.966771)
			(xy 240.99139 -61.967364) (xy 240.990374 -61.967364) (xy 240.976658 -61.967364) (xy 240.967768 -61.966602)
			(xy 240.944654 -61.96457) (xy 240.915952 -61.959998) (xy 240.915444 -61.959998) (xy 240.888726 -61.954073)
			(xy 240.837216 -61.935586) (xy 240.812828 -61.923168) (xy 240.787304 -61.90903) (xy 240.740489 -61.874208)
			(xy 240.71961 -61.853826) (xy 240.712498 -61.846714) (xy 240.68532 -61.835284) (xy 240.680581 -61.833413)
			(xy 240.670601 -61.831364) (xy 240.665508 -61.83122) (xy 239.052862 -61.83122) (xy 239.042702 -61.835792)
			(xy 239.018037 -61.846386) (xy 238.966477 -61.861321) (xy 238.913332 -61.86887) (xy 238.886492 -61.86932)
			(xy 238.859654 -61.868844) (xy 238.806512 -61.861291) (xy 238.754948 -61.846378) (xy 238.730282 -61.835792)
			(xy 238.720122 -61.83122) (xy 233.862372 -61.83122) (xy 233.853766 -61.831549) (xy 233.837529 -61.837254)
			(xy 233.830622 -61.842396) (xy 233.828082 -61.844428) (xy 233.754676 -61.917834) (xy 233.747346 -61.925904)
			(xy 233.739719 -61.946304) (xy 233.739944 -61.957204) (xy 233.749596 -62.038992) (xy 233.750397 -62.044571)
			(xy 233.754121 -62.055206) (xy 233.756962 -62.060074) (xy 233.762296 -62.06871) (xy 233.772964 -62.075314)
			(xy 233.79631 -62.090314) (xy 233.838806 -62.125997) (xy 233.875685 -62.167459) (xy 233.90617 -62.213825)
			(xy 233.929617 -62.264118) (xy 233.945533 -62.317277) (xy 233.953581 -62.372181) (xy 233.954066 -62.399926)
			(xy 233.953901 -62.409578) (xy 238.418114 -62.409578) (xy 238.422185 -62.353956) (xy 238.434311 -62.299519)
			(xy 238.454234 -62.247428) (xy 238.48153 -62.198793) (xy 238.515616 -62.15465) (xy 238.555765 -62.115941)
			(xy 238.601123 -62.08349) (xy 238.650723 -62.057989) (xy 238.703507 -62.039982) (xy 238.75835 -62.029852)
			(xy 238.814084 -62.027815) (xy 238.869521 -62.033915) (xy 238.923478 -62.048021) (xy 238.974807 -62.069833)
			(xy 239.022413 -62.098887) (xy 239.065281 -62.134562) (xy 239.102498 -62.176099) (xy 239.133271 -62.222612)
			(xy 239.156943 -62.273109) (xy 239.173011 -62.326516) (xy 239.181131 -62.381692) (xy 239.18164 -62.409578)
			(xy 239.181131 -62.437464) (xy 239.173011 -62.49264) (xy 239.156943 -62.546047) (xy 239.133271 -62.596544)
			(xy 239.102498 -62.643057) (xy 239.065281 -62.684594) (xy 239.022413 -62.720269) (xy 238.974807 -62.749323)
			(xy 238.923478 -62.771135) (xy 238.869521 -62.785241) (xy 238.814084 -62.791341) (xy 238.75835 -62.789304)
			(xy 238.703507 -62.779174) (xy 238.650723 -62.761167) (xy 238.601123 -62.735666) (xy 238.555765 -62.703215)
			(xy 238.515616 -62.664506) (xy 238.48153 -62.620363) (xy 238.454234 -62.571728) (xy 238.434311 -62.519637)
			(xy 238.422185 -62.4652) (xy 238.418114 -62.409578) (xy 233.953901 -62.409578) (xy 233.953601 -62.427177)
			(xy 233.945841 -62.481122) (xy 233.930482 -62.533415) (xy 233.907837 -62.582989) (xy 233.878368 -62.628836)
			(xy 233.842674 -62.670022) (xy 233.801481 -62.705709) (xy 233.755629 -62.73517) (xy 233.706051 -62.757806)
			(xy 233.653756 -62.773155) (xy 233.599809 -62.780906) (xy 233.572558 -62.781434) (xy 233.571542 -62.781434)
			(xy 233.550206 -62.780672) (xy 233.549698 -62.780672) (xy 233.522266 -62.778132) (xy 233.51109 -62.776862)
			(xy 233.50093 -62.77991) (xy 233.495834 -62.781686) (xy 233.486477 -62.787057) (xy 233.482388 -62.790578)
			(xy 233.475276 -62.796674) (xy 233.474768 -62.797182) (xy 233.42346 -62.842394) (xy 233.416334 -62.849816)
			(xy 233.408196 -62.868693) (xy 233.407712 -62.87897) (xy 233.407712 -63.121032) (xy 233.40824 -63.1313)
			(xy 233.416367 -63.150165) (xy 233.42346 -63.157608) (xy 233.474768 -63.20282) (xy 233.475276 -63.203328)
			(xy 233.482388 -63.209424) (xy 233.486478 -63.212946) (xy 233.495829 -63.218329) (xy 233.50093 -63.220092)
			(xy 233.51109 -63.22314) (xy 233.522266 -63.22187) (xy 233.549698 -63.21933) (xy 233.550206 -63.21933)
			(xy 233.571542 -63.218568) (xy 233.572558 -63.218568) (xy 233.599815 -63.219028) (xy 233.653773 -63.226781)
			(xy 233.70608 -63.242134) (xy 233.755668 -63.264776) (xy 233.80153 -63.294244) (xy 233.84273 -63.32994)
			(xy 233.87843 -63.371137) (xy 233.907904 -63.416995) (xy 233.923425 -63.450978) (xy 237.60633 -63.450978)
			(xy 237.610401 -63.395356) (xy 237.622527 -63.340919) (xy 237.64245 -63.288828) (xy 237.669746 -63.240193)
			(xy 237.703832 -63.19605) (xy 237.743981 -63.157341) (xy 237.789339 -63.12489) (xy 237.838939 -63.099389)
			(xy 237.891723 -63.081382) (xy 237.946566 -63.071252) (xy 238.0023 -63.069215) (xy 238.057737 -63.075315)
			(xy 238.111694 -63.089421) (xy 238.163023 -63.111233) (xy 238.210629 -63.140287) (xy 238.253497 -63.175962)
			(xy 238.290714 -63.217499) (xy 238.309271 -63.245548) (xy 249.304592 -63.245548) (xy 249.304592 -63.191052)
			(xy 249.312347 -63.13711) (xy 249.3277 -63.084821) (xy 249.350337 -63.035248) (xy 249.379798 -62.989402)
			(xy 249.415483 -62.948214) (xy 249.456666 -62.912524) (xy 249.50251 -62.883058) (xy 249.552079 -62.860415)
			(xy 249.604367 -62.845057) (xy 249.658308 -62.837295) (xy 249.685556 -62.836806) (xy 249.712925 -62.837296)
			(xy 249.767103 -62.845108) (xy 249.819606 -62.860591) (xy 249.869354 -62.883428) (xy 249.915322 -62.913147)
			(xy 249.936254 -62.930786) (xy 249.936508 -62.93104) (xy 249.943585 -62.936641) (xy 249.960509 -62.942878)
			(xy 249.969528 -62.943232) (xy 250.036584 -62.943232) (xy 250.045599 -62.94286) (xy 250.062516 -62.936622)
			(xy 250.069604 -62.93104) (xy 250.069604 -62.930786) (xy 250.069858 -62.930786) (xy 250.090791 -62.913145)
			(xy 250.136759 -62.883421) (xy 250.186505 -62.860575) (xy 250.239007 -62.845079) (xy 250.293185 -62.83725)
			(xy 250.347927 -62.83725) (xy 250.402105 -62.845079) (xy 250.454607 -62.860575) (xy 250.504353 -62.883421)
			(xy 250.550321 -62.913145) (xy 250.571254 -62.930786) (xy 250.571508 -62.93104) (xy 250.578585 -62.936641)
			(xy 250.595509 -62.942878) (xy 250.604528 -62.943232) (xy 250.671584 -62.943232) (xy 250.680599 -62.94286)
			(xy 250.697516 -62.936622) (xy 250.704604 -62.93104) (xy 250.704604 -62.930786) (xy 250.704858 -62.930786)
			(xy 250.725793 -62.913151) (xy 250.771765 -62.883439) (xy 250.821512 -62.860602) (xy 250.874012 -62.84511)
			(xy 250.928187 -62.837281) (xy 250.955556 -62.836806) (xy 250.982812 -62.837238) (xy 251.03677 -62.84499)
			(xy 251.089075 -62.860343) (xy 251.138662 -62.882984) (xy 251.184523 -62.912452) (xy 251.225722 -62.948147)
			(xy 251.261422 -62.989342) (xy 251.290895 -63.035199) (xy 251.313542 -63.084784) (xy 251.328901 -63.137087)
			(xy 251.336659 -63.191044) (xy 251.336659 -63.245556) (xy 251.328901 -63.299513) (xy 251.313542 -63.351816)
			(xy 251.290895 -63.401401) (xy 251.261422 -63.447258) (xy 251.225722 -63.488453) (xy 251.184523 -63.524148)
			(xy 251.138662 -63.553616) (xy 251.089075 -63.576257) (xy 251.03677 -63.59161) (xy 250.982812 -63.599362)
			(xy 250.955556 -63.599822) (xy 250.928186 -63.599342) (xy 250.874007 -63.591531) (xy 250.821503 -63.576046)
			(xy 250.771756 -63.553207) (xy 250.725789 -63.523483) (xy 250.704858 -63.505842) (xy 250.704604 -63.505588)
			(xy 250.697521 -63.499996) (xy 250.680602 -63.493753) (xy 250.671584 -63.493396) (xy 250.604528 -63.493396)
			(xy 250.595513 -63.493767) (xy 250.578596 -63.500005) (xy 250.571508 -63.505588) (xy 250.571254 -63.505842)
			(xy 250.550321 -63.523483) (xy 250.504353 -63.553207) (xy 250.454607 -63.576053) (xy 250.402105 -63.591549)
			(xy 250.347927 -63.599378) (xy 250.293185 -63.599378) (xy 250.239007 -63.591549) (xy 250.186505 -63.576053)
			(xy 250.136759 -63.553207) (xy 250.090791 -63.523483) (xy 250.069858 -63.505842) (xy 250.069604 -63.505588)
			(xy 250.062521 -63.499996) (xy 250.045602 -63.493753) (xy 250.036584 -63.493396) (xy 249.969528 -63.493396)
			(xy 249.960513 -63.493767) (xy 249.943596 -63.500005) (xy 249.936508 -63.505588) (xy 249.936508 -63.505842)
			(xy 249.936254 -63.505842) (xy 249.915318 -63.523476) (xy 249.869346 -63.553187) (xy 249.819599 -63.576024)
			(xy 249.7671 -63.591516) (xy 249.712925 -63.599347) (xy 249.685556 -63.599822) (xy 249.658308 -63.599305)
			(xy 249.604367 -63.591543) (xy 249.552079 -63.576185) (xy 249.50251 -63.553542) (xy 249.456666 -63.524076)
			(xy 249.415483 -63.488386) (xy 249.379798 -63.447198) (xy 249.350337 -63.401352) (xy 249.3277 -63.351779)
			(xy 249.312347 -63.29949) (xy 249.304592 -63.245548) (xy 238.309271 -63.245548) (xy 238.321487 -63.264012)
			(xy 238.345159 -63.314509) (xy 238.361227 -63.367916) (xy 238.369347 -63.423092) (xy 238.369856 -63.450978)
			(xy 238.369347 -63.478864) (xy 238.361227 -63.53404) (xy 238.345159 -63.587447) (xy 238.321487 -63.637944)
			(xy 238.31478 -63.648082) (xy 241.242594 -63.648082) (xy 241.246665 -63.59246) (xy 241.258791 -63.538023)
			(xy 241.278714 -63.485932) (xy 241.30601 -63.437297) (xy 241.340096 -63.393154) (xy 241.380245 -63.354445)
			(xy 241.425603 -63.321994) (xy 241.475203 -63.296493) (xy 241.527987 -63.278486) (xy 241.58283 -63.268356)
			(xy 241.638564 -63.266319) (xy 241.694001 -63.272419) (xy 241.747958 -63.286525) (xy 241.799287 -63.308337)
			(xy 241.846893 -63.337391) (xy 241.889761 -63.373066) (xy 241.926978 -63.414603) (xy 241.957751 -63.461116)
			(xy 241.981423 -63.511613) (xy 241.997491 -63.56502) (xy 242.005611 -63.620196) (xy 242.00612 -63.648082)
			(xy 242.005611 -63.675968) (xy 241.997491 -63.731144) (xy 241.981423 -63.784551) (xy 241.957751 -63.835048)
			(xy 241.926978 -63.881561) (xy 241.889761 -63.923098) (xy 241.846893 -63.958773) (xy 241.799287 -63.987827)
			(xy 241.747958 -64.009639) (xy 241.694001 -64.023745) (xy 241.638564 -64.029845) (xy 241.58283 -64.027808)
			(xy 241.527987 -64.017678) (xy 241.475203 -63.999671) (xy 241.425603 -63.97417) (xy 241.380245 -63.941719)
			(xy 241.340096 -63.90301) (xy 241.30601 -63.858867) (xy 241.278714 -63.810232) (xy 241.258791 -63.758141)
			(xy 241.246665 -63.703704) (xy 241.242594 -63.648082) (xy 238.31478 -63.648082) (xy 238.290714 -63.684457)
			(xy 238.253497 -63.725994) (xy 238.210629 -63.761669) (xy 238.163023 -63.790723) (xy 238.111694 -63.812535)
			(xy 238.057737 -63.826641) (xy 238.0023 -63.832741) (xy 237.946566 -63.830704) (xy 237.891723 -63.820574)
			(xy 237.838939 -63.802567) (xy 237.789339 -63.777066) (xy 237.743981 -63.744615) (xy 237.703832 -63.705906)
			(xy 237.669746 -63.661763) (xy 237.64245 -63.613128) (xy 237.622527 -63.561037) (xy 237.610401 -63.5066)
			(xy 237.60633 -63.450978) (xy 233.923425 -63.450978) (xy 233.930551 -63.466581) (xy 233.94591 -63.518885)
			(xy 233.953669 -63.572843) (xy 233.953669 -63.627357) (xy 233.94591 -63.681315) (xy 233.930551 -63.733619)
			(xy 233.907904 -63.783205) (xy 233.87843 -63.829063) (xy 233.84273 -63.87026) (xy 233.80153 -63.905956)
			(xy 233.755668 -63.935424) (xy 233.70608 -63.958066) (xy 233.653773 -63.973419) (xy 233.599815 -63.981172)
			(xy 233.572558 -63.981584) (xy 233.571542 -63.981584) (xy 233.550206 -63.980822) (xy 233.549698 -63.980822)
			(xy 233.522266 -63.978282) (xy 233.51109 -63.977012) (xy 233.50093 -63.98006) (xy 233.495835 -63.981838)
			(xy 233.486481 -63.987213) (xy 233.482388 -63.990728) (xy 233.475276 -63.996824) (xy 233.474768 -63.997332)
			(xy 233.42346 -64.042544) (xy 233.416342 -64.049969) (xy 233.408223 -64.068846) (xy 233.407712 -64.07912)
			(xy 233.407712 -64.261492) (xy 239.918748 -64.261492) (xy 239.919234 -64.234241) (xy 239.92699 -64.180293)
			(xy 239.942345 -64.127998) (xy 239.964987 -64.078421) (xy 239.994453 -64.032571) (xy 240.030144 -63.99138)
			(xy 240.071335 -63.955689) (xy 240.117185 -63.926223) (xy 240.166762 -63.903581) (xy 240.219057 -63.888226)
			(xy 240.273005 -63.88047) (xy 240.327507 -63.88047) (xy 240.381455 -63.888226) (xy 240.43375 -63.903581)
			(xy 240.483327 -63.926223) (xy 240.529177 -63.955689) (xy 240.570368 -63.99138) (xy 240.606059 -64.032571)
			(xy 240.635525 -64.078421) (xy 240.658167 -64.127998) (xy 240.673522 -64.180293) (xy 240.681278 -64.234241)
			(xy 240.681764 -64.261492) (xy 240.681249 -64.290339) (xy 240.672568 -64.347377) (xy 240.655388 -64.402454)
			(xy 240.630102 -64.454312) (xy 240.597288 -64.501765) (xy 240.577878 -64.523112) (xy 240.570627 -64.531847)
			(xy 240.563761 -64.553453) (xy 240.56467 -64.564768) (xy 240.577624 -64.655192) (xy 240.590324 -64.674242)
			(xy 240.60023 -64.680084) (xy 240.624355 -64.69489) (xy 240.668318 -64.730546) (xy 240.706533 -64.772302)
			(xy 240.738163 -64.819244) (xy 240.762515 -64.870342) (xy 240.779055 -64.924475) (xy 240.787419 -64.980458)
			(xy 240.787936 -65.00876) (xy 240.78745 -65.036011) (xy 240.779694 -65.089959) (xy 240.764339 -65.142254)
			(xy 240.756285 -65.15989) (xy 251.316488 -65.15989) (xy 251.320559 -65.104268) (xy 251.332685 -65.049831)
			(xy 251.352608 -64.99774) (xy 251.379904 -64.949105) (xy 251.41399 -64.904962) (xy 251.454139 -64.866253)
			(xy 251.499497 -64.833802) (xy 251.549097 -64.808301) (xy 251.601881 -64.790294) (xy 251.656724 -64.780164)
			(xy 251.712458 -64.778127) (xy 251.767895 -64.784227) (xy 251.821852 -64.798333) (xy 251.873181 -64.820145)
			(xy 251.920787 -64.849199) (xy 251.963655 -64.884874) (xy 252.000872 -64.926411) (xy 252.031645 -64.972924)
			(xy 252.055317 -65.023421) (xy 252.071385 -65.076828) (xy 252.079505 -65.132004) (xy 252.080014 -65.15989)
			(xy 252.079505 -65.187776) (xy 252.071385 -65.242952) (xy 252.055317 -65.296359) (xy 252.031645 -65.346856)
			(xy 252.000872 -65.393369) (xy 251.963655 -65.434906) (xy 251.920787 -65.470581) (xy 251.873181 -65.499635)
			(xy 251.821852 -65.521447) (xy 251.767895 -65.535553) (xy 251.712458 -65.541653) (xy 251.656724 -65.539616)
			(xy 251.601881 -65.529486) (xy 251.549097 -65.511479) (xy 251.499497 -65.485978) (xy 251.454139 -65.453527)
			(xy 251.41399 -65.414818) (xy 251.379904 -65.370675) (xy 251.352608 -65.32204) (xy 251.332685 -65.269949)
			(xy 251.320559 -65.215512) (xy 251.316488 -65.15989) (xy 240.756285 -65.15989) (xy 240.741697 -65.191831)
			(xy 240.712231 -65.237681) (xy 240.67654 -65.278872) (xy 240.635349 -65.314563) (xy 240.589499 -65.344029)
			(xy 240.539922 -65.366671) (xy 240.487627 -65.382026) (xy 240.433679 -65.389782) (xy 240.379177 -65.389782)
			(xy 240.325229 -65.382026) (xy 240.272934 -65.366671) (xy 240.223357 -65.344029) (xy 240.177507 -65.314563)
			(xy 240.136316 -65.278872) (xy 240.100625 -65.237681) (xy 240.071159 -65.191831) (xy 240.048517 -65.142254)
			(xy 240.033162 -65.089959) (xy 240.025406 -65.036011) (xy 240.02492 -65.00876) (xy 240.025471 -64.979914)
			(xy 240.034144 -64.922879) (xy 240.051315 -64.867802) (xy 240.076593 -64.815944) (xy 240.1094 -64.768488)
			(xy 240.128806 -64.74714) (xy 240.13608 -64.738421) (xy 240.142933 -64.716802) (xy 240.142014 -64.705484)
			(xy 240.12906 -64.61506) (xy 240.11636 -64.59601) (xy 240.106454 -64.590168) (xy 240.082371 -64.575296)
			(xy 240.038405 -64.539654) (xy 240.000184 -64.497911) (xy 239.968547 -64.45098) (xy 239.944188 -64.399892)
			(xy 239.927641 -64.345767) (xy 239.919269 -64.289791) (xy 239.918748 -64.261492) (xy 233.407712 -64.261492)
			(xy 233.407712 -64.320928) (xy 233.408239 -64.331196) (xy 233.416365 -64.350062) (xy 233.42346 -64.357504)
			(xy 233.474768 -64.402716) (xy 233.475276 -64.403224) (xy 233.482388 -64.40932) (xy 233.486478 -64.412842)
			(xy 233.495829 -64.418225) (xy 233.50093 -64.419988) (xy 233.51109 -64.423036) (xy 233.522266 -64.421766)
			(xy 233.549698 -64.419226) (xy 233.550206 -64.419226) (xy 233.571542 -64.418464) (xy 233.572558 -64.418464)
			(xy 233.599815 -64.418924) (xy 233.653774 -64.426677) (xy 233.706081 -64.44203) (xy 233.75567 -64.464672)
			(xy 233.801532 -64.494141) (xy 233.842733 -64.529837) (xy 233.878434 -64.571034) (xy 233.907908 -64.616893)
			(xy 233.930555 -64.666479) (xy 233.945914 -64.718785) (xy 233.953673 -64.772743) (xy 233.953673 -64.827257)
			(xy 233.945914 -64.881215) (xy 233.930555 -64.933521) (xy 233.907908 -64.983107) (xy 233.878434 -65.028966)
			(xy 233.842733 -65.070163) (xy 233.801532 -65.105859) (xy 233.75567 -65.135328) (xy 233.706081 -65.15797)
			(xy 233.653774 -65.173323) (xy 233.599815 -65.181076) (xy 233.572558 -65.18148) (xy 233.571542 -65.18148)
			(xy 233.550206 -65.180718) (xy 233.549698 -65.180718) (xy 233.522266 -65.178178) (xy 233.51109 -65.176908)
			(xy 233.50093 -65.179956) (xy 233.495835 -65.181734) (xy 233.486481 -65.187108) (xy 233.482388 -65.190624)
			(xy 233.475276 -65.19672) (xy 233.474768 -65.197228) (xy 233.42346 -65.24244) (xy 233.416341 -65.249865)
			(xy 233.40822 -65.268742) (xy 233.407712 -65.279016) (xy 233.407712 -65.521078) (xy 233.40823 -65.53135)
			(xy 233.416344 -65.55023) (xy 233.42346 -65.557654) (xy 233.474768 -65.602866) (xy 233.475276 -65.603374)
			(xy 233.482388 -65.60947) (xy 233.486479 -65.612989) (xy 233.495832 -65.618367) (xy 233.50093 -65.620138)
			(xy 233.51109 -65.623186) (xy 233.522266 -65.621916) (xy 233.549698 -65.619376) (xy 233.550206 -65.619376)
			(xy 233.571542 -65.618614) (xy 233.572558 -65.618614) (xy 233.599811 -65.619074) (xy 233.653764 -65.626826)
			(xy 233.706063 -65.642178) (xy 233.755646 -65.664816) (xy 233.801502 -65.694282) (xy 233.842697 -65.729973)
			(xy 233.864835 -65.75552) (xy 246.546622 -65.75552) (xy 246.550693 -65.699898) (xy 246.562819 -65.645461)
			(xy 246.582742 -65.59337) (xy 246.610038 -65.544735) (xy 246.644124 -65.500592) (xy 246.684273 -65.461883)
			(xy 246.729631 -65.429432) (xy 246.779231 -65.403931) (xy 246.832015 -65.385924) (xy 246.886858 -65.375794)
			(xy 246.942592 -65.373757) (xy 246.998029 -65.379857) (xy 247.051986 -65.393963) (xy 247.103315 -65.415775)
			(xy 247.150921 -65.444829) (xy 247.193789 -65.480504) (xy 247.231006 -65.522041) (xy 247.261779 -65.568554)
			(xy 247.285451 -65.619051) (xy 247.301519 -65.672458) (xy 247.309639 -65.727634) (xy 247.310148 -65.75552)
			(xy 247.309639 -65.783406) (xy 247.301519 -65.838582) (xy 247.285451 -65.891989) (xy 247.261779 -65.942486)
			(xy 247.231006 -65.988999) (xy 247.193789 -66.030536) (xy 247.150921 -66.066211) (xy 247.103315 -66.095265)
			(xy 247.051986 -66.117077) (xy 246.998029 -66.131183) (xy 246.942592 -66.137283) (xy 246.886858 -66.135246)
			(xy 246.832015 -66.125116) (xy 246.779231 -66.107109) (xy 246.729631 -66.081608) (xy 246.684273 -66.049157)
			(xy 246.644124 -66.010448) (xy 246.610038 -65.966305) (xy 246.582742 -65.91767) (xy 246.562819 -65.865579)
			(xy 246.550693 -65.811142) (xy 246.546622 -65.75552) (xy 233.864835 -65.75552) (xy 233.878393 -65.771165)
			(xy 233.907863 -65.817017) (xy 233.930508 -65.866597) (xy 233.945865 -65.918895) (xy 233.953623 -65.972847)
			(xy 233.953623 -66.027353) (xy 233.945865 -66.081305) (xy 233.930508 -66.133603) (xy 233.907863 -66.183183)
			(xy 233.878393 -66.229035) (xy 233.842697 -66.270227) (xy 233.801502 -66.305918) (xy 233.755646 -66.335384)
			(xy 233.706063 -66.358022) (xy 233.653764 -66.373374) (xy 233.599811 -66.381126) (xy 233.572558 -66.38163)
			(xy 233.571542 -66.38163) (xy 233.550206 -66.380868) (xy 233.549698 -66.380868) (xy 233.522266 -66.378328)
			(xy 233.51109 -66.377058) (xy 233.50093 -66.380106) (xy 233.495834 -66.381882) (xy 233.486477 -66.387253)
			(xy 233.482388 -66.390774) (xy 233.475276 -66.39687) (xy 233.474768 -66.397378) (xy 233.42346 -66.44259)
			(xy 233.416333 -66.450012) (xy 233.408194 -66.468889) (xy 233.407712 -66.479166) (xy 233.407712 -66.720974)
			(xy 233.408229 -66.731246) (xy 233.416342 -66.750127) (xy 233.42346 -66.75755) (xy 233.474768 -66.802762)
			(xy 233.475276 -66.80327) (xy 233.482388 -66.809366) (xy 233.486479 -66.812885) (xy 233.495832 -66.818264)
			(xy 233.50093 -66.820034) (xy 233.51109 -66.823082) (xy 233.522266 -66.821812) (xy 233.549698 -66.819272)
			(xy 233.550206 -66.819272) (xy 233.571542 -66.81851) (xy 233.572558 -66.81851) (xy 233.599812 -66.81897)
			(xy 233.653764 -66.826722) (xy 233.706065 -66.842074) (xy 233.755648 -66.864713) (xy 233.801504 -66.894178)
			(xy 233.8427 -66.92987) (xy 233.878396 -66.971062) (xy 233.907867 -67.016915) (xy 233.930511 -67.066496)
			(xy 233.945869 -67.118794) (xy 233.953627 -67.172747) (xy 233.953627 -67.227253) (xy 233.945869 -67.281206)
			(xy 233.930511 -67.333504) (xy 233.907867 -67.383085) (xy 233.878396 -67.428938) (xy 233.8427 -67.47013)
			(xy 233.822012 -67.488054) (xy 250.979176 -67.488054) (xy 250.983247 -67.432432) (xy 250.995373 -67.377995)
			(xy 251.015296 -67.325904) (xy 251.042592 -67.277269) (xy 251.076678 -67.233126) (xy 251.116827 -67.194417)
			(xy 251.162185 -67.161966) (xy 251.211785 -67.136465) (xy 251.264569 -67.118458) (xy 251.319412 -67.108328)
			(xy 251.375146 -67.106291) (xy 251.430583 -67.112391) (xy 251.48454 -67.126497) (xy 251.535869 -67.148309)
			(xy 251.583475 -67.177363) (xy 251.626343 -67.213038) (xy 251.66356 -67.254575) (xy 251.694333 -67.301088)
			(xy 251.718005 -67.351585) (xy 251.734073 -67.404992) (xy 251.742193 -67.460168) (xy 251.742702 -67.488054)
			(xy 251.742193 -67.51594) (xy 251.734073 -67.571116) (xy 251.718005 -67.624523) (xy 251.694333 -67.67502)
			(xy 251.66356 -67.721533) (xy 251.626343 -67.76307) (xy 251.583475 -67.798745) (xy 251.535869 -67.827799)
			(xy 251.48454 -67.849611) (xy 251.430583 -67.863717) (xy 251.375146 -67.869817) (xy 251.319412 -67.86778)
			(xy 251.264569 -67.85765) (xy 251.211785 -67.839643) (xy 251.162185 -67.814142) (xy 251.116827 -67.781691)
			(xy 251.076678 -67.742982) (xy 251.042592 -67.698839) (xy 251.015296 -67.650204) (xy 250.995373 -67.598113)
			(xy 250.983247 -67.543676) (xy 250.979176 -67.488054) (xy 233.822012 -67.488054) (xy 233.801504 -67.505822)
			(xy 233.755648 -67.535287) (xy 233.706065 -67.557926) (xy 233.653764 -67.573278) (xy 233.599812 -67.58103)
			(xy 233.572558 -67.581526) (xy 233.571542 -67.581526) (xy 233.550206 -67.580764) (xy 233.549698 -67.580764)
			(xy 233.522266 -67.578224) (xy 233.51109 -67.576954) (xy 233.50093 -67.580002) (xy 233.495834 -67.581778)
			(xy 233.486476 -67.587148) (xy 233.482388 -67.59067) (xy 233.475276 -67.596766) (xy 233.474768 -67.597274)
			(xy 233.42346 -67.642486) (xy 233.416333 -67.649908) (xy 233.408192 -67.668785) (xy 233.407712 -67.679062)
			(xy 233.407712 -67.713606) (xy 233.40822 -67.72021) (xy 233.409693 -67.729022) (xy 233.417904 -67.744878)
			(xy 233.424222 -67.751198) (xy 233.485944 -67.803268) (xy 233.490167 -67.806469) (xy 233.499646 -67.811203)
			(xy 233.50474 -67.812666) (xy 233.51109 -67.814444) (xy 233.524044 -67.812412) (xy 233.538555 -67.810282)
			(xy 233.567798 -67.80799) (xy 233.582464 -67.80784) (xy 233.593132 -67.80784) (xy 233.594148 -67.80784)
			(xy 233.621396 -67.80833) (xy 233.675336 -67.816092) (xy 233.727622 -67.831452) (xy 233.77719 -67.854096)
			(xy 233.823031 -67.883564) (xy 233.864211 -67.919257) (xy 233.899893 -67.960446) (xy 233.92935 -68.006294)
			(xy 233.951982 -68.055868) (xy 233.967329 -68.108158) (xy 233.975077 -68.1621) (xy 233.975656 -68.189348)
			(xy 233.975168 -68.217239) (xy 233.967037 -68.272426) (xy 233.950955 -68.32584) (xy 233.927265 -68.376342)
			(xy 233.896473 -68.422855) (xy 233.859235 -68.464388) (xy 233.816345 -68.500055) (xy 233.792776 -68.514976)
			(xy 233.79176 -68.515484) (xy 233.786866 -68.518863) (xy 233.778648 -68.527455) (xy 233.775504 -68.532502)
			(xy 233.774996 -68.533264) (xy 233.771971 -68.538914) (xy 233.768507 -68.551249) (xy 233.768138 -68.557648)
			(xy 233.765598 -68.6435) (xy 233.766077 -68.654081) (xy 233.774465 -68.673505) (xy 233.781854 -68.681092)
			(xy 233.787696 -68.685156) (xy 233.809317 -68.700457) (xy 233.848517 -68.736079) (xy 233.882406 -68.776785)
			(xy 233.910333 -68.821792) (xy 233.931759 -68.870233) (xy 233.94627 -68.921173) (xy 233.953589 -68.973632)
			(xy 233.954066 -69.000116) (xy 233.954066 -69.00037) (xy 233.953634 -69.026262) (xy 233.946628 -69.077568)
			(xy 233.93274 -69.127454) (xy 233.912226 -69.175001) (xy 233.885464 -69.219332) (xy 233.852946 -69.259632)
			(xy 233.834432 -69.277738) (xy 233.833924 -69.278246) (xy 233.829675 -69.282352) (xy 233.823005 -69.292102)
			(xy 233.820716 -69.29755) (xy 233.817668 -69.305678) (xy 233.820208 -69.34454) (xy 233.820208 -69.345048)
			(xy 233.823764 -69.395086) (xy 233.824209 -69.399826) (xy 233.826643 -69.409029) (xy 233.82859 -69.413374)
			(xy 233.8324 -69.421248) (xy 233.84002 -69.42963) (xy 233.844846 -69.433186) (xy 233.865648 -69.448593)
			(xy 233.903295 -69.484123) (xy 233.935787 -69.52442) (xy 233.962529 -69.568743) (xy 233.983027 -69.616277)
			(xy 233.996904 -69.666148) (xy 234.003906 -69.717437) (xy 234.004358 -69.74332) (xy 234.003808 -69.772437)
			(xy 233.99496 -69.829996) (xy 233.977473 -69.885543) (xy 233.951753 -69.93779) (xy 233.918396 -69.985525)
			(xy 233.898694 -70.006972) (xy 233.893842 -70.012463) (xy 233.887139 -70.025487) (xy 233.885486 -70.032626)
			(xy 233.884216 -70.040246) (xy 233.88574 -70.054724) (xy 233.90225 -70.09384) (xy 233.925364 -70.147688)
			(xy 233.928412 -70.153784) (xy 233.945938 -70.17131) (xy 233.951942 -70.174702) (xy 233.965208 -70.178446)
			(xy 233.9721 -70.178676)
		)
		(stroke
			(width 0)
			(type solid)
		)
		(fill yes)
		(layer "In9.Cu")
		(net "P12V_SSD8_R")
	)
	(gr_poly
		(pts
			(xy 462.504028 -332.243938) (xy 462.511632 -332.242421) (xy 462.525464 -332.235433) (xy 462.531206 -332.230222)
			(xy 463.694526 -331.066902) (xy 463.701381 -331.059507) (xy 463.709128 -331.040908) (xy 463.709512 -331.030834)
			(xy 463.709512 -326.14743) (xy 463.709077 -326.137365) (xy 463.701346 -326.118778) (xy 463.694526 -326.111362)
			(xy 462.861914 -325.278496) (xy 462.854511 -325.271664) (xy 462.835912 -325.263961) (xy 462.825846 -325.26351)
			(xy 450.778372 -325.26351) (xy 450.768304 -325.263082) (xy 450.749706 -325.255362) (xy 450.742304 -325.248524)
			(xy 448.047364 -322.553584) (xy 448.040513 -322.546188) (xy 448.032775 -322.527589) (xy 448.032378 -322.517516)
			(xy 448.032378 -312.057034) (xy 448.03186 -312.046105) (xy 448.022778 -312.026222) (xy 448.014852 -312.01868)
			(xy 447.95694 -311.968388) (xy 447.94836 -311.961623) (xy 447.927431 -311.955426) (xy 447.916554 -311.95645)
			(xy 447.83922 -311.966769) (xy 447.683846 -311.981125) (xy 447.527974 -311.988288) (xy 447.449956 -311.988708)
			(xy 447.368303 -311.988214) (xy 447.205186 -311.980322) (xy 447.042642 -311.964558) (xy 446.881049 -311.94096)
			(xy 446.720785 -311.909583) (xy 446.562224 -311.870499) (xy 446.405736 -311.823801) (xy 446.251687 -311.769596)
			(xy 446.100437 -311.708013) (xy 445.952339 -311.639193) (xy 445.807738 -311.5633) (xy 445.666973 -311.480508)
			(xy 445.530372 -311.391013) (xy 445.398255 -311.295022) (xy 445.27093 -311.192761) (xy 445.148693 -311.084468)
			(xy 445.031832 -310.970395) (xy 444.920618 -310.85081) (xy 444.815311 -310.725991) (xy 444.716158 -310.596231)
			(xy 444.62339 -310.461831) (xy 444.537223 -310.323107) (xy 444.457859 -310.180381) (xy 444.385484 -310.033988)
			(xy 444.320265 -309.884269) (xy 444.262356 -309.731575) (xy 444.211892 -309.57626) (xy 444.16899 -309.418689)
			(xy 444.133752 -309.25923) (xy 444.106258 -309.098254) (xy 444.086574 -308.936137) (xy 444.074745 -308.773259)
			(xy 444.070798 -308.61) (xy 444.074745 -308.446741) (xy 444.086574 -308.283863) (xy 444.106258 -308.121746)
			(xy 444.133752 -307.96077) (xy 444.16899 -307.801311) (xy 444.211892 -307.64374) (xy 444.262356 -307.488425)
			(xy 444.320265 -307.335731) (xy 444.385484 -307.186012) (xy 444.457859 -307.039619) (xy 444.537223 -306.896893)
			(xy 444.62339 -306.758169) (xy 444.716158 -306.623769) (xy 444.815311 -306.494009) (xy 444.920618 -306.36919)
			(xy 445.031832 -306.249605) (xy 445.148693 -306.135532) (xy 445.27093 -306.027239) (xy 445.398255 -305.924978)
			(xy 445.530372 -305.828987) (xy 445.666973 -305.739492) (xy 445.807738 -305.6567) (xy 445.952339 -305.580807)
			(xy 446.100437 -305.511987) (xy 446.251687 -305.450404) (xy 446.405736 -305.396199) (xy 446.562224 -305.349501)
			(xy 446.720785 -305.310417) (xy 446.881049 -305.27904) (xy 447.042642 -305.255442) (xy 447.205186 -305.239678)
			(xy 447.368303 -305.231786) (xy 447.449956 -305.231292) (xy 447.527974 -305.231724) (xy 447.683845 -305.238889)
			(xy 447.839219 -305.253238) (xy 447.916554 -305.26355) (xy 447.92773 -305.265328) (xy 447.948558 -305.258978)
			(xy 448.014852 -305.20132) (xy 448.015868 -305.200304) (xy 448.016122 -305.200304) (xy 448.023495 -305.19278)
			(xy 448.031893 -305.173489) (xy 448.032378 -305.162966) (xy 448.032378 -293.130224) (xy 448.03194 -293.12016)
			(xy 448.024204 -293.101578) (xy 448.017392 -293.094156) (xy 443.275974 -288.352738) (xy 443.268576 -288.345891)
			(xy 443.249977 -288.33816) (xy 443.239906 -288.337752) (xy 441.05957 -288.337752) (xy 441.049503 -288.338182)
			(xy 441.030912 -288.34591) (xy 441.023502 -288.352738) (xy 440.64174 -288.7345) (xy 440.634338 -288.741337)
			(xy 440.61574 -288.74905) (xy 440.605672 -288.749486) (xy 435.802278 -288.749486) (xy 435.796773 -288.749602)
			(xy 435.786007 -288.751899) (xy 435.780942 -288.754058) (xy 434.848762 -289.18154) (xy 434.84165 -289.189414)
			(xy 434.834538 -289.197288) (xy 434.831236 -289.207194) (xy 434.822363 -289.232062) (xy 434.79873 -289.279275)
			(xy 434.768811 -289.322779) (xy 434.733179 -289.361741) (xy 434.692515 -289.395417) (xy 434.647595 -289.423165)
			(xy 434.599278 -289.444452) (xy 434.548487 -289.458874) (xy 434.496193 -289.466154) (xy 434.469794 -289.466528)
			(xy 434.452554 -289.466373) (xy 434.41821 -289.463323) (xy 434.401214 -289.460432) (xy 434.388768 -289.458146)
			(xy 434.365146 -289.465512) (xy 434.047646 -289.783012) (xy 434.04024 -289.79119) (xy 434.0326 -289.811862)
			(xy 434.032914 -289.82289) (xy 434.040026 -289.911028) (xy 434.050694 -289.930332) (xy 434.059838 -289.936936)
			(xy 434.080414 -289.952373) (xy 434.117624 -289.987889) (xy 434.149723 -290.028084) (xy 434.176127 -290.072229)
			(xy 434.196358 -290.119523) (xy 434.210048 -290.169106) (xy 434.216949 -290.22008) (xy 434.217194 -290.237164)
			(xy 437.464452 -290.237164) (xy 437.468523 -290.181542) (xy 437.480649 -290.127105) (xy 437.500572 -290.075014)
			(xy 437.527868 -290.026379) (xy 437.561954 -289.982236) (xy 437.602103 -289.943527) (xy 437.647461 -289.911076)
			(xy 437.697061 -289.885575) (xy 437.749845 -289.867568) (xy 437.804688 -289.857438) (xy 437.860422 -289.855401)
			(xy 437.915859 -289.861501) (xy 437.969816 -289.875607) (xy 438.021145 -289.897419) (xy 438.068751 -289.926473)
			(xy 438.111619 -289.962148) (xy 438.148836 -290.003685) (xy 438.179609 -290.050198) (xy 438.203281 -290.100695)
			(xy 438.219349 -290.154102) (xy 438.227469 -290.209278) (xy 438.227978 -290.237164) (xy 438.227469 -290.26505)
			(xy 438.219349 -290.320226) (xy 438.203281 -290.373633) (xy 438.179609 -290.42413) (xy 438.148836 -290.470643)
			(xy 438.111619 -290.51218) (xy 438.068751 -290.547855) (xy 438.021145 -290.576909) (xy 437.969816 -290.598721)
			(xy 437.915859 -290.612827) (xy 437.860422 -290.618927) (xy 437.804688 -290.61689) (xy 437.749845 -290.60676)
			(xy 437.697061 -290.588753) (xy 437.647461 -290.563252) (xy 437.602103 -290.530801) (xy 437.561954 -290.492092)
			(xy 437.527868 -290.447949) (xy 437.500572 -290.399314) (xy 437.480649 -290.347223) (xy 437.468523 -290.292786)
			(xy 437.464452 -290.237164) (xy 434.217194 -290.237164) (xy 434.217318 -290.2458) (xy 434.216832 -290.273052)
			(xy 434.209076 -290.327) (xy 434.193721 -290.379295) (xy 434.17108 -290.428873) (xy 434.141614 -290.474724)
			(xy 434.105922 -290.515915) (xy 434.064732 -290.551608) (xy 434.018882 -290.581075) (xy 433.969304 -290.603717)
			(xy 433.91701 -290.619074) (xy 433.863061 -290.626832) (xy 433.83581 -290.627308) (xy 433.810096 -290.626882)
			(xy 433.759134 -290.619964) (xy 433.709562 -290.606267) (xy 433.662279 -290.586037) (xy 433.61814 -290.559642)
			(xy 433.577945 -290.527559) (xy 433.542422 -290.49037) (xy 433.526946 -290.469828) (xy 433.520342 -290.460684)
			(xy 433.501038 -290.450016) (xy 433.4129 -290.442904) (xy 433.401867 -290.442563) (xy 433.381188 -290.450209)
			(xy 433.373022 -290.457636) (xy 433.091844 -290.738814) (xy 433.084995 -290.746211) (xy 433.077259 -290.76481)
			(xy 433.076858 -290.774882) (xy 433.076858 -290.84651) (xy 433.076432 -290.856578) (xy 433.06871 -290.875176)
			(xy 433.061872 -290.882578) (xy 432.705764 -291.238686) (xy 434.296564 -291.238686) (xy 434.300635 -291.183064)
			(xy 434.312761 -291.128627) (xy 434.332684 -291.076536) (xy 434.35998 -291.027901) (xy 434.394066 -290.983758)
			(xy 434.434215 -290.945049) (xy 434.479573 -290.912598) (xy 434.529173 -290.887097) (xy 434.581957 -290.86909)
			(xy 434.6368 -290.85896) (xy 434.692534 -290.856923) (xy 434.747971 -290.863023) (xy 434.801928 -290.877129)
			(xy 434.853257 -290.898941) (xy 434.900863 -290.927995) (xy 434.943731 -290.96367) (xy 434.980948 -291.005207)
			(xy 435.011721 -291.05172) (xy 435.035393 -291.102217) (xy 435.051461 -291.155624) (xy 435.059581 -291.2108)
			(xy 435.06009 -291.238686) (xy 435.059581 -291.266572) (xy 435.051461 -291.321748) (xy 435.035393 -291.375155)
			(xy 435.011721 -291.425652) (xy 434.980948 -291.472165) (xy 434.943731 -291.513702) (xy 434.900863 -291.549377)
			(xy 434.853257 -291.578431) (xy 434.821326 -291.592) (xy 436.741822 -291.592) (xy 436.745893 -291.536378)
			(xy 436.758019 -291.481941) (xy 436.777942 -291.42985) (xy 436.805238 -291.381215) (xy 436.839324 -291.337072)
			(xy 436.879473 -291.298363) (xy 436.924831 -291.265912) (xy 436.974431 -291.240411) (xy 437.027215 -291.222404)
			(xy 437.082058 -291.212274) (xy 437.137792 -291.210237) (xy 437.193229 -291.216337) (xy 437.247186 -291.230443)
			(xy 437.298515 -291.252255) (xy 437.346121 -291.281309) (xy 437.388989 -291.316984) (xy 437.393482 -291.321998)
			(xy 441.5569 -291.321998) (xy 441.560971 -291.266376) (xy 441.573097 -291.211939) (xy 441.59302 -291.159848)
			(xy 441.620316 -291.111213) (xy 441.654402 -291.06707) (xy 441.694551 -291.028361) (xy 441.739909 -290.99591)
			(xy 441.789509 -290.970409) (xy 441.842293 -290.952402) (xy 441.897136 -290.942272) (xy 441.95287 -290.940235)
			(xy 442.008307 -290.946335) (xy 442.062264 -290.960441) (xy 442.113593 -290.982253) (xy 442.161199 -291.011307)
			(xy 442.204067 -291.046982) (xy 442.241284 -291.088519) (xy 442.272057 -291.135032) (xy 442.295729 -291.185529)
			(xy 442.311797 -291.238936) (xy 442.319917 -291.294112) (xy 442.320426 -291.321998) (xy 442.319917 -291.349884)
			(xy 442.311797 -291.40506) (xy 442.295729 -291.458467) (xy 442.272057 -291.508964) (xy 442.241284 -291.555477)
			(xy 442.204067 -291.597014) (xy 442.161199 -291.632689) (xy 442.113593 -291.661743) (xy 442.062264 -291.683555)
			(xy 442.008307 -291.697661) (xy 441.95287 -291.703761) (xy 441.897136 -291.701724) (xy 441.842293 -291.691594)
			(xy 441.789509 -291.673587) (xy 441.739909 -291.648086) (xy 441.694551 -291.615635) (xy 441.654402 -291.576926)
			(xy 441.620316 -291.532783) (xy 441.59302 -291.484148) (xy 441.573097 -291.432057) (xy 441.560971 -291.37762)
			(xy 441.5569 -291.321998) (xy 437.393482 -291.321998) (xy 437.426206 -291.358521) (xy 437.456979 -291.405034)
			(xy 437.480651 -291.455531) (xy 437.496719 -291.508938) (xy 437.504839 -291.564114) (xy 437.505348 -291.592)
			(xy 437.504839 -291.619886) (xy 437.496719 -291.675062) (xy 437.480651 -291.728469) (xy 437.456979 -291.778966)
			(xy 437.426206 -291.825479) (xy 437.388989 -291.867016) (xy 437.346121 -291.902691) (xy 437.298515 -291.931745)
			(xy 437.247186 -291.953557) (xy 437.193229 -291.967663) (xy 437.137792 -291.973763) (xy 437.082058 -291.971726)
			(xy 437.027215 -291.961596) (xy 436.974431 -291.943589) (xy 436.924831 -291.918088) (xy 436.879473 -291.885637)
			(xy 436.839324 -291.846928) (xy 436.805238 -291.802785) (xy 436.777942 -291.75415) (xy 436.758019 -291.702059)
			(xy 436.745893 -291.647622) (xy 436.741822 -291.592) (xy 434.821326 -291.592) (xy 434.801928 -291.600243)
			(xy 434.747971 -291.614349) (xy 434.692534 -291.620449) (xy 434.6368 -291.618412) (xy 434.581957 -291.608282)
			(xy 434.529173 -291.590275) (xy 434.479573 -291.564774) (xy 434.434215 -291.532323) (xy 434.394066 -291.493614)
			(xy 434.35998 -291.449471) (xy 434.332684 -291.400836) (xy 434.312761 -291.348745) (xy 434.300635 -291.294308)
			(xy 434.296564 -291.238686) (xy 432.705764 -291.238686) (xy 432.43881 -291.50564) (xy 432.431969 -291.51304)
			(xy 432.424247 -291.531638) (xy 432.423824 -291.541708) (xy 432.423824 -294.655465) (xy 437.463125 -294.655465)
			(xy 437.47088 -294.601509) (xy 437.486235 -294.549206) (xy 437.508877 -294.499621) (xy 437.538345 -294.453763)
			(xy 437.57404 -294.412565) (xy 437.615234 -294.376867) (xy 437.661089 -294.347394) (xy 437.710673 -294.324748)
			(xy 437.762974 -294.309388) (xy 437.816929 -294.301628) (xy 437.844184 -294.301164) (xy 437.869584 -294.301926)
			(xy 437.884316 -294.302449) (xy 437.913046 -294.295896) (xy 437.938712 -294.281417) (xy 437.959178 -294.260214)
			(xy 437.97274 -294.234052) (xy 437.978272 -294.205107) (xy 437.975313 -294.175788) (xy 437.970168 -294.161972)
			(xy 437.961006 -294.13877) (xy 437.948116 -294.090579) (xy 437.941616 -294.041119) (xy 437.941212 -294.016176)
			(xy 437.941704 -293.988927) (xy 437.949463 -293.934985) (xy 437.96482 -293.882695) (xy 437.987461 -293.833124)
			(xy 438.016927 -293.787279) (xy 438.052618 -293.746094) (xy 438.093806 -293.710407) (xy 438.139653 -293.680945)
			(xy 438.189227 -293.658308) (xy 438.241517 -293.642956) (xy 438.29546 -293.635202) (xy 438.349958 -293.635203)
			(xy 438.403901 -293.64296) (xy 438.456191 -293.658314) (xy 438.505763 -293.680954) (xy 438.551609 -293.710418)
			(xy 438.592796 -293.746107) (xy 438.628484 -293.787294) (xy 438.657948 -293.83314) (xy 438.680587 -293.882713)
			(xy 438.695941 -293.935003) (xy 438.702499 -293.980616) (xy 439.58078 -293.980616) (xy 439.584851 -293.924994)
			(xy 439.596977 -293.870557) (xy 439.6169 -293.818466) (xy 439.644196 -293.769831) (xy 439.678282 -293.725688)
			(xy 439.718431 -293.686979) (xy 439.763789 -293.654528) (xy 439.813389 -293.629027) (xy 439.866173 -293.61102)
			(xy 439.921016 -293.60089) (xy 439.97675 -293.598853) (xy 440.032187 -293.604953) (xy 440.086144 -293.619059)
			(xy 440.137473 -293.640871) (xy 440.185079 -293.669925) (xy 440.227947 -293.7056) (xy 440.265164 -293.747137)
			(xy 440.295937 -293.79365) (xy 440.319609 -293.844147) (xy 440.335677 -293.897554) (xy 440.343797 -293.95273)
			(xy 440.344306 -293.980616) (xy 440.343797 -294.008502) (xy 440.335677 -294.063678) (xy 440.319609 -294.117085)
			(xy 440.295937 -294.167582) (xy 440.265164 -294.214095) (xy 440.227947 -294.255632) (xy 440.185079 -294.291307)
			(xy 440.137473 -294.320361) (xy 440.086144 -294.342173) (xy 440.032187 -294.356279) (xy 439.97675 -294.362379)
			(xy 439.921016 -294.360342) (xy 439.866173 -294.350212) (xy 439.813389 -294.332205) (xy 439.763789 -294.306704)
			(xy 439.718431 -294.274253) (xy 439.678282 -294.235544) (xy 439.644196 -294.191401) (xy 439.6169 -294.142766)
			(xy 439.596977 -294.090675) (xy 439.584851 -294.036238) (xy 439.58078 -293.980616) (xy 438.702499 -293.980616)
			(xy 438.703697 -293.988946) (xy 438.703698 -294.043444) (xy 438.695943 -294.097387) (xy 438.680591 -294.149677)
			(xy 438.657953 -294.19925) (xy 438.62849 -294.245098) (xy 438.592803 -294.286285) (xy 438.551618 -294.321975)
			(xy 438.505773 -294.351441) (xy 438.456201 -294.374082) (xy 438.403911 -294.389438) (xy 438.349969 -294.397196)
			(xy 438.32272 -294.397684) (xy 438.29732 -294.396922) (xy 438.28259 -294.396475) (xy 438.253872 -294.403022)
			(xy 438.228216 -294.417492) (xy 438.207756 -294.438681) (xy 438.194192 -294.464827) (xy 438.188653 -294.493757)
			(xy 438.189439 -294.50157) (xy 438.83656 -294.50157) (xy 438.840631 -294.445948) (xy 438.852757 -294.391511)
			(xy 438.87268 -294.33942) (xy 438.899976 -294.290785) (xy 438.934062 -294.246642) (xy 438.974211 -294.207933)
			(xy 439.019569 -294.175482) (xy 439.069169 -294.149981) (xy 439.121953 -294.131974) (xy 439.176796 -294.121844)
			(xy 439.23253 -294.119807) (xy 439.287967 -294.125907) (xy 439.341924 -294.140013) (xy 439.393253 -294.161825)
			(xy 439.440859 -294.190879) (xy 439.483727 -294.226554) (xy 439.520944 -294.268091) (xy 439.551717 -294.314604)
			(xy 439.575389 -294.365101) (xy 439.591457 -294.418508) (xy 439.599577 -294.473684) (xy 439.600086 -294.50157)
			(xy 439.599577 -294.529456) (xy 439.591457 -294.584632) (xy 439.575389 -294.638039) (xy 439.551717 -294.688536)
			(xy 439.520944 -294.735049) (xy 439.483727 -294.776586) (xy 439.440859 -294.812261) (xy 439.393253 -294.841315)
			(xy 439.341924 -294.863127) (xy 439.287967 -294.877233) (xy 439.23253 -294.883333) (xy 439.176796 -294.881296)
			(xy 439.121953 -294.871166) (xy 439.069169 -294.853159) (xy 439.019569 -294.827658) (xy 438.974211 -294.795207)
			(xy 438.934062 -294.756498) (xy 438.899976 -294.712355) (xy 438.87268 -294.66372) (xy 438.852757 -294.611629)
			(xy 438.840631 -294.557192) (xy 438.83656 -294.50157) (xy 438.189439 -294.50157) (xy 438.1916 -294.523064)
			(xy 438.196736 -294.536876) (xy 438.205882 -294.560084) (xy 438.218779 -294.608272) (xy 438.225284 -294.65773)
			(xy 438.225692 -294.682672) (xy 438.225275 -294.709927) (xy 438.217521 -294.763883) (xy 438.202168 -294.816186)
			(xy 438.179527 -294.865772) (xy 438.15006 -294.911631) (xy 438.114366 -294.952829) (xy 438.073172 -294.988529)
			(xy 438.027318 -295.018002) (xy 437.977735 -295.04065) (xy 437.925434 -295.05601) (xy 437.871479 -295.063771)
			(xy 437.816969 -295.063775) (xy 437.763013 -295.056021) (xy 437.71071 -295.040666) (xy 437.661125 -295.018025)
			(xy 437.615266 -294.988557) (xy 437.574068 -294.952863) (xy 437.538369 -294.911669) (xy 437.508896 -294.865814)
			(xy 437.486249 -294.816231) (xy 437.470889 -294.76393) (xy 437.463128 -294.709975) (xy 437.463125 -294.655465)
			(xy 432.423824 -294.655465) (xy 432.423824 -295.355518) (xy 440.915804 -295.355518) (xy 440.919875 -295.299896)
			(xy 440.932001 -295.245459) (xy 440.951924 -295.193368) (xy 440.97922 -295.144733) (xy 441.013306 -295.10059)
			(xy 441.053455 -295.061881) (xy 441.098813 -295.02943) (xy 441.148413 -295.003929) (xy 441.201197 -294.985922)
			(xy 441.25604 -294.975792) (xy 441.311774 -294.973755) (xy 441.367211 -294.979855) (xy 441.421168 -294.993961)
			(xy 441.472497 -295.015773) (xy 441.520103 -295.044827) (xy 441.562971 -295.080502) (xy 441.600188 -295.122039)
			(xy 441.630961 -295.168552) (xy 441.654633 -295.219049) (xy 441.670701 -295.272456) (xy 441.678821 -295.327632)
			(xy 441.67933 -295.355518) (xy 441.678821 -295.383404) (xy 441.670701 -295.43858) (xy 441.654633 -295.491987)
			(xy 441.630961 -295.542484) (xy 441.600188 -295.588997) (xy 441.562971 -295.630534) (xy 441.520103 -295.666209)
			(xy 441.472497 -295.695263) (xy 441.421168 -295.717075) (xy 441.367211 -295.731181) (xy 441.311774 -295.737281)
			(xy 441.25604 -295.735244) (xy 441.201197 -295.725114) (xy 441.148413 -295.707107) (xy 441.098813 -295.681606)
			(xy 441.053455 -295.649155) (xy 441.013306 -295.610446) (xy 440.97922 -295.566303) (xy 440.951924 -295.517668)
			(xy 440.932001 -295.465577) (xy 440.919875 -295.41114) (xy 440.915804 -295.355518) (xy 432.423824 -295.355518)
			(xy 432.423824 -296.613072) (xy 437.562496 -296.613072) (xy 437.566567 -296.55745) (xy 437.578693 -296.503013)
			(xy 437.598616 -296.450922) (xy 437.625912 -296.402287) (xy 437.659998 -296.358144) (xy 437.700147 -296.319435)
			(xy 437.745505 -296.286984) (xy 437.795105 -296.261483) (xy 437.847889 -296.243476) (xy 437.902732 -296.233346)
			(xy 437.958466 -296.231309) (xy 438.013903 -296.237409) (xy 438.06786 -296.251515) (xy 438.119189 -296.273327)
			(xy 438.166795 -296.302381) (xy 438.209663 -296.338056) (xy 438.24688 -296.379593) (xy 438.277653 -296.426106)
			(xy 438.301325 -296.476603) (xy 438.317393 -296.53001) (xy 438.325513 -296.585186) (xy 438.326022 -296.613072)
			(xy 438.837322 -296.613072) (xy 438.841393 -296.55745) (xy 438.853519 -296.503013) (xy 438.873442 -296.450922)
			(xy 438.900738 -296.402287) (xy 438.934824 -296.358144) (xy 438.974973 -296.319435) (xy 439.020331 -296.286984)
			(xy 439.069931 -296.261483) (xy 439.122715 -296.243476) (xy 439.177558 -296.233346) (xy 439.233292 -296.231309)
			(xy 439.288729 -296.237409) (xy 439.342686 -296.251515) (xy 439.394015 -296.273327) (xy 439.441621 -296.302381)
			(xy 439.484489 -296.338056) (xy 439.521706 -296.379593) (xy 439.552479 -296.426106) (xy 439.576151 -296.476603)
			(xy 439.592219 -296.53001) (xy 439.600339 -296.585186) (xy 439.600848 -296.613072) (xy 439.600339 -296.640958)
			(xy 439.592219 -296.696134) (xy 439.576151 -296.749541) (xy 439.552479 -296.800038) (xy 439.521706 -296.846551)
			(xy 439.484489 -296.888088) (xy 439.441621 -296.923763) (xy 439.394015 -296.952817) (xy 439.342686 -296.974629)
			(xy 439.288729 -296.988735) (xy 439.233292 -296.994835) (xy 439.177558 -296.992798) (xy 439.122715 -296.982668)
			(xy 439.069931 -296.964661) (xy 439.020331 -296.93916) (xy 438.974973 -296.906709) (xy 438.934824 -296.868)
			(xy 438.900738 -296.823857) (xy 438.873442 -296.775222) (xy 438.853519 -296.723131) (xy 438.841393 -296.668694)
			(xy 438.837322 -296.613072) (xy 438.326022 -296.613072) (xy 438.325513 -296.640958) (xy 438.317393 -296.696134)
			(xy 438.301325 -296.749541) (xy 438.277653 -296.800038) (xy 438.24688 -296.846551) (xy 438.209663 -296.888088)
			(xy 438.166795 -296.923763) (xy 438.119189 -296.952817) (xy 438.06786 -296.974629) (xy 438.013903 -296.988735)
			(xy 437.958466 -296.994835) (xy 437.902732 -296.992798) (xy 437.847889 -296.982668) (xy 437.795105 -296.964661)
			(xy 437.745505 -296.93916) (xy 437.700147 -296.906709) (xy 437.659998 -296.868) (xy 437.625912 -296.823857)
			(xy 437.598616 -296.775222) (xy 437.578693 -296.723131) (xy 437.566567 -296.668694) (xy 437.562496 -296.613072)
			(xy 432.423824 -296.613072) (xy 432.423824 -297.834558) (xy 432.424466 -297.846495) (xy 432.435192 -297.867827)
			(xy 432.444398 -297.875452) (xy 432.519328 -297.931332) (xy 432.54295 -297.935396) (xy 432.55438 -297.932094)
			(xy 432.581069 -297.924641) (xy 432.635895 -297.916613) (xy 432.6636 -297.916092) (xy 432.688532 -297.916496)
			(xy 432.737971 -297.922986) (xy 432.786145 -297.935855) (xy 432.832235 -297.954883) (xy 432.875456 -297.979749)
			(xy 432.895502 -297.994578) (xy 432.906678 -298.003214) (xy 432.933856 -298.006516) (xy 433.041044 -297.959526)
			(xy 433.057046 -297.937174) (xy 433.058316 -297.923458) (xy 433.06141 -297.895395) (xy 433.074814 -297.840553)
			(xy 433.096156 -297.788285) (xy 433.12497 -297.739735) (xy 433.160626 -297.695963) (xy 433.202346 -297.657926)
			(xy 433.249217 -297.626454) (xy 433.300216 -297.602236) (xy 433.354227 -297.585801) (xy 433.410071 -297.577507)
			(xy 433.4383 -297.577002) (xy 433.46555 -297.577488) (xy 433.519497 -297.585245) (xy 433.57179 -297.600599)
			(xy 433.621366 -297.62324) (xy 433.667215 -297.652705) (xy 433.693291 -297.6753) (xy 434.599586 -297.6753)
			(xy 434.603657 -297.619678) (xy 434.615783 -297.565241) (xy 434.635706 -297.51315) (xy 434.663002 -297.464515)
			(xy 434.697088 -297.420372) (xy 434.737237 -297.381663) (xy 434.782595 -297.349212) (xy 434.832195 -297.323711)
			(xy 434.884979 -297.305704) (xy 434.939822 -297.295574) (xy 434.995556 -297.293537) (xy 435.050993 -297.299637)
			(xy 435.10495 -297.313743) (xy 435.156279 -297.335555) (xy 435.203885 -297.364609) (xy 435.216152 -297.374818)
			(xy 440.915804 -297.374818) (xy 440.919875 -297.319196) (xy 440.932001 -297.264759) (xy 440.951924 -297.212668)
			(xy 440.97922 -297.164033) (xy 441.013306 -297.11989) (xy 441.053455 -297.081181) (xy 441.098813 -297.04873)
			(xy 441.148413 -297.023229) (xy 441.201197 -297.005222) (xy 441.25604 -296.995092) (xy 441.311774 -296.993055)
			(xy 441.367211 -296.999155) (xy 441.421168 -297.013261) (xy 441.472497 -297.035073) (xy 441.520103 -297.064127)
			(xy 441.562971 -297.099802) (xy 441.600188 -297.141339) (xy 441.630961 -297.187852) (xy 441.654633 -297.238349)
			(xy 441.670701 -297.291756) (xy 441.678821 -297.346932) (xy 441.67933 -297.374818) (xy 441.678821 -297.402704)
			(xy 441.670701 -297.45788) (xy 441.654633 -297.511287) (xy 441.630961 -297.561784) (xy 441.600188 -297.608297)
			(xy 441.562971 -297.649834) (xy 441.520103 -297.685509) (xy 441.472497 -297.714563) (xy 441.421168 -297.736375)
			(xy 441.367211 -297.750481) (xy 441.311774 -297.756581) (xy 441.25604 -297.754544) (xy 441.201197 -297.744414)
			(xy 441.148413 -297.726407) (xy 441.098813 -297.700906) (xy 441.053455 -297.668455) (xy 441.013306 -297.629746)
			(xy 440.97922 -297.585603) (xy 440.951924 -297.536968) (xy 440.932001 -297.484877) (xy 440.919875 -297.43044)
			(xy 440.915804 -297.374818) (xy 435.216152 -297.374818) (xy 435.246753 -297.400284) (xy 435.28397 -297.441821)
			(xy 435.314743 -297.488334) (xy 435.338415 -297.538831) (xy 435.354483 -297.592238) (xy 435.362603 -297.647414)
			(xy 435.363112 -297.6753) (xy 435.362603 -297.703186) (xy 435.354483 -297.758362) (xy 435.338415 -297.811769)
			(xy 435.314743 -297.862266) (xy 435.28397 -297.908779) (xy 435.246753 -297.950316) (xy 435.203885 -297.985991)
			(xy 435.156279 -298.015045) (xy 435.10495 -298.036857) (xy 435.050993 -298.050963) (xy 434.995556 -298.057063)
			(xy 434.939822 -298.055026) (xy 434.884979 -298.044896) (xy 434.832195 -298.026889) (xy 434.782595 -298.001388)
			(xy 434.737237 -297.968937) (xy 434.697088 -297.930228) (xy 434.663002 -297.886085) (xy 434.635706 -297.83745)
			(xy 434.615783 -297.785359) (xy 434.603657 -297.730922) (xy 434.599586 -297.6753) (xy 433.693291 -297.6753)
			(xy 433.708404 -297.688396) (xy 433.744095 -297.729585) (xy 433.77356 -297.775434) (xy 433.796201 -297.82501)
			(xy 433.811555 -297.877303) (xy 433.819312 -297.93125) (xy 433.819312 -297.98575) (xy 433.811555 -298.039697)
			(xy 433.796201 -298.09199) (xy 433.77356 -298.141566) (xy 433.744095 -298.187415) (xy 433.708404 -298.228604)
			(xy 433.667215 -298.264295) (xy 433.621366 -298.29376) (xy 433.57179 -298.316401) (xy 433.519497 -298.331755)
			(xy 433.46555 -298.339512) (xy 433.4383 -298.340018) (xy 433.413368 -298.339614) (xy 433.363929 -298.333124)
			(xy 433.315754 -298.320256) (xy 433.269665 -298.301227) (xy 433.226443 -298.276362) (xy 433.206398 -298.261532)
			(xy 433.195222 -298.252896) (xy 433.168044 -298.249594) (xy 433.060856 -298.296584) (xy 433.044854 -298.318936)
			(xy 433.043584 -298.332652) (xy 433.040489 -298.360714) (xy 433.027084 -298.415556) (xy 433.005742 -298.467822)
			(xy 432.976927 -298.516371) (xy 432.941271 -298.560142) (xy 432.899551 -298.598178) (xy 432.85268 -298.629648)
			(xy 432.801682 -298.653866) (xy 432.747672 -298.6703) (xy 432.691828 -298.678594) (xy 432.6636 -298.679108)
			(xy 432.635893 -298.678613) (xy 432.581065 -298.670579) (xy 432.55438 -298.663106) (xy 432.54295 -298.659804)
			(xy 432.519328 -298.663868) (xy 432.452572 -298.713652) (xy 434.780688 -298.713652) (xy 434.784759 -298.65803)
			(xy 434.796885 -298.603593) (xy 434.816808 -298.551502) (xy 434.844104 -298.502867) (xy 434.87819 -298.458724)
			(xy 434.918339 -298.420015) (xy 434.963697 -298.387564) (xy 435.013297 -298.362063) (xy 435.066081 -298.344056)
			(xy 435.120924 -298.333926) (xy 435.176658 -298.331889) (xy 435.232095 -298.337989) (xy 435.286052 -298.352095)
			(xy 435.337381 -298.373907) (xy 435.384987 -298.402961) (xy 435.427855 -298.438636) (xy 435.465072 -298.480173)
			(xy 435.495845 -298.526686) (xy 435.519517 -298.577183) (xy 435.535585 -298.63059) (xy 435.543705 -298.685766)
			(xy 435.544214 -298.713652) (xy 435.543705 -298.741538) (xy 435.535585 -298.796714) (xy 435.519517 -298.850121)
			(xy 435.495845 -298.900618) (xy 435.465072 -298.947131) (xy 435.427855 -298.988668) (xy 435.384987 -299.024343)
			(xy 435.337381 -299.053397) (xy 435.286052 -299.075209) (xy 435.232095 -299.089315) (xy 435.176658 -299.095415)
			(xy 435.120924 -299.093378) (xy 435.066081 -299.083248) (xy 435.013297 -299.065241) (xy 434.963697 -299.03974)
			(xy 434.918339 -299.007289) (xy 434.87819 -298.96858) (xy 434.844104 -298.924437) (xy 434.816808 -298.875802)
			(xy 434.796885 -298.823711) (xy 434.784759 -298.769274) (xy 434.780688 -298.713652) (xy 432.452572 -298.713652)
			(xy 432.444398 -298.719748) (xy 432.435164 -298.727356) (xy 432.424414 -298.748694) (xy 432.423824 -298.760642)
			(xy 432.423824 -299.27296) (xy 438.614564 -299.27296) (xy 438.618635 -299.217338) (xy 438.630761 -299.162901)
			(xy 438.650684 -299.11081) (xy 438.67798 -299.062175) (xy 438.712066 -299.018032) (xy 438.752215 -298.979323)
			(xy 438.797573 -298.946872) (xy 438.847173 -298.921371) (xy 438.899957 -298.903364) (xy 438.9548 -298.893234)
			(xy 439.010534 -298.891197) (xy 439.065971 -298.897297) (xy 439.119928 -298.911403) (xy 439.171257 -298.933215)
			(xy 439.218863 -298.962269) (xy 439.261731 -298.997944) (xy 439.298948 -299.039481) (xy 439.329721 -299.085994)
			(xy 439.353393 -299.136491) (xy 439.369461 -299.189898) (xy 439.377581 -299.245074) (xy 439.37809 -299.27296)
			(xy 439.377581 -299.300846) (xy 439.369461 -299.356022) (xy 439.353393 -299.409429) (xy 439.329721 -299.459926)
			(xy 439.298948 -299.506439) (xy 439.261731 -299.547976) (xy 439.218863 -299.583651) (xy 439.171257 -299.612705)
			(xy 439.119928 -299.634517) (xy 439.065971 -299.648623) (xy 439.010534 -299.654723) (xy 438.9548 -299.652686)
			(xy 438.899957 -299.642556) (xy 438.847173 -299.624549) (xy 438.797573 -299.599048) (xy 438.752215 -299.566597)
			(xy 438.712066 -299.527888) (xy 438.67798 -299.483745) (xy 438.650684 -299.43511) (xy 438.630761 -299.383019)
			(xy 438.618635 -299.328582) (xy 438.614564 -299.27296) (xy 432.423824 -299.27296) (xy 432.423824 -299.76445)
			(xy 436.341772 -299.76445) (xy 436.345843 -299.708828) (xy 436.357969 -299.654391) (xy 436.377892 -299.6023)
			(xy 436.405188 -299.553665) (xy 436.439274 -299.509522) (xy 436.479423 -299.470813) (xy 436.524781 -299.438362)
			(xy 436.574381 -299.412861) (xy 436.627165 -299.394854) (xy 436.682008 -299.384724) (xy 436.737742 -299.382687)
			(xy 436.793179 -299.388787) (xy 436.847136 -299.402893) (xy 436.898465 -299.424705) (xy 436.946071 -299.453759)
			(xy 436.988939 -299.489434) (xy 437.026156 -299.530971) (xy 437.056929 -299.577484) (xy 437.080601 -299.627981)
			(xy 437.096669 -299.681388) (xy 437.104789 -299.736564) (xy 437.105298 -299.76445) (xy 437.10502 -299.77969)
			(xy 440.93841 -299.77969) (xy 440.942481 -299.724068) (xy 440.954607 -299.669631) (xy 440.97453 -299.61754)
			(xy 441.001826 -299.568905) (xy 441.035912 -299.524762) (xy 441.076061 -299.486053) (xy 441.121419 -299.453602)
			(xy 441.171019 -299.428101) (xy 441.223803 -299.410094) (xy 441.278646 -299.399964) (xy 441.33438 -299.397927)
			(xy 441.389817 -299.404027) (xy 441.443774 -299.418133) (xy 441.495103 -299.439945) (xy 441.542709 -299.468999)
			(xy 441.585577 -299.504674) (xy 441.622794 -299.546211) (xy 441.653567 -299.592724) (xy 441.677239 -299.643221)
			(xy 441.693307 -299.696628) (xy 441.701427 -299.751804) (xy 441.701936 -299.77969) (xy 441.701427 -299.807576)
			(xy 441.693307 -299.862752) (xy 441.677239 -299.916159) (xy 441.653567 -299.966656) (xy 441.622794 -300.013169)
			(xy 441.585577 -300.054706) (xy 441.542709 -300.090381) (xy 441.495103 -300.119435) (xy 441.443774 -300.141247)
			(xy 441.389817 -300.155353) (xy 441.33438 -300.161453) (xy 441.278646 -300.159416) (xy 441.223803 -300.149286)
			(xy 441.171019 -300.131279) (xy 441.121419 -300.105778) (xy 441.076061 -300.073327) (xy 441.035912 -300.034618)
			(xy 441.001826 -299.990475) (xy 440.97453 -299.94184) (xy 440.954607 -299.889749) (xy 440.942481 -299.835312)
			(xy 440.93841 -299.77969) (xy 437.10502 -299.77969) (xy 437.104789 -299.792336) (xy 437.096669 -299.847512)
			(xy 437.080601 -299.900919) (xy 437.056929 -299.951416) (xy 437.026156 -299.997929) (xy 436.988939 -300.039466)
			(xy 436.946071 -300.075141) (xy 436.898465 -300.104195) (xy 436.847136 -300.126007) (xy 436.793179 -300.140113)
			(xy 436.737742 -300.146213) (xy 436.682008 -300.144176) (xy 436.627165 -300.134046) (xy 436.574381 -300.116039)
			(xy 436.524781 -300.090538) (xy 436.479423 -300.058087) (xy 436.439274 -300.019378) (xy 436.405188 -299.975235)
			(xy 436.377892 -299.9266) (xy 436.357969 -299.874509) (xy 436.345843 -299.820072) (xy 436.341772 -299.76445)
			(xy 432.423824 -299.76445) (xy 432.423824 -301.04207) (xy 438.617104 -301.04207) (xy 438.621175 -300.986448)
			(xy 438.633301 -300.932011) (xy 438.653224 -300.87992) (xy 438.68052 -300.831285) (xy 438.714606 -300.787142)
			(xy 438.754755 -300.748433) (xy 438.800113 -300.715982) (xy 438.849713 -300.690481) (xy 438.902497 -300.672474)
			(xy 438.95734 -300.662344) (xy 439.013074 -300.660307) (xy 439.068511 -300.666407) (xy 439.122468 -300.680513)
			(xy 439.173797 -300.702325) (xy 439.221403 -300.731379) (xy 439.264271 -300.767054) (xy 439.301488 -300.808591)
			(xy 439.332261 -300.855104) (xy 439.355933 -300.905601) (xy 439.372001 -300.959008) (xy 439.380121 -301.014184)
			(xy 439.38063 -301.04207) (xy 439.380477 -301.050452) (xy 440.990988 -301.050452) (xy 440.995059 -300.99483)
			(xy 441.007185 -300.940393) (xy 441.027108 -300.888302) (xy 441.054404 -300.839667) (xy 441.08849 -300.795524)
			(xy 441.128639 -300.756815) (xy 441.173997 -300.724364) (xy 441.223597 -300.698863) (xy 441.276381 -300.680856)
			(xy 441.331224 -300.670726) (xy 441.386958 -300.668689) (xy 441.442395 -300.674789) (xy 441.496352 -300.688895)
			(xy 441.547681 -300.710707) (xy 441.595287 -300.739761) (xy 441.638155 -300.775436) (xy 441.675372 -300.816973)
			(xy 441.706145 -300.863486) (xy 441.729817 -300.913983) (xy 441.745885 -300.96739) (xy 441.754005 -301.022566)
			(xy 441.754514 -301.050452) (xy 441.754005 -301.078338) (xy 441.745885 -301.133514) (xy 441.729817 -301.186921)
			(xy 441.706145 -301.237418) (xy 441.675372 -301.283931) (xy 441.638155 -301.325468) (xy 441.595287 -301.361143)
			(xy 441.547681 -301.390197) (xy 441.496352 -301.412009) (xy 441.442395 -301.426115) (xy 441.386958 -301.432215)
			(xy 441.331224 -301.430178) (xy 441.276381 -301.420048) (xy 441.223597 -301.402041) (xy 441.173997 -301.37654)
			(xy 441.128639 -301.344089) (xy 441.08849 -301.30538) (xy 441.054404 -301.261237) (xy 441.027108 -301.212602)
			(xy 441.007185 -301.160511) (xy 440.995059 -301.106074) (xy 440.990988 -301.050452) (xy 439.380477 -301.050452)
			(xy 439.380121 -301.069956) (xy 439.372001 -301.125132) (xy 439.355933 -301.178539) (xy 439.332261 -301.229036)
			(xy 439.301488 -301.275549) (xy 439.264271 -301.317086) (xy 439.221403 -301.352761) (xy 439.173797 -301.381815)
			(xy 439.122468 -301.403627) (xy 439.068511 -301.417733) (xy 439.013074 -301.423833) (xy 438.95734 -301.421796)
			(xy 438.902497 -301.411666) (xy 438.849713 -301.393659) (xy 438.800113 -301.368158) (xy 438.754755 -301.335707)
			(xy 438.714606 -301.296998) (xy 438.68052 -301.252855) (xy 438.653224 -301.20422) (xy 438.633301 -301.152129)
			(xy 438.621175 -301.097692) (xy 438.617104 -301.04207) (xy 432.423824 -301.04207) (xy 432.423824 -302.062134)
			(xy 433.675788 -302.062134) (xy 433.679859 -302.006512) (xy 433.691985 -301.952075) (xy 433.711908 -301.899984)
			(xy 433.739204 -301.851349) (xy 433.77329 -301.807206) (xy 433.813439 -301.768497) (xy 433.858797 -301.736046)
			(xy 433.908397 -301.710545) (xy 433.961181 -301.692538) (xy 434.016024 -301.682408) (xy 434.071758 -301.680371)
			(xy 434.127195 -301.686471) (xy 434.181152 -301.700577) (xy 434.232481 -301.722389) (xy 434.280087 -301.751443)
			(xy 434.322955 -301.787118) (xy 434.360172 -301.828655) (xy 434.390945 -301.875168) (xy 434.392741 -301.879)
			(xy 434.647592 -301.879) (xy 434.651663 -301.823378) (xy 434.663789 -301.768941) (xy 434.683712 -301.71685)
			(xy 434.711008 -301.668215) (xy 434.745094 -301.624072) (xy 434.785243 -301.585363) (xy 434.830601 -301.552912)
			(xy 434.880201 -301.527411) (xy 434.932985 -301.509404) (xy 434.987828 -301.499274) (xy 435.043562 -301.497237)
			(xy 435.098999 -301.503337) (xy 435.152956 -301.517443) (xy 435.204285 -301.539255) (xy 435.226168 -301.55261)
			(xy 436.41975 -301.55261) (xy 436.423821 -301.496988) (xy 436.435947 -301.442551) (xy 436.45587 -301.39046)
			(xy 436.483166 -301.341825) (xy 436.517252 -301.297682) (xy 436.557401 -301.258973) (xy 436.602759 -301.226522)
			(xy 436.652359 -301.201021) (xy 436.705143 -301.183014) (xy 436.759986 -301.172884) (xy 436.81572 -301.170847)
			(xy 436.871157 -301.176947) (xy 436.925114 -301.191053) (xy 436.976443 -301.212865) (xy 437.024049 -301.241919)
			(xy 437.066917 -301.277594) (xy 437.104134 -301.319131) (xy 437.134907 -301.365644) (xy 437.158579 -301.416141)
			(xy 437.174647 -301.469548) (xy 437.182767 -301.524724) (xy 437.183276 -301.55261) (xy 437.182836 -301.57674)
			(xy 439.81319 -301.57674) (xy 439.817261 -301.521118) (xy 439.829387 -301.466681) (xy 439.84931 -301.41459)
			(xy 439.876606 -301.365955) (xy 439.910692 -301.321812) (xy 439.950841 -301.283103) (xy 439.996199 -301.250652)
			(xy 440.045799 -301.225151) (xy 440.098583 -301.207144) (xy 440.153426 -301.197014) (xy 440.20916 -301.194977)
			(xy 440.264597 -301.201077) (xy 440.318554 -301.215183) (xy 440.369883 -301.236995) (xy 440.417489 -301.266049)
			(xy 440.460357 -301.301724) (xy 440.497574 -301.343261) (xy 440.528347 -301.389774) (xy 440.552019 -301.440271)
			(xy 440.568087 -301.493678) (xy 440.576207 -301.548854) (xy 440.576716 -301.57674) (xy 440.576207 -301.604626)
			(xy 440.568087 -301.659802) (xy 440.552019 -301.713209) (xy 440.528347 -301.763706) (xy 440.497574 -301.810219)
			(xy 440.460357 -301.851756) (xy 440.417489 -301.887431) (xy 440.369883 -301.916485) (xy 440.318554 -301.938297)
			(xy 440.264597 -301.952403) (xy 440.20916 -301.958503) (xy 440.153426 -301.956466) (xy 440.098583 -301.946336)
			(xy 440.045799 -301.928329) (xy 439.996199 -301.902828) (xy 439.950841 -301.870377) (xy 439.910692 -301.831668)
			(xy 439.876606 -301.787525) (xy 439.84931 -301.73889) (xy 439.829387 -301.686799) (xy 439.817261 -301.632362)
			(xy 439.81319 -301.57674) (xy 437.182836 -301.57674) (xy 437.182767 -301.580496) (xy 437.174647 -301.635672)
			(xy 437.158579 -301.689079) (xy 437.134907 -301.739576) (xy 437.104134 -301.786089) (xy 437.066917 -301.827626)
			(xy 437.024049 -301.863301) (xy 436.976443 -301.892355) (xy 436.925114 -301.914167) (xy 436.871157 -301.928273)
			(xy 436.81572 -301.934373) (xy 436.759986 -301.932336) (xy 436.705143 -301.922206) (xy 436.652359 -301.904199)
			(xy 436.602759 -301.878698) (xy 436.557401 -301.846247) (xy 436.517252 -301.807538) (xy 436.483166 -301.763395)
			(xy 436.45587 -301.71476) (xy 436.435947 -301.662669) (xy 436.423821 -301.608232) (xy 436.41975 -301.55261)
			(xy 435.226168 -301.55261) (xy 435.251891 -301.568309) (xy 435.294759 -301.603984) (xy 435.331976 -301.645521)
			(xy 435.362749 -301.692034) (xy 435.386421 -301.742531) (xy 435.402489 -301.795938) (xy 435.410609 -301.851114)
			(xy 435.411118 -301.879) (xy 435.410609 -301.906886) (xy 435.402489 -301.962062) (xy 435.386421 -302.015469)
			(xy 435.362749 -302.065966) (xy 435.331976 -302.112479) (xy 435.294759 -302.154016) (xy 435.251891 -302.189691)
			(xy 435.204285 -302.218745) (xy 435.152956 -302.240557) (xy 435.098999 -302.254663) (xy 435.043562 -302.260763)
			(xy 434.987828 -302.258726) (xy 434.932985 -302.248596) (xy 434.880201 -302.230589) (xy 434.830601 -302.205088)
			(xy 434.785243 -302.172637) (xy 434.745094 -302.133928) (xy 434.711008 -302.089785) (xy 434.683712 -302.04115)
			(xy 434.663789 -301.989059) (xy 434.651663 -301.934622) (xy 434.647592 -301.879) (xy 434.392741 -301.879)
			(xy 434.414617 -301.925665) (xy 434.430685 -301.979072) (xy 434.438805 -302.034248) (xy 434.439314 -302.062134)
			(xy 434.438805 -302.09002) (xy 434.430685 -302.145196) (xy 434.414617 -302.198603) (xy 434.390945 -302.2491)
			(xy 434.360172 -302.295613) (xy 434.322955 -302.33715) (xy 434.280087 -302.372825) (xy 434.232481 -302.401879)
			(xy 434.181152 -302.423691) (xy 434.127195 -302.437797) (xy 434.071758 -302.443897) (xy 434.016024 -302.44186)
			(xy 433.961181 -302.43173) (xy 433.908397 -302.413723) (xy 433.858797 -302.388222) (xy 433.813439 -302.355771)
			(xy 433.77329 -302.317062) (xy 433.739204 -302.272919) (xy 433.711908 -302.224284) (xy 433.691985 -302.172193)
			(xy 433.679859 -302.117756) (xy 433.675788 -302.062134) (xy 432.423824 -302.062134) (xy 432.423824 -303.237392)
			(xy 434.411374 -303.237392) (xy 434.41186 -303.210141) (xy 434.419616 -303.156193) (xy 434.434971 -303.103898)
			(xy 434.457613 -303.054321) (xy 434.487079 -303.008471) (xy 434.52277 -302.96728) (xy 434.563961 -302.931589)
			(xy 434.609811 -302.902123) (xy 434.659388 -302.879481) (xy 434.711683 -302.864126) (xy 434.765631 -302.85637)
			(xy 434.820133 -302.85637) (xy 434.874081 -302.864126) (xy 434.926376 -302.879481) (xy 434.975953 -302.902123)
			(xy 435.021803 -302.931589) (xy 435.062994 -302.96728) (xy 435.098685 -303.008471) (xy 435.110481 -303.026826)
			(xy 436.919622 -303.026826) (xy 436.923693 -302.971204) (xy 436.935819 -302.916767) (xy 436.955742 -302.864676)
			(xy 436.983038 -302.816041) (xy 437.017124 -302.771898) (xy 437.057273 -302.733189) (xy 437.102631 -302.700738)
			(xy 437.152231 -302.675237) (xy 437.205015 -302.65723) (xy 437.259858 -302.6471) (xy 437.315592 -302.645063)
			(xy 437.371029 -302.651163) (xy 437.424986 -302.665269) (xy 437.476315 -302.687081) (xy 437.523921 -302.716135)
			(xy 437.566789 -302.75181) (xy 437.604006 -302.793347) (xy 437.634779 -302.83986) (xy 437.658451 -302.890357)
			(xy 437.674519 -302.943764) (xy 437.682639 -302.99894) (xy 437.683148 -303.026826) (xy 437.935622 -303.026826)
			(xy 437.939693 -302.971204) (xy 437.951819 -302.916767) (xy 437.971742 -302.864676) (xy 437.999038 -302.816041)
			(xy 438.033124 -302.771898) (xy 438.073273 -302.733189) (xy 438.118631 -302.700738) (xy 438.168231 -302.675237)
			(xy 438.221015 -302.65723) (xy 438.275858 -302.6471) (xy 438.331592 -302.645063) (xy 438.387029 -302.651163)
			(xy 438.440986 -302.665269) (xy 438.492315 -302.687081) (xy 438.539921 -302.716135) (xy 438.582789 -302.75181)
			(xy 438.620006 -302.793347) (xy 438.650779 -302.83986) (xy 438.674451 -302.890357) (xy 438.690519 -302.943764)
			(xy 438.698639 -302.99894) (xy 438.699148 -303.026826) (xy 438.951622 -303.026826) (xy 438.955693 -302.971204)
			(xy 438.967819 -302.916767) (xy 438.987742 -302.864676) (xy 439.015038 -302.816041) (xy 439.049124 -302.771898)
			(xy 439.089273 -302.733189) (xy 439.134631 -302.700738) (xy 439.184231 -302.675237) (xy 439.237015 -302.65723)
			(xy 439.291858 -302.6471) (xy 439.347592 -302.645063) (xy 439.403029 -302.651163) (xy 439.456986 -302.665269)
			(xy 439.508315 -302.687081) (xy 439.555921 -302.716135) (xy 439.598789 -302.75181) (xy 439.636006 -302.793347)
			(xy 439.666779 -302.83986) (xy 439.690451 -302.890357) (xy 439.706519 -302.943764) (xy 439.714639 -302.99894)
			(xy 439.715148 -303.026826) (xy 439.967622 -303.026826) (xy 439.971693 -302.971204) (xy 439.983819 -302.916767)
			(xy 440.003742 -302.864676) (xy 440.031038 -302.816041) (xy 440.065124 -302.771898) (xy 440.105273 -302.733189)
			(xy 440.150631 -302.700738) (xy 440.200231 -302.675237) (xy 440.253015 -302.65723) (xy 440.307858 -302.6471)
			(xy 440.363592 -302.645063) (xy 440.419029 -302.651163) (xy 440.472986 -302.665269) (xy 440.524315 -302.687081)
			(xy 440.571921 -302.716135) (xy 440.614789 -302.75181) (xy 440.652006 -302.793347) (xy 440.682779 -302.83986)
			(xy 440.706451 -302.890357) (xy 440.722519 -302.943764) (xy 440.730639 -302.99894) (xy 440.731148 -303.026826)
			(xy 440.983622 -303.026826) (xy 440.987693 -302.971204) (xy 440.999819 -302.916767) (xy 441.019742 -302.864676)
			(xy 441.047038 -302.816041) (xy 441.081124 -302.771898) (xy 441.121273 -302.733189) (xy 441.166631 -302.700738)
			(xy 441.216231 -302.675237) (xy 441.269015 -302.65723) (xy 441.323858 -302.6471) (xy 441.379592 -302.645063)
			(xy 441.435029 -302.651163) (xy 441.488986 -302.665269) (xy 441.540315 -302.687081) (xy 441.587921 -302.716135)
			(xy 441.630789 -302.75181) (xy 441.668006 -302.793347) (xy 441.698779 -302.83986) (xy 441.722451 -302.890357)
			(xy 441.738519 -302.943764) (xy 441.746639 -302.99894) (xy 441.747148 -303.026826) (xy 441.746639 -303.054712)
			(xy 441.738519 -303.109888) (xy 441.722451 -303.163295) (xy 441.698779 -303.213792) (xy 441.668006 -303.260305)
			(xy 441.630789 -303.301842) (xy 441.587921 -303.337517) (xy 441.540315 -303.366571) (xy 441.488986 -303.388383)
			(xy 441.435029 -303.402489) (xy 441.379592 -303.408589) (xy 441.323858 -303.406552) (xy 441.269015 -303.396422)
			(xy 441.216231 -303.378415) (xy 441.166631 -303.352914) (xy 441.121273 -303.320463) (xy 441.081124 -303.281754)
			(xy 441.047038 -303.237611) (xy 441.019742 -303.188976) (xy 440.999819 -303.136885) (xy 440.987693 -303.082448)
			(xy 440.983622 -303.026826) (xy 440.731148 -303.026826) (xy 440.730639 -303.054712) (xy 440.722519 -303.109888)
			(xy 440.706451 -303.163295) (xy 440.682779 -303.213792) (xy 440.652006 -303.260305) (xy 440.614789 -303.301842)
			(xy 440.571921 -303.337517) (xy 440.524315 -303.366571) (xy 440.472986 -303.388383) (xy 440.419029 -303.402489)
			(xy 440.363592 -303.408589) (xy 440.307858 -303.406552) (xy 440.253015 -303.396422) (xy 440.200231 -303.378415)
			(xy 440.150631 -303.352914) (xy 440.105273 -303.320463) (xy 440.065124 -303.281754) (xy 440.031038 -303.237611)
			(xy 440.003742 -303.188976) (xy 439.983819 -303.136885) (xy 439.971693 -303.082448) (xy 439.967622 -303.026826)
			(xy 439.715148 -303.026826) (xy 439.714639 -303.054712) (xy 439.706519 -303.109888) (xy 439.690451 -303.163295)
			(xy 439.666779 -303.213792) (xy 439.636006 -303.260305) (xy 439.598789 -303.301842) (xy 439.555921 -303.337517)
			(xy 439.508315 -303.366571) (xy 439.456986 -303.388383) (xy 439.403029 -303.402489) (xy 439.347592 -303.408589)
			(xy 439.291858 -303.406552) (xy 439.237015 -303.396422) (xy 439.184231 -303.378415) (xy 439.134631 -303.352914)
			(xy 439.089273 -303.320463) (xy 439.049124 -303.281754) (xy 439.015038 -303.237611) (xy 438.987742 -303.188976)
			(xy 438.967819 -303.136885) (xy 438.955693 -303.082448) (xy 438.951622 -303.026826) (xy 438.699148 -303.026826)
			(xy 438.698639 -303.054712) (xy 438.690519 -303.109888) (xy 438.674451 -303.163295) (xy 438.650779 -303.213792)
			(xy 438.620006 -303.260305) (xy 438.582789 -303.301842) (xy 438.539921 -303.337517) (xy 438.492315 -303.366571)
			(xy 438.440986 -303.388383) (xy 438.387029 -303.402489) (xy 438.331592 -303.408589) (xy 438.275858 -303.406552)
			(xy 438.221015 -303.396422) (xy 438.168231 -303.378415) (xy 438.118631 -303.352914) (xy 438.073273 -303.320463)
			(xy 438.033124 -303.281754) (xy 437.999038 -303.237611) (xy 437.971742 -303.188976) (xy 437.951819 -303.136885)
			(xy 437.939693 -303.082448) (xy 437.935622 -303.026826) (xy 437.683148 -303.026826) (xy 437.682639 -303.054712)
			(xy 437.674519 -303.109888) (xy 437.658451 -303.163295) (xy 437.634779 -303.213792) (xy 437.604006 -303.260305)
			(xy 437.566789 -303.301842) (xy 437.523921 -303.337517) (xy 437.476315 -303.366571) (xy 437.424986 -303.388383)
			(xy 437.371029 -303.402489) (xy 437.315592 -303.408589) (xy 437.259858 -303.406552) (xy 437.205015 -303.396422)
			(xy 437.152231 -303.378415) (xy 437.102631 -303.352914) (xy 437.057273 -303.320463) (xy 437.017124 -303.281754)
			(xy 436.983038 -303.237611) (xy 436.955742 -303.188976) (xy 436.935819 -303.136885) (xy 436.923693 -303.082448)
			(xy 436.919622 -303.026826) (xy 435.110481 -303.026826) (xy 435.128151 -303.054321) (xy 435.150793 -303.103898)
			(xy 435.166148 -303.156193) (xy 435.173904 -303.210141) (xy 435.17439 -303.237392) (xy 435.173917 -303.265054)
			(xy 435.165948 -303.3198) (xy 435.150161 -303.372823) (xy 435.126886 -303.423013) (xy 435.11216 -303.446434)
			(xy 435.106064 -303.455578) (xy 435.102762 -303.477168) (xy 435.128924 -303.57191) (xy 435.14264 -303.58842)
			(xy 435.152546 -303.593246) (xy 435.176365 -303.605269) (xy 435.220622 -303.635074) (xy 435.260295 -303.670753)
			(xy 435.294611 -303.711612) (xy 435.3229 -303.756852) (xy 435.34461 -303.805593) (xy 435.359318 -303.856883)
			(xy 435.366738 -303.909721) (xy 435.367176 -303.9364) (xy 435.36669 -303.963651) (xy 435.358934 -304.017599)
			(xy 435.343579 -304.069894) (xy 435.320937 -304.119471) (xy 435.291471 -304.165321) (xy 435.25578 -304.206512)
			(xy 435.214589 -304.242203) (xy 435.168739 -304.271669) (xy 435.119162 -304.294311) (xy 435.066867 -304.309666)
			(xy 435.012919 -304.317422) (xy 434.958417 -304.317422) (xy 434.904469 -304.309666) (xy 434.852174 -304.294311)
			(xy 434.802597 -304.271669) (xy 434.756747 -304.242203) (xy 434.715556 -304.206512) (xy 434.679865 -304.165321)
			(xy 434.650399 -304.119471) (xy 434.627757 -304.069894) (xy 434.612402 -304.017599) (xy 434.604646 -303.963651)
			(xy 434.60416 -303.9364) (xy 434.604621 -303.908738) (xy 434.612592 -303.85399) (xy 434.628383 -303.800967)
			(xy 434.651662 -303.750779) (xy 434.66639 -303.727358) (xy 434.672486 -303.718214) (xy 434.675788 -303.696624)
			(xy 434.649626 -303.601882) (xy 434.63591 -303.585372) (xy 434.626004 -303.580546) (xy 434.602193 -303.568507)
			(xy 434.557934 -303.538707) (xy 434.518259 -303.503031) (xy 434.483941 -303.462175) (xy 434.455651 -303.416936)
			(xy 434.43394 -303.368197) (xy 434.419231 -303.316908) (xy 434.411812 -303.26407) (xy 434.411374 -303.237392)
			(xy 432.423824 -303.237392) (xy 432.423824 -304.780052) (xy 436.149734 -304.780052) (xy 436.149734 -304.725548)
			(xy 436.15749 -304.671598) (xy 436.172844 -304.619302) (xy 436.195484 -304.569722) (xy 436.224949 -304.523869)
			(xy 436.26064 -304.482675) (xy 436.301829 -304.446979) (xy 436.347678 -304.417508) (xy 436.397255 -304.394862)
			(xy 436.449549 -304.3795) (xy 436.503498 -304.371737) (xy 436.53075 -304.371248) (xy 436.557895 -304.371688)
			(xy 436.61164 -304.37937) (xy 436.663751 -304.3946) (xy 436.713173 -304.417069) (xy 436.758908 -304.446324)
			(xy 436.800029 -304.481771) (xy 436.835704 -304.522695) (xy 436.865213 -304.568266) (xy 436.887956 -304.617563)
			(xy 436.903475 -304.669588) (xy 436.90794 -304.696368) (xy 436.910763 -304.711197) (xy 436.923798 -304.738405)
			(xy 436.944204 -304.760626) (xy 436.970207 -304.775926) (xy 436.999542 -304.782973) (xy 437.029656 -304.781154)
			(xy 437.05793 -304.770627) (xy 437.070246 -304.7619) (xy 437.090311 -304.747097) (xy 437.133526 -304.722227)
			(xy 437.179611 -304.703192) (xy 437.227781 -304.690318) (xy 437.277218 -304.683822) (xy 437.302148 -304.683414)
			(xy 437.329399 -304.683859) (xy 437.383344 -304.691622) (xy 437.435636 -304.706982) (xy 437.48521 -304.729627)
			(xy 437.531057 -304.759096) (xy 437.572244 -304.79479) (xy 437.607933 -304.835981) (xy 437.637396 -304.881832)
			(xy 437.660035 -304.931409) (xy 437.675389 -304.983703) (xy 437.683144 -305.037649) (xy 437.683144 -305.064922)
			(xy 437.935114 -305.064922) (xy 437.939185 -305.0093) (xy 437.951311 -304.954863) (xy 437.971234 -304.902772)
			(xy 437.99853 -304.854137) (xy 438.032616 -304.809994) (xy 438.072765 -304.771285) (xy 438.118123 -304.738834)
			(xy 438.167723 -304.713333) (xy 438.220507 -304.695326) (xy 438.27535 -304.685196) (xy 438.331084 -304.683159)
			(xy 438.386521 -304.689259) (xy 438.440478 -304.703365) (xy 438.491807 -304.725177) (xy 438.539413 -304.754231)
			(xy 438.582281 -304.789906) (xy 438.619498 -304.831443) (xy 438.650271 -304.877956) (xy 438.673943 -304.928453)
			(xy 438.690011 -304.98186) (xy 438.698131 -305.037036) (xy 438.69864 -305.064922) (xy 438.943494 -305.064922)
			(xy 438.947565 -305.0093) (xy 438.959691 -304.954863) (xy 438.979614 -304.902772) (xy 439.00691 -304.854137)
			(xy 439.040996 -304.809994) (xy 439.081145 -304.771285) (xy 439.126503 -304.738834) (xy 439.176103 -304.713333)
			(xy 439.228887 -304.695326) (xy 439.28373 -304.685196) (xy 439.339464 -304.683159) (xy 439.394901 -304.689259)
			(xy 439.448858 -304.703365) (xy 439.500187 -304.725177) (xy 439.547793 -304.754231) (xy 439.590661 -304.789906)
			(xy 439.627878 -304.831443) (xy 439.658651 -304.877956) (xy 439.682323 -304.928453) (xy 439.698391 -304.98186)
			(xy 439.706511 -305.037036) (xy 439.707001 -305.063906) (xy 439.96813 -305.063906) (xy 439.972201 -305.008284)
			(xy 439.984327 -304.953847) (xy 440.00425 -304.901756) (xy 440.031546 -304.853121) (xy 440.065632 -304.808978)
			(xy 440.105781 -304.770269) (xy 440.151139 -304.737818) (xy 440.200739 -304.712317) (xy 440.253523 -304.69431)
			(xy 440.308366 -304.68418) (xy 440.3641 -304.682143) (xy 440.419537 -304.688243) (xy 440.473494 -304.702349)
			(xy 440.524823 -304.724161) (xy 440.572429 -304.753215) (xy 440.615297 -304.78889) (xy 440.652514 -304.830427)
			(xy 440.683287 -304.87694) (xy 440.706959 -304.927437) (xy 440.723027 -304.980844) (xy 440.731147 -305.03602)
			(xy 440.731331 -305.046126) (xy 440.98413 -305.046126) (xy 440.988201 -304.990504) (xy 441.000327 -304.936067)
			(xy 441.02025 -304.883976) (xy 441.047546 -304.835341) (xy 441.081632 -304.791198) (xy 441.121781 -304.752489)
			(xy 441.167139 -304.720038) (xy 441.216739 -304.694537) (xy 441.269523 -304.67653) (xy 441.324366 -304.6664)
			(xy 441.3801 -304.664363) (xy 441.435537 -304.670463) (xy 441.489494 -304.684569) (xy 441.540823 -304.706381)
			(xy 441.588429 -304.735435) (xy 441.631297 -304.77111) (xy 441.668514 -304.812647) (xy 441.699287 -304.85916)
			(xy 441.722959 -304.909657) (xy 441.739027 -304.963064) (xy 441.747147 -305.01824) (xy 441.747656 -305.046126)
			(xy 441.747147 -305.074012) (xy 441.739027 -305.129188) (xy 441.722959 -305.182595) (xy 441.699287 -305.233092)
			(xy 441.668514 -305.279605) (xy 441.631297 -305.321142) (xy 441.588429 -305.356817) (xy 441.540823 -305.385871)
			(xy 441.489494 -305.407683) (xy 441.435537 -305.421789) (xy 441.3801 -305.427889) (xy 441.324366 -305.425852)
			(xy 441.269523 -305.415722) (xy 441.216739 -305.397715) (xy 441.167139 -305.372214) (xy 441.121781 -305.339763)
			(xy 441.081632 -305.301054) (xy 441.047546 -305.256911) (xy 441.02025 -305.208276) (xy 441.000327 -305.156185)
			(xy 440.988201 -305.101748) (xy 440.98413 -305.046126) (xy 440.731331 -305.046126) (xy 440.731656 -305.063906)
			(xy 440.731147 -305.091792) (xy 440.723027 -305.146968) (xy 440.706959 -305.200375) (xy 440.683287 -305.250872)
			(xy 440.652514 -305.297385) (xy 440.615297 -305.338922) (xy 440.572429 -305.374597) (xy 440.524823 -305.403651)
			(xy 440.473494 -305.425463) (xy 440.419537 -305.439569) (xy 440.3641 -305.445669) (xy 440.308366 -305.443632)
			(xy 440.253523 -305.433502) (xy 440.200739 -305.415495) (xy 440.151139 -305.389994) (xy 440.105781 -305.357543)
			(xy 440.065632 -305.318834) (xy 440.031546 -305.274691) (xy 440.00425 -305.226056) (xy 439.984327 -305.173965)
			(xy 439.972201 -305.119528) (xy 439.96813 -305.063906) (xy 439.707001 -305.063906) (xy 439.70702 -305.064922)
			(xy 439.706511 -305.092808) (xy 439.698391 -305.147984) (xy 439.682323 -305.201391) (xy 439.658651 -305.251888)
			(xy 439.627878 -305.298401) (xy 439.590661 -305.339938) (xy 439.547793 -305.375613) (xy 439.500187 -305.404667)
			(xy 439.448858 -305.426479) (xy 439.394901 -305.440585) (xy 439.339464 -305.446685) (xy 439.28373 -305.444648)
			(xy 439.228887 -305.434518) (xy 439.176103 -305.416511) (xy 439.126503 -305.39101) (xy 439.081145 -305.358559)
			(xy 439.040996 -305.31985) (xy 439.00691 -305.275707) (xy 438.979614 -305.227072) (xy 438.959691 -305.174981)
			(xy 438.947565 -305.120544) (xy 438.943494 -305.064922) (xy 438.69864 -305.064922) (xy 438.698131 -305.092808)
			(xy 438.690011 -305.147984) (xy 438.673943 -305.201391) (xy 438.650271 -305.251888) (xy 438.619498 -305.298401)
			(xy 438.582281 -305.339938) (xy 438.539413 -305.375613) (xy 438.491807 -305.404667) (xy 438.440478 -305.426479)
			(xy 438.386521 -305.440585) (xy 438.331084 -305.446685) (xy 438.27535 -305.444648) (xy 438.220507 -305.434518)
			(xy 438.167723 -305.416511) (xy 438.118123 -305.39101) (xy 438.072765 -305.358559) (xy 438.032616 -305.31985)
			(xy 437.99853 -305.275707) (xy 437.971234 -305.227072) (xy 437.951311 -305.174981) (xy 437.939185 -305.120544)
			(xy 437.935114 -305.064922) (xy 437.683144 -305.064922) (xy 437.683144 -305.092151) (xy 437.675389 -305.146097)
			(xy 437.660035 -305.198391) (xy 437.637396 -305.247968) (xy 437.607933 -305.293819) (xy 437.572244 -305.33501)
			(xy 437.531057 -305.370704) (xy 437.48521 -305.400173) (xy 437.435636 -305.422818) (xy 437.383344 -305.438178)
			(xy 437.329399 -305.445941) (xy 437.302148 -305.44643) (xy 437.275002 -305.44601) (xy 437.221256 -305.438328)
			(xy 437.169143 -305.423097) (xy 437.119719 -305.400625) (xy 437.073984 -305.371369) (xy 437.032863 -305.335919)
			(xy 436.997188 -305.294993) (xy 436.96768 -305.249419) (xy 436.944938 -305.200119) (xy 436.929421 -305.148091)
			(xy 436.924958 -305.12131) (xy 436.922149 -305.106479) (xy 436.909109 -305.079272) (xy 436.8887 -305.057053)
			(xy 436.862695 -305.041755) (xy 436.83336 -305.034708) (xy 436.803244 -305.036527) (xy 436.774969 -305.047052)
			(xy 436.762652 -305.055778) (xy 436.742596 -305.070592) (xy 436.699377 -305.095459) (xy 436.65329 -305.11449)
			(xy 436.605118 -305.127362) (xy 436.555681 -305.133857) (xy 436.53075 -305.134264) (xy 436.503498 -305.133863)
			(xy 436.449549 -305.1261) (xy 436.397255 -305.110738) (xy 436.347678 -305.088092) (xy 436.301829 -305.058621)
			(xy 436.26064 -305.022925) (xy 436.224949 -304.981731) (xy 436.195484 -304.935878) (xy 436.172844 -304.886298)
			(xy 436.15749 -304.834002) (xy 436.149734 -304.780052) (xy 432.423824 -304.780052) (xy 432.423824 -307.33536)
			(xy 439.450128 -307.33536) (xy 439.457883 -307.281404) (xy 439.473239 -307.229101) (xy 439.495882 -307.179516)
			(xy 439.525351 -307.133658) (xy 439.561047 -307.092461) (xy 439.602242 -307.056763) (xy 439.648098 -307.027291)
			(xy 439.697682 -307.004646) (xy 439.749985 -306.989288) (xy 439.80394 -306.981529) (xy 439.858451 -306.981529)
			(xy 439.912406 -306.989286) (xy 439.964709 -307.004643) (xy 440.014293 -307.027287) (xy 440.06015 -307.056757)
			(xy 440.091847 -307.084222) (xy 441.014356 -307.084222) (xy 441.018427 -307.0286) (xy 441.030553 -306.974163)
			(xy 441.050476 -306.922072) (xy 441.077772 -306.873437) (xy 441.111858 -306.829294) (xy 441.152007 -306.790585)
			(xy 441.197365 -306.758134) (xy 441.246965 -306.732633) (xy 441.299749 -306.714626) (xy 441.354592 -306.704496)
			(xy 441.410326 -306.702459) (xy 441.465763 -306.708559) (xy 441.51972 -306.722665) (xy 441.571049 -306.744477)
			(xy 441.618655 -306.773531) (xy 441.661523 -306.809206) (xy 441.69874 -306.850743) (xy 441.729513 -306.897256)
			(xy 441.753185 -306.947753) (xy 441.769253 -307.00116) (xy 441.777373 -307.056336) (xy 441.777882 -307.084222)
			(xy 441.777373 -307.112108) (xy 441.769253 -307.167284) (xy 441.753185 -307.220691) (xy 441.729513 -307.271188)
			(xy 441.69874 -307.317701) (xy 441.661523 -307.359238) (xy 441.618655 -307.394913) (xy 441.571049 -307.423967)
			(xy 441.51972 -307.445779) (xy 441.465763 -307.459885) (xy 441.410326 -307.465985) (xy 441.354592 -307.463948)
			(xy 441.299749 -307.453818) (xy 441.246965 -307.435811) (xy 441.197365 -307.41031) (xy 441.152007 -307.377859)
			(xy 441.111858 -307.33915) (xy 441.077772 -307.295007) (xy 441.050476 -307.246372) (xy 441.030553 -307.194281)
			(xy 441.018427 -307.139844) (xy 441.014356 -307.084222) (xy 440.091847 -307.084222) (xy 440.101347 -307.092454)
			(xy 440.137043 -307.133651) (xy 440.166514 -307.179508) (xy 440.189158 -307.229092) (xy 440.204515 -307.281395)
			(xy 440.212271 -307.335351) (xy 440.212734 -307.362606) (xy 440.210956 -307.399182) (xy 440.20994 -307.410612)
			(xy 440.21756 -307.431694) (xy 440.289188 -307.503322) (xy 440.310524 -307.510942) (xy 440.321954 -307.509926)
			(xy 440.35853 -307.508148) (xy 440.38578 -307.50865) (xy 440.439725 -307.516409) (xy 440.492017 -307.531766)
			(xy 440.541591 -307.554407) (xy 440.587439 -307.583873) (xy 440.628628 -307.619562) (xy 440.664319 -307.66075)
			(xy 440.693786 -307.706597) (xy 440.716429 -307.75617) (xy 440.731788 -307.808461) (xy 440.739549 -307.862406)
			(xy 440.740038 -307.889656) (xy 440.739682 -307.912162) (xy 440.734339 -307.956856) (xy 440.72937 -307.97881)
			(xy 440.726322 -307.992018) (xy 440.733434 -308.017164) (xy 440.813698 -308.097428) (xy 440.838844 -308.10454)
			(xy 440.852052 -308.101492) (xy 440.874008 -308.096534) (xy 440.918701 -308.091184) (xy 440.941206 -308.090824)
			(xy 440.968456 -308.091284) (xy 441.022402 -308.099041) (xy 441.074695 -308.114396) (xy 441.12427 -308.137037)
			(xy 441.170118 -308.166502) (xy 441.211307 -308.202192) (xy 441.246997 -308.243381) (xy 441.276463 -308.28923)
			(xy 441.299104 -308.338805) (xy 441.314459 -308.391097) (xy 441.322216 -308.445043) (xy 441.322217 -308.499544)
			(xy 441.314462 -308.553489) (xy 441.299108 -308.605783) (xy 441.276469 -308.655359) (xy 441.247005 -308.701208)
			(xy 441.211317 -308.742398) (xy 441.170129 -308.77809) (xy 441.124282 -308.807557) (xy 441.074707 -308.830199)
			(xy 441.022415 -308.845556) (xy 440.96847 -308.853315) (xy 440.913969 -308.853318) (xy 440.860023 -308.845564)
			(xy 440.807729 -308.830213) (xy 440.758152 -308.807575) (xy 440.712302 -308.778113) (xy 440.671111 -308.742426)
			(xy 440.635418 -308.701239) (xy 440.605949 -308.655393) (xy 440.583305 -308.605819) (xy 440.567947 -308.553527)
			(xy 440.560186 -308.499582) (xy 440.559698 -308.472332) (xy 440.560053 -308.449826) (xy 440.565397 -308.405132)
			(xy 440.570366 -308.383178) (xy 440.573414 -308.36997) (xy 440.566302 -308.344824) (xy 440.486038 -308.26456)
			(xy 440.460892 -308.257448) (xy 440.447684 -308.260496) (xy 440.425731 -308.265464) (xy 440.381036 -308.270807)
			(xy 440.35853 -308.271164) (xy 440.331276 -308.270717) (xy 440.277322 -308.262963) (xy 440.225021 -308.247608)
			(xy 440.175438 -308.224966) (xy 440.129583 -308.195497) (xy 440.088389 -308.159801) (xy 440.052695 -308.118606)
			(xy 440.023227 -308.072749) (xy 440.000587 -308.023166) (xy 439.985234 -307.970864) (xy 439.977482 -307.91691)
			(xy 439.977022 -307.889656) (xy 439.9788 -307.85308) (xy 439.979816 -307.84165) (xy 439.972196 -307.820568)
			(xy 439.900568 -307.74894) (xy 439.879232 -307.74132) (xy 439.867802 -307.742336) (xy 439.831226 -307.744114)
			(xy 439.803971 -307.743673) (xy 439.750015 -307.735919) (xy 439.697711 -307.720565) (xy 439.648125 -307.697923)
			(xy 439.602267 -307.668455) (xy 439.561068 -307.632761) (xy 439.525369 -307.591567) (xy 439.495897 -307.545711)
			(xy 439.47325 -307.496128) (xy 439.45789 -307.443826) (xy 439.45013 -307.389871) (xy 439.450128 -307.33536)
			(xy 432.423824 -307.33536) (xy 432.423824 -309.175912) (xy 436.634126 -309.175912) (xy 436.638197 -309.12029)
			(xy 436.650323 -309.065853) (xy 436.670246 -309.013762) (xy 436.697542 -308.965127) (xy 436.731628 -308.920984)
			(xy 436.771777 -308.882275) (xy 436.817135 -308.849824) (xy 436.866735 -308.824323) (xy 436.919519 -308.806316)
			(xy 436.974362 -308.796186) (xy 437.030096 -308.794149) (xy 437.085533 -308.800249) (xy 437.13949 -308.814355)
			(xy 437.190819 -308.836167) (xy 437.238425 -308.865221) (xy 437.281293 -308.900896) (xy 437.31851 -308.942433)
			(xy 437.349283 -308.988946) (xy 437.372955 -309.039443) (xy 437.389023 -309.09285) (xy 437.397143 -309.148026)
			(xy 437.397652 -309.175912) (xy 437.397143 -309.203798) (xy 437.389023 -309.258974) (xy 437.372955 -309.312381)
			(xy 437.349283 -309.362878) (xy 437.31851 -309.409391) (xy 437.281293 -309.450928) (xy 437.238425 -309.486603)
			(xy 437.190819 -309.515657) (xy 437.13949 -309.537469) (xy 437.085533 -309.551575) (xy 437.030096 -309.557675)
			(xy 436.974362 -309.555638) (xy 436.919519 -309.545508) (xy 436.866735 -309.527501) (xy 436.817135 -309.502)
			(xy 436.771777 -309.469549) (xy 436.731628 -309.43084) (xy 436.697542 -309.386697) (xy 436.670246 -309.338062)
			(xy 436.650323 -309.285971) (xy 436.638197 -309.231534) (xy 436.634126 -309.175912) (xy 432.423824 -309.175912)
			(xy 432.423824 -309.85333) (xy 437.310782 -309.85333) (xy 437.314853 -309.797708) (xy 437.326979 -309.743271)
			(xy 437.346902 -309.69118) (xy 437.374198 -309.642545) (xy 437.408284 -309.598402) (xy 437.448433 -309.559693)
			(xy 437.493791 -309.527242) (xy 437.543391 -309.501741) (xy 437.596175 -309.483734) (xy 437.651018 -309.473604)
			(xy 437.706752 -309.471567) (xy 437.762189 -309.477667) (xy 437.816146 -309.491773) (xy 437.867475 -309.513585)
			(xy 437.915081 -309.542639) (xy 437.957949 -309.578314) (xy 437.995166 -309.619851) (xy 438.025939 -309.666364)
			(xy 438.037261 -309.690516) (xy 441.777372 -309.690516) (xy 441.781443 -309.634894) (xy 441.793569 -309.580457)
			(xy 441.813492 -309.528366) (xy 441.840788 -309.479731) (xy 441.874874 -309.435588) (xy 441.915023 -309.396879)
			(xy 441.960381 -309.364428) (xy 442.009981 -309.338927) (xy 442.062765 -309.32092) (xy 442.117608 -309.31079)
			(xy 442.173342 -309.308753) (xy 442.228779 -309.314853) (xy 442.282736 -309.328959) (xy 442.334065 -309.350771)
			(xy 442.381671 -309.379825) (xy 442.424539 -309.4155) (xy 442.461756 -309.457037) (xy 442.492529 -309.50355)
			(xy 442.516201 -309.554047) (xy 442.532269 -309.607454) (xy 442.540389 -309.66263) (xy 442.540898 -309.690516)
			(xy 442.540389 -309.718402) (xy 442.532269 -309.773578) (xy 442.516201 -309.826985) (xy 442.492529 -309.877482)
			(xy 442.461756 -309.923995) (xy 442.424539 -309.965532) (xy 442.381671 -310.001207) (xy 442.334065 -310.030261)
			(xy 442.282736 -310.052073) (xy 442.228779 -310.066179) (xy 442.173342 -310.072279) (xy 442.117608 -310.070242)
			(xy 442.062765 -310.060112) (xy 442.009981 -310.042105) (xy 441.960381 -310.016604) (xy 441.915023 -309.984153)
			(xy 441.874874 -309.945444) (xy 441.840788 -309.901301) (xy 441.813492 -309.852666) (xy 441.793569 -309.800575)
			(xy 441.781443 -309.746138) (xy 441.777372 -309.690516) (xy 438.037261 -309.690516) (xy 438.049611 -309.716861)
			(xy 438.065679 -309.770268) (xy 438.073799 -309.825444) (xy 438.074308 -309.85333) (xy 438.073799 -309.881216)
			(xy 438.065679 -309.936392) (xy 438.049611 -309.989799) (xy 438.025939 -310.040296) (xy 437.995166 -310.086809)
			(xy 437.957949 -310.128346) (xy 437.915081 -310.164021) (xy 437.867475 -310.193075) (xy 437.816146 -310.214887)
			(xy 437.762189 -310.228993) (xy 437.706752 -310.235093) (xy 437.651018 -310.233056) (xy 437.596175 -310.222926)
			(xy 437.543391 -310.204919) (xy 437.493791 -310.179418) (xy 437.448433 -310.146967) (xy 437.408284 -310.108258)
			(xy 437.374198 -310.064115) (xy 437.346902 -310.01548) (xy 437.326979 -309.963389) (xy 437.314853 -309.908952)
			(xy 437.310782 -309.85333) (xy 432.423824 -309.85333) (xy 432.423824 -310.68518) (xy 438.142632 -310.68518)
			(xy 438.146703 -310.629558) (xy 438.158829 -310.575121) (xy 438.178752 -310.52303) (xy 438.206048 -310.474395)
			(xy 438.240134 -310.430252) (xy 438.280283 -310.391543) (xy 438.325641 -310.359092) (xy 438.375241 -310.333591)
			(xy 438.428025 -310.315584) (xy 438.482868 -310.305454) (xy 438.538602 -310.303417) (xy 438.594039 -310.309517)
			(xy 438.647996 -310.323623) (xy 438.699325 -310.345435) (xy 438.746931 -310.374489) (xy 438.789799 -310.410164)
			(xy 438.827016 -310.451701) (xy 438.857789 -310.498214) (xy 438.881461 -310.548711) (xy 438.897529 -310.602118)
			(xy 438.905649 -310.657294) (xy 438.906158 -310.68518) (xy 438.905649 -310.713066) (xy 438.897529 -310.768242)
			(xy 438.881461 -310.821649) (xy 438.857789 -310.872146) (xy 438.827016 -310.918659) (xy 438.789799 -310.960196)
			(xy 438.746931 -310.995871) (xy 438.699325 -311.024925) (xy 438.647996 -311.046737) (xy 438.594039 -311.060843)
			(xy 438.538602 -311.066943) (xy 438.482868 -311.064906) (xy 438.428025 -311.054776) (xy 438.375241 -311.036769)
			(xy 438.325641 -311.011268) (xy 438.280283 -310.978817) (xy 438.240134 -310.940108) (xy 438.206048 -310.895965)
			(xy 438.178752 -310.84733) (xy 438.158829 -310.795239) (xy 438.146703 -310.740802) (xy 438.142632 -310.68518)
			(xy 432.423824 -310.68518) (xy 432.423824 -311.435354) (xy 438.86679 -311.435354) (xy 438.86679 -311.380854)
			(xy 438.874545 -311.32691) (xy 438.889898 -311.274618) (xy 438.912537 -311.225043) (xy 438.942001 -311.179195)
			(xy 438.977689 -311.138006) (xy 439.018875 -311.102315) (xy 439.064722 -311.072849) (xy 439.114295 -311.050207)
			(xy 439.166586 -311.03485) (xy 439.22053 -311.027092) (xy 439.27503 -311.027089) (xy 439.328975 -311.034842)
			(xy 439.381267 -311.050193) (xy 439.430843 -311.07283) (xy 439.476693 -311.102291) (xy 439.517883 -311.137977)
			(xy 439.553575 -311.179163) (xy 439.583044 -311.225008) (xy 439.605688 -311.27458) (xy 439.621046 -311.326871)
			(xy 439.628807 -311.380814) (xy 439.629296 -311.408064) (xy 439.6291 -311.425112) (xy 439.626045 -311.459072)
			(xy 439.6232 -311.475882) (xy 439.621161 -311.489766) (xy 439.623883 -311.517684) (xy 439.634091 -311.543811)
			(xy 439.651016 -311.56618) (xy 439.673383 -311.583106) (xy 439.69951 -311.593316) (xy 439.727428 -311.596039)
			(xy 439.74131 -311.593992) (xy 439.758181 -311.591119) (xy 439.792269 -311.588068) (xy 439.809382 -311.587896)
			(xy 439.836636 -311.588336) (xy 439.890591 -311.596091) (xy 439.942892 -311.611445) (xy 439.992476 -311.634087)
			(xy 440.038333 -311.663554) (xy 440.07953 -311.699248) (xy 440.115227 -311.740442) (xy 440.144698 -311.786296)
			(xy 440.167344 -311.835878) (xy 440.182703 -311.888179) (xy 440.190462 -311.942132) (xy 440.190464 -311.996641)
			(xy 440.182708 -312.050595) (xy 440.167353 -312.102897) (xy 440.144711 -312.15248) (xy 440.115243 -312.198337)
			(xy 440.079548 -312.239533) (xy 440.038354 -312.27523) (xy 439.9925 -312.304701) (xy 439.942917 -312.327346)
			(xy 439.890617 -312.342704) (xy 439.836663 -312.350462) (xy 439.782154 -312.350464) (xy 439.7282 -312.342707)
			(xy 439.675899 -312.327352) (xy 439.626316 -312.304709) (xy 439.580459 -312.27524) (xy 439.539264 -312.239545)
			(xy 439.503568 -312.198351) (xy 439.474097 -312.152495) (xy 439.451453 -312.102913) (xy 439.436095 -312.050612)
			(xy 439.428337 -311.996658) (xy 439.427874 -311.969404) (xy 439.428079 -311.952356) (xy 439.431128 -311.918397)
			(xy 439.43397 -311.901586) (xy 439.436077 -311.88771) (xy 439.433347 -311.859783) (xy 439.423129 -311.833649)
			(xy 439.406193 -311.811276) (xy 439.383813 -311.794349) (xy 439.357675 -311.784143) (xy 439.329746 -311.781425)
			(xy 439.31586 -311.783476) (xy 439.298988 -311.78634) (xy 439.2649 -311.789396) (xy 439.247788 -311.789572)
			(xy 439.220538 -311.789109) (xy 439.166594 -311.781351) (xy 439.114303 -311.765996) (xy 439.064729 -311.743355)
			(xy 439.018882 -311.71389) (xy 438.977694 -311.6782) (xy 438.942005 -311.637012) (xy 438.912541 -311.591164)
			(xy 438.889901 -311.54159) (xy 438.874547 -311.489298) (xy 438.86679 -311.435354) (xy 432.423824 -311.435354)
			(xy 432.423824 -312.876052) (xy 434.16853 -312.876052) (xy 434.16853 -312.821548) (xy 434.176286 -312.767597)
			(xy 434.19164 -312.7153) (xy 434.214281 -312.66572) (xy 434.243746 -312.619866) (xy 434.279437 -312.578672)
			(xy 434.320626 -312.542976) (xy 434.366476 -312.513505) (xy 434.416053 -312.490858) (xy 434.468349 -312.475497)
			(xy 434.522298 -312.467733) (xy 434.54955 -312.467244) (xy 434.561584 -312.467349) (xy 434.585605 -312.468874)
			(xy 434.597556 -312.470292) (xy 434.611702 -312.471595) (xy 434.639763 -312.467237) (xy 434.665541 -312.455327)
			(xy 434.687048 -312.436783) (xy 434.702622 -312.413038) (xy 434.711061 -312.385924) (xy 434.711856 -312.37174)
			(xy 434.712819 -312.344857) (xy 434.721495 -312.291768) (xy 434.73754 -312.240423) (xy 434.760634 -312.191838)
			(xy 434.790321 -312.146978) (xy 434.826013 -312.106731) (xy 434.867002 -312.071893) (xy 434.912477 -312.043156)
			(xy 434.961536 -312.021088) (xy 435.013207 -312.006127) (xy 435.066467 -311.998569) (xy 435.093364 -311.998106)
			(xy 435.12062 -311.998538) (xy 435.174576 -312.006292) (xy 435.226881 -312.021645) (xy 435.276467 -312.044286)
			(xy 435.322326 -312.073754) (xy 435.363525 -312.109449) (xy 435.399224 -312.150645) (xy 435.428696 -312.196501)
			(xy 435.451342 -312.246086) (xy 435.466701 -312.298388) (xy 435.474459 -312.352344) (xy 435.474459 -312.406856)
			(xy 435.466701 -312.460812) (xy 435.451342 -312.513114) (xy 435.428696 -312.562699) (xy 435.399224 -312.608555)
			(xy 435.363525 -312.649751) (xy 435.322326 -312.685446) (xy 435.276467 -312.714914) (xy 435.226881 -312.737555)
			(xy 435.174576 -312.752908) (xy 435.12062 -312.760662) (xy 435.093364 -312.761122) (xy 435.08133 -312.761016)
			(xy 435.057309 -312.759492) (xy 435.045358 -312.758074) (xy 435.031213 -312.756721) (xy 435.003142 -312.761078)
			(xy 434.977355 -312.772995) (xy 434.955845 -312.791549) (xy 434.940274 -312.815309) (xy 434.931845 -312.842437)
			(xy 434.931058 -312.856626) (xy 434.93005 -312.883506) (xy 434.921379 -312.936593) (xy 434.90534 -312.987937)
			(xy 434.88225 -313.036521) (xy 434.852568 -313.08138) (xy 434.816881 -313.121628) (xy 434.775896 -313.156466)
			(xy 434.730425 -313.185205) (xy 434.68137 -313.207274) (xy 434.629702 -313.222237) (xy 434.576445 -313.229796)
			(xy 434.54955 -313.23026) (xy 434.522298 -313.229867) (xy 434.468349 -313.222103) (xy 434.416053 -313.206742)
			(xy 434.366476 -313.184095) (xy 434.320626 -313.154624) (xy 434.279437 -313.118928) (xy 434.243746 -313.077734)
			(xy 434.214281 -313.03188) (xy 434.19164 -312.9823) (xy 434.176286 -312.930003) (xy 434.16853 -312.876052)
			(xy 432.423824 -312.876052) (xy 432.423824 -320.900044) (xy 433.198785 -320.900044) (xy 433.202791 -320.704989)
			(xy 433.214801 -320.510263) (xy 433.234796 -320.316194) (xy 433.262741 -320.12311) (xy 433.29859 -319.931335)
			(xy 433.342282 -319.741195) (xy 433.393743 -319.553008) (xy 433.452887 -319.367093) (xy 433.519614 -319.183762)
			(xy 433.593811 -319.003326) (xy 433.675353 -318.826088) (xy 433.764104 -318.652347) (xy 433.859912 -318.482396)
			(xy 433.962617 -318.316522) (xy 434.072045 -318.155004) (xy 434.188012 -317.998115) (xy 434.310323 -317.84612)
			(xy 434.43877 -317.699274) (xy 434.573138 -317.557825) (xy 434.7132 -317.422012) (xy 434.858719 -317.292063)
			(xy 435.009451 -317.168199) (xy 435.165141 -317.050627) (xy 435.325527 -316.939547) (xy 435.490338 -316.835144)
			(xy 435.659296 -316.737596) (xy 435.832117 -316.647067) (xy 436.008509 -316.563709) (xy 436.188174 -316.487663)
			(xy 436.370809 -316.419058) (xy 436.556108 -316.358008) (xy 436.743756 -316.304618) (xy 436.933438 -316.258976)
			(xy 437.124835 -316.22116) (xy 437.317622 -316.191234) (xy 437.511475 -316.169248) (xy 437.706068 -316.155239)
			(xy 437.901071 -316.149231) (xy 438.096157 -316.151234) (xy 438.290996 -316.161245) (xy 438.48526 -316.179246)
			(xy 438.678621 -316.205208) (xy 438.870754 -316.239086) (xy 439.061333 -316.280823) (xy 439.250038 -316.33035)
			(xy 439.436551 -316.387582) (xy 439.620557 -316.452423) (xy 439.801745 -316.524764) (xy 439.979811 -316.604482)
			(xy 440.154454 -316.691444) (xy 440.32538 -316.785503) (xy 440.492299 -316.886499) (xy 440.654932 -316.994264)
			(xy 440.813003 -317.108614) (xy 440.966246 -317.229357) (xy 441.114403 -317.356291) (xy 441.257224 -317.489199)
			(xy 441.394468 -317.627859) (xy 441.525904 -317.772037) (xy 441.651309 -317.92149) (xy 441.770473 -318.075964)
			(xy 441.883194 -318.235201) (xy 441.989283 -318.398932) (xy 442.088561 -318.566879) (xy 442.180859 -318.738762)
			(xy 442.266024 -318.914288) (xy 442.34391 -319.093163) (xy 442.414387 -319.275085) (xy 442.477335 -319.459747)
			(xy 442.53265 -319.646837) (xy 442.580236 -319.836041) (xy 442.620015 -320.027038) (xy 442.651919 -320.219508)
			(xy 442.675894 -320.413126) (xy 442.6919 -320.607564) (xy 442.699909 -320.802496) (xy 442.70041 -320.900044)
			(xy 442.699909 -320.997592) (xy 442.6919 -321.192524) (xy 442.675894 -321.386962) (xy 442.651919 -321.58058)
			(xy 442.620015 -321.77305) (xy 442.580236 -321.964047) (xy 442.53265 -322.153251) (xy 442.477335 -322.340341)
			(xy 442.414387 -322.525003) (xy 442.34391 -322.706925) (xy 442.266024 -322.8858) (xy 442.180859 -323.061326)
			(xy 442.088561 -323.233209) (xy 441.989283 -323.401156) (xy 441.883194 -323.564887) (xy 441.770473 -323.724124)
			(xy 441.651309 -323.878598) (xy 441.525904 -324.028051) (xy 441.394468 -324.172229) (xy 441.257224 -324.310889)
			(xy 441.114403 -324.443797) (xy 440.966246 -324.570731) (xy 440.813003 -324.691474) (xy 440.654932 -324.805824)
			(xy 440.492299 -324.913589) (xy 440.32538 -325.014585) (xy 440.154454 -325.108644) (xy 439.979811 -325.195606)
			(xy 439.801745 -325.275324) (xy 439.620557 -325.347665) (xy 439.436551 -325.412506) (xy 439.250038 -325.469738)
			(xy 439.061333 -325.519265) (xy 438.870754 -325.561002) (xy 438.678621 -325.59488) (xy 438.48526 -325.620842)
			(xy 438.290996 -325.638843) (xy 438.096157 -325.648854) (xy 437.901071 -325.650857) (xy 437.706068 -325.644849)
			(xy 437.511475 -325.63084) (xy 437.317622 -325.608854) (xy 437.124835 -325.578928) (xy 436.933438 -325.541112)
			(xy 436.743756 -325.49547) (xy 436.556108 -325.44208) (xy 436.370809 -325.38103) (xy 436.188174 -325.312425)
			(xy 436.008509 -325.236379) (xy 435.832117 -325.153021) (xy 435.659296 -325.062492) (xy 435.490338 -324.964944)
			(xy 435.325527 -324.860541) (xy 435.165141 -324.749461) (xy 435.009451 -324.631889) (xy 434.858719 -324.508025)
			(xy 434.7132 -324.378076) (xy 434.573138 -324.242263) (xy 434.43877 -324.100814) (xy 434.310323 -323.953968)
			(xy 434.188012 -323.801973) (xy 434.072045 -323.645084) (xy 433.962617 -323.483566) (xy 433.859912 -323.317692)
			(xy 433.764104 -323.147741) (xy 433.675353 -322.974) (xy 433.593811 -322.796762) (xy 433.519614 -322.616326)
			(xy 433.452887 -322.432995) (xy 433.393743 -322.24708) (xy 433.342282 -322.058893) (xy 433.29859 -321.868753)
			(xy 433.262741 -321.676978) (xy 433.234796 -321.483894) (xy 433.214801 -321.289825) (xy 433.202791 -321.095099)
			(xy 433.198785 -320.900044) (xy 432.423824 -320.900044) (xy 432.423824 -326.944736) (xy 432.424288 -326.954611)
			(xy 432.431738 -326.972903) (xy 432.438302 -326.980296) (xy 432.438556 -326.98055) (xy 437.68772 -332.229714)
			(xy 437.688228 -332.230222) (xy 437.695606 -332.236812) (xy 437.713906 -332.244276) (xy 437.723788 -332.2447)
			(xy 462.495646 -332.2447)
		)
		(stroke
			(width 0)
			(type solid)
		)
		(fill yes)
		(layer "In9.Cu")
		(net "P3V3_AUX")
	)
	(gr_poly
		(pts
			(xy 326.885808 -228.789484) (xy 326.895487 -228.789051) (xy 326.913473 -228.78189) (xy 326.927563 -228.768614)
			(xy 326.932036 -228.76002) (xy 326.932036 -228.759766) (xy 326.943809 -228.735199) (xy 326.973289 -228.68939)
			(xy 327.008985 -228.648238) (xy 327.050171 -228.612583) (xy 327.096009 -228.583147) (xy 327.145568 -228.56053)
			(xy 327.19784 -228.545192) (xy 327.251762 -228.537444) (xy 327.306238 -228.537444) (xy 327.36016 -228.545192)
			(xy 327.412432 -228.56053) (xy 327.461991 -228.583147) (xy 327.507829 -228.612583) (xy 327.549015 -228.648238)
			(xy 327.584711 -228.68939) (xy 327.614191 -228.735199) (xy 327.625964 -228.759766) (xy 327.625964 -228.76002)
			(xy 327.630405 -228.768642) (xy 327.644477 -228.781963) (xy 327.662501 -228.789081) (xy 327.672192 -228.789484)
			(xy 327.782936 -228.789484) (xy 327.807574 -228.774244) (xy 327.813924 -228.761036) (xy 327.82688 -228.735778)
			(xy 327.859132 -228.689068) (xy 327.897948 -228.647651) (xy 327.942471 -228.612441) (xy 327.99172 -228.584216)
			(xy 328.044606 -228.563598) (xy 328.099963 -228.551042) (xy 328.15657 -228.546826) (xy 328.213177 -228.551042)
			(xy 328.268534 -228.563598) (xy 328.32142 -228.584216) (xy 328.370669 -228.612441) (xy 328.415192 -228.647651)
			(xy 328.454008 -228.689068) (xy 328.48626 -228.735778) (xy 328.499216 -228.761036) (xy 328.505566 -228.774244)
			(xy 328.530204 -228.789484) (xy 330.24953 -228.789484) (xy 330.259145 -228.789066) (xy 330.277019 -228.781972)
			(xy 330.291024 -228.768793) (xy 330.295504 -228.760274) (xy 330.34097 -228.663246) (xy 330.33716 -228.63429)
			(xy 330.327762 -228.62286) (xy 330.311144 -228.602211) (xy 330.283174 -228.557189) (xy 330.261708 -228.508727)
			(xy 330.247161 -228.457759) (xy 330.239811 -228.405268) (xy 330.23937 -228.378766) (xy 330.239856 -228.351515)
			(xy 330.247612 -228.297567) (xy 330.262967 -228.245272) (xy 330.285609 -228.195695) (xy 330.315075 -228.149845)
			(xy 330.350766 -228.108654) (xy 330.391957 -228.072963) (xy 330.437807 -228.043497) (xy 330.487384 -228.020855)
			(xy 330.539679 -228.0055) (xy 330.593627 -227.997744) (xy 330.648129 -227.997744) (xy 330.702077 -228.0055)
			(xy 330.754372 -228.020855) (xy 330.803949 -228.043497) (xy 330.849799 -228.072963) (xy 330.89099 -228.108654)
			(xy 330.926681 -228.149845) (xy 330.956147 -228.195695) (xy 330.978789 -228.245272) (xy 330.994144 -228.297567)
			(xy 331.0019 -228.351515) (xy 331.002386 -228.378766) (xy 331.001933 -228.405268) (xy 330.994594 -228.457761)
			(xy 330.980053 -228.508731) (xy 330.958591 -228.557195) (xy 330.930622 -228.602219) (xy 330.913994 -228.62286)
			(xy 330.904596 -228.63429) (xy 330.900786 -228.663246) (xy 330.946252 -228.760274) (xy 330.950713 -228.768803)
			(xy 330.964727 -228.781974) (xy 330.98261 -228.789053) (xy 330.992226 -228.789484) (xy 331.032866 -228.789484)
			(xy 331.042739 -228.789015) (xy 331.061024 -228.781558) (xy 331.068426 -228.775006) (xy 331.06868 -228.774752)
			(xy 331.318108 -228.525324) (xy 331.324966 -228.498654) (xy 331.321156 -228.485192) (xy 331.314642 -228.461141)
			(xy 331.30763 -228.411808) (xy 331.307186 -228.386894) (xy 331.307735 -228.358911) (xy 331.316491 -228.303634)
			(xy 331.333786 -228.250408) (xy 331.359194 -228.200542) (xy 331.392091 -228.155264) (xy 331.431664 -228.115691)
			(xy 331.476942 -228.082794) (xy 331.526808 -228.057386) (xy 331.580034 -228.040091) (xy 331.635311 -228.031335)
			(xy 331.663294 -228.030786) (xy 331.688205 -228.031262) (xy 331.737533 -228.038278) (xy 331.761592 -228.044756)
			(xy 331.775054 -228.048566) (xy 331.801724 -228.041708) (xy 332.903068 -226.940364) (xy 332.910467 -226.933521)
			(xy 332.929066 -226.925801) (xy 332.939136 -226.925378) (xy 334.06334 -226.925378) (xy 334.073939 -226.924827)
			(xy 334.093343 -226.916289) (xy 334.100932 -226.908868) (xy 334.158844 -226.845876) (xy 334.165448 -226.826064)
			(xy 334.164686 -226.815142) (xy 334.163416 -226.786948) (xy 334.163926 -226.760961) (xy 334.172056 -226.709626)
			(xy 334.188117 -226.660196) (xy 334.211713 -226.613886) (xy 334.242263 -226.571838) (xy 334.279014 -226.535087)
			(xy 334.321062 -226.504537) (xy 334.367372 -226.480941) (xy 334.416802 -226.46488) (xy 334.468137 -226.45675)
			(xy 334.520111 -226.45675) (xy 334.571446 -226.46488) (xy 334.620876 -226.480941) (xy 334.667186 -226.504537)
			(xy 334.709234 -226.535087) (xy 334.745985 -226.571838) (xy 334.776535 -226.613886) (xy 334.800131 -226.660196)
			(xy 334.816192 -226.709626) (xy 334.824322 -226.760961) (xy 334.824832 -226.786948) (xy 334.82453 -226.806048)
			(xy 334.820073 -226.843989) (xy 334.815942 -226.86264) (xy 334.814672 -226.868482) (xy 334.814672 -226.874578)
			(xy 334.815156 -226.884591) (xy 334.82281 -226.903095) (xy 334.836963 -226.917262) (xy 334.85546 -226.924934)
			(xy 334.865472 -226.925378) (xy 334.922622 -226.925378) (xy 334.932625 -226.924886) (xy 334.951106 -226.917222)
			(xy 334.965246 -226.903069) (xy 334.972895 -226.884582) (xy 334.973422 -226.874578) (xy 334.973422 -226.868482)
			(xy 334.972152 -226.86264) (xy 334.968011 -226.843991) (xy 334.963549 -226.806049) (xy 334.963262 -226.786948)
			(xy 334.963772 -226.760961) (xy 334.971902 -226.709626) (xy 334.987963 -226.660196) (xy 335.011559 -226.613886)
			(xy 335.042109 -226.571838) (xy 335.07886 -226.535087) (xy 335.120908 -226.504537) (xy 335.167218 -226.480941)
			(xy 335.216648 -226.46488) (xy 335.267983 -226.45675) (xy 335.319957 -226.45675) (xy 335.371292 -226.46488)
			(xy 335.420722 -226.480941) (xy 335.467032 -226.504537) (xy 335.50908 -226.535087) (xy 335.545831 -226.571838)
			(xy 335.576381 -226.613886) (xy 335.599977 -226.660196) (xy 335.616038 -226.709626) (xy 335.624168 -226.760961)
			(xy 335.624678 -226.786948) (xy 335.624376 -226.806048) (xy 335.619919 -226.843989) (xy 335.615788 -226.86264)
			(xy 335.614518 -226.868482) (xy 335.614518 -226.874578) (xy 335.614934 -226.884601) (xy 335.622601 -226.903122)
			(xy 335.636774 -226.917297) (xy 335.655295 -226.924965) (xy 335.665318 -226.925378) (xy 335.722722 -226.925378)
			(xy 335.732725 -226.924886) (xy 335.751206 -226.917222) (xy 335.765346 -226.903069) (xy 335.772995 -226.884582)
			(xy 335.773522 -226.874578) (xy 335.773522 -226.868482) (xy 335.772252 -226.86264) (xy 335.768111 -226.843991)
			(xy 335.763649 -226.806049) (xy 335.763362 -226.786948) (xy 335.763872 -226.760961) (xy 335.772002 -226.709626)
			(xy 335.788063 -226.660196) (xy 335.811659 -226.613886) (xy 335.842209 -226.571838) (xy 335.87896 -226.535087)
			(xy 335.921008 -226.504537) (xy 335.967318 -226.480941) (xy 336.016748 -226.46488) (xy 336.068083 -226.45675)
			(xy 336.120057 -226.45675) (xy 336.171392 -226.46488) (xy 336.220822 -226.480941) (xy 336.267132 -226.504537)
			(xy 336.30918 -226.535087) (xy 336.345931 -226.571838) (xy 336.376481 -226.613886) (xy 336.400077 -226.660196)
			(xy 336.416138 -226.709626) (xy 336.424268 -226.760961) (xy 336.424778 -226.786948) (xy 336.424476 -226.806048)
			(xy 336.420019 -226.843989) (xy 336.415888 -226.86264) (xy 336.414618 -226.868482) (xy 336.414618 -226.874578)
			(xy 336.415034 -226.884601) (xy 336.422701 -226.903122) (xy 336.436874 -226.917297) (xy 336.455395 -226.924965)
			(xy 336.465418 -226.925378) (xy 336.522822 -226.925378) (xy 336.532825 -226.924886) (xy 336.551306 -226.917222)
			(xy 336.565446 -226.903069) (xy 336.573095 -226.884582) (xy 336.573622 -226.874578) (xy 336.573622 -226.868482)
			(xy 336.572352 -226.86264) (xy 336.568211 -226.843991) (xy 336.563749 -226.806049) (xy 336.563462 -226.786948)
			(xy 336.563942 -226.760955) (xy 336.572067 -226.709609) (xy 336.588124 -226.660166) (xy 336.611719 -226.613844)
			(xy 336.64227 -226.571784) (xy 336.679024 -226.535021) (xy 336.721078 -226.50446) (xy 336.767394 -226.480854)
			(xy 336.816833 -226.464785) (xy 336.868178 -226.456648) (xy 336.89417 -226.45624) (xy 336.922757 -226.456842)
			(xy 336.979079 -226.466666) (xy 337.032874 -226.486028) (xy 337.058 -226.499674) (xy 337.072986 -226.50831)
			(xy 337.107022 -226.503738) (xy 337.398614 -226.212146) (xy 337.404324 -226.206077) (xy 337.41172 -226.191155)
			(xy 337.413092 -226.182936) (xy 337.414362 -226.1743) (xy 337.41106 -226.158298) (xy 337.406742 -226.150932)
			(xy 337.39309 -226.125762) (xy 337.373716 -226.071884) (xy 337.363905 -226.015476) (xy 337.363308 -225.986848)
			(xy 337.363788 -225.960857) (xy 337.371913 -225.909513) (xy 337.387971 -225.860073) (xy 337.411567 -225.813755)
			(xy 337.442118 -225.771698) (xy 337.478874 -225.734939) (xy 337.520927 -225.704383) (xy 337.567244 -225.680783)
			(xy 337.616682 -225.66472) (xy 337.668025 -225.65659) (xy 337.694016 -225.65614) (xy 337.722645 -225.656723)
			(xy 337.779056 -225.666534) (xy 337.832935 -225.685911) (xy 337.8581 -225.699574) (xy 337.865474 -225.703455)
			(xy 337.881807 -225.706697) (xy 337.890104 -225.705924) (xy 337.898293 -225.704463) (xy 337.91318 -225.697066)
			(xy 337.919314 -225.691446) (xy 338.198714 -225.412046) (xy 338.204424 -225.405977) (xy 338.21182 -225.391055)
			(xy 338.213192 -225.382836) (xy 338.214462 -225.3742) (xy 338.21116 -225.358198) (xy 338.206842 -225.350832)
			(xy 338.19319 -225.325662) (xy 338.173816 -225.271784) (xy 338.164005 -225.215376) (xy 338.163408 -225.186748)
			(xy 338.163888 -225.160757) (xy 338.172013 -225.109413) (xy 338.188071 -225.059973) (xy 338.211667 -225.013655)
			(xy 338.242218 -224.971598) (xy 338.278974 -224.934839) (xy 338.321027 -224.904283) (xy 338.367344 -224.880683)
			(xy 338.416782 -224.86462) (xy 338.468125 -224.85649) (xy 338.494116 -224.85604) (xy 338.522745 -224.856623)
			(xy 338.579156 -224.866434) (xy 338.633035 -224.885811) (xy 338.6582 -224.899474) (xy 338.665574 -224.903355)
			(xy 338.681907 -224.906597) (xy 338.690204 -224.905824) (xy 338.698393 -224.904363) (xy 338.71328 -224.896966)
			(xy 338.719414 -224.891346) (xy 338.99856 -224.6122) (xy 339.004272 -224.606132) (xy 339.011677 -224.591211)
			(xy 339.013038 -224.58299) (xy 339.014308 -224.574354) (xy 339.011006 -224.558352) (xy 339.006688 -224.550986)
			(xy 338.993031 -224.525817) (xy 338.973645 -224.471941) (xy 338.963823 -224.415531) (xy 338.963254 -224.386902)
			(xy 338.963763 -224.360914) (xy 338.971893 -224.309577) (xy 338.987954 -224.260143) (xy 339.011549 -224.213831)
			(xy 339.042098 -224.171779) (xy 339.078849 -224.135024) (xy 339.120897 -224.10447) (xy 339.167206 -224.080869)
			(xy 339.216638 -224.064803) (xy 339.267974 -224.056667) (xy 339.293962 -224.056194) (xy 339.32259 -224.056781)
			(xy 339.378998 -224.066597) (xy 339.432874 -224.085978) (xy 339.458046 -224.099628) (xy 339.46542 -224.103505)
			(xy 339.481752 -224.106735) (xy 339.49005 -224.105978) (xy 339.498244 -224.104526) (xy 339.513148 -224.097146)
			(xy 339.51926 -224.0915) (xy 339.593936 -224.016824) (xy 339.594444 -224.016316) (xy 339.601022 -224.008934)
			(xy 339.608463 -223.990634) (xy 339.608922 -223.980756) (xy 339.608922 -223.962722) (xy 339.608922 -223.960182)
			(xy 339.607783 -223.949065) (xy 339.597374 -223.929318) (xy 339.588856 -223.922082) (xy 339.583522 -223.91878)
			(xy 339.495892 -223.867726) (xy 339.469222 -223.867726) (xy 339.457284 -223.87433) (xy 339.432221 -223.887891)
			(xy 339.37859 -223.907139) (xy 339.322452 -223.916904) (xy 339.293962 -223.91751) (xy 339.267977 -223.916998)
			(xy 339.216646 -223.908862) (xy 339.167221 -223.892798) (xy 339.120916 -223.8692) (xy 339.078873 -223.838649)
			(xy 339.042126 -223.801898) (xy 339.01158 -223.759851) (xy 338.987988 -223.713544) (xy 338.971929 -223.664117)
			(xy 338.963799 -223.612785) (xy 338.963799 -223.560815) (xy 338.971929 -223.509483) (xy 338.987988 -223.460056)
			(xy 339.01158 -223.413749) (xy 339.042126 -223.371702) (xy 339.078873 -223.334951) (xy 339.120916 -223.3044)
			(xy 339.167221 -223.280802) (xy 339.216646 -223.264738) (xy 339.267977 -223.256602) (xy 339.293962 -223.256094)
			(xy 339.322454 -223.256688) (xy 339.378594 -223.266451) (xy 339.43223 -223.285694) (xy 339.457284 -223.299274)
			(xy 339.469222 -223.305878) (xy 339.495892 -223.305878) (xy 339.583522 -223.254824) (xy 339.588856 -223.251522)
			(xy 339.59743 -223.244332) (xy 339.607844 -223.224559) (xy 339.608922 -223.213422) (xy 339.608922 -223.162876)
			(xy 339.608922 -223.160336) (xy 339.607793 -223.149213) (xy 339.597396 -223.129449) (xy 339.588856 -223.122236)
			(xy 339.583522 -223.118934) (xy 339.495892 -223.06788) (xy 339.469222 -223.06788) (xy 339.457284 -223.074484)
			(xy 339.43222 -223.088043) (xy 339.378589 -223.107287) (xy 339.322452 -223.117051) (xy 339.293962 -223.117664)
			(xy 339.26798 -223.117151) (xy 339.216657 -223.109017) (xy 339.167238 -223.092955) (xy 339.12094 -223.06936)
			(xy 339.078903 -223.038814) (xy 339.042161 -223.002068) (xy 339.01162 -222.960027) (xy 338.988031 -222.913726)
			(xy 338.971974 -222.864306) (xy 338.963846 -222.812982) (xy 338.963846 -222.761018) (xy 338.971974 -222.709694)
			(xy 338.988031 -222.660274) (xy 339.01162 -222.613973) (xy 339.042161 -222.571932) (xy 339.078903 -222.535186)
			(xy 339.12094 -222.50464) (xy 339.167238 -222.481045) (xy 339.216657 -222.464983) (xy 339.26798 -222.456849)
			(xy 339.293962 -222.456248) (xy 339.322454 -222.456842) (xy 339.378594 -222.466606) (xy 339.432228 -222.485853)
			(xy 339.457284 -222.499428) (xy 339.469222 -222.506032) (xy 339.495892 -222.506032) (xy 339.583522 -222.454978)
			(xy 339.588856 -222.451676) (xy 339.597438 -222.44449) (xy 339.607873 -222.424718) (xy 339.608922 -222.413576)
			(xy 339.608922 -221.099634) (xy 339.608487 -221.089569) (xy 339.600759 -221.070979) (xy 339.593936 -221.063566)
			(xy 339.427566 -220.897196) (xy 339.420454 -220.88983) (xy 339.401658 -220.88221) (xy 338.875624 -220.88221)
			(xy 338.866496 -220.882632) (xy 338.849439 -220.889144) (xy 338.84235 -220.89491) (xy 338.836254 -220.89999)
			(xy 338.787486 -220.98127) (xy 338.783246 -220.988932) (xy 338.779729 -221.006072) (xy 338.782213 -221.023393)
			(xy 338.785962 -221.031308) (xy 338.786216 -221.031562) (xy 338.786216 -221.031816) (xy 338.798415 -221.055979)
			(xy 338.815657 -221.107284) (xy 338.824338 -221.160708) (xy 338.824824 -221.187772) (xy 338.824824 -221.192344)
			(xy 338.823902 -221.218044) (xy 338.815086 -221.268706) (xy 338.798536 -221.317394) (xy 338.774649 -221.362934)
			(xy 338.744003 -221.404228) (xy 338.707335 -221.440282) (xy 338.665529 -221.470226) (xy 338.619592 -221.493339)
			(xy 338.570632 -221.509065) (xy 338.519828 -221.517023) (xy 338.468404 -221.517023) (xy 338.4176 -221.509065)
			(xy 338.36864 -221.493339) (xy 338.322703 -221.470226) (xy 338.280897 -221.440282) (xy 338.244229 -221.404228)
			(xy 338.213583 -221.362934) (xy 338.189696 -221.317394) (xy 338.173146 -221.268706) (xy 338.16433 -221.218044)
			(xy 338.163408 -221.192344) (xy 338.163408 -221.187772) (xy 338.163858 -221.160704) (xy 338.172511 -221.107268)
			(xy 338.189777 -221.055963) (xy 338.202016 -221.031816) (xy 338.202016 -221.031562) (xy 338.20227 -221.031308)
			(xy 338.20602 -221.023395) (xy 338.208484 -221.006071) (xy 338.204995 -220.988925) (xy 338.200746 -220.98127)
			(xy 338.156042 -220.906848) (xy 338.15392 -220.903532) (xy 338.14881 -220.897543) (xy 338.145882 -220.89491)
			(xy 338.138779 -220.889173) (xy 338.121728 -220.882675) (xy 338.112608 -220.88221) (xy 338.075524 -220.88221)
			(xy 338.066396 -220.882632) (xy 338.049339 -220.889144) (xy 338.04225 -220.89491) (xy 338.036154 -220.89999)
			(xy 337.987386 -220.98127) (xy 337.983146 -220.988932) (xy 337.979629 -221.006072) (xy 337.982113 -221.023393)
			(xy 337.985862 -221.031308) (xy 337.986116 -221.031562) (xy 337.986116 -221.031816) (xy 337.998315 -221.055979)
			(xy 338.015557 -221.107284) (xy 338.024238 -221.160708) (xy 338.024724 -221.187772) (xy 338.024724 -221.192344)
			(xy 338.023802 -221.218044) (xy 338.014986 -221.268706) (xy 337.998436 -221.317394) (xy 337.974549 -221.362934)
			(xy 337.943903 -221.404228) (xy 337.907235 -221.440282) (xy 337.865429 -221.470226) (xy 337.819492 -221.493339)
			(xy 337.770532 -221.509065) (xy 337.719728 -221.517023) (xy 337.668304 -221.517023) (xy 337.6175 -221.509065)
			(xy 337.56854 -221.493339) (xy 337.522603 -221.470226) (xy 337.480797 -221.440282) (xy 337.444129 -221.404228)
			(xy 337.413483 -221.362934) (xy 337.389596 -221.317394) (xy 337.373046 -221.268706) (xy 337.36423 -221.218044)
			(xy 337.363308 -221.192344) (xy 337.363308 -221.187772) (xy 337.363758 -221.160704) (xy 337.372411 -221.107268)
			(xy 337.389677 -221.055963) (xy 337.401916 -221.031816) (xy 337.401916 -221.031562) (xy 337.40217 -221.031308)
			(xy 337.40592 -221.023395) (xy 337.408384 -221.006071) (xy 337.404895 -220.988925) (xy 337.400646 -220.98127)
			(xy 337.355942 -220.906848) (xy 337.35382 -220.903532) (xy 337.34871 -220.897543) (xy 337.345782 -220.89491)
			(xy 337.338679 -220.889173) (xy 337.321628 -220.882675) (xy 337.312508 -220.88221) (xy 337.275678 -220.88221)
			(xy 337.266553 -220.88264) (xy 337.249506 -220.889163) (xy 337.242404 -220.89491) (xy 337.236308 -220.89999)
			(xy 337.18754 -220.98127) (xy 337.183303 -220.988933) (xy 337.17979 -221.006072) (xy 337.182271 -221.023392)
			(xy 337.186016 -221.031308) (xy 337.18627 -221.031562) (xy 337.18627 -221.031816) (xy 337.198467 -221.05598)
			(xy 337.215706 -221.107285) (xy 337.224386 -221.160709) (xy 337.224878 -221.187772) (xy 337.224878 -221.192344)
			(xy 337.223956 -221.218044) (xy 337.21514 -221.268706) (xy 337.19859 -221.317394) (xy 337.174703 -221.362934)
			(xy 337.144057 -221.404228) (xy 337.107389 -221.440282) (xy 337.065583 -221.470226) (xy 337.019646 -221.493339)
			(xy 336.970686 -221.509065) (xy 336.919882 -221.517023) (xy 336.868458 -221.517023) (xy 336.817654 -221.509065)
			(xy 336.768694 -221.493339) (xy 336.722757 -221.470226) (xy 336.680951 -221.440282) (xy 336.644283 -221.404228)
			(xy 336.613637 -221.362934) (xy 336.58975 -221.317394) (xy 336.5732 -221.268706) (xy 336.564384 -221.218044)
			(xy 336.563462 -221.192344) (xy 336.563462 -221.187772) (xy 336.563912 -221.160704) (xy 336.572564 -221.107267)
			(xy 336.589827 -221.055961) (xy 336.60207 -221.031816) (xy 336.60207 -221.031562) (xy 336.602324 -221.031308)
			(xy 336.606077 -221.023396) (xy 336.608543 -221.006071) (xy 336.605051 -220.988924) (xy 336.6008 -220.98127)
			(xy 336.556096 -220.906848) (xy 336.553976 -220.90353) (xy 336.54887 -220.897537) (xy 336.545936 -220.89491)
			(xy 336.538835 -220.889165) (xy 336.521785 -220.88265) (xy 336.512662 -220.88221) (xy 336.475578 -220.88221)
			(xy 336.466453 -220.88264) (xy 336.449406 -220.889163) (xy 336.442304 -220.89491) (xy 336.436208 -220.89999)
			(xy 336.38744 -220.98127) (xy 336.383203 -220.988933) (xy 336.37969 -221.006072) (xy 336.382171 -221.023392)
			(xy 336.385916 -221.031308) (xy 336.38617 -221.031562) (xy 336.38617 -221.031816) (xy 336.398367 -221.05598)
			(xy 336.415606 -221.107285) (xy 336.424286 -221.160709) (xy 336.424778 -221.187772) (xy 336.424778 -221.192344)
			(xy 336.423856 -221.218044) (xy 336.41504 -221.268706) (xy 336.39849 -221.317394) (xy 336.374603 -221.362934)
			(xy 336.343957 -221.404228) (xy 336.307289 -221.440282) (xy 336.265483 -221.470226) (xy 336.219546 -221.493339)
			(xy 336.170586 -221.509065) (xy 336.119782 -221.517023) (xy 336.068358 -221.517023) (xy 336.017554 -221.509065)
			(xy 335.968594 -221.493339) (xy 335.922657 -221.470226) (xy 335.880851 -221.440282) (xy 335.844183 -221.404228)
			(xy 335.813537 -221.362934) (xy 335.78965 -221.317394) (xy 335.7731 -221.268706) (xy 335.764284 -221.218044)
			(xy 335.763362 -221.192344) (xy 335.763362 -221.187772) (xy 335.763812 -221.160704) (xy 335.772464 -221.107267)
			(xy 335.789727 -221.055961) (xy 335.80197 -221.031816) (xy 335.80197 -221.031562) (xy 335.802224 -221.031308)
			(xy 335.805977 -221.023396) (xy 335.808443 -221.006071) (xy 335.804951 -220.988924) (xy 335.8007 -220.98127)
			(xy 335.755996 -220.906848) (xy 335.753876 -220.90353) (xy 335.74877 -220.897537) (xy 335.745836 -220.89491)
			(xy 335.738735 -220.889165) (xy 335.721685 -220.88265) (xy 335.712562 -220.88221) (xy 335.675478 -220.88221)
			(xy 335.666353 -220.88264) (xy 335.649306 -220.889163) (xy 335.642204 -220.89491) (xy 335.636108 -220.89999)
			(xy 335.58734 -220.98127) (xy 335.583103 -220.988933) (xy 335.57959 -221.006072) (xy 335.582071 -221.023392)
			(xy 335.585816 -221.031308) (xy 335.58607 -221.031562) (xy 335.58607 -221.031816) (xy 335.598267 -221.05598)
			(xy 335.615506 -221.107285) (xy 335.624186 -221.160709) (xy 335.624678 -221.187772) (xy 335.624678 -221.192344)
			(xy 335.623756 -221.218044) (xy 335.61494 -221.268706) (xy 335.59839 -221.317394) (xy 335.574503 -221.362934)
			(xy 335.543857 -221.404228) (xy 335.507189 -221.440282) (xy 335.465383 -221.470226) (xy 335.419446 -221.493339)
			(xy 335.370486 -221.509065) (xy 335.319682 -221.517023) (xy 335.268258 -221.517023) (xy 335.217454 -221.509065)
			(xy 335.168494 -221.493339) (xy 335.122557 -221.470226) (xy 335.080751 -221.440282) (xy 335.044083 -221.404228)
			(xy 335.013437 -221.362934) (xy 334.98955 -221.317394) (xy 334.973 -221.268706) (xy 334.964184 -221.218044)
			(xy 334.963262 -221.192344) (xy 334.963262 -221.187772) (xy 334.963712 -221.160704) (xy 334.972364 -221.107267)
			(xy 334.989627 -221.055961) (xy 335.00187 -221.031816) (xy 335.00187 -221.031562) (xy 335.002124 -221.031308)
			(xy 335.005877 -221.023396) (xy 335.008343 -221.006071) (xy 335.004851 -220.988924) (xy 335.0006 -220.98127)
			(xy 334.955896 -220.906848) (xy 334.953776 -220.90353) (xy 334.94867 -220.897537) (xy 334.945736 -220.89491)
			(xy 334.938635 -220.889165) (xy 334.921585 -220.88265) (xy 334.912462 -220.88221) (xy 333.290672 -220.88221)
			(xy 333.285338 -220.882464) (xy 333.275651 -220.883973) (xy 333.258392 -220.893235) (xy 333.25181 -220.900498)
			(xy 333.248 -220.905832) (xy 333.194914 -220.98889) (xy 333.193136 -221.014798) (xy 333.198724 -221.026482)
			(xy 333.209224 -221.050144) (xy 333.224042 -221.099744) (xy 333.231526 -221.150967) (xy 333.231998 -221.17685)
			(xy 333.2315 -221.203499) (xy 333.223557 -221.256203) (xy 333.207847 -221.307133) (xy 333.184721 -221.355154)
			(xy 333.154697 -221.399191) (xy 333.118445 -221.438262) (xy 333.076774 -221.471493) (xy 333.030616 -221.498142)
			(xy 332.981002 -221.517614) (xy 332.92904 -221.529474) (xy 332.87589 -221.533458) (xy 332.82274 -221.529474)
			(xy 332.770778 -221.517614) (xy 332.721164 -221.498142) (xy 332.675006 -221.471493) (xy 332.633335 -221.438262)
			(xy 332.597083 -221.399191) (xy 332.567059 -221.355154) (xy 332.543933 -221.307133) (xy 332.528223 -221.256203)
			(xy 332.52028 -221.203499) (xy 332.519782 -221.17685) (xy 332.520249 -221.150967) (xy 332.527745 -221.099748)
			(xy 332.542571 -221.050151) (xy 332.553056 -221.026482) (xy 332.558644 -221.014798) (xy 332.556866 -220.98889)
			(xy 332.50378 -220.905832) (xy 332.49997 -220.900498) (xy 332.493368 -220.893257) (xy 332.476122 -220.88399)
			(xy 332.466442 -220.882464) (xy 332.461108 -220.88221) (xy 326.40524 -220.88221) (xy 326.395175 -220.882644)
			(xy 326.376587 -220.890375) (xy 326.369172 -220.897196) (xy 325.829168 -221.4372) (xy 328.166982 -221.4372)
			(xy 328.171053 -221.381578) (xy 328.183179 -221.327141) (xy 328.203102 -221.27505) (xy 328.230398 -221.226415)
			(xy 328.264484 -221.182272) (xy 328.304633 -221.143563) (xy 328.349991 -221.111112) (xy 328.399591 -221.085611)
			(xy 328.452375 -221.067604) (xy 328.507218 -221.057474) (xy 328.562952 -221.055437) (xy 328.618389 -221.061537)
			(xy 328.672346 -221.075643) (xy 328.723675 -221.097455) (xy 328.771281 -221.126509) (xy 328.814149 -221.162184)
			(xy 328.851366 -221.203721) (xy 328.882139 -221.250234) (xy 328.905811 -221.300731) (xy 328.921879 -221.354138)
			(xy 328.929999 -221.409314) (xy 328.930508 -221.4372) (xy 328.929999 -221.465086) (xy 328.921879 -221.520262)
			(xy 328.905811 -221.573669) (xy 328.882139 -221.624166) (xy 328.851366 -221.670679) (xy 328.814149 -221.712216)
			(xy 328.771281 -221.747891) (xy 328.723675 -221.776945) (xy 328.672346 -221.798757) (xy 328.618389 -221.812863)
			(xy 328.562952 -221.818963) (xy 328.507218 -221.816926) (xy 328.452375 -221.806796) (xy 328.399591 -221.788789)
			(xy 328.349991 -221.763288) (xy 328.304633 -221.730837) (xy 328.264484 -221.692128) (xy 328.230398 -221.647985)
			(xy 328.203102 -221.59935) (xy 328.183179 -221.547259) (xy 328.171053 -221.492822) (xy 328.166982 -221.4372)
			(xy 325.829168 -221.4372) (xy 325.3359 -221.930468) (xy 325.329804 -221.96044) (xy 325.335646 -221.974664)
			(xy 325.344726 -221.997753) (xy 325.348748 -222.012843) (xy 334.963772 -222.012843) (xy 334.963772 -221.960869)
			(xy 334.971902 -221.909534) (xy 334.987963 -221.860104) (xy 335.011559 -221.813794) (xy 335.042109 -221.771746)
			(xy 335.07886 -221.734995) (xy 335.120908 -221.704445) (xy 335.167218 -221.680849) (xy 335.216648 -221.664788)
			(xy 335.267983 -221.656658) (xy 335.319957 -221.656658) (xy 335.371292 -221.664788) (xy 335.420722 -221.680849)
			(xy 335.467032 -221.704445) (xy 335.50908 -221.734995) (xy 335.545831 -221.771746) (xy 335.576381 -221.813794)
			(xy 335.599977 -221.860104) (xy 335.616038 -221.909534) (xy 335.624168 -221.960869) (xy 335.624678 -221.986856)
			(xy 335.624168 -222.012843) (xy 335.624128 -222.013097) (xy 335.763618 -222.013097) (xy 335.763618 -221.961123)
			(xy 335.771748 -221.909788) (xy 335.787809 -221.860358) (xy 335.811405 -221.814048) (xy 335.841955 -221.772)
			(xy 335.878706 -221.735249) (xy 335.920754 -221.704699) (xy 335.967064 -221.681103) (xy 336.016494 -221.665042)
			(xy 336.067829 -221.656912) (xy 336.119803 -221.656912) (xy 336.171138 -221.665042) (xy 336.220568 -221.681103)
			(xy 336.266878 -221.704699) (xy 336.308926 -221.735249) (xy 336.345677 -221.772) (xy 336.376227 -221.814048)
			(xy 336.399823 -221.860358) (xy 336.415884 -221.909788) (xy 336.424014 -221.961123) (xy 336.424524 -221.98711)
			(xy 336.424019 -222.012843) (xy 336.563972 -222.012843) (xy 336.563972 -221.960869) (xy 336.572102 -221.909534)
			(xy 336.588163 -221.860104) (xy 336.611759 -221.813794) (xy 336.642309 -221.771746) (xy 336.67906 -221.734995)
			(xy 336.721108 -221.704445) (xy 336.767418 -221.680849) (xy 336.816848 -221.664788) (xy 336.868183 -221.656658)
			(xy 336.920157 -221.656658) (xy 336.971492 -221.664788) (xy 337.020922 -221.680849) (xy 337.067232 -221.704445)
			(xy 337.10928 -221.734995) (xy 337.146031 -221.771746) (xy 337.176581 -221.813794) (xy 337.200177 -221.860104)
			(xy 337.216238 -221.909534) (xy 337.224368 -221.960869) (xy 337.224878 -221.986856) (xy 337.224368 -222.012843)
			(xy 337.363818 -222.012843) (xy 337.363818 -221.960869) (xy 337.371948 -221.909534) (xy 337.388009 -221.860104)
			(xy 337.411605 -221.813794) (xy 337.442155 -221.771746) (xy 337.478906 -221.734995) (xy 337.520954 -221.704445)
			(xy 337.567264 -221.680849) (xy 337.616694 -221.664788) (xy 337.668029 -221.656658) (xy 337.720003 -221.656658)
			(xy 337.771338 -221.664788) (xy 337.820768 -221.680849) (xy 337.867078 -221.704445) (xy 337.909126 -221.734995)
			(xy 337.945877 -221.771746) (xy 337.976427 -221.813794) (xy 338.000023 -221.860104) (xy 338.016084 -221.909534)
			(xy 338.024214 -221.960869) (xy 338.024724 -221.986856) (xy 338.024214 -222.012843) (xy 338.163918 -222.012843)
			(xy 338.163918 -221.960869) (xy 338.172048 -221.909534) (xy 338.188109 -221.860104) (xy 338.211705 -221.813794)
			(xy 338.242255 -221.771746) (xy 338.279006 -221.734995) (xy 338.321054 -221.704445) (xy 338.367364 -221.680849)
			(xy 338.416794 -221.664788) (xy 338.468129 -221.656658) (xy 338.520103 -221.656658) (xy 338.571438 -221.664788)
			(xy 338.620868 -221.680849) (xy 338.667178 -221.704445) (xy 338.709226 -221.734995) (xy 338.745977 -221.771746)
			(xy 338.776527 -221.813794) (xy 338.800123 -221.860104) (xy 338.816184 -221.909534) (xy 338.824314 -221.960869)
			(xy 338.824824 -221.986856) (xy 338.824314 -222.012843) (xy 338.816184 -222.064178) (xy 338.800123 -222.113608)
			(xy 338.776527 -222.159918) (xy 338.745977 -222.201966) (xy 338.709226 -222.238717) (xy 338.667178 -222.269267)
			(xy 338.620868 -222.292863) (xy 338.571438 -222.308924) (xy 338.520103 -222.317054) (xy 338.468129 -222.317054)
			(xy 338.416794 -222.308924) (xy 338.367364 -222.292863) (xy 338.321054 -222.269267) (xy 338.279006 -222.238717)
			(xy 338.242255 -222.201966) (xy 338.211705 -222.159918) (xy 338.188109 -222.113608) (xy 338.172048 -222.064178)
			(xy 338.163918 -222.012843) (xy 338.024214 -222.012843) (xy 338.016084 -222.064178) (xy 338.000023 -222.113608)
			(xy 337.976427 -222.159918) (xy 337.945877 -222.201966) (xy 337.909126 -222.238717) (xy 337.867078 -222.269267)
			(xy 337.820768 -222.292863) (xy 337.771338 -222.308924) (xy 337.720003 -222.317054) (xy 337.668029 -222.317054)
			(xy 337.616694 -222.308924) (xy 337.567264 -222.292863) (xy 337.520954 -222.269267) (xy 337.478906 -222.238717)
			(xy 337.442155 -222.201966) (xy 337.411605 -222.159918) (xy 337.388009 -222.113608) (xy 337.371948 -222.064178)
			(xy 337.363818 -222.012843) (xy 337.224368 -222.012843) (xy 337.216238 -222.064178) (xy 337.200177 -222.113608)
			(xy 337.176581 -222.159918) (xy 337.146031 -222.201966) (xy 337.10928 -222.238717) (xy 337.067232 -222.269267)
			(xy 337.020922 -222.292863) (xy 336.971492 -222.308924) (xy 336.920157 -222.317054) (xy 336.868183 -222.317054)
			(xy 336.816848 -222.308924) (xy 336.767418 -222.292863) (xy 336.721108 -222.269267) (xy 336.67906 -222.238717)
			(xy 336.642309 -222.201966) (xy 336.611759 -222.159918) (xy 336.588163 -222.113608) (xy 336.572102 -222.064178)
			(xy 336.563972 -222.012843) (xy 336.424019 -222.012843) (xy 336.424014 -222.013097) (xy 336.415884 -222.064432)
			(xy 336.399823 -222.113862) (xy 336.376227 -222.160172) (xy 336.345677 -222.20222) (xy 336.308926 -222.238971)
			(xy 336.266878 -222.269521) (xy 336.220568 -222.293117) (xy 336.171138 -222.309178) (xy 336.119803 -222.317308)
			(xy 336.067829 -222.317308) (xy 336.016494 -222.309178) (xy 335.967064 -222.293117) (xy 335.920754 -222.269521)
			(xy 335.878706 -222.238971) (xy 335.841955 -222.20222) (xy 335.811405 -222.160172) (xy 335.787809 -222.113862)
			(xy 335.771748 -222.064432) (xy 335.763618 -222.013097) (xy 335.624128 -222.013097) (xy 335.616038 -222.064178)
			(xy 335.599977 -222.113608) (xy 335.576381 -222.159918) (xy 335.545831 -222.201966) (xy 335.50908 -222.238717)
			(xy 335.467032 -222.269267) (xy 335.420722 -222.292863) (xy 335.371292 -222.308924) (xy 335.319957 -222.317054)
			(xy 335.267983 -222.317054) (xy 335.216648 -222.308924) (xy 335.167218 -222.292863) (xy 335.120908 -222.269267)
			(xy 335.07886 -222.238717) (xy 335.042109 -222.201966) (xy 335.011559 -222.159918) (xy 334.987963 -222.113608)
			(xy 334.971902 -222.064178) (xy 334.963772 -222.012843) (xy 325.348748 -222.012843) (xy 325.357504 -222.045695)
			(xy 325.363942 -222.09489) (xy 325.364348 -222.119698) (xy 325.363856 -222.147365) (xy 325.355865 -222.202118)
			(xy 325.340052 -222.255143) (xy 325.316746 -222.305329) (xy 325.286438 -222.351624) (xy 325.249761 -222.393056)
			(xy 325.207486 -222.428757) (xy 325.184262 -222.443802) (xy 325.178674 -222.447104) (xy 325.170292 -222.455994)
			(xy 325.155052 -222.48241) (xy 325.151905 -222.488286) (xy 325.148423 -222.501149) (xy 325.148194 -222.50781)
			(xy 325.148194 -222.829882) (xy 326.08469 -222.829882) (xy 326.088761 -222.77426) (xy 326.100887 -222.719823)
			(xy 326.12081 -222.667732) (xy 326.148106 -222.619097) (xy 326.182192 -222.574954) (xy 326.222341 -222.536245)
			(xy 326.267699 -222.503794) (xy 326.317299 -222.478293) (xy 326.370083 -222.460286) (xy 326.424926 -222.450156)
			(xy 326.48066 -222.448119) (xy 326.526836 -222.4532) (xy 328.166982 -222.4532) (xy 328.171053 -222.397578)
			(xy 328.183179 -222.343141) (xy 328.203102 -222.29105) (xy 328.230398 -222.242415) (xy 328.264484 -222.198272)
			(xy 328.304633 -222.159563) (xy 328.349991 -222.127112) (xy 328.399591 -222.101611) (xy 328.452375 -222.083604)
			(xy 328.507218 -222.073474) (xy 328.562952 -222.071437) (xy 328.618389 -222.077537) (xy 328.672346 -222.091643)
			(xy 328.723675 -222.113455) (xy 328.771281 -222.142509) (xy 328.814149 -222.178184) (xy 328.851366 -222.219721)
			(xy 328.882139 -222.266234) (xy 328.905811 -222.316731) (xy 328.921879 -222.370138) (xy 328.929999 -222.425314)
			(xy 328.930508 -222.4532) (xy 328.929999 -222.481086) (xy 328.921879 -222.536262) (xy 328.905811 -222.589669)
			(xy 328.882139 -222.640166) (xy 328.851366 -222.686679) (xy 328.814149 -222.728216) (xy 328.771281 -222.763891)
			(xy 328.723675 -222.792945) (xy 328.672346 -222.814757) (xy 328.618389 -222.828863) (xy 328.562952 -222.834963)
			(xy 328.507218 -222.832926) (xy 328.452375 -222.822796) (xy 328.399591 -222.804789) (xy 328.349991 -222.779288)
			(xy 328.304633 -222.746837) (xy 328.264484 -222.708128) (xy 328.230398 -222.663985) (xy 328.203102 -222.61535)
			(xy 328.183179 -222.563259) (xy 328.171053 -222.508822) (xy 328.166982 -222.4532) (xy 326.526836 -222.4532)
			(xy 326.536097 -222.454219) (xy 326.590054 -222.468325) (xy 326.641383 -222.490137) (xy 326.688989 -222.519191)
			(xy 326.731857 -222.554866) (xy 326.769074 -222.596403) (xy 326.799847 -222.642916) (xy 326.823519 -222.693413)
			(xy 326.839587 -222.74682) (xy 326.847707 -222.801996) (xy 326.848216 -222.829882) (xy 326.847707 -222.857768)
			(xy 326.842428 -222.893636) (xy 331.275942 -222.893636) (xy 331.280013 -222.838014) (xy 331.292139 -222.783577)
			(xy 331.312062 -222.731486) (xy 331.339358 -222.682851) (xy 331.373444 -222.638708) (xy 331.413593 -222.599999)
			(xy 331.458951 -222.567548) (xy 331.508551 -222.542047) (xy 331.561335 -222.52404) (xy 331.616178 -222.51391)
			(xy 331.671912 -222.511873) (xy 331.727349 -222.517973) (xy 331.781306 -222.532079) (xy 331.832635 -222.553891)
			(xy 331.880241 -222.582945) (xy 331.923109 -222.61862) (xy 331.960326 -222.660157) (xy 331.991099 -222.70667)
			(xy 332.014771 -222.757167) (xy 332.030839 -222.810574) (xy 332.038959 -222.86575) (xy 332.039468 -222.893636)
			(xy 332.039213 -222.907606) (xy 332.295244 -222.907606) (xy 332.299315 -222.851984) (xy 332.311441 -222.797547)
			(xy 332.331364 -222.745456) (xy 332.35866 -222.696821) (xy 332.392746 -222.652678) (xy 332.432895 -222.613969)
			(xy 332.478253 -222.581518) (xy 332.527853 -222.556017) (xy 332.580637 -222.53801) (xy 332.63548 -222.52788)
			(xy 332.691214 -222.525843) (xy 332.746651 -222.531943) (xy 332.800608 -222.546049) (xy 332.851937 -222.567861)
			(xy 332.899543 -222.596915) (xy 332.942411 -222.63259) (xy 332.979628 -222.674127) (xy 333.010401 -222.72064)
			(xy 333.034073 -222.771137) (xy 333.046651 -222.812943) (xy 334.963772 -222.812943) (xy 334.963772 -222.760969)
			(xy 334.971902 -222.709634) (xy 334.987963 -222.660204) (xy 335.011559 -222.613894) (xy 335.042109 -222.571846)
			(xy 335.07886 -222.535095) (xy 335.120908 -222.504545) (xy 335.167218 -222.480949) (xy 335.216648 -222.464888)
			(xy 335.267983 -222.456758) (xy 335.319957 -222.456758) (xy 335.371292 -222.464888) (xy 335.420722 -222.480949)
			(xy 335.467032 -222.504545) (xy 335.50908 -222.535095) (xy 335.545831 -222.571846) (xy 335.576381 -222.613894)
			(xy 335.599977 -222.660204) (xy 335.616038 -222.709634) (xy 335.624168 -222.760969) (xy 335.624678 -222.786956)
			(xy 335.624168 -222.812943) (xy 335.763872 -222.812943) (xy 335.763872 -222.760969) (xy 335.772002 -222.709634)
			(xy 335.788063 -222.660204) (xy 335.811659 -222.613894) (xy 335.842209 -222.571846) (xy 335.87896 -222.535095)
			(xy 335.921008 -222.504545) (xy 335.967318 -222.480949) (xy 336.016748 -222.464888) (xy 336.068083 -222.456758)
			(xy 336.120057 -222.456758) (xy 336.171392 -222.464888) (xy 336.220822 -222.480949) (xy 336.267132 -222.504545)
			(xy 336.30918 -222.535095) (xy 336.345931 -222.571846) (xy 336.376481 -222.613894) (xy 336.400077 -222.660204)
			(xy 336.416138 -222.709634) (xy 336.424268 -222.760969) (xy 336.424778 -222.786956) (xy 336.424268 -222.812943)
			(xy 336.563972 -222.812943) (xy 336.563972 -222.760969) (xy 336.572102 -222.709634) (xy 336.588163 -222.660204)
			(xy 336.611759 -222.613894) (xy 336.642309 -222.571846) (xy 336.67906 -222.535095) (xy 336.721108 -222.504545)
			(xy 336.767418 -222.480949) (xy 336.816848 -222.464888) (xy 336.868183 -222.456758) (xy 336.920157 -222.456758)
			(xy 336.971492 -222.464888) (xy 337.020922 -222.480949) (xy 337.067232 -222.504545) (xy 337.10928 -222.535095)
			(xy 337.146031 -222.571846) (xy 337.176581 -222.613894) (xy 337.200177 -222.660204) (xy 337.216238 -222.709634)
			(xy 337.224368 -222.760969) (xy 337.224878 -222.786956) (xy 337.224368 -222.812943) (xy 337.363818 -222.812943)
			(xy 337.363818 -222.760969) (xy 337.371948 -222.709634) (xy 337.388009 -222.660204) (xy 337.411605 -222.613894)
			(xy 337.442155 -222.571846) (xy 337.478906 -222.535095) (xy 337.520954 -222.504545) (xy 337.567264 -222.480949)
			(xy 337.616694 -222.464888) (xy 337.668029 -222.456758) (xy 337.720003 -222.456758) (xy 337.771338 -222.464888)
			(xy 337.820768 -222.480949) (xy 337.867078 -222.504545) (xy 337.909126 -222.535095) (xy 337.945877 -222.571846)
			(xy 337.976427 -222.613894) (xy 338.000023 -222.660204) (xy 338.016084 -222.709634) (xy 338.024214 -222.760969)
			(xy 338.024724 -222.786956) (xy 338.024214 -222.812943) (xy 338.163918 -222.812943) (xy 338.163918 -222.760969)
			(xy 338.172048 -222.709634) (xy 338.188109 -222.660204) (xy 338.211705 -222.613894) (xy 338.242255 -222.571846)
			(xy 338.279006 -222.535095) (xy 338.321054 -222.504545) (xy 338.367364 -222.480949) (xy 338.416794 -222.464888)
			(xy 338.468129 -222.456758) (xy 338.520103 -222.456758) (xy 338.571438 -222.464888) (xy 338.620868 -222.480949)
			(xy 338.667178 -222.504545) (xy 338.709226 -222.535095) (xy 338.745977 -222.571846) (xy 338.776527 -222.613894)
			(xy 338.800123 -222.660204) (xy 338.816184 -222.709634) (xy 338.824314 -222.760969) (xy 338.824824 -222.786956)
			(xy 338.824314 -222.812943) (xy 338.816184 -222.864278) (xy 338.800123 -222.913708) (xy 338.776527 -222.960018)
			(xy 338.745977 -223.002066) (xy 338.709226 -223.038817) (xy 338.667178 -223.069367) (xy 338.620868 -223.092963)
			(xy 338.571438 -223.109024) (xy 338.520103 -223.117154) (xy 338.468129 -223.117154) (xy 338.416794 -223.109024)
			(xy 338.367364 -223.092963) (xy 338.321054 -223.069367) (xy 338.279006 -223.038817) (xy 338.242255 -223.002066)
			(xy 338.211705 -222.960018) (xy 338.188109 -222.913708) (xy 338.172048 -222.864278) (xy 338.163918 -222.812943)
			(xy 338.024214 -222.812943) (xy 338.016084 -222.864278) (xy 338.000023 -222.913708) (xy 337.976427 -222.960018)
			(xy 337.945877 -223.002066) (xy 337.909126 -223.038817) (xy 337.867078 -223.069367) (xy 337.820768 -223.092963)
			(xy 337.771338 -223.109024) (xy 337.720003 -223.117154) (xy 337.668029 -223.117154) (xy 337.616694 -223.109024)
			(xy 337.567264 -223.092963) (xy 337.520954 -223.069367) (xy 337.478906 -223.038817) (xy 337.442155 -223.002066)
			(xy 337.411605 -222.960018) (xy 337.388009 -222.913708) (xy 337.371948 -222.864278) (xy 337.363818 -222.812943)
			(xy 337.224368 -222.812943) (xy 337.216238 -222.864278) (xy 337.200177 -222.913708) (xy 337.176581 -222.960018)
			(xy 337.146031 -223.002066) (xy 337.10928 -223.038817) (xy 337.067232 -223.069367) (xy 337.020922 -223.092963)
			(xy 336.971492 -223.109024) (xy 336.920157 -223.117154) (xy 336.868183 -223.117154) (xy 336.816848 -223.109024)
			(xy 336.767418 -223.092963) (xy 336.721108 -223.069367) (xy 336.67906 -223.038817) (xy 336.642309 -223.002066)
			(xy 336.611759 -222.960018) (xy 336.588163 -222.913708) (xy 336.572102 -222.864278) (xy 336.563972 -222.812943)
			(xy 336.424268 -222.812943) (xy 336.416138 -222.864278) (xy 336.400077 -222.913708) (xy 336.376481 -222.960018)
			(xy 336.345931 -223.002066) (xy 336.30918 -223.038817) (xy 336.267132 -223.069367) (xy 336.220822 -223.092963)
			(xy 336.171392 -223.109024) (xy 336.120057 -223.117154) (xy 336.068083 -223.117154) (xy 336.016748 -223.109024)
			(xy 335.967318 -223.092963) (xy 335.921008 -223.069367) (xy 335.87896 -223.038817) (xy 335.842209 -223.002066)
			(xy 335.811659 -222.960018) (xy 335.788063 -222.913708) (xy 335.772002 -222.864278) (xy 335.763872 -222.812943)
			(xy 335.624168 -222.812943) (xy 335.616038 -222.864278) (xy 335.599977 -222.913708) (xy 335.576381 -222.960018)
			(xy 335.545831 -223.002066) (xy 335.50908 -223.038817) (xy 335.467032 -223.069367) (xy 335.420722 -223.092963)
			(xy 335.371292 -223.109024) (xy 335.319957 -223.117154) (xy 335.267983 -223.117154) (xy 335.216648 -223.109024)
			(xy 335.167218 -223.092963) (xy 335.120908 -223.069367) (xy 335.07886 -223.038817) (xy 335.042109 -223.002066)
			(xy 335.011559 -222.960018) (xy 334.987963 -222.913708) (xy 334.971902 -222.864278) (xy 334.963772 -222.812943)
			(xy 333.046651 -222.812943) (xy 333.050141 -222.824544) (xy 333.058261 -222.87972) (xy 333.05877 -222.907606)
			(xy 333.058261 -222.935492) (xy 333.050141 -222.990668) (xy 333.034073 -223.044075) (xy 333.010401 -223.094572)
			(xy 332.979628 -223.141085) (xy 332.942411 -223.182622) (xy 332.899543 -223.218297) (xy 332.851937 -223.247351)
			(xy 332.800608 -223.269163) (xy 332.746651 -223.283269) (xy 332.691214 -223.289369) (xy 332.63548 -223.287332)
			(xy 332.580637 -223.277202) (xy 332.527853 -223.259195) (xy 332.478253 -223.233694) (xy 332.432895 -223.201243)
			(xy 332.392746 -223.162534) (xy 332.35866 -223.118391) (xy 332.331364 -223.069756) (xy 332.311441 -223.017665)
			(xy 332.299315 -222.963228) (xy 332.295244 -222.907606) (xy 332.039213 -222.907606) (xy 332.038959 -222.921522)
			(xy 332.030839 -222.976698) (xy 332.014771 -223.030105) (xy 331.991099 -223.080602) (xy 331.960326 -223.127115)
			(xy 331.923109 -223.168652) (xy 331.880241 -223.204327) (xy 331.832635 -223.233381) (xy 331.781306 -223.255193)
			(xy 331.727349 -223.269299) (xy 331.671912 -223.275399) (xy 331.616178 -223.273362) (xy 331.561335 -223.263232)
			(xy 331.508551 -223.245225) (xy 331.458951 -223.219724) (xy 331.413593 -223.187273) (xy 331.373444 -223.148564)
			(xy 331.339358 -223.104421) (xy 331.312062 -223.055786) (xy 331.292139 -223.003695) (xy 331.280013 -222.949258)
			(xy 331.275942 -222.893636) (xy 326.842428 -222.893636) (xy 326.839587 -222.912944) (xy 326.823519 -222.966351)
			(xy 326.799847 -223.016848) (xy 326.769074 -223.063361) (xy 326.731857 -223.104898) (xy 326.688989 -223.140573)
			(xy 326.641383 -223.169627) (xy 326.590054 -223.191439) (xy 326.536097 -223.205545) (xy 326.48066 -223.211645)
			(xy 326.424926 -223.209608) (xy 326.370083 -223.199478) (xy 326.317299 -223.181471) (xy 326.267699 -223.15597)
			(xy 326.222341 -223.123519) (xy 326.182192 -223.08481) (xy 326.148106 -223.040667) (xy 326.12081 -222.992032)
			(xy 326.100887 -222.939941) (xy 326.088761 -222.885504) (xy 326.08469 -222.829882) (xy 325.148194 -222.829882)
			(xy 325.148194 -223.001586) (xy 325.148387 -223.008254) (xy 325.151859 -223.021129) (xy 325.155052 -223.026986)
			(xy 325.170038 -223.053402) (xy 325.178674 -223.062038) (xy 325.184262 -223.065594) (xy 325.207148 -223.080393)
			(xy 325.248874 -223.115454) (xy 325.285194 -223.156088) (xy 325.315372 -223.20147) (xy 325.327518 -223.225868)
			(xy 325.332344 -223.236282) (xy 325.34987 -223.250506) (xy 325.448676 -223.27489) (xy 325.470774 -223.270572)
			(xy 325.479918 -223.26346) (xy 325.504839 -223.245606) (xy 325.55918 -223.217238) (xy 325.617354 -223.197912)
			(xy 325.677868 -223.188125) (xy 325.708518 -223.187514) (xy 325.735769 -223.187979) (xy 325.789717 -223.195738)
			(xy 325.842012 -223.211096) (xy 325.891588 -223.233739) (xy 325.937437 -223.263208) (xy 325.978626 -223.298902)
			(xy 326.014316 -223.340095) (xy 326.04378 -223.385947) (xy 326.066418 -223.435526) (xy 326.076304 -223.4692)
			(xy 328.166982 -223.4692) (xy 328.171053 -223.413578) (xy 328.183179 -223.359141) (xy 328.203102 -223.30705)
			(xy 328.230398 -223.258415) (xy 328.264484 -223.214272) (xy 328.304633 -223.175563) (xy 328.349991 -223.143112)
			(xy 328.399591 -223.117611) (xy 328.452375 -223.099604) (xy 328.507218 -223.089474) (xy 328.562952 -223.087437)
			(xy 328.618389 -223.093537) (xy 328.672346 -223.107643) (xy 328.723675 -223.129455) (xy 328.771281 -223.158509)
			(xy 328.814149 -223.194184) (xy 328.851366 -223.235721) (xy 328.882139 -223.282234) (xy 328.905811 -223.332731)
			(xy 328.921879 -223.386138) (xy 328.929999 -223.441314) (xy 328.930508 -223.4692) (xy 328.929999 -223.497086)
			(xy 328.921879 -223.552262) (xy 328.905811 -223.605669) (xy 328.902473 -223.612789) (xy 334.963772 -223.612789)
			(xy 334.963772 -223.560815) (xy 334.971902 -223.50948) (xy 334.987963 -223.46005) (xy 335.011559 -223.41374)
			(xy 335.042109 -223.371692) (xy 335.07886 -223.334941) (xy 335.120908 -223.304391) (xy 335.167218 -223.280795)
			(xy 335.216648 -223.264734) (xy 335.267983 -223.256604) (xy 335.319957 -223.256604) (xy 335.371292 -223.264734)
			(xy 335.420722 -223.280795) (xy 335.467032 -223.304391) (xy 335.50908 -223.334941) (xy 335.545831 -223.371692)
			(xy 335.576381 -223.41374) (xy 335.599977 -223.46005) (xy 335.616038 -223.50948) (xy 335.624168 -223.560815)
			(xy 335.624678 -223.586802) (xy 335.624168 -223.612789) (xy 335.763872 -223.612789) (xy 335.763872 -223.560815)
			(xy 335.772002 -223.50948) (xy 335.788063 -223.46005) (xy 335.811659 -223.41374) (xy 335.842209 -223.371692)
			(xy 335.87896 -223.334941) (xy 335.921008 -223.304391) (xy 335.967318 -223.280795) (xy 336.016748 -223.264734)
			(xy 336.068083 -223.256604) (xy 336.120057 -223.256604) (xy 336.171392 -223.264734) (xy 336.220822 -223.280795)
			(xy 336.267132 -223.304391) (xy 336.30918 -223.334941) (xy 336.345931 -223.371692) (xy 336.376481 -223.41374)
			(xy 336.400077 -223.46005) (xy 336.416138 -223.50948) (xy 336.424268 -223.560815) (xy 336.424778 -223.586802)
			(xy 336.424268 -223.612789) (xy 336.563972 -223.612789) (xy 336.563972 -223.560815) (xy 336.572102 -223.50948)
			(xy 336.588163 -223.46005) (xy 336.611759 -223.41374) (xy 336.642309 -223.371692) (xy 336.67906 -223.334941)
			(xy 336.721108 -223.304391) (xy 336.767418 -223.280795) (xy 336.816848 -223.264734) (xy 336.868183 -223.256604)
			(xy 336.920157 -223.256604) (xy 336.971492 -223.264734) (xy 337.020922 -223.280795) (xy 337.067232 -223.304391)
			(xy 337.10928 -223.334941) (xy 337.146031 -223.371692) (xy 337.176581 -223.41374) (xy 337.200177 -223.46005)
			(xy 337.216238 -223.50948) (xy 337.224368 -223.560815) (xy 337.224878 -223.586802) (xy 337.224368 -223.612789)
			(xy 337.363818 -223.612789) (xy 337.363818 -223.560815) (xy 337.371948 -223.50948) (xy 337.388009 -223.46005)
			(xy 337.411605 -223.41374) (xy 337.442155 -223.371692) (xy 337.478906 -223.334941) (xy 337.520954 -223.304391)
			(xy 337.567264 -223.280795) (xy 337.616694 -223.264734) (xy 337.668029 -223.256604) (xy 337.720003 -223.256604)
			(xy 337.771338 -223.264734) (xy 337.820768 -223.280795) (xy 337.867078 -223.304391) (xy 337.909126 -223.334941)
			(xy 337.945877 -223.371692) (xy 337.976427 -223.41374) (xy 338.000023 -223.46005) (xy 338.016084 -223.50948)
			(xy 338.024214 -223.560815) (xy 338.024724 -223.586802) (xy 338.024214 -223.612789) (xy 338.163918 -223.612789)
			(xy 338.163918 -223.560815) (xy 338.172048 -223.50948) (xy 338.188109 -223.46005) (xy 338.211705 -223.41374)
			(xy 338.242255 -223.371692) (xy 338.279006 -223.334941) (xy 338.321054 -223.304391) (xy 338.367364 -223.280795)
			(xy 338.416794 -223.264734) (xy 338.468129 -223.256604) (xy 338.520103 -223.256604) (xy 338.571438 -223.264734)
			(xy 338.620868 -223.280795) (xy 338.667178 -223.304391) (xy 338.709226 -223.334941) (xy 338.745977 -223.371692)
			(xy 338.776527 -223.41374) (xy 338.800123 -223.46005) (xy 338.816184 -223.50948) (xy 338.824314 -223.560815)
			(xy 338.824824 -223.586802) (xy 338.824314 -223.612789) (xy 338.816184 -223.664124) (xy 338.800123 -223.713554)
			(xy 338.776527 -223.759864) (xy 338.745977 -223.801912) (xy 338.709226 -223.838663) (xy 338.667178 -223.869213)
			(xy 338.620868 -223.892809) (xy 338.571438 -223.90887) (xy 338.520103 -223.917) (xy 338.468129 -223.917)
			(xy 338.416794 -223.90887) (xy 338.367364 -223.892809) (xy 338.321054 -223.869213) (xy 338.279006 -223.838663)
			(xy 338.242255 -223.801912) (xy 338.211705 -223.759864) (xy 338.188109 -223.713554) (xy 338.172048 -223.664124)
			(xy 338.163918 -223.612789) (xy 338.024214 -223.612789) (xy 338.016084 -223.664124) (xy 338.000023 -223.713554)
			(xy 337.976427 -223.759864) (xy 337.945877 -223.801912) (xy 337.909126 -223.838663) (xy 337.867078 -223.869213)
			(xy 337.820768 -223.892809) (xy 337.771338 -223.90887) (xy 337.720003 -223.917) (xy 337.668029 -223.917)
			(xy 337.616694 -223.90887) (xy 337.567264 -223.892809) (xy 337.520954 -223.869213) (xy 337.478906 -223.838663)
			(xy 337.442155 -223.801912) (xy 337.411605 -223.759864) (xy 337.388009 -223.713554) (xy 337.371948 -223.664124)
			(xy 337.363818 -223.612789) (xy 337.224368 -223.612789) (xy 337.216238 -223.664124) (xy 337.200177 -223.713554)
			(xy 337.176581 -223.759864) (xy 337.146031 -223.801912) (xy 337.10928 -223.838663) (xy 337.067232 -223.869213)
			(xy 337.020922 -223.892809) (xy 336.971492 -223.90887) (xy 336.920157 -223.917) (xy 336.868183 -223.917)
			(xy 336.816848 -223.90887) (xy 336.767418 -223.892809) (xy 336.721108 -223.869213) (xy 336.67906 -223.838663)
			(xy 336.642309 -223.801912) (xy 336.611759 -223.759864) (xy 336.588163 -223.713554) (xy 336.572102 -223.664124)
			(xy 336.563972 -223.612789) (xy 336.424268 -223.612789) (xy 336.416138 -223.664124) (xy 336.400077 -223.713554)
			(xy 336.376481 -223.759864) (xy 336.345931 -223.801912) (xy 336.30918 -223.838663) (xy 336.267132 -223.869213)
			(xy 336.220822 -223.892809) (xy 336.171392 -223.90887) (xy 336.120057 -223.917) (xy 336.068083 -223.917)
			(xy 336.016748 -223.90887) (xy 335.967318 -223.892809) (xy 335.921008 -223.869213) (xy 335.87896 -223.838663)
			(xy 335.842209 -223.801912) (xy 335.811659 -223.759864) (xy 335.788063 -223.713554) (xy 335.772002 -223.664124)
			(xy 335.763872 -223.612789) (xy 335.624168 -223.612789) (xy 335.616038 -223.664124) (xy 335.599977 -223.713554)
			(xy 335.576381 -223.759864) (xy 335.545831 -223.801912) (xy 335.50908 -223.838663) (xy 335.467032 -223.869213)
			(xy 335.420722 -223.892809) (xy 335.371292 -223.90887) (xy 335.319957 -223.917) (xy 335.267983 -223.917)
			(xy 335.216648 -223.90887) (xy 335.167218 -223.892809) (xy 335.120908 -223.869213) (xy 335.07886 -223.838663)
			(xy 335.042109 -223.801912) (xy 335.011559 -223.759864) (xy 334.987963 -223.713554) (xy 334.971902 -223.664124)
			(xy 334.963772 -223.612789) (xy 328.902473 -223.612789) (xy 328.882139 -223.656166) (xy 328.851366 -223.702679)
			(xy 328.814149 -223.744216) (xy 328.771281 -223.779891) (xy 328.723675 -223.808945) (xy 328.672346 -223.830757)
			(xy 328.618389 -223.844863) (xy 328.562952 -223.850963) (xy 328.507218 -223.848926) (xy 328.452375 -223.838796)
			(xy 328.399591 -223.820789) (xy 328.349991 -223.795288) (xy 328.304633 -223.762837) (xy 328.264484 -223.724128)
			(xy 328.230398 -223.679985) (xy 328.203102 -223.63135) (xy 328.183179 -223.579259) (xy 328.171053 -223.524822)
			(xy 328.166982 -223.4692) (xy 326.076304 -223.4692) (xy 326.081771 -223.487822) (xy 326.089524 -223.541771)
			(xy 326.090026 -223.569022) (xy 326.090026 -223.574356) (xy 326.089772 -223.588834) (xy 326.10425 -223.613218)
			(xy 326.209406 -223.669098) (xy 326.2376 -223.667574) (xy 326.249538 -223.659192) (xy 326.273597 -223.643183)
			(xy 326.325527 -223.617834) (xy 326.380687 -223.600611) (xy 326.437815 -223.591908) (xy 326.466708 -223.591374)
			(xy 326.493962 -223.591837) (xy 326.547916 -223.599596) (xy 326.600216 -223.614954) (xy 326.649799 -223.637599)
			(xy 326.695653 -223.66707) (xy 326.736847 -223.702766) (xy 326.772542 -223.743962) (xy 326.80201 -223.789818)
			(xy 326.824653 -223.839402) (xy 326.840008 -223.891703) (xy 326.847764 -223.945657) (xy 326.847762 -224.000166)
			(xy 326.840003 -224.054119) (xy 326.824645 -224.106419) (xy 326.801999 -224.156001) (xy 326.772528 -224.201856)
			(xy 326.736831 -224.24305) (xy 326.695635 -224.278744) (xy 326.649779 -224.308212) (xy 326.600195 -224.330854)
			(xy 326.547894 -224.346209) (xy 326.49394 -224.353964) (xy 326.439431 -224.353962) (xy 326.385478 -224.346203)
			(xy 326.333177 -224.330844) (xy 326.283596 -224.308198) (xy 326.237741 -224.278726) (xy 326.196548 -224.243029)
			(xy 326.160854 -224.201833) (xy 326.131386 -224.155976) (xy 326.108745 -224.106392) (xy 326.09339 -224.054091)
			(xy 326.085636 -224.000136) (xy 326.0852 -223.972882) (xy 326.0852 -223.967548) (xy 326.085454 -223.95307)
			(xy 326.070976 -223.928686) (xy 325.96582 -223.872806) (xy 325.937626 -223.87433) (xy 325.925688 -223.882712)
			(xy 325.901629 -223.898722) (xy 325.8497 -223.924075) (xy 325.79454 -223.941301) (xy 325.737412 -223.950008)
			(xy 325.708518 -223.95053) (xy 325.681642 -223.950064) (xy 325.628424 -223.942507) (xy 325.576795 -223.927552)
			(xy 325.527776 -223.905497) (xy 325.482339 -223.876779) (xy 325.441384 -223.841966) (xy 325.405722 -223.801748)
			(xy 325.376059 -223.756922) (xy 325.364094 -223.732852) (xy 325.359014 -223.722438) (xy 325.341488 -223.708214)
			(xy 325.242682 -223.68383) (xy 325.220838 -223.688402) (xy 325.21144 -223.69526) (xy 325.184262 -223.713802)
			(xy 325.178674 -223.717358) (xy 325.170038 -223.725994) (xy 325.155052 -223.75241) (xy 325.151905 -223.758286)
			(xy 325.148423 -223.771149) (xy 325.148194 -223.77781) (xy 325.148194 -224.271586) (xy 325.148387 -224.278254)
			(xy 325.151859 -224.291129) (xy 325.155052 -224.296986) (xy 325.170038 -224.323402) (xy 325.178674 -224.332038)
			(xy 325.184262 -224.335594) (xy 325.207492 -224.350628) (xy 325.24976 -224.386336) (xy 325.286429 -224.427772)
			(xy 325.316731 -224.474069) (xy 325.321899 -224.4852) (xy 328.166982 -224.4852) (xy 328.171053 -224.429578)
			(xy 328.183179 -224.375141) (xy 328.203102 -224.32305) (xy 328.230398 -224.274415) (xy 328.264484 -224.230272)
			(xy 328.304633 -224.191563) (xy 328.349991 -224.159112) (xy 328.399591 -224.133611) (xy 328.452375 -224.115604)
			(xy 328.507218 -224.105474) (xy 328.562952 -224.103437) (xy 328.618389 -224.109537) (xy 328.672346 -224.123643)
			(xy 328.723675 -224.145455) (xy 328.771281 -224.174509) (xy 328.814149 -224.210184) (xy 328.851366 -224.251721)
			(xy 328.882139 -224.298234) (xy 328.905811 -224.348731) (xy 328.921879 -224.402138) (xy 328.923461 -224.412889)
			(xy 334.163926 -224.412889) (xy 334.163926 -224.360915) (xy 334.172056 -224.30958) (xy 334.188117 -224.26015)
			(xy 334.211713 -224.21384) (xy 334.242263 -224.171792) (xy 334.279014 -224.135041) (xy 334.321062 -224.104491)
			(xy 334.367372 -224.080895) (xy 334.416802 -224.064834) (xy 334.468137 -224.056704) (xy 334.520111 -224.056704)
			(xy 334.571446 -224.064834) (xy 334.620876 -224.080895) (xy 334.667186 -224.104491) (xy 334.709234 -224.135041)
			(xy 334.745985 -224.171792) (xy 334.776535 -224.21384) (xy 334.800131 -224.26015) (xy 334.816192 -224.30958)
			(xy 334.824322 -224.360915) (xy 334.824832 -224.386902) (xy 334.824322 -224.412889) (xy 335.763872 -224.412889)
			(xy 335.763872 -224.360915) (xy 335.772002 -224.30958) (xy 335.788063 -224.26015) (xy 335.811659 -224.21384)
			(xy 335.842209 -224.171792) (xy 335.87896 -224.135041) (xy 335.921008 -224.104491) (xy 335.967318 -224.080895)
			(xy 336.016748 -224.064834) (xy 336.068083 -224.056704) (xy 336.120057 -224.056704) (xy 336.171392 -224.064834)
			(xy 336.220822 -224.080895) (xy 336.267132 -224.104491) (xy 336.30918 -224.135041) (xy 336.345931 -224.171792)
			(xy 336.376481 -224.21384) (xy 336.400077 -224.26015) (xy 336.416138 -224.30958) (xy 336.424268 -224.360915)
			(xy 336.424778 -224.386902) (xy 336.424268 -224.412889) (xy 336.563972 -224.412889) (xy 336.563972 -224.360915)
			(xy 336.572102 -224.30958) (xy 336.588163 -224.26015) (xy 336.611759 -224.21384) (xy 336.642309 -224.171792)
			(xy 336.67906 -224.135041) (xy 336.721108 -224.104491) (xy 336.767418 -224.080895) (xy 336.816848 -224.064834)
			(xy 336.868183 -224.056704) (xy 336.920157 -224.056704) (xy 336.971492 -224.064834) (xy 337.020922 -224.080895)
			(xy 337.067232 -224.104491) (xy 337.10928 -224.135041) (xy 337.146031 -224.171792) (xy 337.176581 -224.21384)
			(xy 337.200177 -224.26015) (xy 337.216238 -224.30958) (xy 337.224368 -224.360915) (xy 337.224878 -224.386902)
			(xy 337.224368 -224.412889) (xy 337.363818 -224.412889) (xy 337.363818 -224.360915) (xy 337.371948 -224.30958)
			(xy 337.388009 -224.26015) (xy 337.411605 -224.21384) (xy 337.442155 -224.171792) (xy 337.478906 -224.135041)
			(xy 337.520954 -224.104491) (xy 337.567264 -224.080895) (xy 337.616694 -224.064834) (xy 337.668029 -224.056704)
			(xy 337.720003 -224.056704) (xy 337.771338 -224.064834) (xy 337.820768 -224.080895) (xy 337.867078 -224.104491)
			(xy 337.909126 -224.135041) (xy 337.945877 -224.171792) (xy 337.976427 -224.21384) (xy 338.000023 -224.26015)
			(xy 338.016084 -224.30958) (xy 338.024214 -224.360915) (xy 338.024724 -224.386902) (xy 338.024214 -224.412889)
			(xy 338.163918 -224.412889) (xy 338.163918 -224.360915) (xy 338.172048 -224.30958) (xy 338.188109 -224.26015)
			(xy 338.211705 -224.21384) (xy 338.242255 -224.171792) (xy 338.279006 -224.135041) (xy 338.321054 -224.104491)
			(xy 338.367364 -224.080895) (xy 338.416794 -224.064834) (xy 338.468129 -224.056704) (xy 338.520103 -224.056704)
			(xy 338.571438 -224.064834) (xy 338.620868 -224.080895) (xy 338.667178 -224.104491) (xy 338.709226 -224.135041)
			(xy 338.745977 -224.171792) (xy 338.776527 -224.21384) (xy 338.800123 -224.26015) (xy 338.816184 -224.30958)
			(xy 338.824314 -224.360915) (xy 338.824824 -224.386902) (xy 338.824314 -224.412889) (xy 338.816184 -224.464224)
			(xy 338.800123 -224.513654) (xy 338.776527 -224.559964) (xy 338.745977 -224.602012) (xy 338.709226 -224.638763)
			(xy 338.667178 -224.669313) (xy 338.620868 -224.692909) (xy 338.571438 -224.70897) (xy 338.520103 -224.7171)
			(xy 338.468129 -224.7171) (xy 338.416794 -224.70897) (xy 338.367364 -224.692909) (xy 338.321054 -224.669313)
			(xy 338.279006 -224.638763) (xy 338.242255 -224.602012) (xy 338.211705 -224.559964) (xy 338.188109 -224.513654)
			(xy 338.172048 -224.464224) (xy 338.163918 -224.412889) (xy 338.024214 -224.412889) (xy 338.016084 -224.464224)
			(xy 338.000023 -224.513654) (xy 337.976427 -224.559964) (xy 337.945877 -224.602012) (xy 337.909126 -224.638763)
			(xy 337.867078 -224.669313) (xy 337.820768 -224.692909) (xy 337.771338 -224.70897) (xy 337.720003 -224.7171)
			(xy 337.668029 -224.7171) (xy 337.616694 -224.70897) (xy 337.567264 -224.692909) (xy 337.520954 -224.669313)
			(xy 337.478906 -224.638763) (xy 337.442155 -224.602012) (xy 337.411605 -224.559964) (xy 337.388009 -224.513654)
			(xy 337.371948 -224.464224) (xy 337.363818 -224.412889) (xy 337.224368 -224.412889) (xy 337.216238 -224.464224)
			(xy 337.200177 -224.513654) (xy 337.176581 -224.559964) (xy 337.146031 -224.602012) (xy 337.10928 -224.638763)
			(xy 337.067232 -224.669313) (xy 337.020922 -224.692909) (xy 336.971492 -224.70897) (xy 336.920157 -224.7171)
			(xy 336.868183 -224.7171) (xy 336.816848 -224.70897) (xy 336.767418 -224.692909) (xy 336.721108 -224.669313)
			(xy 336.67906 -224.638763) (xy 336.642309 -224.602012) (xy 336.611759 -224.559964) (xy 336.588163 -224.513654)
			(xy 336.572102 -224.464224) (xy 336.563972 -224.412889) (xy 336.424268 -224.412889) (xy 336.416138 -224.464224)
			(xy 336.400077 -224.513654) (xy 336.376481 -224.559964) (xy 336.345931 -224.602012) (xy 336.30918 -224.638763)
			(xy 336.267132 -224.669313) (xy 336.220822 -224.692909) (xy 336.171392 -224.70897) (xy 336.120057 -224.7171)
			(xy 336.068083 -224.7171) (xy 336.016748 -224.70897) (xy 335.967318 -224.692909) (xy 335.921008 -224.669313)
			(xy 335.87896 -224.638763) (xy 335.842209 -224.602012) (xy 335.811659 -224.559964) (xy 335.788063 -224.513654)
			(xy 335.772002 -224.464224) (xy 335.763872 -224.412889) (xy 334.824322 -224.412889) (xy 334.816192 -224.464224)
			(xy 334.800131 -224.513654) (xy 334.776535 -224.559964) (xy 334.745985 -224.602012) (xy 334.709234 -224.638763)
			(xy 334.667186 -224.669313) (xy 334.620876 -224.692909) (xy 334.571446 -224.70897) (xy 334.520111 -224.7171)
			(xy 334.468137 -224.7171) (xy 334.416802 -224.70897) (xy 334.367372 -224.692909) (xy 334.321062 -224.669313)
			(xy 334.279014 -224.638763) (xy 334.242263 -224.602012) (xy 334.211713 -224.559964) (xy 334.188117 -224.513654)
			(xy 334.172056 -224.464224) (xy 334.163926 -224.412889) (xy 328.923461 -224.412889) (xy 328.929999 -224.457314)
			(xy 328.930508 -224.4852) (xy 328.929999 -224.513086) (xy 328.921879 -224.568262) (xy 328.905811 -224.621669)
			(xy 328.882139 -224.672166) (xy 328.851366 -224.718679) (xy 328.814149 -224.760216) (xy 328.771281 -224.795891)
			(xy 328.723675 -224.824945) (xy 328.672346 -224.846757) (xy 328.618389 -224.860863) (xy 328.562952 -224.866963)
			(xy 328.507218 -224.864926) (xy 328.452375 -224.854796) (xy 328.399591 -224.836789) (xy 328.349991 -224.811288)
			(xy 328.304633 -224.778837) (xy 328.264484 -224.740128) (xy 328.230398 -224.695985) (xy 328.203102 -224.64735)
			(xy 328.183179 -224.595259) (xy 328.171053 -224.540822) (xy 328.166982 -224.4852) (xy 325.321899 -224.4852)
			(xy 325.340031 -224.524256) (xy 325.355842 -224.577281) (xy 325.363831 -224.632033) (xy 325.363831 -224.687365)
			(xy 325.355842 -224.742117) (xy 325.340032 -224.795142) (xy 325.316732 -224.845329) (xy 325.28643 -224.891626)
			(xy 325.249761 -224.933063) (xy 325.207494 -224.968771) (xy 325.184262 -224.983802) (xy 325.178674 -224.987358)
			(xy 325.17715 -224.988882) (xy 326.08469 -224.988882) (xy 326.088761 -224.93326) (xy 326.100887 -224.878823)
			(xy 326.12081 -224.826732) (xy 326.148106 -224.778097) (xy 326.182192 -224.733954) (xy 326.222341 -224.695245)
			(xy 326.267699 -224.662794) (xy 326.317299 -224.637293) (xy 326.370083 -224.619286) (xy 326.424926 -224.609156)
			(xy 326.48066 -224.607119) (xy 326.536097 -224.613219) (xy 326.590054 -224.627325) (xy 326.641383 -224.649137)
			(xy 326.688989 -224.678191) (xy 326.731857 -224.713866) (xy 326.769074 -224.755403) (xy 326.799847 -224.801916)
			(xy 326.823519 -224.852413) (xy 326.839587 -224.90582) (xy 326.847707 -224.960996) (xy 326.848216 -224.988882)
			(xy 326.847707 -225.016768) (xy 326.839587 -225.071944) (xy 326.823519 -225.125351) (xy 326.799847 -225.175848)
			(xy 326.769074 -225.222361) (xy 326.731857 -225.263898) (xy 326.688989 -225.299573) (xy 326.641383 -225.328627)
			(xy 326.590054 -225.350439) (xy 326.536097 -225.364545) (xy 326.48066 -225.370645) (xy 326.424926 -225.368608)
			(xy 326.370083 -225.358478) (xy 326.317299 -225.340471) (xy 326.267699 -225.31497) (xy 326.222341 -225.282519)
			(xy 326.182192 -225.24381) (xy 326.148106 -225.199667) (xy 326.12081 -225.151032) (xy 326.100887 -225.098941)
			(xy 326.088761 -225.044504) (xy 326.08469 -224.988882) (xy 325.17715 -224.988882) (xy 325.170038 -224.995994)
			(xy 325.155052 -225.02241) (xy 325.151905 -225.028286) (xy 325.148423 -225.041149) (xy 325.148194 -225.04781)
			(xy 325.148194 -225.5012) (xy 328.10907 -225.5012) (xy 328.113141 -225.445578) (xy 328.125267 -225.391141)
			(xy 328.14519 -225.33905) (xy 328.172486 -225.290415) (xy 328.206572 -225.246272) (xy 328.246721 -225.207563)
			(xy 328.292079 -225.175112) (xy 328.341679 -225.149611) (xy 328.394463 -225.131604) (xy 328.449306 -225.121474)
			(xy 328.50504 -225.119437) (xy 328.560477 -225.125537) (xy 328.614434 -225.139643) (xy 328.665763 -225.161455)
			(xy 328.713369 -225.190509) (xy 328.740076 -225.212735) (xy 334.963772 -225.212735) (xy 334.963772 -225.160761)
			(xy 334.971902 -225.109426) (xy 334.987963 -225.059996) (xy 335.011559 -225.013686) (xy 335.042109 -224.971638)
			(xy 335.07886 -224.934887) (xy 335.120908 -224.904337) (xy 335.167218 -224.880741) (xy 335.216648 -224.86468)
			(xy 335.267983 -224.85655) (xy 335.319957 -224.85655) (xy 335.371292 -224.86468) (xy 335.420722 -224.880741)
			(xy 335.467032 -224.904337) (xy 335.50908 -224.934887) (xy 335.545831 -224.971638) (xy 335.576381 -225.013686)
			(xy 335.599977 -225.059996) (xy 335.616038 -225.109426) (xy 335.624168 -225.160761) (xy 335.624678 -225.186748)
			(xy 335.624168 -225.212735) (xy 335.763872 -225.212735) (xy 335.763872 -225.160761) (xy 335.772002 -225.109426)
			(xy 335.788063 -225.059996) (xy 335.811659 -225.013686) (xy 335.842209 -224.971638) (xy 335.87896 -224.934887)
			(xy 335.921008 -224.904337) (xy 335.967318 -224.880741) (xy 336.016748 -224.86468) (xy 336.068083 -224.85655)
			(xy 336.120057 -224.85655) (xy 336.171392 -224.86468) (xy 336.220822 -224.880741) (xy 336.267132 -224.904337)
			(xy 336.30918 -224.934887) (xy 336.345931 -224.971638) (xy 336.376481 -225.013686) (xy 336.400077 -225.059996)
			(xy 336.416138 -225.109426) (xy 336.424268 -225.160761) (xy 336.424778 -225.186748) (xy 336.424268 -225.212735)
			(xy 336.563972 -225.212735) (xy 336.563972 -225.160761) (xy 336.572102 -225.109426) (xy 336.588163 -225.059996)
			(xy 336.611759 -225.013686) (xy 336.642309 -224.971638) (xy 336.67906 -224.934887) (xy 336.721108 -224.904337)
			(xy 336.767418 -224.880741) (xy 336.816848 -224.86468) (xy 336.868183 -224.85655) (xy 336.920157 -224.85655)
			(xy 336.971492 -224.86468) (xy 337.020922 -224.880741) (xy 337.067232 -224.904337) (xy 337.10928 -224.934887)
			(xy 337.146031 -224.971638) (xy 337.176581 -225.013686) (xy 337.200177 -225.059996) (xy 337.216238 -225.109426)
			(xy 337.224368 -225.160761) (xy 337.224878 -225.186748) (xy 337.224368 -225.212735) (xy 337.363818 -225.212735)
			(xy 337.363818 -225.160761) (xy 337.371948 -225.109426) (xy 337.388009 -225.059996) (xy 337.411605 -225.013686)
			(xy 337.442155 -224.971638) (xy 337.478906 -224.934887) (xy 337.520954 -224.904337) (xy 337.567264 -224.880741)
			(xy 337.616694 -224.86468) (xy 337.668029 -224.85655) (xy 337.720003 -224.85655) (xy 337.771338 -224.86468)
			(xy 337.820768 -224.880741) (xy 337.867078 -224.904337) (xy 337.909126 -224.934887) (xy 337.945877 -224.971638)
			(xy 337.976427 -225.013686) (xy 338.000023 -225.059996) (xy 338.016084 -225.109426) (xy 338.024214 -225.160761)
			(xy 338.024724 -225.186748) (xy 338.024214 -225.212735) (xy 338.016084 -225.26407) (xy 338.000023 -225.3135)
			(xy 337.976427 -225.35981) (xy 337.945877 -225.401858) (xy 337.909126 -225.438609) (xy 337.867078 -225.469159)
			(xy 337.820768 -225.492755) (xy 337.771338 -225.508816) (xy 337.720003 -225.516946) (xy 337.668029 -225.516946)
			(xy 337.616694 -225.508816) (xy 337.567264 -225.492755) (xy 337.520954 -225.469159) (xy 337.478906 -225.438609)
			(xy 337.442155 -225.401858) (xy 337.411605 -225.35981) (xy 337.388009 -225.3135) (xy 337.371948 -225.26407)
			(xy 337.363818 -225.212735) (xy 337.224368 -225.212735) (xy 337.216238 -225.26407) (xy 337.200177 -225.3135)
			(xy 337.176581 -225.35981) (xy 337.146031 -225.401858) (xy 337.10928 -225.438609) (xy 337.067232 -225.469159)
			(xy 337.020922 -225.492755) (xy 336.971492 -225.508816) (xy 336.920157 -225.516946) (xy 336.868183 -225.516946)
			(xy 336.816848 -225.508816) (xy 336.767418 -225.492755) (xy 336.721108 -225.469159) (xy 336.67906 -225.438609)
			(xy 336.642309 -225.401858) (xy 336.611759 -225.35981) (xy 336.588163 -225.3135) (xy 336.572102 -225.26407)
			(xy 336.563972 -225.212735) (xy 336.424268 -225.212735) (xy 336.416138 -225.26407) (xy 336.400077 -225.3135)
			(xy 336.376481 -225.35981) (xy 336.345931 -225.401858) (xy 336.30918 -225.438609) (xy 336.267132 -225.469159)
			(xy 336.220822 -225.492755) (xy 336.171392 -225.508816) (xy 336.120057 -225.516946) (xy 336.068083 -225.516946)
			(xy 336.016748 -225.508816) (xy 335.967318 -225.492755) (xy 335.921008 -225.469159) (xy 335.87896 -225.438609)
			(xy 335.842209 -225.401858) (xy 335.811659 -225.35981) (xy 335.788063 -225.3135) (xy 335.772002 -225.26407)
			(xy 335.763872 -225.212735) (xy 335.624168 -225.212735) (xy 335.616038 -225.26407) (xy 335.599977 -225.3135)
			(xy 335.576381 -225.35981) (xy 335.545831 -225.401858) (xy 335.50908 -225.438609) (xy 335.467032 -225.469159)
			(xy 335.420722 -225.492755) (xy 335.371292 -225.508816) (xy 335.319957 -225.516946) (xy 335.267983 -225.516946)
			(xy 335.216648 -225.508816) (xy 335.167218 -225.492755) (xy 335.120908 -225.469159) (xy 335.07886 -225.438609)
			(xy 335.042109 -225.401858) (xy 335.011559 -225.35981) (xy 334.987963 -225.3135) (xy 334.971902 -225.26407)
			(xy 334.963772 -225.212735) (xy 328.740076 -225.212735) (xy 328.756237 -225.226184) (xy 328.793454 -225.267721)
			(xy 328.824227 -225.314234) (xy 328.847899 -225.364731) (xy 328.863967 -225.418138) (xy 328.872087 -225.473314)
			(xy 328.872596 -225.5012) (xy 328.872087 -225.529086) (xy 328.863967 -225.584262) (xy 328.847899 -225.637669)
			(xy 328.824227 -225.688166) (xy 328.793454 -225.734679) (xy 328.756237 -225.776216) (xy 328.713369 -225.811891)
			(xy 328.665763 -225.840945) (xy 328.614434 -225.862757) (xy 328.560477 -225.876863) (xy 328.50504 -225.882963)
			(xy 328.449306 -225.880926) (xy 328.394463 -225.870796) (xy 328.341679 -225.852789) (xy 328.292079 -225.827288)
			(xy 328.246721 -225.794837) (xy 328.206572 -225.756128) (xy 328.172486 -225.711985) (xy 328.14519 -225.66335)
			(xy 328.125267 -225.611259) (xy 328.113141 -225.556822) (xy 328.10907 -225.5012) (xy 325.148194 -225.5012)
			(xy 325.148194 -225.541586) (xy 325.148387 -225.548254) (xy 325.151859 -225.561129) (xy 325.155052 -225.566986)
			(xy 325.170038 -225.593402) (xy 325.178674 -225.602038) (xy 325.184262 -225.605594) (xy 325.207492 -225.620628)
			(xy 325.24976 -225.656336) (xy 325.286429 -225.697772) (xy 325.316731 -225.744069) (xy 325.340031 -225.794256)
			(xy 325.355842 -225.847281) (xy 325.36306 -225.896751) (xy 331.152478 -225.896751) (xy 331.152478 -225.842249)
			(xy 331.160234 -225.788301) (xy 331.175589 -225.736006) (xy 331.198231 -225.686429) (xy 331.227697 -225.640579)
			(xy 331.263388 -225.599388) (xy 331.304579 -225.563697) (xy 331.350429 -225.534231) (xy 331.400006 -225.511589)
			(xy 331.452301 -225.496234) (xy 331.506249 -225.488478) (xy 331.5335 -225.487992) (xy 331.562038 -225.488538)
			(xy 331.618479 -225.497029) (xy 331.673025 -225.513836) (xy 331.724456 -225.538585) (xy 331.771625 -225.570722)
			(xy 331.813478 -225.609529) (xy 331.831696 -225.631502) (xy 331.838808 -225.640646) (xy 331.859636 -225.650552)
			(xy 331.962252 -225.650552) (xy 331.982826 -225.640646) (xy 331.990192 -225.631502) (xy 332.008441 -225.609652)
			(xy 332.050276 -225.571045) (xy 332.097379 -225.539078) (xy 332.148707 -225.51446) (xy 332.203122 -225.497738)
			(xy 332.259417 -225.489282) (xy 332.28788 -225.488754) (xy 332.31763 -225.489321) (xy 332.376409 -225.498549)
			(xy 332.433045 -225.516785) (xy 332.486166 -225.543587) (xy 332.534485 -225.578307) (xy 332.576833 -225.620102)
			(xy 332.594966 -225.643694) (xy 332.60157 -225.652838) (xy 332.621382 -225.66376) (xy 332.721712 -225.669856)
			(xy 332.742794 -225.661474) (xy 332.750668 -225.653346) (xy 332.771003 -225.632659) (xy 332.817116 -225.597472)
			(xy 332.86832 -225.570222) (xy 332.923263 -225.551628) (xy 332.980492 -225.542181) (xy 333.009494 -225.541586)
			(xy 333.036145 -225.542071) (xy 333.088852 -225.550014) (xy 333.139786 -225.565725) (xy 333.18781 -225.588851)
			(xy 333.23185 -225.618876) (xy 333.270923 -225.655131) (xy 333.304157 -225.696804) (xy 333.330808 -225.742964)
			(xy 333.350282 -225.792582) (xy 333.362143 -225.844547) (xy 333.366126 -225.8977) (xy 333.362143 -225.950853)
			(xy 333.350282 -226.002818) (xy 333.346351 -226.012835) (xy 334.963772 -226.012835) (xy 334.963772 -225.960861)
			(xy 334.971902 -225.909526) (xy 334.987963 -225.860096) (xy 335.011559 -225.813786) (xy 335.042109 -225.771738)
			(xy 335.07886 -225.734987) (xy 335.120908 -225.704437) (xy 335.167218 -225.680841) (xy 335.216648 -225.66478)
			(xy 335.267983 -225.65665) (xy 335.319957 -225.65665) (xy 335.371292 -225.66478) (xy 335.420722 -225.680841)
			(xy 335.467032 -225.704437) (xy 335.50908 -225.734987) (xy 335.545831 -225.771738) (xy 335.576381 -225.813786)
			(xy 335.599977 -225.860096) (xy 335.616038 -225.909526) (xy 335.624168 -225.960861) (xy 335.624678 -225.986848)
			(xy 335.624168 -226.012835) (xy 335.624128 -226.013089) (xy 335.763618 -226.013089) (xy 335.763618 -225.961115)
			(xy 335.771748 -225.90978) (xy 335.787809 -225.86035) (xy 335.811405 -225.81404) (xy 335.841955 -225.771992)
			(xy 335.878706 -225.735241) (xy 335.920754 -225.704691) (xy 335.967064 -225.681095) (xy 336.016494 -225.665034)
			(xy 336.067829 -225.656904) (xy 336.119803 -225.656904) (xy 336.171138 -225.665034) (xy 336.220568 -225.681095)
			(xy 336.266878 -225.704691) (xy 336.308926 -225.735241) (xy 336.345677 -225.771992) (xy 336.376227 -225.81404)
			(xy 336.399823 -225.86035) (xy 336.415884 -225.90978) (xy 336.424014 -225.961115) (xy 336.424524 -225.987102)
			(xy 336.424019 -226.012835) (xy 336.563972 -226.012835) (xy 336.563972 -225.960861) (xy 336.572102 -225.909526)
			(xy 336.588163 -225.860096) (xy 336.611759 -225.813786) (xy 336.642309 -225.771738) (xy 336.67906 -225.734987)
			(xy 336.721108 -225.704437) (xy 336.767418 -225.680841) (xy 336.816848 -225.66478) (xy 336.868183 -225.65665)
			(xy 336.920157 -225.65665) (xy 336.971492 -225.66478) (xy 337.020922 -225.680841) (xy 337.067232 -225.704437)
			(xy 337.10928 -225.734987) (xy 337.146031 -225.771738) (xy 337.176581 -225.813786) (xy 337.200177 -225.860096)
			(xy 337.216238 -225.909526) (xy 337.224368 -225.960861) (xy 337.224878 -225.986848) (xy 337.224368 -226.012835)
			(xy 337.216238 -226.06417) (xy 337.200177 -226.1136) (xy 337.176581 -226.15991) (xy 337.146031 -226.201958)
			(xy 337.10928 -226.238709) (xy 337.067232 -226.269259) (xy 337.020922 -226.292855) (xy 336.971492 -226.308916)
			(xy 336.920157 -226.317046) (xy 336.868183 -226.317046) (xy 336.816848 -226.308916) (xy 336.767418 -226.292855)
			(xy 336.721108 -226.269259) (xy 336.67906 -226.238709) (xy 336.642309 -226.201958) (xy 336.611759 -226.15991)
			(xy 336.588163 -226.1136) (xy 336.572102 -226.06417) (xy 336.563972 -226.012835) (xy 336.424019 -226.012835)
			(xy 336.424014 -226.013089) (xy 336.415884 -226.064424) (xy 336.399823 -226.113854) (xy 336.376227 -226.160164)
			(xy 336.345677 -226.202212) (xy 336.308926 -226.238963) (xy 336.266878 -226.269513) (xy 336.220568 -226.293109)
			(xy 336.171138 -226.30917) (xy 336.119803 -226.3173) (xy 336.067829 -226.3173) (xy 336.016494 -226.30917)
			(xy 335.967064 -226.293109) (xy 335.920754 -226.269513) (xy 335.878706 -226.238963) (xy 335.841955 -226.202212)
			(xy 335.811405 -226.160164) (xy 335.787809 -226.113854) (xy 335.771748 -226.064424) (xy 335.763618 -226.013089)
			(xy 335.624128 -226.013089) (xy 335.616038 -226.06417) (xy 335.599977 -226.1136) (xy 335.576381 -226.15991)
			(xy 335.545831 -226.201958) (xy 335.50908 -226.238709) (xy 335.467032 -226.269259) (xy 335.420722 -226.292855)
			(xy 335.371292 -226.308916) (xy 335.319957 -226.317046) (xy 335.267983 -226.317046) (xy 335.216648 -226.308916)
			(xy 335.167218 -226.292855) (xy 335.120908 -226.269259) (xy 335.07886 -226.238709) (xy 335.042109 -226.201958)
			(xy 335.011559 -226.15991) (xy 334.987963 -226.1136) (xy 334.971902 -226.06417) (xy 334.963772 -226.012835)
			(xy 333.346351 -226.012835) (xy 333.330808 -226.052436) (xy 333.304157 -226.098596) (xy 333.270923 -226.140269)
			(xy 333.23185 -226.176524) (xy 333.18781 -226.206549) (xy 333.139786 -226.229675) (xy 333.088852 -226.245386)
			(xy 333.036145 -226.253329) (xy 333.009494 -226.253802) (xy 332.983051 -226.253367) (xy 332.930746 -226.245556)
			(xy 332.880173 -226.230092) (xy 332.832444 -226.207315) (xy 332.78861 -226.177727) (xy 332.749637 -226.141979)
			(xy 332.732634 -226.121722) (xy 332.725522 -226.113086) (xy 332.705456 -226.10318) (xy 332.604872 -226.101656)
			(xy 332.584298 -226.1108) (xy 332.576932 -226.119436) (xy 332.5587 -226.139809) (xy 332.517436 -226.175674)
			(xy 332.471481 -226.205289) (xy 332.421773 -226.22805) (xy 332.369327 -226.243491) (xy 332.315216 -226.251297)
			(xy 332.28788 -226.25177) (xy 332.259342 -226.251216) (xy 332.202903 -226.242723) (xy 332.148359 -226.225916)
			(xy 332.096928 -226.201169) (xy 332.049758 -226.169035) (xy 332.007903 -226.130231) (xy 331.989684 -226.10826)
			(xy 331.982572 -226.099116) (xy 331.961744 -226.08921) (xy 331.859128 -226.08921) (xy 331.838554 -226.099116)
			(xy 331.831188 -226.10826) (xy 331.812965 -226.130133) (xy 331.771124 -226.168736) (xy 331.724014 -226.200698)
			(xy 331.672681 -226.225311) (xy 331.618262 -226.24203) (xy 331.561964 -226.250482) (xy 331.5335 -226.251008)
			(xy 331.506249 -226.250522) (xy 331.452301 -226.242766) (xy 331.400006 -226.227411) (xy 331.350429 -226.204769)
			(xy 331.304579 -226.175303) (xy 331.263388 -226.139612) (xy 331.227697 -226.098421) (xy 331.198231 -226.052571)
			(xy 331.175589 -226.002994) (xy 331.160234 -225.950699) (xy 331.152478 -225.896751) (xy 325.36306 -225.896751)
			(xy 325.363831 -225.902033) (xy 325.363831 -225.957365) (xy 325.355842 -226.012117) (xy 325.340032 -226.065142)
			(xy 325.316732 -226.115329) (xy 325.28643 -226.161626) (xy 325.249761 -226.203063) (xy 325.207494 -226.238771)
			(xy 325.184262 -226.253802) (xy 325.178674 -226.257358) (xy 325.170038 -226.265994) (xy 325.155052 -226.29241)
			(xy 325.151905 -226.298286) (xy 325.148423 -226.311149) (xy 325.148194 -226.31781) (xy 325.148194 -226.63965)
			(xy 326.134205 -226.63965) (xy 326.134205 -226.58515) (xy 326.141962 -226.531204) (xy 326.157317 -226.478911)
			(xy 326.179958 -226.429336) (xy 326.209424 -226.383488) (xy 326.245116 -226.3423) (xy 326.286306 -226.306611)
			(xy 326.332155 -226.277148) (xy 326.381732 -226.254509) (xy 326.434025 -226.239157) (xy 326.487972 -226.231404)
			(xy 326.515222 -226.230942) (xy 326.54218 -226.231417) (xy 326.595558 -226.23901) (xy 326.647336 -226.254041)
			(xy 326.696482 -226.276212) (xy 326.742018 -226.305081) (xy 326.783036 -226.340073) (xy 326.801226 -226.359974)
			(xy 326.808084 -226.367594) (xy 326.82561 -226.37623) (xy 326.917558 -226.38258) (xy 326.9361 -226.37623)
			(xy 326.943974 -226.369626) (xy 326.964894 -226.35218) (xy 327.010714 -226.322724) (xy 327.060254 -226.30008)
			(xy 327.112511 -226.284707) (xy 327.166421 -226.276916) (xy 327.193656 -226.276408) (xy 327.22117 -226.276884)
			(xy 327.275627 -226.284791) (xy 327.328381 -226.300445) (xy 327.378336 -226.323522) (xy 327.424454 -226.353542)
			(xy 327.465776 -226.389881) (xy 327.483978 -226.41052) (xy 327.491598 -226.41941) (xy 327.512426 -226.428554)
			(xy 327.615042 -226.425506) (xy 327.635362 -226.415092) (xy 327.642474 -226.405694) (xy 327.660648 -226.382616)
			(xy 327.702836 -226.341747) (xy 327.750791 -226.307828) (xy 327.803378 -226.28166) (xy 327.859354 -226.263861)
			(xy 327.917397 -226.254853) (xy 327.946766 -226.25431) (xy 327.974022 -226.254735) (xy 328.027979 -226.262488)
			(xy 328.080283 -226.277842) (xy 328.12987 -226.300483) (xy 328.17573 -226.329952) (xy 328.216929 -226.365647)
			(xy 328.252628 -226.406843) (xy 328.2821 -226.4527) (xy 328.304746 -226.502285) (xy 328.320105 -226.554588)
			(xy 328.327863 -226.608544) (xy 328.327863 -226.663056) (xy 328.320105 -226.717012) (xy 328.304746 -226.769315)
			(xy 328.2821 -226.8189) (xy 328.252628 -226.864757) (xy 328.216929 -226.905953) (xy 328.17573 -226.941648)
			(xy 328.12987 -226.971117) (xy 328.080283 -226.993758) (xy 328.027979 -227.009112) (xy 327.974022 -227.016865)
			(xy 327.946766 -227.017326) (xy 327.919253 -227.016823) (xy 327.864798 -227.00892) (xy 327.812045 -226.993271)
			(xy 327.76209 -226.970199) (xy 327.715971 -226.940184) (xy 327.674647 -226.90385) (xy 327.656444 -226.883214)
			(xy 327.648824 -226.874324) (xy 327.627996 -226.86518) (xy 327.52538 -226.868228) (xy 327.50506 -226.878642)
			(xy 327.497948 -226.88804) (xy 327.479828 -226.911162) (xy 327.437627 -226.952027) (xy 327.389661 -226.98594)
			(xy 327.337064 -227.0121) (xy 327.281079 -227.029889) (xy 327.223028 -227.038887) (xy 327.193656 -227.039424)
			(xy 327.166697 -227.038976) (xy 327.113317 -227.031379) (xy 327.061538 -227.016343) (xy 327.012392 -226.994167)
			(xy 326.966857 -226.965293) (xy 326.925841 -226.930296) (xy 326.907652 -226.910392) (xy 326.900794 -226.902772)
			(xy 326.883268 -226.894136) (xy 326.79132 -226.887786) (xy 326.772778 -226.894136) (xy 326.764904 -226.90074)
			(xy 326.744 -226.918207) (xy 326.698175 -226.947657) (xy 326.64863 -226.970296) (xy 326.596371 -226.985665)
			(xy 326.542458 -226.993451) (xy 326.515222 -226.993958) (xy 326.487972 -226.993396) (xy 326.434025 -226.985643)
			(xy 326.381732 -226.970291) (xy 326.332155 -226.947652) (xy 326.286306 -226.918189) (xy 326.245116 -226.8825)
			(xy 326.209424 -226.841312) (xy 326.179958 -226.795464) (xy 326.157317 -226.745889) (xy 326.141962 -226.693596)
			(xy 326.134205 -226.63965) (xy 325.148194 -226.63965) (xy 325.148194 -227.328222) (xy 329.021946 -227.328222)
			(xy 329.026017 -227.2726) (xy 329.038143 -227.218163) (xy 329.058066 -227.166072) (xy 329.085362 -227.117437)
			(xy 329.119448 -227.073294) (xy 329.159597 -227.034585) (xy 329.204955 -227.002134) (xy 329.254555 -226.976633)
			(xy 329.307339 -226.958626) (xy 329.362182 -226.948496) (xy 329.417916 -226.946459) (xy 329.473353 -226.952559)
			(xy 329.52731 -226.966665) (xy 329.578639 -226.988477) (xy 329.626245 -227.017531) (xy 329.669113 -227.053206)
			(xy 329.70633 -227.094743) (xy 329.737103 -227.141256) (xy 329.760775 -227.191753) (xy 329.776843 -227.24516)
			(xy 329.784963 -227.300336) (xy 329.785472 -227.328222) (xy 329.784963 -227.356108) (xy 329.776843 -227.411284)
			(xy 329.760775 -227.464691) (xy 329.737103 -227.515188) (xy 329.70633 -227.561701) (xy 329.669113 -227.603238)
			(xy 329.626245 -227.638913) (xy 329.578639 -227.667967) (xy 329.52731 -227.689779) (xy 329.473353 -227.703885)
			(xy 329.417916 -227.709985) (xy 329.362182 -227.707948) (xy 329.307339 -227.697818) (xy 329.254555 -227.679811)
			(xy 329.204955 -227.65431) (xy 329.159597 -227.621859) (xy 329.119448 -227.58315) (xy 329.085362 -227.539007)
			(xy 329.058066 -227.490372) (xy 329.038143 -227.438281) (xy 329.026017 -227.383844) (xy 329.021946 -227.328222)
			(xy 325.148194 -227.328222) (xy 325.148194 -227.708968) (xy 325.148663 -227.718841) (xy 325.156118 -227.737127)
			(xy 325.162672 -227.744528) (xy 325.162926 -227.744782) (xy 325.401432 -227.983288) (xy 325.410079 -227.991177)
			(xy 325.432183 -227.998796) (xy 325.45538 -227.995872) (xy 325.46544 -227.989892) (xy 325.488476 -227.975374)
			(xy 325.537795 -227.952301) (xy 325.589891 -227.936465) (xy 325.643708 -227.928187) (xy 325.670926 -227.927408)
			(xy 325.674736 -227.927408) (xy 325.702475 -227.927908) (xy 325.757368 -227.935945) (xy 325.810519 -227.951844)
			(xy 325.860809 -227.97527) (xy 325.907177 -228.00573) (xy 325.948647 -228.042582) (xy 325.984345 -228.085049)
			(xy 326.013519 -228.132237) (xy 326.035554 -228.183151) (xy 326.049986 -228.236719) (xy 326.053704 -228.264212)
			(xy 326.055228 -228.278182) (xy 326.056498 -228.308916) (xy 326.056003 -228.336661) (xy 326.047964 -228.391564)
			(xy 326.032043 -228.44472) (xy 326.008578 -228.495004) (xy 325.99376 -228.518466) (xy 325.987914 -228.528518)
			(xy 325.985082 -228.551574) (xy 325.992612 -228.573549) (xy 326.000364 -228.58222) (xy 326.192642 -228.774498)
			(xy 326.19315 -228.775006) (xy 326.200529 -228.781594) (xy 326.218828 -228.789052) (xy 326.22871 -228.789484)
		)
		(stroke
			(width 0)
			(type solid)
		)
		(fill yes)
		(layer "In9.Cu")
		(net "P3V3_FPGA_VCCIO5")
	)
	(gr_poly
		(pts
			(xy 254.709676 -229.943406) (xy 254.74422 -229.941882) (xy 254.778764 -229.943406) (xy 254.78105 -229.94366)
			(xy 254.9652 -229.94366) (xy 254.993902 -229.91826) (xy 254.996188 -229.898956) (xy 255.000013 -229.871546)
			(xy 255.01455 -229.818148) (xy 255.03665 -229.76741) (xy 255.06585 -229.720399) (xy 255.101536 -229.6781)
			(xy 255.14296 -229.641401) (xy 255.189251 -229.611072) (xy 255.239439 -229.587751) (xy 255.29247 -229.571926)
			(xy 255.347231 -229.563929) (xy 255.402573 -229.563929) (xy 255.457334 -229.571926) (xy 255.510365 -229.587751)
			(xy 255.560553 -229.611072) (xy 255.606844 -229.641401) (xy 255.648268 -229.6781) (xy 255.683954 -229.720399)
			(xy 255.713154 -229.76741) (xy 255.735254 -229.818148) (xy 255.749791 -229.871546) (xy 255.753616 -229.898956)
			(xy 255.755902 -229.91826) (xy 255.784604 -229.94366) (xy 258.559808 -229.94366) (xy 258.569687 -229.943203)
			(xy 258.587993 -229.935769) (xy 258.595368 -229.929182) (xy 258.595622 -229.928928) (xy 259.623306 -228.901244)
			(xy 259.630143 -228.893842) (xy 259.637856 -228.875244) (xy 259.638292 -228.865176) (xy 259.638292 -227.80498)
			(xy 259.637688 -227.793649) (xy 259.62793 -227.773199) (xy 259.619496 -227.76561) (xy 259.549138 -227.70846)
			(xy 259.52704 -227.703126) (xy 259.51561 -227.705412) (xy 259.496336 -227.70919) (xy 259.45727 -227.71326)
			(xy 259.437632 -227.71354) (xy 259.410375 -227.713079) (xy 259.356416 -227.705325) (xy 259.30411 -227.689971)
			(xy 259.254522 -227.667328) (xy 259.208661 -227.637859) (xy 259.167461 -227.602162) (xy 259.131761 -227.560965)
			(xy 259.102287 -227.515106) (xy 259.07964 -227.46552) (xy 259.064281 -227.413215) (xy 259.056523 -227.359257)
			(xy 259.056523 -227.304743) (xy 259.064281 -227.250785) (xy 259.07964 -227.19848) (xy 259.102287 -227.148894)
			(xy 259.131761 -227.103035) (xy 259.167461 -227.061838) (xy 259.208661 -227.026141) (xy 259.254522 -226.996672)
			(xy 259.30411 -226.974029) (xy 259.356416 -226.958675) (xy 259.410375 -226.950921) (xy 259.437632 -226.950524)
			(xy 259.457335 -226.950771) (xy 259.49653 -226.954848) (xy 259.515864 -226.958652) (xy 259.527294 -226.960938)
			(xy 259.549392 -226.955604) (xy 259.619496 -226.898454) (xy 259.627885 -226.890833) (xy 259.637626 -226.8704)
			(xy 259.638292 -226.859084) (xy 259.638292 -224.89414) (xy 259.638292 -224.877376) (xy 259.638292 -216.033096)
			(xy 259.637646 -216.021116) (xy 259.626777 -215.999766) (xy 259.617464 -215.992202) (xy 259.551678 -215.944196)
			(xy 259.541714 -215.937689) (xy 259.518277 -215.933729) (xy 259.50672 -215.936576) (xy 259.506466 -215.936576)
			(xy 259.499608 -215.938608) (xy 259.489956 -215.941148) (xy 259.48894 -215.941402) (xy 259.488432 -215.941402)
			(xy 259.462778 -215.947498) (xy 259.444543 -215.950784) (xy 259.407647 -215.954214) (xy 259.389118 -215.954356)
			(xy 259.361911 -215.953803) (xy 259.308067 -215.945934) (xy 259.255888 -215.930494) (xy 259.206431 -215.907798)
			(xy 259.1607 -215.878306) (xy 259.119623 -215.842616) (xy 259.084034 -215.801452) (xy 259.054653 -215.755649)
			(xy 259.032078 -215.706136) (xy 259.016766 -215.653919) (xy 259.009029 -215.600056) (xy 259.008626 -215.572848)
			(xy 259.009086 -215.545594) (xy 259.016838 -215.491639) (xy 259.03219 -215.439338) (xy 259.05483 -215.389754)
			(xy 259.084297 -215.343897) (xy 259.119992 -215.302701) (xy 259.161186 -215.267006) (xy 259.207042 -215.237537)
			(xy 259.256625 -215.214895) (xy 259.308926 -215.199541) (xy 259.36288 -215.191787) (xy 259.390134 -215.19134)
			(xy 259.390896 -215.19134) (xy 259.408978 -215.191566) (xy 259.444979 -215.195003) (xy 259.462778 -215.198198)
			(xy 259.488432 -215.204294) (xy 259.48894 -215.204294) (xy 259.489956 -215.204548) (xy 259.499608 -215.207088)
			(xy 259.506466 -215.20912) (xy 259.525008 -215.20912) (xy 259.533046 -215.208762) (xy 259.548317 -215.203724)
			(xy 259.55498 -215.199214) (xy 259.617464 -215.153494) (xy 259.618988 -215.152224) (xy 259.627668 -215.1447)
			(xy 259.637725 -215.124072) (xy 259.638292 -215.1126) (xy 259.638292 -213.146132) (xy 259.62356 -213.122002)
			(xy 259.61086 -213.115398) (xy 259.51815 -213.067138) (xy 259.489956 -213.068916) (xy 259.478272 -213.077298)
			(xy 259.454027 -213.09373) (xy 259.401558 -213.119753) (xy 259.345726 -213.137447) (xy 259.287846 -213.146397)
			(xy 259.258562 -213.146894) (xy 259.231314 -213.146405) (xy 259.177372 -213.138645) (xy 259.125084 -213.123287)
			(xy 259.075513 -213.100644) (xy 259.029669 -213.071178) (xy 258.988485 -213.035488) (xy 258.952799 -212.9943)
			(xy 258.923337 -212.948453) (xy 258.9007 -212.898881) (xy 258.885347 -212.846591) (xy 258.877592 -212.792648)
			(xy 258.877592 -212.738152) (xy 258.885347 -212.684209) (xy 258.9007 -212.631919) (xy 258.923337 -212.582347)
			(xy 258.952799 -212.5365) (xy 258.988485 -212.495312) (xy 259.029669 -212.459622) (xy 259.075513 -212.430156)
			(xy 259.125084 -212.407513) (xy 259.177372 -212.392155) (xy 259.231314 -212.384395) (xy 259.258562 -212.383878)
			(xy 259.287843 -212.384416) (xy 259.345717 -212.393369) (xy 259.401544 -212.411057) (xy 259.454015 -212.437064)
			(xy 259.478272 -212.453474) (xy 259.48613 -212.458493) (xy 259.504197 -212.463036) (xy 259.522691 -212.460793)
			(xy 259.531104 -212.456776) (xy 259.53847 -212.452966) (xy 259.54101 -212.451696) (xy 259.541772 -212.451188)
			(xy 259.579618 -212.43163) (xy 259.583682 -212.429598) (xy 259.61086 -212.415628) (xy 259.618014 -212.41151)
			(xy 259.629421 -212.399592) (xy 259.633212 -212.39226) (xy 259.638292 -212.381846) (xy 259.638292 -212.150198)
			(xy 259.637022 -212.139022) (xy 259.634482 -212.1281) (xy 259.630926 -212.117432) (xy 259.6261 -212.107018)
			(xy 259.583682 -212.085174) (xy 259.579618 -212.083142) (xy 259.544312 -212.064854) (xy 259.542788 -212.063838)
			(xy 259.53529 -212.059712) (xy 259.518547 -212.056217) (xy 259.510022 -212.05698) (xy 259.49148 -212.059266)
			(xy 259.485823 -212.06011) (xy 259.475054 -212.063953) (xy 259.470144 -212.066886) (xy 259.469636 -212.067394)
			(xy 259.469382 -212.067394) (xy 259.445984 -212.082318) (xy 259.395788 -212.105987) (xy 259.342699 -212.122157)
			(xy 259.287831 -212.130487) (xy 259.260086 -212.131148) (xy 259.249418 -212.130894) (xy 259.222595 -212.129798)
			(xy 259.169638 -212.121007) (xy 259.118437 -212.104877) (xy 259.070003 -212.081727) (xy 259.025294 -212.052014)
			(xy 258.985193 -212.016325) (xy 258.950492 -211.975366) (xy 258.921878 -211.929946) (xy 258.899915 -211.880963)
			(xy 258.885038 -211.829383) (xy 258.87754 -211.776227) (xy 258.877054 -211.749386) (xy 258.877541 -211.722134)
			(xy 258.885299 -211.668186) (xy 258.900655 -211.615891) (xy 258.923296 -211.566313) (xy 258.952762 -211.520462)
			(xy 258.988453 -211.47927) (xy 259.029642 -211.443576) (xy 259.075492 -211.414108) (xy 259.125068 -211.391463)
			(xy 259.177363 -211.376104) (xy 259.23131 -211.368342) (xy 259.258562 -211.367878) (xy 259.287843 -211.368416)
			(xy 259.345717 -211.377369) (xy 259.401544 -211.395057) (xy 259.454015 -211.421064) (xy 259.478272 -211.437474)
			(xy 259.48613 -211.442493) (xy 259.504197 -211.447036) (xy 259.522691 -211.444793) (xy 259.531104 -211.440776)
			(xy 259.53847 -211.436966) (xy 259.54101 -211.435696) (xy 259.541772 -211.435188) (xy 259.579618 -211.41563)
			(xy 259.583682 -211.413598) (xy 259.61086 -211.399628) (xy 259.618014 -211.39551) (xy 259.629421 -211.383592)
			(xy 259.633212 -211.37626) (xy 259.638292 -211.365846) (xy 259.638292 -208.50225) (xy 259.638097 -208.495146)
			(xy 259.634232 -208.481476) (xy 259.630672 -208.475326) (xy 259.627624 -208.4705) (xy 259.606034 -208.44764)
			(xy 259.569204 -208.409032) (xy 259.551678 -208.400904) (xy 259.541772 -208.400396) (xy 259.514215 -208.398493)
			(xy 259.460035 -208.38774) (xy 259.407973 -208.369285) (xy 259.359116 -208.343515) (xy 259.314486 -208.310968)
			(xy 259.275017 -208.272325) (xy 259.241534 -208.228394) (xy 259.214736 -208.180093) (xy 259.195184 -208.128432)
			(xy 259.183287 -208.074492) (xy 259.179294 -208.0194) (xy 259.183287 -207.964308) (xy 259.195184 -207.910367)
			(xy 259.214736 -207.858707) (xy 259.241534 -207.810406) (xy 259.275018 -207.766475) (xy 259.314487 -207.727832)
			(xy 259.359116 -207.695285) (xy 259.407973 -207.669515) (xy 259.460036 -207.65106) (xy 259.514215 -207.640307)
			(xy 259.541772 -207.638396) (xy 259.546563 -207.638011) (xy 259.555893 -207.635708) (xy 259.560314 -207.633824)
			(xy 259.569204 -207.62976) (xy 259.588762 -207.609186) (xy 259.589016 -207.608932) (xy 259.624322 -207.571594)
			(xy 259.63071 -207.564275) (xy 259.637905 -207.546248) (xy 259.638292 -207.536542) (xy 259.638292 -196.563742)
			(xy 259.637845 -196.553955) (xy 259.630532 -196.535798) (xy 259.624068 -196.528436) (xy 259.582158 -196.485002)
			(xy 259.575554 -196.478144) (xy 259.54228 -196.46265) (xy 259.532882 -196.461888) (xy 259.505589 -196.459375)
			(xy 259.452079 -196.447514) (xy 259.400817 -196.428119) (xy 259.352858 -196.401588) (xy 259.309188 -196.368468)
			(xy 259.270706 -196.32944) (xy 259.238205 -196.285308) (xy 259.212353 -196.236979) (xy 259.193683 -196.185449)
			(xy 259.182578 -196.131777) (xy 259.179266 -196.077068) (xy 259.183817 -196.022449) (xy 259.196136 -195.969043)
			(xy 259.215971 -195.917949) (xy 259.242912 -195.870219) (xy 259.276405 -195.826835) (xy 259.315762 -195.78869)
			(xy 259.360171 -195.756568) (xy 259.40872 -195.731132) (xy 259.460408 -195.712904) (xy 259.514174 -195.702259)
			(xy 259.541518 -195.700396) (xy 259.550815 -195.699509) (xy 259.567871 -195.691938) (xy 259.574792 -195.685664)
			(xy 259.578602 -195.681854) (xy 259.58292 -195.677282) (xy 259.601208 -195.657978) (xy 259.624068 -195.634102)
			(xy 259.630555 -195.626752) (xy 259.637883 -195.60859) (xy 259.638292 -195.598796) (xy 259.638292 -183.552084)
			(xy 259.630672 -183.533288) (xy 259.623306 -183.526176) (xy 258.131056 -182.033926) (xy 258.123944 -182.02656)
			(xy 258.105148 -182.01894) (xy 254.53086 -182.01894) (xy 254.512064 -182.02656) (xy 254.504952 -182.033926)
			(xy 252.927866 -183.611012) (xy 252.9205 -183.618124) (xy 252.91288 -183.63692) (xy 252.91288 -190.696342)
			(xy 257.043426 -190.696342) (xy 257.047497 -190.64072) (xy 257.059623 -190.586283) (xy 257.079546 -190.534192)
			(xy 257.106842 -190.485557) (xy 257.140928 -190.441414) (xy 257.181077 -190.402705) (xy 257.226435 -190.370254)
			(xy 257.276035 -190.344753) (xy 257.328819 -190.326746) (xy 257.383662 -190.316616) (xy 257.439396 -190.314579)
			(xy 257.494833 -190.320679) (xy 257.54879 -190.334785) (xy 257.600119 -190.356597) (xy 257.647725 -190.385651)
			(xy 257.690593 -190.421326) (xy 257.72781 -190.462863) (xy 257.758583 -190.509376) (xy 257.782255 -190.559873)
			(xy 257.798323 -190.61328) (xy 257.806443 -190.668456) (xy 257.806952 -190.696342) (xy 257.806443 -190.724228)
			(xy 257.798323 -190.779404) (xy 257.782255 -190.832811) (xy 257.758583 -190.883308) (xy 257.749187 -190.89751)
			(xy 258.193792 -190.89751) (xy 258.197863 -190.841888) (xy 258.209989 -190.787451) (xy 258.229912 -190.73536)
			(xy 258.257208 -190.686725) (xy 258.291294 -190.642582) (xy 258.331443 -190.603873) (xy 258.376801 -190.571422)
			(xy 258.426401 -190.545921) (xy 258.479185 -190.527914) (xy 258.534028 -190.517784) (xy 258.589762 -190.515747)
			(xy 258.645199 -190.521847) (xy 258.699156 -190.535953) (xy 258.750485 -190.557765) (xy 258.798091 -190.586819)
			(xy 258.840959 -190.622494) (xy 258.878176 -190.664031) (xy 258.908949 -190.710544) (xy 258.932621 -190.761041)
			(xy 258.948689 -190.814448) (xy 258.956809 -190.869624) (xy 258.957318 -190.89751) (xy 258.956809 -190.925396)
			(xy 258.948689 -190.980572) (xy 258.932621 -191.033979) (xy 258.908949 -191.084476) (xy 258.878176 -191.130989)
			(xy 258.840959 -191.172526) (xy 258.798091 -191.208201) (xy 258.750485 -191.237255) (xy 258.699156 -191.259067)
			(xy 258.645199 -191.273173) (xy 258.589762 -191.279273) (xy 258.534028 -191.277236) (xy 258.479185 -191.267106)
			(xy 258.426401 -191.249099) (xy 258.376801 -191.223598) (xy 258.331443 -191.191147) (xy 258.291294 -191.152438)
			(xy 258.257208 -191.108295) (xy 258.229912 -191.05966) (xy 258.209989 -191.007569) (xy 258.197863 -190.953132)
			(xy 258.193792 -190.89751) (xy 257.749187 -190.89751) (xy 257.72781 -190.929821) (xy 257.690593 -190.971358)
			(xy 257.647725 -191.007033) (xy 257.600119 -191.036087) (xy 257.54879 -191.057899) (xy 257.494833 -191.072005)
			(xy 257.439396 -191.078105) (xy 257.383662 -191.076068) (xy 257.328819 -191.065938) (xy 257.276035 -191.047931)
			(xy 257.226435 -191.02243) (xy 257.181077 -190.989979) (xy 257.140928 -190.95127) (xy 257.106842 -190.907127)
			(xy 257.079546 -190.858492) (xy 257.059623 -190.806401) (xy 257.047497 -190.751964) (xy 257.043426 -190.696342)
			(xy 252.91288 -190.696342) (xy 252.91288 -192.320926) (xy 254.316736 -192.320926) (xy 254.320807 -192.265304)
			(xy 254.332933 -192.210867) (xy 254.352856 -192.158776) (xy 254.380152 -192.110141) (xy 254.414238 -192.065998)
			(xy 254.454387 -192.027289) (xy 254.499745 -191.994838) (xy 254.549345 -191.969337) (xy 254.602129 -191.95133)
			(xy 254.656972 -191.9412) (xy 254.712706 -191.939163) (xy 254.768143 -191.945263) (xy 254.8221 -191.959369)
			(xy 254.873429 -191.981181) (xy 254.921035 -192.010235) (xy 254.963903 -192.04591) (xy 255.00112 -192.087447)
			(xy 255.031893 -192.13396) (xy 255.055565 -192.184457) (xy 255.06277 -192.208404) (xy 256.958336 -192.208404)
			(xy 256.962407 -192.152782) (xy 256.974533 -192.098345) (xy 256.994456 -192.046254) (xy 257.021752 -191.997619)
			(xy 257.055838 -191.953476) (xy 257.095987 -191.914767) (xy 257.141345 -191.882316) (xy 257.190945 -191.856815)
			(xy 257.243729 -191.838808) (xy 257.298572 -191.828678) (xy 257.354306 -191.826641) (xy 257.409743 -191.832741)
			(xy 257.4637 -191.846847) (xy 257.515029 -191.868659) (xy 257.562635 -191.897713) (xy 257.605503 -191.933388)
			(xy 257.64272 -191.974925) (xy 257.673493 -192.021438) (xy 257.697165 -192.071935) (xy 257.713233 -192.125342)
			(xy 257.721353 -192.180518) (xy 257.721862 -192.208404) (xy 257.721353 -192.23629) (xy 257.713233 -192.291466)
			(xy 257.697165 -192.344873) (xy 257.673493 -192.39537) (xy 257.64272 -192.441883) (xy 257.605503 -192.48342)
			(xy 257.562635 -192.519095) (xy 257.515029 -192.548149) (xy 257.4637 -192.569961) (xy 257.409743 -192.584067)
			(xy 257.354306 -192.590167) (xy 257.298572 -192.58813) (xy 257.243729 -192.578) (xy 257.190945 -192.559993)
			(xy 257.141345 -192.534492) (xy 257.095987 -192.502041) (xy 257.055838 -192.463332) (xy 257.021752 -192.419189)
			(xy 256.994456 -192.370554) (xy 256.974533 -192.318463) (xy 256.962407 -192.264026) (xy 256.958336 -192.208404)
			(xy 255.06277 -192.208404) (xy 255.071633 -192.237864) (xy 255.079753 -192.29304) (xy 255.080262 -192.320926)
			(xy 255.079753 -192.348812) (xy 255.071633 -192.403988) (xy 255.055565 -192.457395) (xy 255.031893 -192.507892)
			(xy 255.00112 -192.554405) (xy 254.963903 -192.595942) (xy 254.921035 -192.631617) (xy 254.873429 -192.660671)
			(xy 254.8221 -192.682483) (xy 254.768143 -192.696589) (xy 254.712706 -192.702689) (xy 254.656972 -192.700652)
			(xy 254.602129 -192.690522) (xy 254.549345 -192.672515) (xy 254.499745 -192.647014) (xy 254.454387 -192.614563)
			(xy 254.414238 -192.575854) (xy 254.380152 -192.531711) (xy 254.352856 -192.483076) (xy 254.332933 -192.430985)
			(xy 254.320807 -192.376548) (xy 254.316736 -192.320926) (xy 252.91288 -192.320926) (xy 252.91288 -193.708528)
			(xy 254.517398 -193.708528) (xy 254.517884 -193.681277) (xy 254.52564 -193.627329) (xy 254.540995 -193.575034)
			(xy 254.563637 -193.525457) (xy 254.593103 -193.479607) (xy 254.628794 -193.438416) (xy 254.669985 -193.402725)
			(xy 254.715835 -193.373259) (xy 254.765412 -193.350617) (xy 254.817707 -193.335262) (xy 254.871655 -193.327506)
			(xy 254.926157 -193.327506) (xy 254.980105 -193.335262) (xy 255.0324 -193.350617) (xy 255.081977 -193.373259)
			(xy 255.127827 -193.402725) (xy 255.169018 -193.438416) (xy 255.204709 -193.479607) (xy 255.205405 -193.48069)
			(xy 255.73685 -193.48069) (xy 255.740921 -193.425068) (xy 255.753047 -193.370631) (xy 255.77297 -193.31854)
			(xy 255.800266 -193.269905) (xy 255.834352 -193.225762) (xy 255.874501 -193.187053) (xy 255.919859 -193.154602)
			(xy 255.969459 -193.129101) (xy 256.022243 -193.111094) (xy 256.077086 -193.100964) (xy 256.13282 -193.098927)
			(xy 256.188257 -193.105027) (xy 256.242214 -193.119133) (xy 256.293543 -193.140945) (xy 256.31709 -193.155316)
			(xy 257.632198 -193.155316) (xy 257.636269 -193.099694) (xy 257.648395 -193.045257) (xy 257.668318 -192.993166)
			(xy 257.695614 -192.944531) (xy 257.7297 -192.900388) (xy 257.769849 -192.861679) (xy 257.815207 -192.829228)
			(xy 257.864807 -192.803727) (xy 257.917591 -192.78572) (xy 257.972434 -192.77559) (xy 258.028168 -192.773553)
			(xy 258.083605 -192.779653) (xy 258.137562 -192.793759) (xy 258.188891 -192.815571) (xy 258.236497 -192.844625)
			(xy 258.279365 -192.8803) (xy 258.316582 -192.921837) (xy 258.347355 -192.96835) (xy 258.371027 -193.018847)
			(xy 258.387095 -193.072254) (xy 258.395215 -193.12743) (xy 258.395724 -193.155316) (xy 258.395215 -193.183202)
			(xy 258.387095 -193.238378) (xy 258.371027 -193.291785) (xy 258.347355 -193.342282) (xy 258.316582 -193.388795)
			(xy 258.279365 -193.430332) (xy 258.236497 -193.466007) (xy 258.188891 -193.495061) (xy 258.137562 -193.516873)
			(xy 258.083605 -193.530979) (xy 258.028168 -193.537079) (xy 257.972434 -193.535042) (xy 257.917591 -193.524912)
			(xy 257.864807 -193.506905) (xy 257.815207 -193.481404) (xy 257.769849 -193.448953) (xy 257.7297 -193.410244)
			(xy 257.695614 -193.366101) (xy 257.668318 -193.317466) (xy 257.648395 -193.265375) (xy 257.636269 -193.210938)
			(xy 257.632198 -193.155316) (xy 256.31709 -193.155316) (xy 256.341149 -193.169999) (xy 256.384017 -193.205674)
			(xy 256.421234 -193.247211) (xy 256.452007 -193.293724) (xy 256.475679 -193.344221) (xy 256.491747 -193.397628)
			(xy 256.499867 -193.452804) (xy 256.500376 -193.48069) (xy 256.499867 -193.508576) (xy 256.491747 -193.563752)
			(xy 256.475679 -193.617159) (xy 256.452007 -193.667656) (xy 256.421234 -193.714169) (xy 256.384017 -193.755706)
			(xy 256.341149 -193.791381) (xy 256.293543 -193.820435) (xy 256.242214 -193.842247) (xy 256.188257 -193.856353)
			(xy 256.13282 -193.862453) (xy 256.077086 -193.860416) (xy 256.022243 -193.850286) (xy 255.969459 -193.832279)
			(xy 255.919859 -193.806778) (xy 255.874501 -193.774327) (xy 255.834352 -193.735618) (xy 255.800266 -193.691475)
			(xy 255.77297 -193.64284) (xy 255.753047 -193.590749) (xy 255.740921 -193.536312) (xy 255.73685 -193.48069)
			(xy 255.205405 -193.48069) (xy 255.234175 -193.525457) (xy 255.256817 -193.575034) (xy 255.272172 -193.627329)
			(xy 255.279928 -193.681277) (xy 255.280414 -193.708528) (xy 255.279889 -193.737538) (xy 255.27112 -193.794891)
			(xy 255.253772 -193.850257) (xy 255.228245 -193.902359) (xy 255.195127 -193.949999) (xy 255.155181 -193.992078)
			(xy 255.132586 -194.01028) (xy 255.120864 -194.02006) (xy 255.1033 -194.045007) (xy 255.093884 -194.074028)
			(xy 255.093456 -194.104535) (xy 255.102053 -194.133808) (xy 255.11891 -194.159239) (xy 255.142523 -194.17856)
			(xy 255.156462 -194.184778) (xy 255.1825 -194.195876) (xy 255.231268 -194.224601) (xy 255.275256 -194.260217)
			(xy 255.313496 -194.301944) (xy 255.34515 -194.348864) (xy 255.369522 -194.399947) (xy 255.386076 -194.45407)
			(xy 255.394449 -194.510047) (xy 255.394968 -194.538346) (xy 255.647442 -194.538346) (xy 255.651513 -194.482724)
			(xy 255.663639 -194.428287) (xy 255.683562 -194.376196) (xy 255.710858 -194.327561) (xy 255.744944 -194.283418)
			(xy 255.785093 -194.244709) (xy 255.830451 -194.212258) (xy 255.880051 -194.186757) (xy 255.932835 -194.16875)
			(xy 255.987678 -194.15862) (xy 256.043412 -194.156583) (xy 256.098849 -194.162683) (xy 256.152806 -194.176789)
			(xy 256.204135 -194.198601) (xy 256.251741 -194.227655) (xy 256.294609 -194.26333) (xy 256.331826 -194.304867)
			(xy 256.362599 -194.35138) (xy 256.386271 -194.401877) (xy 256.402339 -194.455284) (xy 256.410459 -194.51046)
			(xy 256.410968 -194.538346) (xy 256.410459 -194.566232) (xy 256.402339 -194.621408) (xy 256.386271 -194.674815)
			(xy 256.362599 -194.725312) (xy 256.331826 -194.771825) (xy 256.294609 -194.813362) (xy 256.251741 -194.849037)
			(xy 256.204135 -194.878091) (xy 256.152806 -194.899903) (xy 256.098849 -194.914009) (xy 256.043412 -194.920109)
			(xy 255.987678 -194.918072) (xy 255.932835 -194.907942) (xy 255.880051 -194.889935) (xy 255.830451 -194.864434)
			(xy 255.785093 -194.831983) (xy 255.744944 -194.793274) (xy 255.710858 -194.749131) (xy 255.683562 -194.700496)
			(xy 255.663639 -194.648405) (xy 255.651513 -194.593968) (xy 255.647442 -194.538346) (xy 255.394968 -194.538346)
			(xy 255.394482 -194.565597) (xy 255.386726 -194.619545) (xy 255.371371 -194.67184) (xy 255.348729 -194.721417)
			(xy 255.319263 -194.767267) (xy 255.283572 -194.808458) (xy 255.242381 -194.844149) (xy 255.196531 -194.873615)
			(xy 255.146954 -194.896257) (xy 255.094659 -194.911612) (xy 255.040711 -194.919368) (xy 254.986209 -194.919368)
			(xy 254.932261 -194.911612) (xy 254.879966 -194.896257) (xy 254.830389 -194.873615) (xy 254.784539 -194.844149)
			(xy 254.743348 -194.808458) (xy 254.707657 -194.767267) (xy 254.678191 -194.721417) (xy 254.655549 -194.67184)
			(xy 254.640194 -194.619545) (xy 254.632438 -194.565597) (xy 254.631952 -194.538346) (xy 254.632471 -194.509336)
			(xy 254.641244 -194.451983) (xy 254.658594 -194.396618) (xy 254.684122 -194.344516) (xy 254.71724 -194.296876)
			(xy 254.757185 -194.254797) (xy 254.77978 -194.236594) (xy 254.791539 -194.226853) (xy 254.80911 -194.201898)
			(xy 254.818528 -194.172867) (xy 254.818953 -194.142349) (xy 254.810348 -194.113066) (xy 254.793479 -194.087631)
			(xy 254.769851 -194.068311) (xy 254.755904 -194.062096) (xy 254.729849 -194.051036) (xy 254.681081 -194.022305)
			(xy 254.637094 -193.986683) (xy 254.598855 -193.94495) (xy 254.567204 -193.898025) (xy 254.542836 -193.846937)
			(xy 254.526285 -193.792809) (xy 254.517916 -193.736829) (xy 254.517398 -193.708528) (xy 252.91288 -193.708528)
			(xy 252.91288 -194.199764) (xy 253.615442 -194.199764) (xy 253.619513 -194.144142) (xy 253.631639 -194.089705)
			(xy 253.651562 -194.037614) (xy 253.678858 -193.988979) (xy 253.712944 -193.944836) (xy 253.753093 -193.906127)
			(xy 253.798451 -193.873676) (xy 253.848051 -193.848175) (xy 253.900835 -193.830168) (xy 253.955678 -193.820038)
			(xy 254.011412 -193.818001) (xy 254.066849 -193.824101) (xy 254.120806 -193.838207) (xy 254.172135 -193.860019)
			(xy 254.219741 -193.889073) (xy 254.262609 -193.924748) (xy 254.299826 -193.966285) (xy 254.330599 -194.012798)
			(xy 254.354271 -194.063295) (xy 254.370339 -194.116702) (xy 254.378459 -194.171878) (xy 254.378968 -194.199764)
			(xy 254.378459 -194.22765) (xy 254.370339 -194.282826) (xy 254.354271 -194.336233) (xy 254.330599 -194.38673)
			(xy 254.299826 -194.433243) (xy 254.262609 -194.47478) (xy 254.219741 -194.510455) (xy 254.172135 -194.539509)
			(xy 254.120806 -194.561321) (xy 254.066849 -194.575427) (xy 254.011412 -194.581527) (xy 253.955678 -194.57949)
			(xy 253.900835 -194.56936) (xy 253.848051 -194.551353) (xy 253.798451 -194.525852) (xy 253.753093 -194.493401)
			(xy 253.712944 -194.454692) (xy 253.678858 -194.410549) (xy 253.651562 -194.361914) (xy 253.631639 -194.309823)
			(xy 253.619513 -194.255386) (xy 253.615442 -194.199764) (xy 252.91288 -194.199764) (xy 252.91288 -196.766434)
			(xy 253.615442 -196.766434) (xy 253.619513 -196.710812) (xy 253.631639 -196.656375) (xy 253.651562 -196.604284)
			(xy 253.678858 -196.555649) (xy 253.712944 -196.511506) (xy 253.753093 -196.472797) (xy 253.798451 -196.440346)
			(xy 253.848051 -196.414845) (xy 253.900835 -196.396838) (xy 253.955678 -196.386708) (xy 254.011412 -196.384671)
			(xy 254.066849 -196.390771) (xy 254.120806 -196.404877) (xy 254.172135 -196.426689) (xy 254.219741 -196.455743)
			(xy 254.262609 -196.491418) (xy 254.299826 -196.532955) (xy 254.330599 -196.579468) (xy 254.354271 -196.629965)
			(xy 254.370339 -196.683372) (xy 254.378459 -196.738548) (xy 254.378968 -196.766434) (xy 254.378459 -196.79432)
			(xy 254.370339 -196.849496) (xy 254.354271 -196.902903) (xy 254.330599 -196.9534) (xy 254.299826 -196.999913)
			(xy 254.262609 -197.04145) (xy 254.219741 -197.077125) (xy 254.172135 -197.106179) (xy 254.120806 -197.127991)
			(xy 254.066849 -197.142097) (xy 254.011412 -197.148197) (xy 253.955678 -197.14616) (xy 253.900835 -197.13603)
			(xy 253.848051 -197.118023) (xy 253.798451 -197.092522) (xy 253.753093 -197.060071) (xy 253.712944 -197.021362)
			(xy 253.678858 -196.977219) (xy 253.651562 -196.928584) (xy 253.631639 -196.876493) (xy 253.619513 -196.822056)
			(xy 253.615442 -196.766434) (xy 252.91288 -196.766434) (xy 252.91288 -197.32371) (xy 252.913338 -197.333588)
			(xy 252.920777 -197.351891) (xy 252.927358 -197.35927) (xy 252.927612 -197.359524) (xy 253.0094 -197.441312)
			(xy 253.009908 -197.44182) (xy 253.017285 -197.448413) (xy 253.035585 -197.455884) (xy 253.045468 -197.456298)
			(xy 253.146052 -197.456298) (xy 253.152402 -197.45452) (xy 253.176412 -197.44858) (xy 253.225461 -197.442206)
			(xy 253.250192 -197.44182) (xy 253.250954 -197.44182) (xy 253.278228 -197.44228) (xy 253.332223 -197.450038)
			(xy 253.359608 -197.458076) (xy 254.337818 -197.458076) (xy 254.341889 -197.402454) (xy 254.354015 -197.348017)
			(xy 254.373938 -197.295926) (xy 254.401234 -197.247291) (xy 254.43532 -197.203148) (xy 254.475469 -197.164439)
			(xy 254.520827 -197.131988) (xy 254.570427 -197.106487) (xy 254.623211 -197.08848) (xy 254.678054 -197.07835)
			(xy 254.733788 -197.076313) (xy 254.789225 -197.082413) (xy 254.843182 -197.096519) (xy 254.894511 -197.118331)
			(xy 254.942117 -197.147385) (xy 254.984985 -197.18306) (xy 255.022202 -197.224597) (xy 255.052975 -197.27111)
			(xy 255.06132 -197.288912) (xy 256.842512 -197.288912) (xy 256.846583 -197.23329) (xy 256.858709 -197.178853)
			(xy 256.878632 -197.126762) (xy 256.905928 -197.078127) (xy 256.940014 -197.033984) (xy 256.980163 -196.995275)
			(xy 257.025521 -196.962824) (xy 257.075121 -196.937323) (xy 257.127905 -196.919316) (xy 257.182748 -196.909186)
			(xy 257.238482 -196.907149) (xy 257.293919 -196.913249) (xy 257.347876 -196.927355) (xy 257.399205 -196.949167)
			(xy 257.446811 -196.978221) (xy 257.489679 -197.013896) (xy 257.526896 -197.055433) (xy 257.557669 -197.101946)
			(xy 257.581341 -197.152443) (xy 257.597409 -197.20585) (xy 257.605529 -197.261026) (xy 257.606038 -197.288912)
			(xy 257.605529 -197.316798) (xy 257.597409 -197.371974) (xy 257.581341 -197.425381) (xy 257.557669 -197.475878)
			(xy 257.526896 -197.522391) (xy 257.489679 -197.563928) (xy 257.446811 -197.599603) (xy 257.399205 -197.628657)
			(xy 257.347876 -197.650469) (xy 257.293919 -197.664575) (xy 257.238482 -197.670675) (xy 257.182748 -197.668638)
			(xy 257.127905 -197.658508) (xy 257.075121 -197.640501) (xy 257.025521 -197.615) (xy 256.980163 -197.582549)
			(xy 256.940014 -197.54384) (xy 256.905928 -197.499697) (xy 256.878632 -197.451062) (xy 256.858709 -197.398971)
			(xy 256.846583 -197.344534) (xy 256.842512 -197.288912) (xy 255.06132 -197.288912) (xy 255.076647 -197.321607)
			(xy 255.092715 -197.375014) (xy 255.100835 -197.43019) (xy 255.101344 -197.458076) (xy 255.100835 -197.485962)
			(xy 255.092715 -197.541138) (xy 255.076647 -197.594545) (xy 255.052975 -197.645042) (xy 255.022202 -197.691555)
			(xy 254.984985 -197.733092) (xy 254.942117 -197.768767) (xy 254.894511 -197.797821) (xy 254.843182 -197.819633)
			(xy 254.789225 -197.833739) (xy 254.733788 -197.839839) (xy 254.678054 -197.837802) (xy 254.623211 -197.827672)
			(xy 254.570427 -197.809665) (xy 254.520827 -197.784164) (xy 254.475469 -197.751713) (xy 254.43532 -197.713004)
			(xy 254.401234 -197.668861) (xy 254.373938 -197.620226) (xy 254.354015 -197.568135) (xy 254.341889 -197.513698)
			(xy 254.337818 -197.458076) (xy 253.359608 -197.458076) (xy 253.384563 -197.465401) (xy 253.434185 -197.488057)
			(xy 253.480076 -197.517544) (xy 253.521304 -197.553264) (xy 253.557028 -197.594487) (xy 253.586521 -197.640375)
			(xy 253.609183 -197.689993) (xy 253.624553 -197.742332) (xy 253.632316 -197.796326) (xy 253.632316 -197.850874)
			(xy 253.626453 -197.891654) (xy 258.104638 -197.891654) (xy 258.108709 -197.836032) (xy 258.120835 -197.781595)
			(xy 258.140758 -197.729504) (xy 258.168054 -197.680869) (xy 258.20214 -197.636726) (xy 258.242289 -197.598017)
			(xy 258.287647 -197.565566) (xy 258.337247 -197.540065) (xy 258.390031 -197.522058) (xy 258.444874 -197.511928)
			(xy 258.500608 -197.509891) (xy 258.556045 -197.515991) (xy 258.610002 -197.530097) (xy 258.661331 -197.551909)
			(xy 258.708937 -197.580963) (xy 258.751805 -197.616638) (xy 258.789022 -197.658175) (xy 258.819795 -197.704688)
			(xy 258.843467 -197.755185) (xy 258.859535 -197.808592) (xy 258.867655 -197.863768) (xy 258.868164 -197.891654)
			(xy 258.867655 -197.91954) (xy 258.859535 -197.974716) (xy 258.843467 -198.028123) (xy 258.819795 -198.07862)
			(xy 258.789022 -198.125133) (xy 258.751805 -198.16667) (xy 258.708937 -198.202345) (xy 258.661331 -198.231399)
			(xy 258.610002 -198.253211) (xy 258.556045 -198.267317) (xy 258.500608 -198.273417) (xy 258.444874 -198.27138)
			(xy 258.390031 -198.26125) (xy 258.337247 -198.243243) (xy 258.287647 -198.217742) (xy 258.242289 -198.185291)
			(xy 258.20214 -198.146582) (xy 258.168054 -198.102439) (xy 258.140758 -198.053804) (xy 258.120835 -198.001713)
			(xy 258.108709 -197.947276) (xy 258.104638 -197.891654) (xy 253.626453 -197.891654) (xy 253.624553 -197.904868)
			(xy 253.609183 -197.957207) (xy 253.586521 -198.006825) (xy 253.557028 -198.052713) (xy 253.521304 -198.093936)
			(xy 253.480076 -198.129656) (xy 253.434185 -198.159143) (xy 253.384563 -198.181799) (xy 253.332223 -198.197162)
			(xy 253.278228 -198.20492) (xy 253.250954 -198.205344) (xy 253.225237 -198.204926) (xy 253.174269 -198.198018)
			(xy 253.124692 -198.18432) (xy 253.077407 -198.164081) (xy 253.05512 -198.151242) (xy 253.042166 -198.145654)
			(xy 253.035562 -198.143876) (xy 252.98019 -198.143876) (xy 252.97012 -198.1443) (xy 252.951516 -198.152014)
			(xy 252.944122 -198.158862) (xy 252.927866 -198.175118) (xy 252.9205 -198.18223) (xy 252.91288 -198.201026)
			(xy 252.91288 -198.896224) (xy 258.539232 -198.896224) (xy 258.543303 -198.840602) (xy 258.555429 -198.786165)
			(xy 258.575352 -198.734074) (xy 258.602648 -198.685439) (xy 258.636734 -198.641296) (xy 258.676883 -198.602587)
			(xy 258.722241 -198.570136) (xy 258.771841 -198.544635) (xy 258.824625 -198.526628) (xy 258.879468 -198.516498)
			(xy 258.935202 -198.514461) (xy 258.990639 -198.520561) (xy 259.044596 -198.534667) (xy 259.095925 -198.556479)
			(xy 259.143531 -198.585533) (xy 259.186399 -198.621208) (xy 259.223616 -198.662745) (xy 259.254389 -198.709258)
			(xy 259.278061 -198.759755) (xy 259.294129 -198.813162) (xy 259.302249 -198.868338) (xy 259.302758 -198.896224)
			(xy 259.302249 -198.92411) (xy 259.294129 -198.979286) (xy 259.278061 -199.032693) (xy 259.254389 -199.08319)
			(xy 259.223616 -199.129703) (xy 259.186399 -199.17124) (xy 259.143531 -199.206915) (xy 259.095925 -199.235969)
			(xy 259.044596 -199.257781) (xy 258.990639 -199.271887) (xy 258.935202 -199.277987) (xy 258.879468 -199.27595)
			(xy 258.824625 -199.26582) (xy 258.771841 -199.247813) (xy 258.722241 -199.222312) (xy 258.676883 -199.189861)
			(xy 258.636734 -199.151152) (xy 258.602648 -199.107009) (xy 258.575352 -199.058374) (xy 258.555429 -199.006283)
			(xy 258.543303 -198.951846) (xy 258.539232 -198.896224) (xy 252.91288 -198.896224) (xy 252.91288 -199.625966)
			(xy 257.001008 -199.625966) (xy 257.005079 -199.570344) (xy 257.017205 -199.515907) (xy 257.037128 -199.463816)
			(xy 257.064424 -199.415181) (xy 257.09851 -199.371038) (xy 257.138659 -199.332329) (xy 257.184017 -199.299878)
			(xy 257.233617 -199.274377) (xy 257.286401 -199.25637) (xy 257.341244 -199.24624) (xy 257.396978 -199.244203)
			(xy 257.452415 -199.250303) (xy 257.506372 -199.264409) (xy 257.557701 -199.286221) (xy 257.605307 -199.315275)
			(xy 257.648175 -199.35095) (xy 257.685392 -199.392487) (xy 257.716165 -199.439) (xy 257.739837 -199.489497)
			(xy 257.755905 -199.542904) (xy 257.764025 -199.59808) (xy 257.764534 -199.625966) (xy 257.764025 -199.653852)
			(xy 257.755905 -199.709028) (xy 257.739837 -199.762435) (xy 257.716165 -199.812932) (xy 257.685392 -199.859445)
			(xy 257.648175 -199.900982) (xy 257.605307 -199.936657) (xy 257.557701 -199.965711) (xy 257.506372 -199.987523)
			(xy 257.452415 -200.001629) (xy 257.396978 -200.007729) (xy 257.341244 -200.005692) (xy 257.286401 -199.995562)
			(xy 257.233617 -199.977555) (xy 257.184017 -199.952054) (xy 257.138659 -199.919603) (xy 257.09851 -199.880894)
			(xy 257.064424 -199.836751) (xy 257.037128 -199.788116) (xy 257.017205 -199.736025) (xy 257.005079 -199.681588)
			(xy 257.001008 -199.625966) (xy 252.91288 -199.625966) (xy 252.91288 -200.08723) (xy 255.155444 -200.08723)
			(xy 255.159515 -200.031608) (xy 255.171641 -199.977171) (xy 255.191564 -199.92508) (xy 255.21886 -199.876445)
			(xy 255.252946 -199.832302) (xy 255.293095 -199.793593) (xy 255.338453 -199.761142) (xy 255.388053 -199.735641)
			(xy 255.440837 -199.717634) (xy 255.49568 -199.707504) (xy 255.551414 -199.705467) (xy 255.606851 -199.711567)
			(xy 255.660808 -199.725673) (xy 255.712137 -199.747485) (xy 255.759743 -199.776539) (xy 255.802611 -199.812214)
			(xy 255.839828 -199.853751) (xy 255.870601 -199.900264) (xy 255.894273 -199.950761) (xy 255.910341 -200.004168)
			(xy 255.918461 -200.059344) (xy 255.91897 -200.08723) (xy 255.918461 -200.115116) (xy 255.910341 -200.170292)
			(xy 255.894273 -200.223699) (xy 255.870601 -200.274196) (xy 255.839828 -200.320709) (xy 255.802611 -200.362246)
			(xy 255.759743 -200.397921) (xy 255.712137 -200.426975) (xy 255.660808 -200.448787) (xy 255.606851 -200.462893)
			(xy 255.551414 -200.468993) (xy 255.49568 -200.466956) (xy 255.440837 -200.456826) (xy 255.388053 -200.438819)
			(xy 255.338453 -200.413318) (xy 255.293095 -200.380867) (xy 255.252946 -200.342158) (xy 255.21886 -200.298015)
			(xy 255.191564 -200.24938) (xy 255.171641 -200.197289) (xy 255.159515 -200.142852) (xy 255.155444 -200.08723)
			(xy 252.91288 -200.08723) (xy 252.91288 -201.415142) (xy 255.40284 -201.415142) (xy 255.406911 -201.35952)
			(xy 255.419037 -201.305083) (xy 255.43896 -201.252992) (xy 255.466256 -201.204357) (xy 255.500342 -201.160214)
			(xy 255.540491 -201.121505) (xy 255.585849 -201.089054) (xy 255.635449 -201.063553) (xy 255.688233 -201.045546)
			(xy 255.743076 -201.035416) (xy 255.79881 -201.033379) (xy 255.854247 -201.039479) (xy 255.908204 -201.053585)
			(xy 255.959533 -201.075397) (xy 256.007139 -201.104451) (xy 256.050007 -201.140126) (xy 256.087224 -201.181663)
			(xy 256.117997 -201.228176) (xy 256.141669 -201.278673) (xy 256.157737 -201.33208) (xy 256.165857 -201.387256)
			(xy 256.166366 -201.415142) (xy 256.165857 -201.443028) (xy 256.157737 -201.498204) (xy 256.141669 -201.551611)
			(xy 256.123842 -201.58964) (xy 257.190238 -201.58964) (xy 257.194309 -201.534018) (xy 257.206435 -201.479581)
			(xy 257.226358 -201.42749) (xy 257.253654 -201.378855) (xy 257.28774 -201.334712) (xy 257.327889 -201.296003)
			(xy 257.373247 -201.263552) (xy 257.422847 -201.238051) (xy 257.475631 -201.220044) (xy 257.530474 -201.209914)
			(xy 257.586208 -201.207877) (xy 257.641645 -201.213977) (xy 257.695602 -201.228083) (xy 257.746931 -201.249895)
			(xy 257.794537 -201.278949) (xy 257.837405 -201.314624) (xy 257.874622 -201.356161) (xy 257.905395 -201.402674)
			(xy 257.929067 -201.453171) (xy 257.945135 -201.506578) (xy 257.953255 -201.561754) (xy 257.953449 -201.572368)
			(xy 258.201158 -201.572368) (xy 258.205229 -201.516746) (xy 258.217355 -201.462309) (xy 258.237278 -201.410218)
			(xy 258.264574 -201.361583) (xy 258.29866 -201.31744) (xy 258.338809 -201.278731) (xy 258.384167 -201.24628)
			(xy 258.433767 -201.220779) (xy 258.486551 -201.202772) (xy 258.541394 -201.192642) (xy 258.597128 -201.190605)
			(xy 258.652565 -201.196705) (xy 258.706522 -201.210811) (xy 258.757851 -201.232623) (xy 258.805457 -201.261677)
			(xy 258.848325 -201.297352) (xy 258.885542 -201.338889) (xy 258.916315 -201.385402) (xy 258.939987 -201.435899)
			(xy 258.956055 -201.489306) (xy 258.964175 -201.544482) (xy 258.964684 -201.572368) (xy 258.964175 -201.600254)
			(xy 258.956055 -201.65543) (xy 258.939987 -201.708837) (xy 258.916315 -201.759334) (xy 258.885542 -201.805847)
			(xy 258.848325 -201.847384) (xy 258.805457 -201.883059) (xy 258.757851 -201.912113) (xy 258.706522 -201.933925)
			(xy 258.652565 -201.948031) (xy 258.597128 -201.954131) (xy 258.541394 -201.952094) (xy 258.486551 -201.941964)
			(xy 258.433767 -201.923957) (xy 258.384167 -201.898456) (xy 258.338809 -201.866005) (xy 258.29866 -201.827296)
			(xy 258.264574 -201.783153) (xy 258.237278 -201.734518) (xy 258.217355 -201.682427) (xy 258.205229 -201.62799)
			(xy 258.201158 -201.572368) (xy 257.953449 -201.572368) (xy 257.953764 -201.58964) (xy 257.953255 -201.617526)
			(xy 257.945135 -201.672702) (xy 257.929067 -201.726109) (xy 257.905395 -201.776606) (xy 257.874622 -201.823119)
			(xy 257.837405 -201.864656) (xy 257.794537 -201.900331) (xy 257.746931 -201.929385) (xy 257.695602 -201.951197)
			(xy 257.641645 -201.965303) (xy 257.586208 -201.971403) (xy 257.530474 -201.969366) (xy 257.475631 -201.959236)
			(xy 257.422847 -201.941229) (xy 257.373247 -201.915728) (xy 257.327889 -201.883277) (xy 257.28774 -201.844568)
			(xy 257.253654 -201.800425) (xy 257.226358 -201.75179) (xy 257.206435 -201.699699) (xy 257.194309 -201.645262)
			(xy 257.190238 -201.58964) (xy 256.123842 -201.58964) (xy 256.117997 -201.602108) (xy 256.087224 -201.648621)
			(xy 256.050007 -201.690158) (xy 256.007139 -201.725833) (xy 255.959533 -201.754887) (xy 255.908204 -201.776699)
			(xy 255.854247 -201.790805) (xy 255.79881 -201.796905) (xy 255.743076 -201.794868) (xy 255.688233 -201.784738)
			(xy 255.635449 -201.766731) (xy 255.585849 -201.74123) (xy 255.540491 -201.708779) (xy 255.500342 -201.67007)
			(xy 255.466256 -201.625927) (xy 255.43896 -201.577292) (xy 255.419037 -201.525201) (xy 255.406911 -201.470764)
			(xy 255.40284 -201.415142) (xy 252.91288 -201.415142) (xy 252.91288 -202.81646) (xy 258.208016 -202.81646)
			(xy 258.212087 -202.760838) (xy 258.224213 -202.706401) (xy 258.244136 -202.65431) (xy 258.271432 -202.605675)
			(xy 258.305518 -202.561532) (xy 258.345667 -202.522823) (xy 258.391025 -202.490372) (xy 258.440625 -202.464871)
			(xy 258.493409 -202.446864) (xy 258.548252 -202.436734) (xy 258.603986 -202.434697) (xy 258.659423 -202.440797)
			(xy 258.71338 -202.454903) (xy 258.764709 -202.476715) (xy 258.812315 -202.505769) (xy 258.855183 -202.541444)
			(xy 258.8924 -202.582981) (xy 258.923173 -202.629494) (xy 258.946845 -202.679991) (xy 258.962913 -202.733398)
			(xy 258.971033 -202.788574) (xy 258.971542 -202.81646) (xy 258.971033 -202.844346) (xy 258.962913 -202.899522)
			(xy 258.946845 -202.952929) (xy 258.923173 -203.003426) (xy 258.8924 -203.049939) (xy 258.855183 -203.091476)
			(xy 258.812315 -203.127151) (xy 258.764709 -203.156205) (xy 258.71338 -203.178017) (xy 258.659423 -203.192123)
			(xy 258.603986 -203.198223) (xy 258.548252 -203.196186) (xy 258.493409 -203.186056) (xy 258.440625 -203.168049)
			(xy 258.391025 -203.142548) (xy 258.345667 -203.110097) (xy 258.305518 -203.071388) (xy 258.271432 -203.027245)
			(xy 258.244136 -202.97861) (xy 258.224213 -202.926519) (xy 258.212087 -202.872082) (xy 258.208016 -202.81646)
			(xy 252.91288 -202.81646) (xy 252.91288 -204.077316) (xy 256.335528 -204.077316) (xy 256.339599 -204.021694)
			(xy 256.351725 -203.967257) (xy 256.371648 -203.915166) (xy 256.398944 -203.866531) (xy 256.43303 -203.822388)
			(xy 256.473179 -203.783679) (xy 256.518537 -203.751228) (xy 256.568137 -203.725727) (xy 256.620921 -203.70772)
			(xy 256.675764 -203.69759) (xy 256.731498 -203.695553) (xy 256.786935 -203.701653) (xy 256.840892 -203.715759)
			(xy 256.892221 -203.737571) (xy 256.939827 -203.766625) (xy 256.982695 -203.8023) (xy 257.019912 -203.843837)
			(xy 257.050685 -203.89035) (xy 257.05903 -203.908152) (xy 257.32308 -203.908152) (xy 257.327151 -203.85253)
			(xy 257.339277 -203.798093) (xy 257.3592 -203.746002) (xy 257.386496 -203.697367) (xy 257.420582 -203.653224)
			(xy 257.460731 -203.614515) (xy 257.506089 -203.582064) (xy 257.555689 -203.556563) (xy 257.608473 -203.538556)
			(xy 257.663316 -203.528426) (xy 257.71905 -203.526389) (xy 257.774487 -203.532489) (xy 257.828444 -203.546595)
			(xy 257.879773 -203.568407) (xy 257.927379 -203.597461) (xy 257.970247 -203.633136) (xy 258.007464 -203.674673)
			(xy 258.038237 -203.721186) (xy 258.061909 -203.771683) (xy 258.077977 -203.82509) (xy 258.086097 -203.880266)
			(xy 258.086606 -203.908152) (xy 258.086097 -203.936038) (xy 258.077977 -203.991214) (xy 258.061909 -204.044621)
			(xy 258.038237 -204.095118) (xy 258.007464 -204.141631) (xy 257.970247 -204.183168) (xy 257.927379 -204.218843)
			(xy 257.879773 -204.247897) (xy 257.828444 -204.269709) (xy 257.774487 -204.283815) (xy 257.71905 -204.289915)
			(xy 257.663316 -204.287878) (xy 257.608473 -204.277748) (xy 257.555689 -204.259741) (xy 257.506089 -204.23424)
			(xy 257.460731 -204.201789) (xy 257.420582 -204.16308) (xy 257.386496 -204.118937) (xy 257.3592 -204.070302)
			(xy 257.339277 -204.018211) (xy 257.327151 -203.963774) (xy 257.32308 -203.908152) (xy 257.05903 -203.908152)
			(xy 257.074357 -203.940847) (xy 257.090425 -203.994254) (xy 257.098545 -204.04943) (xy 257.099054 -204.077316)
			(xy 257.098545 -204.105202) (xy 257.090425 -204.160378) (xy 257.074357 -204.213785) (xy 257.050685 -204.264282)
			(xy 257.019912 -204.310795) (xy 256.982695 -204.352332) (xy 256.939827 -204.388007) (xy 256.892221 -204.417061)
			(xy 256.840892 -204.438873) (xy 256.786935 -204.452979) (xy 256.731498 -204.459079) (xy 256.675764 -204.457042)
			(xy 256.620921 -204.446912) (xy 256.568137 -204.428905) (xy 256.518537 -204.403404) (xy 256.473179 -204.370953)
			(xy 256.43303 -204.332244) (xy 256.398944 -204.288101) (xy 256.371648 -204.239466) (xy 256.351725 -204.187375)
			(xy 256.339599 -204.132938) (xy 256.335528 -204.077316) (xy 252.91288 -204.077316) (xy 252.91288 -204.950822)
			(xy 252.912626 -204.95133) (xy 252.912626 -205.98638) (xy 253.205486 -205.98638) (xy 253.209557 -205.930758)
			(xy 253.221683 -205.876321) (xy 253.241606 -205.82423) (xy 253.268902 -205.775595) (xy 253.302988 -205.731452)
			(xy 253.343137 -205.692743) (xy 253.388495 -205.660292) (xy 253.438095 -205.634791) (xy 253.490879 -205.616784)
			(xy 253.545722 -205.606654) (xy 253.601456 -205.604617) (xy 253.656893 -205.610717) (xy 253.71085 -205.624823)
			(xy 253.762179 -205.646635) (xy 253.809785 -205.675689) (xy 253.852653 -205.711364) (xy 253.88987 -205.752901)
			(xy 253.920643 -205.799414) (xy 253.944315 -205.849911) (xy 253.960383 -205.903318) (xy 253.968503 -205.958494)
			(xy 253.969007 -205.986126) (xy 255.155698 -205.986126) (xy 255.159769 -205.930504) (xy 255.171895 -205.876067)
			(xy 255.191818 -205.823976) (xy 255.219114 -205.775341) (xy 255.2532 -205.731198) (xy 255.293349 -205.692489)
			(xy 255.338707 -205.660038) (xy 255.388307 -205.634537) (xy 255.441091 -205.61653) (xy 255.495934 -205.6064)
			(xy 255.551668 -205.604363) (xy 255.607105 -205.610463) (xy 255.661062 -205.624569) (xy 255.712391 -205.646381)
			(xy 255.759997 -205.675435) (xy 255.802865 -205.71111) (xy 255.840082 -205.752647) (xy 255.870855 -205.79916)
			(xy 255.894527 -205.849657) (xy 255.910595 -205.903064) (xy 255.918715 -205.95824) (xy 255.919224 -205.986126)
			(xy 255.918715 -206.014012) (xy 255.910595 -206.069188) (xy 255.894527 -206.122595) (xy 255.870855 -206.173092)
			(xy 255.840082 -206.219605) (xy 255.802865 -206.261142) (xy 255.759997 -206.296817) (xy 255.712391 -206.325871)
			(xy 255.661062 -206.347683) (xy 255.607105 -206.361789) (xy 255.551668 -206.367889) (xy 255.495934 -206.365852)
			(xy 255.441091 -206.355722) (xy 255.388307 -206.337715) (xy 255.338707 -206.312214) (xy 255.293349 -206.279763)
			(xy 255.2532 -206.241054) (xy 255.219114 -206.196911) (xy 255.191818 -206.148276) (xy 255.171895 -206.096185)
			(xy 255.159769 -206.041748) (xy 255.155698 -205.986126) (xy 253.969007 -205.986126) (xy 253.969012 -205.98638)
			(xy 253.968503 -206.014266) (xy 253.960383 -206.069442) (xy 253.944315 -206.122849) (xy 253.920643 -206.173346)
			(xy 253.88987 -206.219859) (xy 253.852653 -206.261396) (xy 253.809785 -206.297071) (xy 253.762179 -206.326125)
			(xy 253.71085 -206.347937) (xy 253.656893 -206.362043) (xy 253.601456 -206.368143) (xy 253.545722 -206.366106)
			(xy 253.490879 -206.355976) (xy 253.438095 -206.337969) (xy 253.388495 -206.312468) (xy 253.343137 -206.280017)
			(xy 253.302988 -206.241308) (xy 253.268902 -206.197165) (xy 253.241606 -206.14853) (xy 253.221683 -206.096439)
			(xy 253.209557 -206.042002) (xy 253.205486 -205.98638) (xy 252.912626 -205.98638) (xy 252.912626 -206.63408)
			(xy 257.129026 -206.63408) (xy 257.129616 -206.605153) (xy 257.138354 -206.547964) (xy 257.155626 -206.492749)
			(xy 257.181036 -206.440775) (xy 257.214003 -206.393233) (xy 257.253769 -206.351213) (xy 257.299424 -206.315679)
			(xy 257.349921 -206.287446) (xy 257.404101 -206.26716) (xy 257.432302 -206.2607) (xy 257.446272 -206.257652)
			(xy 257.466338 -206.23911) (xy 257.50012 -206.126588) (xy 257.493516 -206.099664) (xy 257.48361 -206.089758)
			(xy 257.46298 -206.068196) (xy 257.428046 -206.019818) (xy 257.401073 -205.966589) (xy 257.382721 -205.909809)
			(xy 257.373438 -205.850862) (xy 257.372866 -205.821026) (xy 257.373262 -205.794627) (xy 257.380539 -205.742334)
			(xy 257.394958 -205.691544) (xy 257.416243 -205.643228) (xy 257.443987 -205.598308) (xy 257.477661 -205.557644)
			(xy 257.516621 -205.522011) (xy 257.560122 -205.492092) (xy 257.607333 -205.468457) (xy 257.6322 -205.459584)
			(xy 257.643122 -205.456028) (xy 257.659632 -205.440026) (xy 257.694684 -205.34376) (xy 257.692652 -205.3209)
			(xy 257.686556 -205.310994) (xy 257.673539 -205.288596) (xy 257.653024 -205.241027) (xy 257.639134 -205.19112)
			(xy 257.632125 -205.139792) (xy 257.631692 -205.11389) (xy 257.632178 -205.086639) (xy 257.639934 -205.032691)
			(xy 257.655289 -204.980396) (xy 257.677931 -204.930819) (xy 257.707397 -204.884969) (xy 257.743088 -204.843778)
			(xy 257.784279 -204.808087) (xy 257.830129 -204.778621) (xy 257.879706 -204.755979) (xy 257.932001 -204.740624)
			(xy 257.985949 -204.732868) (xy 258.040451 -204.732868) (xy 258.094399 -204.740624) (xy 258.146694 -204.755979)
			(xy 258.196271 -204.778621) (xy 258.242121 -204.808087) (xy 258.283312 -204.843778) (xy 258.319003 -204.884969)
			(xy 258.348469 -204.930819) (xy 258.371111 -204.980396) (xy 258.386466 -205.032691) (xy 258.394222 -205.086639)
			(xy 258.394708 -205.11389) (xy 258.394276 -205.140287) (xy 258.386999 -205.192576) (xy 258.372581 -205.243363)
			(xy 258.351299 -205.291676) (xy 258.323559 -205.336594) (xy 258.28989 -205.377259) (xy 258.250937 -205.412893)
			(xy 258.207442 -205.442815) (xy 258.160237 -205.466455) (xy 258.135374 -205.475332) (xy 258.124452 -205.478888)
			(xy 258.107942 -205.49489) (xy 258.07289 -205.591156) (xy 258.074922 -205.614016) (xy 258.081018 -205.623922)
			(xy 258.094039 -205.646318) (xy 258.114554 -205.693887) (xy 258.128443 -205.743795) (xy 258.13545 -205.795124)
			(xy 258.135882 -205.821026) (xy 258.135291 -205.849953) (xy 258.126553 -205.907142) (xy 258.10928 -205.962356)
			(xy 258.08387 -206.01433) (xy 258.050903 -206.061872) (xy 258.011137 -206.103891) (xy 257.965483 -206.139425)
			(xy 257.914987 -206.167659) (xy 257.860807 -206.187945) (xy 257.832606 -206.194406) (xy 257.818636 -206.197454)
			(xy 257.79857 -206.215996) (xy 257.781565 -206.272638) (xy 258.178552 -206.272638) (xy 258.182623 -206.217016)
			(xy 258.194749 -206.162579) (xy 258.214672 -206.110488) (xy 258.241968 -206.061853) (xy 258.276054 -206.01771)
			(xy 258.316203 -205.979001) (xy 258.361561 -205.94655) (xy 258.411161 -205.921049) (xy 258.463945 -205.903042)
			(xy 258.518788 -205.892912) (xy 258.574522 -205.890875) (xy 258.629959 -205.896975) (xy 258.683916 -205.911081)
			(xy 258.735245 -205.932893) (xy 258.782851 -205.961947) (xy 258.825719 -205.997622) (xy 258.862936 -206.039159)
			(xy 258.893709 -206.085672) (xy 258.917381 -206.136169) (xy 258.933449 -206.189576) (xy 258.941569 -206.244752)
			(xy 258.942078 -206.272638) (xy 258.941569 -206.300524) (xy 258.933449 -206.3557) (xy 258.917381 -206.409107)
			(xy 258.893709 -206.459604) (xy 258.862936 -206.506117) (xy 258.825719 -206.547654) (xy 258.782851 -206.583329)
			(xy 258.735245 -206.612383) (xy 258.683916 -206.634195) (xy 258.629959 -206.648301) (xy 258.574522 -206.654401)
			(xy 258.518788 -206.652364) (xy 258.463945 -206.642234) (xy 258.411161 -206.624227) (xy 258.361561 -206.598726)
			(xy 258.316203 -206.566275) (xy 258.276054 -206.527566) (xy 258.241968 -206.483423) (xy 258.214672 -206.434788)
			(xy 258.194749 -206.382697) (xy 258.182623 -206.32826) (xy 258.178552 -206.272638) (xy 257.781565 -206.272638)
			(xy 257.764788 -206.328518) (xy 257.771392 -206.355442) (xy 257.781298 -206.365348) (xy 257.801932 -206.386906)
			(xy 257.836866 -206.435285) (xy 257.863837 -206.488515) (xy 257.882188 -206.545297) (xy 257.891471 -206.604243)
			(xy 257.892042 -206.63408) (xy 257.891556 -206.661331) (xy 257.8838 -206.715279) (xy 257.868445 -206.767574)
			(xy 257.845803 -206.817151) (xy 257.816337 -206.863001) (xy 257.780646 -206.904192) (xy 257.739455 -206.939883)
			(xy 257.693605 -206.969349) (xy 257.644028 -206.991991) (xy 257.591733 -207.007346) (xy 257.537785 -207.015102)
			(xy 257.483283 -207.015102) (xy 257.429335 -207.007346) (xy 257.37704 -206.991991) (xy 257.327463 -206.969349)
			(xy 257.281613 -206.939883) (xy 257.240422 -206.904192) (xy 257.204731 -206.863001) (xy 257.175265 -206.817151)
			(xy 257.152623 -206.767574) (xy 257.137268 -206.715279) (xy 257.129512 -206.661331) (xy 257.129026 -206.63408)
			(xy 252.912626 -206.63408) (xy 252.912626 -206.821278) (xy 252.913064 -206.831341) (xy 252.920801 -206.849923)
			(xy 252.927612 -206.857346) (xy 252.930152 -206.859886) (xy 252.987556 -206.90967) (xy 252.994681 -206.915341)
			(xy 253.011731 -206.921703) (xy 253.02083 -206.922116) (xy 253.027942 -206.922116) (xy 253.031244 -206.921608)
			(xy 253.043822 -206.920049) (xy 253.069116 -206.918398) (xy 253.08179 -206.918306) (xy 253.109042 -206.918769)
			(xy 253.162992 -206.926524) (xy 253.215289 -206.941879) (xy 253.264869 -206.96452) (xy 253.310722 -206.993986)
			(xy 253.351914 -207.029679) (xy 253.387608 -207.07087) (xy 253.417075 -207.116722) (xy 253.439718 -207.166301)
			(xy 253.455074 -207.218598) (xy 253.462831 -207.272548) (xy 253.462831 -207.327052) (xy 253.455074 -207.381002)
			(xy 253.439718 -207.433299) (xy 253.417075 -207.482878) (xy 253.387608 -207.52873) (xy 253.351914 -207.569921)
			(xy 253.310722 -207.605614) (xy 253.264869 -207.63508) (xy 253.215289 -207.657721) (xy 253.162992 -207.673076)
			(xy 253.109042 -207.680831) (xy 253.08179 -207.681322) (xy 253.068409 -207.681184) (xy 253.041715 -207.679275)
			(xy 253.02845 -207.677512) (xy 253.017528 -207.675988) (xy 252.9967 -207.682084) (xy 252.930406 -207.739234)
			(xy 252.928882 -207.741012) (xy 252.927612 -207.742282) (xy 252.920246 -207.749394) (xy 252.912626 -207.76819)
			(xy 252.912626 -208.177252) (xy 253.57453 -208.177252) (xy 253.57453 -208.122748) (xy 253.582286 -208.068797)
			(xy 253.59764 -208.0165) (xy 253.620281 -207.96692) (xy 253.649746 -207.921066) (xy 253.685437 -207.879872)
			(xy 253.726626 -207.844176) (xy 253.772476 -207.814705) (xy 253.822053 -207.792058) (xy 253.874349 -207.776697)
			(xy 253.928298 -207.768933) (xy 253.95555 -207.768444) (xy 253.982641 -207.768951) (xy 254.036277 -207.776615)
			(xy 254.088288 -207.791796) (xy 254.137626 -207.814189) (xy 254.183296 -207.843341) (xy 254.224379 -207.878666)
			(xy 254.24257 -207.898746) (xy 254.25019 -207.907128) (xy 254.269748 -207.916018) (xy 254.369062 -207.915764)
			(xy 254.388874 -207.90662) (xy 254.39624 -207.897984) (xy 254.414439 -207.877522) (xy 254.455698 -207.841518)
			(xy 254.501683 -207.811785) (xy 254.551447 -207.788935) (xy 254.603968 -207.773437) (xy 254.658166 -207.765612)
			(xy 254.685546 -207.765142) (xy 254.712799 -207.765531) (xy 254.766748 -207.773294) (xy 254.819045 -207.788655)
			(xy 254.868622 -207.811302) (xy 254.914473 -207.840773) (xy 254.955663 -207.876469) (xy 254.991354 -207.917664)
			(xy 255.02082 -207.963518) (xy 255.043461 -208.013099) (xy 255.058816 -208.065397) (xy 255.066572 -208.119347)
			(xy 255.066572 -208.173853) (xy 255.058816 -208.227803) (xy 255.043461 -208.280101) (xy 255.02082 -208.329682)
			(xy 254.991354 -208.375536) (xy 254.955663 -208.416731) (xy 254.914473 -208.452427) (xy 254.868622 -208.481898)
			(xy 254.819045 -208.504545) (xy 254.766748 -208.519906) (xy 254.712799 -208.527669) (xy 254.685546 -208.528158)
			(xy 254.658455 -208.527653) (xy 254.604819 -208.519989) (xy 254.552808 -208.504807) (xy 254.50347 -208.482414)
			(xy 254.4578 -208.453261) (xy 254.416717 -208.417936) (xy 254.398526 -208.397856) (xy 254.390906 -208.389474)
			(xy 254.371348 -208.380584) (xy 254.272034 -208.380838) (xy 254.252222 -208.389982) (xy 254.244856 -208.398618)
			(xy 254.22666 -208.419082) (xy 254.1854 -208.455086) (xy 254.139415 -208.484819) (xy 254.08965 -208.507669)
			(xy 254.037128 -208.523165) (xy 253.98293 -208.530991) (xy 253.95555 -208.53146) (xy 253.928298 -208.531067)
			(xy 253.874349 -208.523303) (xy 253.822053 -208.507942) (xy 253.772476 -208.485295) (xy 253.726626 -208.455824)
			(xy 253.685437 -208.420128) (xy 253.649746 -208.378934) (xy 253.620281 -208.33308) (xy 253.59764 -208.2835)
			(xy 253.582286 -208.231203) (xy 253.57453 -208.177252) (xy 252.912626 -208.177252) (xy 252.912626 -210.434174)
			(xy 257.763262 -210.434174) (xy 257.767333 -210.378552) (xy 257.779459 -210.324115) (xy 257.799382 -210.272024)
			(xy 257.826678 -210.223389) (xy 257.860764 -210.179246) (xy 257.900913 -210.140537) (xy 257.946271 -210.108086)
			(xy 257.995871 -210.082585) (xy 258.048655 -210.064578) (xy 258.103498 -210.054448) (xy 258.159232 -210.052411)
			(xy 258.214669 -210.058511) (xy 258.268626 -210.072617) (xy 258.319955 -210.094429) (xy 258.367561 -210.123483)
			(xy 258.410429 -210.159158) (xy 258.447646 -210.200695) (xy 258.478419 -210.247208) (xy 258.502091 -210.297705)
			(xy 258.518159 -210.351112) (xy 258.526279 -210.406288) (xy 258.526788 -210.434174) (xy 258.526279 -210.46206)
			(xy 258.518159 -210.517236) (xy 258.502091 -210.570643) (xy 258.478419 -210.62114) (xy 258.447646 -210.667653)
			(xy 258.410429 -210.70919) (xy 258.367561 -210.744865) (xy 258.319955 -210.773919) (xy 258.268626 -210.795731)
			(xy 258.214669 -210.809837) (xy 258.159232 -210.815937) (xy 258.103498 -210.8139) (xy 258.048655 -210.80377)
			(xy 257.995871 -210.785763) (xy 257.946271 -210.760262) (xy 257.900913 -210.727811) (xy 257.860764 -210.689102)
			(xy 257.826678 -210.644959) (xy 257.799382 -210.596324) (xy 257.779459 -210.544233) (xy 257.767333 -210.489796)
			(xy 257.763262 -210.434174) (xy 252.912626 -210.434174) (xy 252.912626 -211.950156) (xy 253.712623 -211.950156)
			(xy 253.712623 -211.895644) (xy 253.720381 -211.841686) (xy 253.73574 -211.789381) (xy 253.758386 -211.739795)
			(xy 253.787859 -211.693937) (xy 253.823559 -211.65274) (xy 253.864758 -211.617044) (xy 253.910618 -211.587574)
			(xy 253.960206 -211.564931) (xy 254.012511 -211.549576) (xy 254.06647 -211.541821) (xy 254.093726 -211.54136)
			(xy 254.12133 -211.541848) (xy 254.17596 -211.549809) (xy 254.228873 -211.56556) (xy 254.278963 -211.588772)
			(xy 254.325185 -211.618962) (xy 254.346202 -211.636864) (xy 254.353314 -211.64296) (xy 254.370586 -211.649564)
			(xy 254.456438 -211.649564) (xy 254.47371 -211.64296) (xy 254.480822 -211.636864) (xy 254.501844 -211.618968)
			(xy 254.548063 -211.588774) (xy 254.598152 -211.56556) (xy 254.651064 -211.549808) (xy 254.705694 -211.541849)
			(xy 254.733298 -211.54136) (xy 254.760549 -211.541887) (xy 254.814495 -211.549643) (xy 254.866789 -211.564998)
			(xy 254.916365 -211.587638) (xy 254.962215 -211.617104) (xy 255.003404 -211.652794) (xy 255.039095 -211.693984)
			(xy 255.068561 -211.739833) (xy 255.091202 -211.789409) (xy 255.106556 -211.841703) (xy 255.114313 -211.895649)
			(xy 255.114313 -211.950151) (xy 255.106556 -212.004097) (xy 255.091202 -212.056391) (xy 255.068561 -212.105967)
			(xy 255.039095 -212.151816) (xy 255.003404 -212.193006) (xy 254.962215 -212.228696) (xy 254.916365 -212.258162)
			(xy 254.866789 -212.280802) (xy 254.814495 -212.296157) (xy 254.760549 -212.303913) (xy 254.733298 -212.304376)
			(xy 254.705695 -212.303864) (xy 254.651066 -212.295908) (xy 254.598154 -212.280162) (xy 254.548063 -212.256955)
			(xy 254.50184 -212.226771) (xy 254.480822 -212.208872) (xy 254.47371 -212.202776) (xy 254.456438 -212.196172)
			(xy 254.370586 -212.196172) (xy 254.353314 -212.202776) (xy 254.346202 -212.208872) (xy 254.325175 -212.226763)
			(xy 254.278957 -212.256956) (xy 254.228869 -212.280171) (xy 254.175958 -212.295924) (xy 254.121329 -212.303885)
			(xy 254.093726 -212.304376) (xy 254.06647 -212.303979) (xy 254.012511 -212.296224) (xy 253.960206 -212.280869)
			(xy 253.910618 -212.258226) (xy 253.864758 -212.228756) (xy 253.823559 -212.19306) (xy 253.787859 -212.151863)
			(xy 253.758386 -212.106005) (xy 253.73574 -212.056419) (xy 253.720381 -212.004114) (xy 253.712623 -211.950156)
			(xy 252.912626 -211.950156) (xy 252.912626 -212.765386) (xy 256.844544 -212.765386) (xy 256.848615 -212.709764)
			(xy 256.860741 -212.655327) (xy 256.880664 -212.603236) (xy 256.90796 -212.554601) (xy 256.942046 -212.510458)
			(xy 256.982195 -212.471749) (xy 257.027553 -212.439298) (xy 257.077153 -212.413797) (xy 257.129937 -212.39579)
			(xy 257.18478 -212.38566) (xy 257.240514 -212.383623) (xy 257.295951 -212.389723) (xy 257.349908 -212.403829)
			(xy 257.401237 -212.425641) (xy 257.448843 -212.454695) (xy 257.491711 -212.49037) (xy 257.528928 -212.531907)
			(xy 257.559701 -212.57842) (xy 257.583373 -212.628917) (xy 257.599441 -212.682324) (xy 257.607561 -212.7375)
			(xy 257.60807 -212.765386) (xy 257.607561 -212.793272) (xy 257.599441 -212.848448) (xy 257.583373 -212.901855)
			(xy 257.559701 -212.952352) (xy 257.528928 -212.998865) (xy 257.491711 -213.040402) (xy 257.448843 -213.076077)
			(xy 257.401237 -213.105131) (xy 257.349908 -213.126943) (xy 257.295951 -213.141049) (xy 257.240514 -213.147149)
			(xy 257.18478 -213.145112) (xy 257.129937 -213.134982) (xy 257.077153 -213.116975) (xy 257.027553 -213.091474)
			(xy 256.982195 -213.059023) (xy 256.942046 -213.020314) (xy 256.90796 -212.976171) (xy 256.880664 -212.927536)
			(xy 256.860741 -212.875445) (xy 256.848615 -212.821008) (xy 256.844544 -212.765386) (xy 252.912626 -212.765386)
			(xy 252.912626 -213.801198) (xy 256.40665 -213.801198) (xy 256.407136 -213.773947) (xy 256.414892 -213.719999)
			(xy 256.430247 -213.667704) (xy 256.452889 -213.618127) (xy 256.482355 -213.572277) (xy 256.518046 -213.531086)
			(xy 256.559237 -213.495395) (xy 256.605087 -213.465929) (xy 256.654664 -213.443287) (xy 256.706959 -213.427932)
			(xy 256.760907 -213.420176) (xy 256.815409 -213.420176) (xy 256.869357 -213.427932) (xy 256.921652 -213.443287)
			(xy 256.971229 -213.465929) (xy 257.017079 -213.495395) (xy 257.05827 -213.531086) (xy 257.093961 -213.572277)
			(xy 257.123427 -213.618127) (xy 257.146069 -213.667704) (xy 257.161424 -213.719999) (xy 257.16918 -213.773947)
			(xy 257.169666 -213.801198) (xy 257.169206 -213.827593) (xy 257.161922 -213.879879) (xy 257.147508 -213.930664)
			(xy 257.126237 -213.97898) (xy 257.098515 -214.023906) (xy 257.082036 -214.04453) (xy 257.07594 -214.051896)
			(xy 257.069844 -214.070438) (xy 257.075432 -214.159338) (xy 257.083814 -214.176864) (xy 257.090926 -214.183468)
			(xy 257.109678 -214.20159) (xy 257.142593 -214.242036) (xy 257.169693 -214.286588) (xy 257.190475 -214.334415)
			(xy 257.20455 -214.384626) (xy 257.211657 -214.436287) (xy 257.212084 -214.46236) (xy 257.211598 -214.489611)
			(xy 257.203842 -214.543559) (xy 257.188487 -214.595854) (xy 257.165845 -214.645431) (xy 257.136379 -214.691281)
			(xy 257.100688 -214.732472) (xy 257.059497 -214.768163) (xy 257.013647 -214.797629) (xy 256.96407 -214.820271)
			(xy 256.911775 -214.835626) (xy 256.857827 -214.843382) (xy 256.803325 -214.843382) (xy 256.749377 -214.835626)
			(xy 256.697082 -214.820271) (xy 256.647505 -214.797629) (xy 256.601655 -214.768163) (xy 256.560464 -214.732472)
			(xy 256.524773 -214.691281) (xy 256.495307 -214.645431) (xy 256.472665 -214.595854) (xy 256.45731 -214.543559)
			(xy 256.449554 -214.489611) (xy 256.449068 -214.46236) (xy 256.449497 -214.435964) (xy 256.456787 -214.383676)
			(xy 256.471208 -214.332891) (xy 256.492486 -214.284575) (xy 256.520215 -214.239651) (xy 256.536698 -214.219028)
			(xy 256.542794 -214.211662) (xy 256.54889 -214.19312) (xy 256.543302 -214.10422) (xy 256.53492 -214.086694)
			(xy 256.527808 -214.08009) (xy 256.509038 -214.061988) (xy 256.47613 -214.021535) (xy 256.449037 -213.976978)
			(xy 256.428263 -213.929147) (xy 256.414195 -213.878933) (xy 256.407095 -213.827272) (xy 256.40665 -213.801198)
			(xy 252.912626 -213.801198) (xy 252.912626 -215.921336) (xy 253.91948 -215.921336) (xy 253.923551 -215.865714)
			(xy 253.935677 -215.811277) (xy 253.9556 -215.759186) (xy 253.982896 -215.710551) (xy 254.016982 -215.666408)
			(xy 254.057131 -215.627699) (xy 254.102489 -215.595248) (xy 254.152089 -215.569747) (xy 254.204873 -215.55174)
			(xy 254.259716 -215.54161) (xy 254.31545 -215.539573) (xy 254.370887 -215.545673) (xy 254.424844 -215.559779)
			(xy 254.476173 -215.581591) (xy 254.523779 -215.610645) (xy 254.566647 -215.64632) (xy 254.603864 -215.687857)
			(xy 254.634637 -215.73437) (xy 254.658309 -215.784867) (xy 254.674377 -215.838274) (xy 254.682497 -215.89345)
			(xy 254.683006 -215.921336) (xy 254.682497 -215.949222) (xy 254.674377 -216.004398) (xy 254.658309 -216.057805)
			(xy 254.634637 -216.108302) (xy 254.603864 -216.154815) (xy 254.566647 -216.196352) (xy 254.524143 -216.231724)
			(xy 257.153154 -216.231724) (xy 257.157225 -216.176102) (xy 257.169351 -216.121665) (xy 257.189274 -216.069574)
			(xy 257.21657 -216.020939) (xy 257.250656 -215.976796) (xy 257.290805 -215.938087) (xy 257.336163 -215.905636)
			(xy 257.385763 -215.880135) (xy 257.438547 -215.862128) (xy 257.49339 -215.851998) (xy 257.549124 -215.849961)
			(xy 257.604561 -215.856061) (xy 257.658518 -215.870167) (xy 257.709847 -215.891979) (xy 257.757453 -215.921033)
			(xy 257.800321 -215.956708) (xy 257.837538 -215.998245) (xy 257.868311 -216.044758) (xy 257.891983 -216.095255)
			(xy 257.908051 -216.148662) (xy 257.916171 -216.203838) (xy 257.91668 -216.231724) (xy 257.916171 -216.25961)
			(xy 257.908051 -216.314786) (xy 257.891983 -216.368193) (xy 257.868311 -216.41869) (xy 257.837538 -216.465203)
			(xy 257.800321 -216.50674) (xy 257.757453 -216.542415) (xy 257.709847 -216.571469) (xy 257.658518 -216.593281)
			(xy 257.604561 -216.607387) (xy 257.549124 -216.613487) (xy 257.49339 -216.61145) (xy 257.438547 -216.60132)
			(xy 257.385763 -216.583313) (xy 257.336163 -216.557812) (xy 257.290805 -216.525361) (xy 257.250656 -216.486652)
			(xy 257.21657 -216.442509) (xy 257.189274 -216.393874) (xy 257.169351 -216.341783) (xy 257.157225 -216.287346)
			(xy 257.153154 -216.231724) (xy 254.524143 -216.231724) (xy 254.523779 -216.232027) (xy 254.476173 -216.261081)
			(xy 254.424844 -216.282893) (xy 254.370887 -216.296999) (xy 254.31545 -216.303099) (xy 254.259716 -216.301062)
			(xy 254.204873 -216.290932) (xy 254.152089 -216.272925) (xy 254.102489 -216.247424) (xy 254.057131 -216.214973)
			(xy 254.016982 -216.176264) (xy 253.982896 -216.132121) (xy 253.9556 -216.083486) (xy 253.935677 -216.031395)
			(xy 253.923551 -215.976958) (xy 253.91948 -215.921336) (xy 252.912626 -215.921336) (xy 252.912626 -216.834466)
			(xy 254.78054 -216.834466) (xy 254.784611 -216.778844) (xy 254.796737 -216.724407) (xy 254.81666 -216.672316)
			(xy 254.843956 -216.623681) (xy 254.878042 -216.579538) (xy 254.918191 -216.540829) (xy 254.963549 -216.508378)
			(xy 255.013149 -216.482877) (xy 255.065933 -216.46487) (xy 255.120776 -216.45474) (xy 255.17651 -216.452703)
			(xy 255.231947 -216.458803) (xy 255.285904 -216.472909) (xy 255.337233 -216.494721) (xy 255.384839 -216.523775)
			(xy 255.427707 -216.55945) (xy 255.464924 -216.600987) (xy 255.495697 -216.6475) (xy 255.519369 -216.697997)
			(xy 255.535437 -216.751404) (xy 255.543557 -216.80658) (xy 255.544066 -216.834466) (xy 255.543557 -216.862352)
			(xy 255.535437 -216.917528) (xy 255.519369 -216.970935) (xy 255.495697 -217.021432) (xy 255.464924 -217.067945)
			(xy 255.427707 -217.109482) (xy 255.384839 -217.145157) (xy 255.337233 -217.174211) (xy 255.285904 -217.196023)
			(xy 255.231947 -217.210129) (xy 255.17651 -217.216229) (xy 255.120776 -217.214192) (xy 255.065933 -217.204062)
			(xy 255.013149 -217.186055) (xy 254.963549 -217.160554) (xy 254.918191 -217.128103) (xy 254.878042 -217.089394)
			(xy 254.843956 -217.045251) (xy 254.81666 -216.996616) (xy 254.796737 -216.944525) (xy 254.784611 -216.890088)
			(xy 254.78054 -216.834466) (xy 252.912626 -216.834466) (xy 252.912626 -218.332812) (xy 252.912201 -218.342882)
			(xy 252.904487 -218.361486) (xy 252.89764 -218.36888) (xy 251.03201 -220.23451) (xy 258.139182 -220.23451)
			(xy 258.143253 -220.178888) (xy 258.155379 -220.124451) (xy 258.175302 -220.07236) (xy 258.202598 -220.023725)
			(xy 258.236684 -219.979582) (xy 258.276833 -219.940873) (xy 258.322191 -219.908422) (xy 258.371791 -219.882921)
			(xy 258.424575 -219.864914) (xy 258.479418 -219.854784) (xy 258.535152 -219.852747) (xy 258.590589 -219.858847)
			(xy 258.644546 -219.872953) (xy 258.695875 -219.894765) (xy 258.743481 -219.923819) (xy 258.786349 -219.959494)
			(xy 258.823566 -220.001031) (xy 258.854339 -220.047544) (xy 258.878011 -220.098041) (xy 258.894079 -220.151448)
			(xy 258.902199 -220.206624) (xy 258.902708 -220.23451) (xy 258.902199 -220.262396) (xy 258.894079 -220.317572)
			(xy 258.878011 -220.370979) (xy 258.854339 -220.421476) (xy 258.823566 -220.467989) (xy 258.786349 -220.509526)
			(xy 258.743481 -220.545201) (xy 258.695875 -220.574255) (xy 258.644546 -220.596067) (xy 258.590589 -220.610173)
			(xy 258.535152 -220.616273) (xy 258.479418 -220.614236) (xy 258.424575 -220.604106) (xy 258.371791 -220.586099)
			(xy 258.322191 -220.560598) (xy 258.276833 -220.528147) (xy 258.236684 -220.489438) (xy 258.202598 -220.445295)
			(xy 258.175302 -220.39666) (xy 258.155379 -220.344569) (xy 258.143253 -220.290132) (xy 258.139182 -220.23451)
			(xy 251.03201 -220.23451) (xy 250.549918 -220.716602) (xy 250.547036 -220.719606) (xy 250.542186 -220.726371)
			(xy 250.540266 -220.730064) (xy 250.533662 -220.743526) (xy 250.532392 -220.748606) (xy 250.525588 -220.773657)
			(xy 250.506125 -220.82178) (xy 250.480317 -220.86682) (xy 250.448642 -220.907946) (xy 250.411685 -220.944398)
			(xy 250.370127 -220.975504) (xy 250.324736 -221.00069) (xy 250.27635 -221.019489) (xy 250.251214 -221.025974)
			(xy 250.244102 -221.027752) (xy 250.232164 -221.034356) (xy 250.185428 -221.081092) (xy 251.697996 -221.081092)
			(xy 251.702067 -221.02547) (xy 251.714193 -220.971033) (xy 251.734116 -220.918942) (xy 251.761412 -220.870307)
			(xy 251.795498 -220.826164) (xy 251.835647 -220.787455) (xy 251.881005 -220.755004) (xy 251.930605 -220.729503)
			(xy 251.983389 -220.711496) (xy 252.038232 -220.701366) (xy 252.093966 -220.699329) (xy 252.149403 -220.705429)
			(xy 252.20336 -220.719535) (xy 252.254689 -220.741347) (xy 252.302295 -220.770401) (xy 252.345163 -220.806076)
			(xy 252.38238 -220.847613) (xy 252.413153 -220.894126) (xy 252.436825 -220.944623) (xy 252.452893 -220.99803)
			(xy 252.461013 -221.053206) (xy 252.461522 -221.081092) (xy 252.461013 -221.108978) (xy 252.452893 -221.164154)
			(xy 252.436825 -221.217561) (xy 252.413153 -221.268058) (xy 252.38238 -221.314571) (xy 252.366042 -221.332806)
			(xy 254.815084 -221.332806) (xy 254.819155 -221.277184) (xy 254.831281 -221.222747) (xy 254.851204 -221.170656)
			(xy 254.8785 -221.122021) (xy 254.912586 -221.077878) (xy 254.952735 -221.039169) (xy 254.998093 -221.006718)
			(xy 255.047693 -220.981217) (xy 255.100477 -220.96321) (xy 255.15532 -220.95308) (xy 255.211054 -220.951043)
			(xy 255.266491 -220.957143) (xy 255.320448 -220.971249) (xy 255.371777 -220.993061) (xy 255.419383 -221.022115)
			(xy 255.462251 -221.05779) (xy 255.499468 -221.099327) (xy 255.530241 -221.14584) (xy 255.553913 -221.196337)
			(xy 255.569981 -221.249744) (xy 255.578101 -221.30492) (xy 255.57861 -221.332806) (xy 255.578101 -221.360692)
			(xy 255.569981 -221.415868) (xy 255.553913 -221.469275) (xy 255.530241 -221.519772) (xy 255.499468 -221.566285)
			(xy 255.462251 -221.607822) (xy 255.419383 -221.643497) (xy 255.371777 -221.672551) (xy 255.320448 -221.694363)
			(xy 255.266491 -221.708469) (xy 255.211054 -221.714569) (xy 255.15532 -221.712532) (xy 255.100477 -221.702402)
			(xy 255.047693 -221.684395) (xy 254.998093 -221.658894) (xy 254.952735 -221.626443) (xy 254.912586 -221.587734)
			(xy 254.8785 -221.543591) (xy 254.851204 -221.494956) (xy 254.831281 -221.442865) (xy 254.819155 -221.388428)
			(xy 254.815084 -221.332806) (xy 252.366042 -221.332806) (xy 252.345163 -221.356108) (xy 252.302295 -221.391783)
			(xy 252.254689 -221.420837) (xy 252.20336 -221.442649) (xy 252.149403 -221.456755) (xy 252.093966 -221.462855)
			(xy 252.038232 -221.460818) (xy 251.983389 -221.450688) (xy 251.930605 -221.432681) (xy 251.881005 -221.40718)
			(xy 251.835647 -221.374729) (xy 251.795498 -221.33602) (xy 251.761412 -221.291877) (xy 251.734116 -221.243242)
			(xy 251.714193 -221.191151) (xy 251.702067 -221.136714) (xy 251.697996 -221.081092) (xy 250.185428 -221.081092)
			(xy 249.087386 -222.179134) (xy 249.077481 -222.189745) (xy 249.063541 -222.21519) (xy 249.057325 -222.24353)
			(xy 249.059337 -222.272474) (xy 249.069412 -222.299682) (xy 249.086737 -222.322955) (xy 249.098054 -222.332042)
			(xy 249.100848 -222.334074) (xy 249.123258 -222.349256) (xy 249.163959 -222.384942) (xy 249.199205 -222.426024)
			(xy 249.228289 -222.471677) (xy 249.250624 -222.520984) (xy 249.265764 -222.572953) (xy 249.273403 -222.626541)
			(xy 249.273822 -222.653606) (xy 249.273431 -222.67808) (xy 249.267133 -222.726621) (xy 249.254667 -222.773954)
			(xy 249.23624 -222.819301) (xy 249.224546 -222.840804) (xy 249.221752 -222.8469) (xy 249.217222 -222.859297)
			(xy 249.213988 -222.885483) (xy 249.217572 -222.911624) (xy 249.227734 -222.935974) (xy 249.243795 -222.956907)
			(xy 249.25401 -222.965264) (xy 249.25782 -222.968058) (xy 249.280818 -222.983111) (xy 249.322637 -223.018778)
			(xy 249.358903 -223.060081) (xy 249.361166 -223.063562) (xy 250.628656 -223.063562) (xy 250.632727 -223.00794)
			(xy 250.644853 -222.953503) (xy 250.664776 -222.901412) (xy 250.692072 -222.852777) (xy 250.726158 -222.808634)
			(xy 250.766307 -222.769925) (xy 250.811665 -222.737474) (xy 250.861265 -222.711973) (xy 250.914049 -222.693966)
			(xy 250.968892 -222.683836) (xy 251.024626 -222.681799) (xy 251.080063 -222.687899) (xy 251.13402 -222.702005)
			(xy 251.185349 -222.723817) (xy 251.232955 -222.752871) (xy 251.275823 -222.788546) (xy 251.31304 -222.830083)
			(xy 251.343813 -222.876596) (xy 251.367485 -222.927093) (xy 251.382255 -222.976186) (xy 255.04267 -222.976186)
			(xy 255.043224 -222.94727) (xy 255.051942 -222.890099) (xy 255.069191 -222.8349) (xy 255.094576 -222.782938)
			(xy 255.127515 -222.735403) (xy 255.167252 -222.693386) (xy 255.189736 -222.675196) (xy 255.198501 -222.667638)
			(xy 255.208681 -222.646876) (xy 255.209294 -222.635318) (xy 255.209294 -222.555054) (xy 255.208694 -222.54349)
			(xy 255.198521 -222.522718) (xy 255.189736 -222.515176) (xy 255.167249 -222.496989) (xy 255.127512 -222.45497)
			(xy 255.094572 -222.407434) (xy 255.069184 -222.355472) (xy 255.05193 -222.300273) (xy 255.043203 -222.243102)
			(xy 255.04267 -222.214186) (xy 255.043156 -222.186935) (xy 255.050912 -222.132987) (xy 255.066267 -222.080692)
			(xy 255.088909 -222.031115) (xy 255.118375 -221.985265) (xy 255.154066 -221.944074) (xy 255.195257 -221.908383)
			(xy 255.241107 -221.878917) (xy 255.290684 -221.856275) (xy 255.342979 -221.84092) (xy 255.396927 -221.833164)
			(xy 255.451429 -221.833164) (xy 255.505377 -221.84092) (xy 255.557672 -221.856275) (xy 255.607249 -221.878917)
			(xy 255.653099 -221.908383) (xy 255.69429 -221.944074) (xy 255.729981 -221.985265) (xy 255.759447 -222.031115)
			(xy 255.782089 -222.080692) (xy 255.797444 -222.132987) (xy 255.8052 -222.186935) (xy 255.805686 -222.214186)
			(xy 255.805163 -222.243103) (xy 255.796436 -222.300274) (xy 255.779179 -222.355473) (xy 255.753788 -222.407435)
			(xy 255.720845 -222.454969) (xy 255.681105 -222.496986) (xy 255.65862 -222.515176) (xy 255.64986 -222.522739)
			(xy 255.639679 -222.543498) (xy 255.639062 -222.555054) (xy 255.639062 -222.635318) (xy 255.639601 -222.646891)
			(xy 255.649816 -222.667662) (xy 255.65862 -222.675196) (xy 255.681106 -222.693384) (xy 255.72084 -222.735405)
			(xy 255.753778 -222.782941) (xy 255.779166 -222.834903) (xy 255.796422 -222.8901) (xy 255.805151 -222.94727)
			(xy 255.805686 -222.976186) (xy 255.8052 -223.003437) (xy 255.797444 -223.057385) (xy 255.782089 -223.10968)
			(xy 255.759447 -223.159257) (xy 255.729981 -223.205107) (xy 255.69429 -223.246298) (xy 255.653099 -223.281989)
			(xy 255.607249 -223.311455) (xy 255.557672 -223.334097) (xy 255.505377 -223.349452) (xy 255.451429 -223.357208)
			(xy 255.396927 -223.357208) (xy 255.342979 -223.349452) (xy 255.290684 -223.334097) (xy 255.241107 -223.311455)
			(xy 255.195257 -223.281989) (xy 255.154066 -223.246298) (xy 255.118375 -223.205107) (xy 255.088909 -223.159257)
			(xy 255.066267 -223.10968) (xy 255.050912 -223.057385) (xy 255.043156 -223.003437) (xy 255.04267 -222.976186)
			(xy 251.382255 -222.976186) (xy 251.383553 -222.9805) (xy 251.391673 -223.035676) (xy 251.392182 -223.063562)
			(xy 251.391673 -223.091448) (xy 251.383553 -223.146624) (xy 251.367485 -223.200031) (xy 251.343813 -223.250528)
			(xy 251.31304 -223.297041) (xy 251.275823 -223.338578) (xy 251.232955 -223.374253) (xy 251.185349 -223.403307)
			(xy 251.13402 -223.425119) (xy 251.080063 -223.439225) (xy 251.024626 -223.445325) (xy 250.968892 -223.443288)
			(xy 250.914049 -223.433158) (xy 250.861265 -223.415151) (xy 250.811665 -223.38965) (xy 250.766307 -223.357199)
			(xy 250.726158 -223.31849) (xy 250.692072 -223.274347) (xy 250.664776 -223.225712) (xy 250.644853 -223.173621)
			(xy 250.632727 -223.119184) (xy 250.628656 -223.063562) (xy 249.361166 -223.063562) (xy 249.388862 -223.106162)
			(xy 249.411895 -223.156067) (xy 249.427523 -223.208763) (xy 249.435424 -223.263156) (xy 249.435874 -223.290638)
			(xy 249.435385 -223.317887) (xy 249.427624 -223.371828) (xy 249.412265 -223.424116) (xy 249.389622 -223.473687)
			(xy 249.360154 -223.51953) (xy 249.324462 -223.560713) (xy 249.283272 -223.596397) (xy 249.237423 -223.625856)
			(xy 249.187849 -223.64849) (xy 249.135558 -223.663839) (xy 249.081615 -223.67159) (xy 249.054366 -223.672146)
			(xy 249.053858 -223.672146) (xy 249.026608 -223.671657) (xy 248.972663 -223.663896) (xy 248.920371 -223.648538)
			(xy 248.870796 -223.625895) (xy 248.824948 -223.596428) (xy 248.78376 -223.560737) (xy 248.74807 -223.519548)
			(xy 248.718603 -223.4737) (xy 248.695961 -223.424126) (xy 248.680603 -223.371834) (xy 248.672842 -223.317888)
			(xy 248.67235 -223.290638) (xy 248.672972 -223.258921) (xy 248.683468 -223.196361) (xy 248.704191 -223.136408)
			(xy 248.718832 -223.108266) (xy 248.725661 -223.094638) (xy 248.731668 -223.064765) (xy 248.728592 -223.034451)
			(xy 248.716706 -223.006394) (xy 248.697069 -222.983095) (xy 248.684542 -222.974408) (xy 248.662782 -222.959848)
			(xy 248.623083 -222.925715) (xy 248.588411 -222.886485) (xy 248.573544 -222.864934) (xy 248.564776 -222.852745)
			(xy 248.541591 -222.833688) (xy 248.513871 -222.822188) (xy 248.484004 -222.819237) (xy 248.454569 -222.82509)
			(xy 248.428104 -222.839242) (xy 248.41708 -222.84944) (xy 247.767094 -223.499426) (xy 247.759728 -223.506538)
			(xy 247.752108 -223.525334) (xy 247.752108 -225.623882) (xy 250.583698 -225.623882) (xy 250.587769 -225.56826)
			(xy 250.599895 -225.513823) (xy 250.619818 -225.461732) (xy 250.647114 -225.413097) (xy 250.6812 -225.368954)
			(xy 250.721349 -225.330245) (xy 250.766707 -225.297794) (xy 250.816307 -225.272293) (xy 250.869091 -225.254286)
			(xy 250.923934 -225.244156) (xy 250.979668 -225.242119) (xy 251.035105 -225.248219) (xy 251.089062 -225.262325)
			(xy 251.140391 -225.284137) (xy 251.187997 -225.313191) (xy 251.230865 -225.348866) (xy 251.268082 -225.390403)
			(xy 251.298855 -225.436916) (xy 251.322527 -225.487413) (xy 251.338595 -225.54082) (xy 251.346715 -225.595996)
			(xy 251.347224 -225.623882) (xy 251.346715 -225.651768) (xy 251.338595 -225.706944) (xy 251.338562 -225.707053)
			(xy 252.38274 -225.707053) (xy 252.38274 -225.652547) (xy 252.390497 -225.598595) (xy 252.405852 -225.546297)
			(xy 252.428494 -225.496716) (xy 252.457962 -225.450862) (xy 252.493655 -225.409668) (xy 252.534847 -225.373973)
			(xy 252.5807 -225.344503) (xy 252.63028 -225.321859) (xy 252.682578 -225.3065) (xy 252.736529 -225.298741)
			(xy 252.763782 -225.298254) (xy 252.793288 -225.298796) (xy 252.851593 -225.307899) (xy 252.907804 -225.325862)
			(xy 252.960584 -225.352256) (xy 253.008677 -225.386453) (xy 253.050939 -225.427639) (xy 253.06909 -225.450908)
			(xy 253.078104 -225.462225) (xy 253.101178 -225.479659) (xy 253.128218 -225.489916) (xy 253.157049 -225.49217)
			(xy 253.185355 -225.486239) (xy 253.210857 -225.472601) (xy 253.231505 -225.452353) (xy 253.239016 -225.439986)
			(xy 253.253643 -225.415103) (xy 253.289177 -225.369623) (xy 253.331157 -225.330014) (xy 253.378625 -225.297181)
			(xy 253.430496 -225.271873) (xy 253.485589 -225.254669) (xy 253.542644 -225.245959) (xy 253.571502 -225.245422)
			(xy 253.598755 -225.245848) (xy 253.652707 -225.253605) (xy 253.705006 -225.268962) (xy 253.754587 -225.291605)
			(xy 253.80044 -225.321074) (xy 253.841634 -225.356768) (xy 253.877328 -225.397961) (xy 253.906796 -225.443815)
			(xy 253.929439 -225.493396) (xy 253.944795 -225.545695) (xy 253.952552 -225.599647) (xy 253.952552 -225.654153)
			(xy 253.944795 -225.708105) (xy 253.929439 -225.760404) (xy 253.906796 -225.809985) (xy 253.877328 -225.855839)
			(xy 253.841634 -225.897032) (xy 253.80044 -225.932726) (xy 253.754587 -225.962195) (xy 253.705006 -225.984838)
			(xy 253.652707 -226.000195) (xy 253.598755 -226.007952) (xy 253.571502 -226.008438) (xy 253.541995 -226.007859)
			(xy 253.48368 -225.998797) (xy 253.427458 -225.980859) (xy 253.374671 -225.954473) (xy 253.32658 -225.920269)
			(xy 253.284333 -225.879064) (xy 253.266194 -225.855784) (xy 253.257198 -225.844452) (xy 253.23412 -225.827018)
			(xy 253.207076 -225.816764) (xy 253.178241 -225.814513) (xy 253.149933 -225.820446) (xy 253.124429 -225.834087)
			(xy 253.103779 -225.854338) (xy 253.096268 -225.866706) (xy 253.081649 -225.891594) (xy 253.046114 -225.937075)
			(xy 253.004133 -225.976684) (xy 252.956664 -226.009516) (xy 252.904791 -226.034823) (xy 252.849697 -226.052027)
			(xy 252.79264 -226.060734) (xy 252.763782 -226.06127) (xy 252.736529 -226.060859) (xy 252.682578 -226.0531)
			(xy 252.63028 -226.037741) (xy 252.5807 -226.015097) (xy 252.534847 -225.985627) (xy 252.493655 -225.949932)
			(xy 252.457962 -225.908738) (xy 252.428494 -225.862884) (xy 252.405852 -225.813303) (xy 252.390497 -225.761005)
			(xy 252.38274 -225.707053) (xy 251.338562 -225.707053) (xy 251.322527 -225.760351) (xy 251.298855 -225.810848)
			(xy 251.268082 -225.857361) (xy 251.230865 -225.898898) (xy 251.187997 -225.934573) (xy 251.140391 -225.963627)
			(xy 251.089062 -225.985439) (xy 251.035105 -225.999545) (xy 250.979668 -226.005645) (xy 250.923934 -226.003608)
			(xy 250.869091 -225.993478) (xy 250.816307 -225.975471) (xy 250.766707 -225.94997) (xy 250.721349 -225.917519)
			(xy 250.6812 -225.87881) (xy 250.647114 -225.834667) (xy 250.619818 -225.786032) (xy 250.599895 -225.733941)
			(xy 250.587769 -225.679504) (xy 250.583698 -225.623882) (xy 247.752108 -225.623882) (xy 247.752108 -227.965)
			(xy 248.081036 -227.965) (xy 248.085107 -227.909378) (xy 248.097233 -227.854941) (xy 248.117156 -227.80285)
			(xy 248.144452 -227.754215) (xy 248.178538 -227.710072) (xy 248.218687 -227.671363) (xy 248.264045 -227.638912)
			(xy 248.313645 -227.613411) (xy 248.366429 -227.595404) (xy 248.421272 -227.585274) (xy 248.477006 -227.583237)
			(xy 248.532443 -227.589337) (xy 248.5864 -227.603443) (xy 248.637729 -227.625255) (xy 248.685335 -227.654309)
			(xy 248.728203 -227.689984) (xy 248.76542 -227.731521) (xy 248.786016 -227.762651) (xy 250.517662 -227.762651)
			(xy 250.517662 -227.708149) (xy 250.525417 -227.654203) (xy 250.540771 -227.601909) (xy 250.56341 -227.552333)
			(xy 250.592874 -227.506482) (xy 250.628563 -227.465291) (xy 250.66975 -227.429598) (xy 250.715597 -227.40013)
			(xy 250.765172 -227.377485) (xy 250.817464 -227.362126) (xy 250.871409 -227.354365) (xy 250.89866 -227.353876)
			(xy 250.925455 -227.354304) (xy 250.978516 -227.361811) (xy 251.030005 -227.376669) (xy 251.078908 -227.398586)
			(xy 251.124264 -227.427129) (xy 251.165179 -227.461739) (xy 251.200849 -227.501733) (xy 251.230572 -227.546324)
			(xy 251.242576 -227.570284) (xy 251.246894 -227.579428) (xy 251.261626 -227.592636) (xy 251.347732 -227.623624)
			(xy 251.36729 -227.622608) (xy 251.376688 -227.618544) (xy 251.401816 -227.607497) (xy 251.45444 -227.591894)
			(xy 251.508756 -227.58399) (xy 251.5362 -227.583492) (xy 251.563451 -227.583978) (xy 251.617399 -227.591734)
			(xy 251.669694 -227.607089) (xy 251.719271 -227.629731) (xy 251.765121 -227.659197) (xy 251.806312 -227.694888)
			(xy 251.842003 -227.736079) (xy 251.871469 -227.781929) (xy 251.894111 -227.831506) (xy 251.909466 -227.883801)
			(xy 251.917222 -227.937749) (xy 251.917222 -227.992251) (xy 251.909466 -228.046199) (xy 251.894111 -228.098494)
			(xy 251.871469 -228.148071) (xy 251.842003 -228.193921) (xy 251.806312 -228.235112) (xy 251.765121 -228.270803)
			(xy 251.719271 -228.300269) (xy 251.669694 -228.322911) (xy 251.617399 -228.338266) (xy 251.563451 -228.346022)
			(xy 251.5362 -228.346508) (xy 251.509406 -228.346038) (xy 251.456347 -228.338539) (xy 251.404858 -228.323688)
			(xy 251.355955 -228.301778) (xy 251.310599 -228.27324) (xy 251.269683 -228.238636) (xy 251.234012 -228.198646)
			(xy 251.204289 -228.154058) (xy 251.192284 -228.1301) (xy 251.187966 -228.120956) (xy 251.173234 -228.107748)
			(xy 251.087128 -228.07676) (xy 251.06757 -228.077776) (xy 251.058172 -228.08184) (xy 251.033052 -228.092905)
			(xy 250.980424 -228.1085) (xy 250.926105 -228.116397) (xy 250.89866 -228.116892) (xy 250.871409 -228.116435)
			(xy 250.817464 -228.108674) (xy 250.765172 -228.093315) (xy 250.715597 -228.07067) (xy 250.66975 -228.041202)
			(xy 250.628563 -228.005509) (xy 250.592874 -227.964318) (xy 250.56341 -227.918467) (xy 250.540771 -227.868891)
			(xy 250.525417 -227.816597) (xy 250.517662 -227.762651) (xy 248.786016 -227.762651) (xy 248.796193 -227.778034)
			(xy 248.819865 -227.828531) (xy 248.835933 -227.881938) (xy 248.844053 -227.937114) (xy 248.844562 -227.965)
			(xy 248.844053 -227.992886) (xy 248.835933 -228.048062) (xy 248.819865 -228.101469) (xy 248.796193 -228.151966)
			(xy 248.76542 -228.198479) (xy 248.728203 -228.240016) (xy 248.685335 -228.275691) (xy 248.637729 -228.304745)
			(xy 248.5864 -228.326557) (xy 248.532443 -228.340663) (xy 248.477006 -228.346763) (xy 248.421272 -228.344726)
			(xy 248.366429 -228.334596) (xy 248.313645 -228.316589) (xy 248.264045 -228.291088) (xy 248.218687 -228.258637)
			(xy 248.178538 -228.219928) (xy 248.144452 -228.175785) (xy 248.117156 -228.12715) (xy 248.097233 -228.075059)
			(xy 248.085107 -228.020622) (xy 248.081036 -227.965) (xy 247.752108 -227.965) (xy 247.752108 -228.538278)
			(xy 249.24588 -228.538278) (xy 249.249951 -228.482656) (xy 249.262077 -228.428219) (xy 249.282 -228.376128)
			(xy 249.309296 -228.327493) (xy 249.343382 -228.28335) (xy 249.383531 -228.244641) (xy 249.428889 -228.21219)
			(xy 249.478489 -228.186689) (xy 249.531273 -228.168682) (xy 249.586116 -228.158552) (xy 249.64185 -228.156515)
			(xy 249.697287 -228.162615) (xy 249.751244 -228.176721) (xy 249.802573 -228.198533) (xy 249.850179 -228.227587)
			(xy 249.893047 -228.263262) (xy 249.930264 -228.304799) (xy 249.961037 -228.351312) (xy 249.984709 -228.401809)
			(xy 250.000777 -228.455216) (xy 250.008897 -228.510392) (xy 250.009406 -228.538278) (xy 250.008897 -228.566164)
			(xy 250.000777 -228.62134) (xy 249.984709 -228.674747) (xy 249.961037 -228.725244) (xy 249.930264 -228.771757)
			(xy 249.893047 -228.813294) (xy 249.850179 -228.848969) (xy 249.802573 -228.878023) (xy 249.751244 -228.899835)
			(xy 249.697287 -228.913941) (xy 249.64185 -228.920041) (xy 249.586116 -228.918004) (xy 249.531273 -228.907874)
			(xy 249.478489 -228.889867) (xy 249.428889 -228.864366) (xy 249.383531 -228.831915) (xy 249.343382 -228.793206)
			(xy 249.309296 -228.749063) (xy 249.282 -228.700428) (xy 249.262077 -228.648337) (xy 249.249951 -228.5939)
			(xy 249.24588 -228.538278) (xy 247.752108 -228.538278) (xy 247.752108 -229.119176) (xy 247.752545 -229.12924)
			(xy 247.76028 -229.147823) (xy 247.767094 -229.155244) (xy 248.540524 -229.928674) (xy 248.547923 -229.93552)
			(xy 248.566521 -229.943249) (xy 248.576592 -229.94366) (xy 254.70739 -229.94366)
		)
		(stroke
			(width 0)
			(type solid)
		)
		(fill yes)
		(layer "In9.Cu")
		(net "P1V8_PEX")
	)
	(gr_poly
		(pts
			(xy 236.990382 -338.430616) (xy 237.000446 -338.430178) (xy 237.01903 -338.422445) (xy 237.02645 -338.41563)
			(xy 239.227614 -336.214212) (xy 239.234472 -336.206818) (xy 239.242224 -336.188219) (xy 239.2426 -336.178144)
			(xy 239.2426 -335.55305) (xy 239.242112 -335.543049) (xy 239.234487 -335.524556) (xy 239.220402 -335.510353)
			(xy 239.211358 -335.50606) (xy 239.197134 -335.500218) (xy 239.167162 -335.50606) (xy 237.264956 -337.408266)
			(xy 237.241686 -337.430893) (xy 237.190941 -337.471362) (xy 237.135984 -337.505898) (xy 237.077507 -337.534064)
			(xy 237.016245 -337.555509) (xy 236.952967 -337.569961) (xy 236.888469 -337.577239) (xy 236.856016 -337.577684)
			(xy 235.894626 -337.577684) (xy 235.884577 -337.578104) (xy 235.866012 -337.585803) (xy 235.851821 -337.600035)
			(xy 235.847636 -337.60918) (xy 235.836455 -337.635001) (xy 235.807608 -337.68331) (xy 235.771974 -337.726855)
			(xy 235.730324 -337.764687) (xy 235.683566 -337.795985) (xy 235.632715 -337.82007) (xy 235.578875 -337.836417)
			(xy 235.523217 -337.844672) (xy 235.495084 -337.845146) (xy 235.467682 -337.844652) (xy 235.413447 -337.836778)
			(xy 235.360892 -337.821238) (xy 235.311097 -337.798349) (xy 235.265082 -337.768581) (xy 235.244132 -337.750912)
			(xy 235.23535 -337.744062) (xy 235.213959 -337.73795) (xy 235.191982 -337.741404) (xy 235.18241 -337.747102)
			(xy 235.153817 -337.765591) (xy 235.093131 -337.796477) (xy 235.029239 -337.820021) (xy 234.963023 -337.8359)
			(xy 234.895401 -337.843891) (xy 234.861354 -337.844384) (xy 234.8611 -337.844384) (xy 234.826152 -337.843877)
			(xy 234.756767 -337.83545) (xy 234.688904 -337.818718) (xy 234.623554 -337.793925) (xy 234.56167 -337.761435)
			(xy 234.504154 -337.721719) (xy 234.451847 -337.675359) (xy 234.405512 -337.62303) (xy 234.365824 -337.565496)
			(xy 234.333362 -337.503596) (xy 234.308601 -337.438234) (xy 234.291901 -337.370363) (xy 234.283506 -337.300974)
			(xy 234.282996 -337.266026) (xy 234.283526 -337.229655) (xy 234.292617 -337.157483) (xy 234.310696 -337.087024)
			(xy 234.337478 -337.019392) (xy 234.372537 -336.955657) (xy 234.393486 -336.92592) (xy 234.398073 -336.919223)
			(xy 234.40313 -336.903807) (xy 234.403392 -336.895694) (xy 234.403392 -336.772758) (xy 234.403099 -336.764649)
			(xy 234.398057 -336.749235) (xy 234.393486 -336.742532) (xy 234.372582 -336.712797) (xy 234.337556 -336.649107)
			(xy 234.310786 -336.581531) (xy 234.292694 -336.511133) (xy 234.283565 -336.439023) (xy 234.282996 -336.40268)
			(xy 234.282996 -336.402426) (xy 234.283522 -336.367481) (xy 234.29194 -336.298101) (xy 234.308658 -336.230241)
			(xy 234.333431 -336.16489) (xy 234.365898 -336.103) (xy 234.405586 -336.045473) (xy 234.451918 -335.993148)
			(xy 234.504216 -335.946788) (xy 234.561721 -335.907067) (xy 234.623592 -335.874565) (xy 234.688929 -335.849755)
			(xy 234.75678 -335.832999) (xy 234.826156 -335.824541) (xy 234.8611 -335.824068) (xy 234.861354 -335.824068)
			(xy 234.8954 -335.824564) (xy 234.96302 -335.832564) (xy 235.029233 -335.848446) (xy 235.093124 -335.871991)
			(xy 235.15381 -335.902873) (xy 235.18241 -335.92135) (xy 235.191956 -335.927119) (xy 235.21396 -335.930608)
			(xy 235.235368 -335.92444) (xy 235.244132 -335.91754) (xy 235.26508 -335.899868) (xy 235.311087 -335.870088)
			(xy 235.360883 -335.847199) (xy 235.413442 -335.831672) (xy 235.467682 -335.823826) (xy 235.495084 -335.823306)
			(xy 235.523212 -335.823815) (xy 235.578856 -335.832091) (xy 235.63268 -335.848451) (xy 235.683518 -335.87254)
			(xy 235.730265 -335.903835) (xy 235.771909 -335.941658) (xy 235.807544 -335.985188) (xy 235.836399 -336.03348)
			(xy 235.847636 -336.059272) (xy 235.851844 -336.068405) (xy 235.866022 -336.082641) (xy 235.88458 -336.090344)
			(xy 235.894626 -336.090768) (xy 236.458506 -336.090768) (xy 236.468575 -336.090343) (xy 236.487175 -336.082624)
			(xy 236.494574 -336.075782) (xy 241.345974 -331.224382) (xy 241.35282 -331.216984) (xy 241.360552 -331.198385)
			(xy 241.36096 -331.188314) (xy 241.36096 -329.732894) (xy 241.360542 -329.72357) (xy 241.353861 -329.706159)
			(xy 241.341388 -329.692296) (xy 241.333274 -329.687682) (xy 241.24031 -329.63993) (xy 241.211862 -329.642216)
			(xy 241.200178 -329.650598) (xy 241.170169 -329.671525) (xy 241.105944 -329.706568) (xy 241.037854 -329.733338)
			(xy 240.966961 -329.751419) (xy 240.894367 -329.76053) (xy 240.857786 -329.761088) (xy 240.822374 -329.760553)
			(xy 240.752065 -329.752014) (xy 240.683298 -329.735063) (xy 240.617076 -329.709948) (xy 240.554364 -329.677033)
			(xy 240.496077 -329.636799) (xy 240.443064 -329.589833) (xy 240.396098 -329.53682) (xy 240.355865 -329.478532)
			(xy 240.322951 -329.41582) (xy 240.297835 -329.349598) (xy 240.280885 -329.280831) (xy 240.272347 -329.210522)
			(xy 240.271808 -329.17511) (xy 240.271808 -324.336664) (xy 240.271379 -324.326596) (xy 240.263656 -324.308001)
			(xy 240.256822 -324.300596) (xy 240.217706 -324.26148) (xy 240.210341 -324.254658) (xy 240.191832 -324.246926)
			(xy 240.171773 -324.246885) (xy 240.162334 -324.250304) (xy 240.14811 -324.256146) (xy 240.131092 -324.281546)
			(xy 240.131092 -331.878432) (xy 240.130604 -331.905774) (xy 240.122822 -331.959901) (xy 240.107416 -332.01237)
			(xy 240.084699 -332.062112) (xy 240.055135 -332.108115) (xy 240.019325 -332.149443) (xy 239.977997 -332.185253)
			(xy 239.931994 -332.214817) (xy 239.882252 -332.237534) (xy 239.829783 -332.25294) (xy 239.775656 -332.260722)
			(xy 239.720972 -332.260722) (xy 239.666845 -332.25294) (xy 239.614376 -332.237534) (xy 239.564634 -332.214817)
			(xy 239.518631 -332.185253) (xy 239.477303 -332.149443) (xy 239.441493 -332.108115) (xy 239.411929 -332.062112)
			(xy 239.389212 -332.01237) (xy 239.373806 -331.959901) (xy 239.366024 -331.905774) (xy 239.365536 -331.878432)
			(xy 239.365536 -324.300088) (xy 239.365109 -324.29002) (xy 239.357384 -324.271425) (xy 239.35055 -324.26402)
			(xy 238.503714 -323.41693) (xy 238.496312 -323.410094) (xy 238.477714 -323.402386) (xy 238.467646 -323.401944)
			(xy 234.017566 -323.401944) (xy 233.987506 -323.401353) (xy 233.928127 -323.391948) (xy 233.870949 -323.373375)
			(xy 233.817377 -323.346091) (xy 233.768731 -323.310766) (xy 233.747056 -323.28993) (xy 232.720134 -322.263008)
			(xy 232.69927 -322.241356) (xy 232.663928 -322.192712) (xy 232.636634 -322.139137) (xy 232.618061 -322.08195)
			(xy 232.608667 -322.022562) (xy 232.60812 -321.992498) (xy 232.60812 -309.013606) (xy 232.607409 -309.001024)
			(xy 232.595421 -308.978893) (xy 232.58526 -308.971442) (xy 232.514648 -308.924452) (xy 232.503718 -308.918066)
			(xy 232.478535 -308.915799) (xy 232.466642 -308.920134) (xy 232.443004 -308.929692) (xy 232.393826 -308.943159)
			(xy 232.343292 -308.949953) (xy 232.317798 -308.95036) (xy 232.29055 -308.949874) (xy 232.23661 -308.942118)
			(xy 232.184322 -308.926765) (xy 232.134751 -308.904126) (xy 232.088907 -308.874664) (xy 232.047722 -308.838977)
			(xy 232.012035 -308.797792) (xy 231.982573 -308.751947) (xy 231.959935 -308.702376) (xy 231.944582 -308.650088)
			(xy 231.936826 -308.596148) (xy 231.936826 -308.541652) (xy 231.944582 -308.487712) (xy 231.959935 -308.435424)
			(xy 231.982573 -308.385853) (xy 232.012035 -308.340008) (xy 232.047722 -308.298823) (xy 232.088907 -308.263136)
			(xy 232.134751 -308.233674) (xy 232.184322 -308.211035) (xy 232.23661 -308.195682) (xy 232.29055 -308.187926)
			(xy 232.317798 -308.187344) (xy 232.343292 -308.187768) (xy 232.393825 -308.194557) (xy 232.443004 -308.208013)
			(xy 232.466642 -308.21757) (xy 232.478533 -308.221955) (xy 232.503743 -308.219705) (xy 232.514648 -308.213252)
			(xy 232.58526 -308.166262) (xy 232.595407 -308.158794) (xy 232.607409 -308.136676) (xy 232.60812 -308.124098)
			(xy 232.60812 -307.929026) (xy 232.607391 -307.916454) (xy 232.595385 -307.894354) (xy 232.58526 -307.886862)
			(xy 232.514648 -307.839872) (xy 232.503718 -307.833485) (xy 232.478535 -307.831216) (xy 232.466642 -307.835554)
			(xy 232.443004 -307.845112) (xy 232.393826 -307.858578) (xy 232.343292 -307.865371) (xy 232.317798 -307.86578)
			(xy 232.290549 -307.865294) (xy 232.236605 -307.857537) (xy 232.184315 -307.842183) (xy 232.134742 -307.819544)
			(xy 232.088895 -307.79008) (xy 232.047708 -307.754391) (xy 232.012019 -307.713204) (xy 231.982555 -307.667357)
			(xy 231.959916 -307.617783) (xy 231.944562 -307.565493) (xy 231.936806 -307.511549) (xy 231.936806 -307.457051)
			(xy 231.944562 -307.403107) (xy 231.959916 -307.350817) (xy 231.982555 -307.301243) (xy 232.012019 -307.255396)
			(xy 232.047708 -307.214209) (xy 232.088895 -307.17852) (xy 232.134742 -307.149056) (xy 232.184315 -307.126417)
			(xy 232.236605 -307.111063) (xy 232.290549 -307.103306) (xy 232.317798 -307.102764) (xy 232.343291 -307.103188)
			(xy 232.393824 -307.109977) (xy 232.443003 -307.123434) (xy 232.466642 -307.13299) (xy 232.478533 -307.137374)
			(xy 232.503743 -307.135125) (xy 232.514648 -307.128672) (xy 232.58526 -307.081682) (xy 232.595411 -307.074215)
			(xy 232.607422 -307.052098) (xy 232.60812 -307.039518) (xy 232.60812 -282.828238) (xy 232.607686 -282.818172)
			(xy 232.599958 -282.799582) (xy 232.593134 -282.79217) (xy 229.637336 -279.836372) (xy 229.616487 -279.814699)
			(xy 229.581124 -279.766062) (xy 229.553796 -279.712495) (xy 229.535177 -279.655316) (xy 229.525722 -279.595929)
			(xy 229.525068 -279.565862) (xy 229.525068 -275.164042) (xy 229.522606 -275.160924) (xy 229.516866 -275.155435)
			(xy 229.513638 -275.15312) (xy 229.435152 -275.105876) (xy 229.429332 -275.102762) (xy 229.416601 -275.099296)
			(xy 229.410006 -275.099018) (xy 229.38613 -275.10486) (xy 229.38105 -275.107654) (xy 229.353941 -275.120906)
			(xy 229.296576 -275.139615) (xy 229.236976 -275.149033) (xy 229.206806 -275.149564) (xy 229.201218 -275.149564)
			(xy 229.174228 -275.148701) (xy 229.120886 -275.140305) (xy 229.06926 -275.124472) (xy 229.020383 -275.101517)
			(xy 228.975231 -275.071899) (xy 228.934706 -275.03621) (xy 228.899619 -274.995164) (xy 228.87067 -274.94958)
			(xy 228.848439 -274.90037) (xy 228.833368 -274.848516) (xy 228.82576 -274.795056) (xy 228.825298 -274.768056)
			(xy 228.825787 -274.740807) (xy 228.833548 -274.686864) (xy 228.848907 -274.634575) (xy 228.871551 -274.585004)
			(xy 228.901019 -274.539159) (xy 228.93671 -274.497975) (xy 228.977899 -274.462289) (xy 229.023748 -274.432827)
			(xy 229.073322 -274.41019) (xy 229.125613 -274.394838) (xy 229.179557 -274.387083) (xy 229.206806 -274.386548)
			(xy 229.237895 -274.387158) (xy 229.299249 -274.397251) (xy 229.358145 -274.417184) (xy 229.385876 -274.431252)
			(xy 229.38613 -274.431252) (xy 229.397379 -274.436393) (xy 229.422072 -274.436528) (xy 229.433374 -274.431506)
			(xy 229.513892 -274.382992) (xy 229.517046 -274.380655) (xy 229.522654 -274.375165) (xy 229.525068 -274.37207)
			(xy 229.525068 -273.87042) (xy 229.517505 -273.861236) (xy 229.496307 -273.8505) (xy 229.484428 -273.849846)
			(xy 229.354634 -273.849846) (xy 229.32644 -273.873976) (xy 229.323392 -273.892264) (xy 229.318229 -273.920029)
			(xy 229.300803 -273.973746) (xy 229.275651 -274.024309) (xy 229.243323 -274.070614) (xy 229.204525 -274.111649)
			(xy 229.160104 -274.14652) (xy 229.111029 -274.174464) (xy 229.058372 -274.194871) (xy 229.003283 -274.207297)
			(xy 228.946964 -274.211469) (xy 228.890645 -274.207297) (xy 228.835556 -274.194871) (xy 228.782899 -274.174464)
			(xy 228.733824 -274.14652) (xy 228.689403 -274.111649) (xy 228.650605 -274.070614) (xy 228.618277 -274.024309)
			(xy 228.593125 -273.973746) (xy 228.575699 -273.920029) (xy 228.570536 -273.892264) (xy 228.567488 -273.873976)
			(xy 228.539294 -273.849846) (xy 228.451664 -273.849846) (xy 228.42347 -273.873214) (xy 228.420168 -273.891502)
			(xy 228.414654 -273.918861) (xy 228.396691 -273.971701) (xy 228.371219 -274.021359) (xy 228.338783 -274.066775)
			(xy 228.300074 -274.106979) (xy 228.25592 -274.141113) (xy 228.207264 -274.168449) (xy 228.155143 -274.188402)
			(xy 228.100671 -274.200547) (xy 228.04501 -274.204624) (xy 227.989349 -274.200547) (xy 227.934877 -274.188402)
			(xy 227.882756 -274.168449) (xy 227.8341 -274.141113) (xy 227.789946 -274.106979) (xy 227.751237 -274.066775)
			(xy 227.718801 -274.021359) (xy 227.693329 -273.971701) (xy 227.675366 -273.918861) (xy 227.669852 -273.891502)
			(xy 227.66655 -273.873214) (xy 227.638356 -273.849846) (xy 220.321124 -273.849846) (xy 220.311103 -273.850262)
			(xy 220.292586 -273.857929) (xy 220.278417 -273.872104) (xy 220.270758 -273.890625) (xy 220.270324 -273.900646)
			(xy 220.270324 -274.632674) (xy 226.694998 -274.632674) (xy 226.699069 -274.577052) (xy 226.711195 -274.522615)
			(xy 226.731118 -274.470524) (xy 226.758414 -274.421889) (xy 226.7925 -274.377746) (xy 226.832649 -274.339037)
			(xy 226.878007 -274.306586) (xy 226.927607 -274.281085) (xy 226.980391 -274.263078) (xy 227.035234 -274.252948)
			(xy 227.090968 -274.250911) (xy 227.146405 -274.257011) (xy 227.200362 -274.271117) (xy 227.251691 -274.292929)
			(xy 227.299297 -274.321983) (xy 227.342165 -274.357658) (xy 227.379382 -274.399195) (xy 227.410155 -274.445708)
			(xy 227.433827 -274.496205) (xy 227.449895 -274.549612) (xy 227.458015 -274.604788) (xy 227.458524 -274.632674)
			(xy 227.458015 -274.66056) (xy 227.449895 -274.715736) (xy 227.433827 -274.769143) (xy 227.410155 -274.81964)
			(xy 227.379382 -274.866153) (xy 227.342165 -274.90769) (xy 227.299297 -274.943365) (xy 227.251691 -274.972419)
			(xy 227.200362 -274.994231) (xy 227.146405 -275.008337) (xy 227.090968 -275.014437) (xy 227.035234 -275.0124)
			(xy 226.980391 -275.00227) (xy 226.927607 -274.984263) (xy 226.878007 -274.958762) (xy 226.832649 -274.926311)
			(xy 226.7925 -274.887602) (xy 226.758414 -274.843459) (xy 226.731118 -274.794824) (xy 226.711195 -274.742733)
			(xy 226.699069 -274.688296) (xy 226.694998 -274.632674) (xy 220.270324 -274.632674) (xy 220.270324 -275.532456)
			(xy 223.168119 -275.532456) (xy 223.168119 -275.477944) (xy 223.175877 -275.423987) (xy 223.191235 -275.371684)
			(xy 223.21388 -275.322098) (xy 223.243352 -275.27624) (xy 223.27905 -275.235043) (xy 223.320248 -275.199346)
			(xy 223.366107 -275.169876) (xy 223.415693 -275.147231) (xy 223.467997 -275.131875) (xy 223.521954 -275.124118)
			(xy 223.54921 -275.123656) (xy 223.576581 -275.124103) (xy 223.630762 -275.131923) (xy 223.683265 -275.147416)
			(xy 223.733012 -275.170262) (xy 223.778977 -275.199992) (xy 223.799908 -275.217636) (xy 223.800162 -275.21789)
			(xy 223.807256 -275.223466) (xy 223.824167 -275.229719) (xy 223.833182 -275.230082) (xy 223.900238 -275.230082)
			(xy 223.909257 -275.229747) (xy 223.926174 -275.223485) (xy 223.933258 -275.21789) (xy 223.933258 -275.217636)
			(xy 223.933512 -275.217636) (xy 223.954471 -275.20003) (xy 224.000436 -275.170312) (xy 224.050176 -275.147469)
			(xy 224.102671 -275.13197) (xy 224.156843 -275.124134) (xy 224.18421 -275.123656) (xy 224.211458 -275.124215)
			(xy 224.2654 -275.131972) (xy 224.317688 -275.147326) (xy 224.367259 -275.169966) (xy 224.413104 -275.19943)
			(xy 224.454289 -275.235118) (xy 224.489976 -275.276304) (xy 224.519439 -275.322149) (xy 224.542077 -275.371721)
			(xy 224.55743 -275.42401) (xy 224.565186 -275.477952) (xy 224.565186 -275.532448) (xy 224.55743 -275.58639)
			(xy 224.542077 -275.638679) (xy 224.519439 -275.688251) (xy 224.489976 -275.734096) (xy 224.454289 -275.775282)
			(xy 224.413104 -275.81097) (xy 224.367259 -275.840434) (xy 224.317688 -275.863074) (xy 224.2654 -275.878428)
			(xy 224.211458 -275.886185) (xy 224.18421 -275.886672) (xy 224.15684 -275.886207) (xy 224.10266 -275.87839)
			(xy 224.050157 -275.862901) (xy 224.00041 -275.840059) (xy 223.954443 -275.810334) (xy 223.933512 -275.792692)
			(xy 223.933258 -275.792438) (xy 223.926164 -275.786862) (xy 223.909253 -275.780611) (xy 223.900238 -275.780246)
			(xy 223.833182 -275.780246) (xy 223.824163 -275.780584) (xy 223.807246 -275.786844) (xy 223.800162 -275.792438)
			(xy 223.800162 -275.792692) (xy 223.799908 -275.792692) (xy 223.778983 -275.81034) (xy 223.733008 -275.84005)
			(xy 223.683259 -275.862885) (xy 223.630757 -275.878374) (xy 223.57658 -275.886199) (xy 223.54921 -275.886672)
			(xy 223.521954 -275.886282) (xy 223.467997 -275.878525) (xy 223.415693 -275.863169) (xy 223.366107 -275.840524)
			(xy 223.320248 -275.811054) (xy 223.27905 -275.775357) (xy 223.243352 -275.73416) (xy 223.21388 -275.688302)
			(xy 223.191235 -275.638716) (xy 223.175877 -275.586413) (xy 223.168119 -275.532456) (xy 220.270324 -275.532456)
			(xy 220.270324 -276.150832) (xy 220.270728 -276.16035) (xy 220.277655 -276.178083) (xy 220.283786 -276.185376)
			(xy 220.33103 -276.236176) (xy 220.337719 -276.242719) (xy 220.354524 -276.250908) (xy 220.363796 -276.252178)
			(xy 220.36405 -276.252178) (xy 220.389666 -276.254626) (xy 220.439955 -276.265531) (xy 220.488326 -276.283085)
			(xy 220.533905 -276.30697) (xy 220.575867 -276.336754) (xy 220.594936 -276.354032) (xy 220.601794 -276.360636)
			(xy 220.619828 -276.367748) (xy 220.708728 -276.367748) (xy 220.726762 -276.360636) (xy 220.73362 -276.354032)
			(xy 220.754947 -276.334762) (xy 220.80231 -276.302197) (xy 220.854021 -276.277106) (xy 220.908912 -276.260056)
			(xy 220.965739 -276.251434) (xy 221.023217 -276.251434) (xy 221.080044 -276.260056) (xy 221.134935 -276.277106)
			(xy 221.186646 -276.302197) (xy 221.234009 -276.334762) (xy 221.255336 -276.354032) (xy 221.262194 -276.360636)
			(xy 221.280228 -276.367748) (xy 221.369128 -276.367748) (xy 221.387162 -276.360636) (xy 221.39402 -276.354032)
			(xy 221.415347 -276.334762) (xy 221.46271 -276.302197) (xy 221.514421 -276.277106) (xy 221.569312 -276.260056)
			(xy 221.626139 -276.251434) (xy 221.683617 -276.251434) (xy 221.740444 -276.260056) (xy 221.795335 -276.277106)
			(xy 221.847046 -276.302197) (xy 221.894409 -276.334762) (xy 221.915736 -276.354032) (xy 221.922594 -276.360636)
			(xy 221.940628 -276.367748) (xy 222.029528 -276.367748) (xy 222.047562 -276.360636) (xy 222.05442 -276.354032)
			(xy 222.075746 -276.33476) (xy 222.123108 -276.302191) (xy 222.174819 -276.277096) (xy 222.22971 -276.260042)
			(xy 222.286538 -276.251416) (xy 222.315278 -276.250908) (xy 222.342531 -276.25137) (xy 222.396484 -276.259124)
			(xy 222.448783 -276.274479) (xy 222.498365 -276.29712) (xy 222.54422 -276.326588) (xy 222.585414 -276.362282)
			(xy 222.591251 -276.369018) (xy 225.13493 -276.369018) (xy 225.139001 -276.313396) (xy 225.151127 -276.258959)
			(xy 225.17105 -276.206868) (xy 225.198346 -276.158233) (xy 225.232432 -276.11409) (xy 225.272581 -276.075381)
			(xy 225.317939 -276.04293) (xy 225.367539 -276.017429) (xy 225.420323 -275.999422) (xy 225.475166 -275.989292)
			(xy 225.5309 -275.987255) (xy 225.586337 -275.993355) (xy 225.640294 -276.007461) (xy 225.691623 -276.029273)
			(xy 225.739229 -276.058327) (xy 225.782097 -276.094002) (xy 225.819314 -276.135539) (xy 225.850087 -276.182052)
			(xy 225.873759 -276.232549) (xy 225.889827 -276.285956) (xy 225.897947 -276.341132) (xy 225.898456 -276.369018)
			(xy 225.897947 -276.396904) (xy 225.889827 -276.45208) (xy 225.873759 -276.505487) (xy 225.850087 -276.555984)
			(xy 225.819314 -276.602497) (xy 225.782097 -276.644034) (xy 225.739229 -276.679709) (xy 225.691623 -276.708763)
			(xy 225.640294 -276.730575) (xy 225.586337 -276.744681) (xy 225.5309 -276.750781) (xy 225.475166 -276.748744)
			(xy 225.420323 -276.738614) (xy 225.367539 -276.720607) (xy 225.317939 -276.695106) (xy 225.272581 -276.662655)
			(xy 225.232432 -276.623946) (xy 225.198346 -276.579803) (xy 225.17105 -276.531168) (xy 225.151127 -276.479077)
			(xy 225.139001 -276.42464) (xy 225.13493 -276.369018) (xy 222.591251 -276.369018) (xy 222.621109 -276.403475)
			(xy 222.650577 -276.449329) (xy 222.673219 -276.498911) (xy 222.688574 -276.55121) (xy 222.69633 -276.605163)
			(xy 222.696786 -276.632416) (xy 222.696313 -276.659786) (xy 222.688487 -276.713962) (xy 222.672998 -276.766464)
			(xy 222.650163 -276.816214) (xy 222.620453 -276.862188) (xy 222.602806 -276.883114) (xy 222.602806 -276.883368)
			(xy 222.602552 -276.883368) (xy 222.596958 -276.890452) (xy 222.590698 -276.907369) (xy 222.59036 -276.916388)
			(xy 222.59036 -276.983444) (xy 222.590726 -276.992458) (xy 222.59698 -277.009367) (xy 222.602552 -277.016464)
			(xy 222.602806 -277.016718) (xy 222.620447 -277.03765) (xy 222.65017 -277.083617) (xy 222.673011 -277.133364)
			(xy 222.688498 -277.185867) (xy 222.696314 -277.240046) (xy 222.696786 -277.267416) (xy 222.696322 -277.294668)
			(xy 222.688563 -277.348616) (xy 222.673205 -277.40091) (xy 222.650561 -277.450487) (xy 222.621092 -277.496336)
			(xy 222.585399 -277.537525) (xy 222.544206 -277.573215) (xy 222.498354 -277.60268) (xy 222.448775 -277.625318)
			(xy 222.396478 -277.640671) (xy 222.34253 -277.648424) (xy 222.315278 -277.648924) (xy 222.28654 -277.648401)
			(xy 222.229715 -277.639774) (xy 222.174828 -277.622719) (xy 222.123121 -277.597621) (xy 222.075765 -277.56505)
			(xy 222.05442 -277.5458) (xy 222.047562 -277.539196) (xy 222.029528 -277.532084) (xy 221.940628 -277.532084)
			(xy 221.922594 -277.539196) (xy 221.915736 -277.5458) (xy 221.894409 -277.56507) (xy 221.847046 -277.597635)
			(xy 221.795335 -277.622726) (xy 221.740444 -277.639776) (xy 221.683617 -277.648398) (xy 221.626139 -277.648398)
			(xy 221.569312 -277.639776) (xy 221.514421 -277.622726) (xy 221.46271 -277.597635) (xy 221.415347 -277.56507)
			(xy 221.39402 -277.5458) (xy 221.387162 -277.539196) (xy 221.369128 -277.532084) (xy 221.280228 -277.532084)
			(xy 221.262194 -277.539196) (xy 221.255336 -277.5458) (xy 221.234009 -277.56507) (xy 221.186646 -277.597635)
			(xy 221.134935 -277.622726) (xy 221.080044 -277.639776) (xy 221.023217 -277.648398) (xy 220.965739 -277.648398)
			(xy 220.908912 -277.639776) (xy 220.854021 -277.622726) (xy 220.80231 -277.597635) (xy 220.754947 -277.56507)
			(xy 220.73362 -277.5458) (xy 220.726762 -277.539196) (xy 220.708728 -277.532084) (xy 220.619828 -277.532084)
			(xy 220.601794 -277.539196) (xy 220.594936 -277.5458) (xy 220.575893 -277.563074) (xy 220.533996 -277.592874)
			(xy 220.488471 -277.616768) (xy 220.440146 -277.634321) (xy 220.389899 -277.645215) (xy 220.364304 -277.647654)
			(xy 220.363796 -277.647654) (xy 220.354495 -277.648813) (xy 220.337664 -277.657034) (xy 220.33103 -277.663656)
			(xy 220.283786 -277.714456) (xy 220.277606 -277.721716) (xy 220.2707 -277.739472) (xy 220.270324 -277.749)
			(xy 220.270324 -277.927308) (xy 220.269869 -277.960164) (xy 220.262522 -278.025463) (xy 220.24791 -278.089529)
			(xy 220.226217 -278.151557) (xy 220.197716 -278.210765) (xy 220.162765 -278.266411) (xy 220.121804 -278.317793)
			(xy 220.098874 -278.341328) (xy 218.339162 -280.10104) (xy 226.403406 -280.10104) (xy 226.407477 -280.045418)
			(xy 226.419603 -279.990981) (xy 226.439526 -279.93889) (xy 226.466822 -279.890255) (xy 226.500908 -279.846112)
			(xy 226.541057 -279.807403) (xy 226.586415 -279.774952) (xy 226.636015 -279.749451) (xy 226.688799 -279.731444)
			(xy 226.743642 -279.721314) (xy 226.799376 -279.719277) (xy 226.854813 -279.725377) (xy 226.90877 -279.739483)
			(xy 226.960099 -279.761295) (xy 227.007705 -279.790349) (xy 227.050573 -279.826024) (xy 227.08779 -279.867561)
			(xy 227.118563 -279.914074) (xy 227.142235 -279.964571) (xy 227.158303 -280.017978) (xy 227.166423 -280.073154)
			(xy 227.166932 -280.10104) (xy 227.166423 -280.128926) (xy 227.158303 -280.184102) (xy 227.142235 -280.237509)
			(xy 227.118563 -280.288006) (xy 227.08779 -280.334519) (xy 227.050573 -280.376056) (xy 227.007705 -280.411731)
			(xy 226.960099 -280.440785) (xy 226.90877 -280.462597) (xy 226.854813 -280.476703) (xy 226.799376 -280.482803)
			(xy 226.743642 -280.480766) (xy 226.688799 -280.470636) (xy 226.636015 -280.452629) (xy 226.586415 -280.427128)
			(xy 226.541057 -280.394677) (xy 226.500908 -280.355968) (xy 226.466822 -280.311825) (xy 226.439526 -280.26319)
			(xy 226.419603 -280.211099) (xy 226.407477 -280.156662) (xy 226.403406 -280.10104) (xy 218.339162 -280.10104)
			(xy 217.93962 -280.500582) (xy 228.815644 -280.500582) (xy 228.819715 -280.44496) (xy 228.831841 -280.390523)
			(xy 228.851764 -280.338432) (xy 228.87906 -280.289797) (xy 228.913146 -280.245654) (xy 228.953295 -280.206945)
			(xy 228.998653 -280.174494) (xy 229.048253 -280.148993) (xy 229.101037 -280.130986) (xy 229.15588 -280.120856)
			(xy 229.211614 -280.118819) (xy 229.267051 -280.124919) (xy 229.321008 -280.139025) (xy 229.372337 -280.160837)
			(xy 229.419943 -280.189891) (xy 229.462811 -280.225566) (xy 229.500028 -280.267103) (xy 229.530801 -280.313616)
			(xy 229.554473 -280.364113) (xy 229.570541 -280.41752) (xy 229.578661 -280.472696) (xy 229.57917 -280.500582)
			(xy 229.578661 -280.528468) (xy 229.570541 -280.583644) (xy 229.554473 -280.637051) (xy 229.530801 -280.687548)
			(xy 229.500028 -280.734061) (xy 229.462811 -280.775598) (xy 229.419943 -280.811273) (xy 229.372337 -280.840327)
			(xy 229.321008 -280.862139) (xy 229.267051 -280.876245) (xy 229.211614 -280.882345) (xy 229.15588 -280.880308)
			(xy 229.101037 -280.870178) (xy 229.048253 -280.852171) (xy 228.998653 -280.82667) (xy 228.953295 -280.794219)
			(xy 228.913146 -280.75551) (xy 228.87906 -280.711367) (xy 228.851764 -280.662732) (xy 228.831841 -280.610641)
			(xy 228.819715 -280.556204) (xy 228.815644 -280.500582) (xy 217.93962 -280.500582) (xy 217.097864 -281.342338)
			(xy 219.957142 -281.342338) (xy 219.957591 -281.315084) (xy 219.965344 -281.26113) (xy 219.980698 -281.208829)
			(xy 220.003339 -281.159245) (xy 220.032808 -281.11339) (xy 220.068504 -281.072195) (xy 220.109699 -281.036501)
			(xy 220.155556 -281.007034) (xy 220.20514 -280.984393) (xy 220.257441 -280.969041) (xy 220.311396 -280.96129)
			(xy 220.33865 -280.96083) (xy 220.367389 -280.961342) (xy 220.424216 -280.96997) (xy 220.479106 -280.987024)
			(xy 220.530818 -281.012118) (xy 220.578181 -281.044683) (xy 220.599508 -281.063954) (xy 220.606366 -281.070558)
			(xy 220.6244 -281.07767) (xy 220.7133 -281.07767) (xy 220.731334 -281.070558) (xy 220.738192 -281.063954)
			(xy 220.759519 -281.044684) (xy 220.806882 -281.012119) (xy 220.858593 -280.987028) (xy 220.913484 -280.969978)
			(xy 220.970311 -280.961356) (xy 221.027789 -280.961356) (xy 221.084616 -280.969978) (xy 221.139507 -280.987028)
			(xy 221.191218 -281.012119) (xy 221.238581 -281.044684) (xy 221.259908 -281.063954) (xy 221.266766 -281.070558)
			(xy 221.2848 -281.07767) (xy 221.3737 -281.07767) (xy 221.391734 -281.070558) (xy 221.398592 -281.063954)
			(xy 221.419901 -281.044662) (xy 221.467268 -281.012098) (xy 221.518984 -280.987009) (xy 221.573879 -280.969964)
			(xy 221.63071 -280.961347) (xy 221.65945 -280.96083) (xy 221.689572 -280.961438) (xy 221.749066 -280.970911)
			(xy 221.806334 -280.989613) (xy 221.859951 -281.017081) (xy 221.908588 -281.052631) (xy 221.930214 -281.073606)
			(xy 221.937615 -281.080445) (xy 221.956213 -281.088165) (xy 221.966282 -281.088592) (xy 222.038418 -281.088592)
			(xy 222.048489 -281.088178) (xy 222.067086 -281.08045) (xy 222.074486 -281.073606) (xy 222.096095 -281.052608)
			(xy 222.144728 -281.017042) (xy 222.198348 -280.989565) (xy 222.255622 -280.970861) (xy 222.315125 -280.961395)
			(xy 222.34525 -280.96083) (xy 222.372503 -280.961302) (xy 222.426456 -280.969053) (xy 222.478756 -280.984405)
			(xy 222.528338 -281.007044) (xy 222.574194 -281.03651) (xy 222.615388 -281.072204) (xy 222.651082 -281.113397)
			(xy 222.68055 -281.159251) (xy 222.703191 -281.208833) (xy 222.718544 -281.261132) (xy 222.726297 -281.315085)
			(xy 222.726758 -281.342338) (xy 222.726758 -281.342592) (xy 222.726286 -281.370304) (xy 222.718269 -281.425144)
			(xy 222.702388 -281.478243) (xy 222.678979 -281.528479) (xy 222.648536 -281.574793) (xy 222.630492 -281.59583)
			(xy 222.624581 -281.602997) (xy 222.617939 -281.62033) (xy 222.617538 -281.629612) (xy 222.617538 -281.70632)
			(xy 222.624396 -281.7241) (xy 222.630492 -281.730704) (xy 222.648552 -281.751802) (xy 222.679062 -281.798204)
			(xy 222.702529 -281.848536) (xy 222.718457 -281.901736) (xy 222.726509 -281.956683) (xy 222.727012 -281.98445)
			(xy 222.726498 -282.011701) (xy 222.718748 -282.06565) (xy 222.703399 -282.117947) (xy 222.680762 -282.167527)
			(xy 222.6513 -282.21338) (xy 222.615611 -282.254573) (xy 222.574423 -282.290267) (xy 222.528574 -282.319736)
			(xy 222.478998 -282.34238) (xy 222.426703 -282.357737) (xy 222.372755 -282.365494) (xy 222.345504 -282.365958)
			(xy 222.315381 -282.365383) (xy 222.255885 -282.355902) (xy 222.198617 -282.337192) (xy 222.145 -282.309718)
			(xy 222.096365 -282.27416) (xy 222.07474 -282.253182) (xy 222.067322 -282.246365) (xy 222.048736 -282.238632)
			(xy 222.038672 -282.238196) (xy 221.966536 -282.238196) (xy 221.956465 -282.238615) (xy 221.937866 -282.246337)
			(xy 221.930468 -282.253182) (xy 221.908833 -282.274152) (xy 221.860207 -282.309722) (xy 221.806594 -282.337204)
			(xy 221.749325 -282.355915) (xy 221.689828 -282.365389) (xy 221.659704 -282.365958) (xy 221.630966 -282.365416)
			(xy 221.57414 -282.356796) (xy 221.51925 -282.339749) (xy 221.467538 -282.314662) (xy 221.420174 -282.282102)
			(xy 221.398846 -282.262834) (xy 221.391988 -282.25623) (xy 221.373954 -282.249118) (xy 221.285054 -282.249118)
			(xy 221.26702 -282.25623) (xy 221.260162 -282.262834) (xy 221.238835 -282.282104) (xy 221.191472 -282.314669)
			(xy 221.139761 -282.33976) (xy 221.08487 -282.35681) (xy 221.028043 -282.365432) (xy 220.970565 -282.365432)
			(xy 220.913738 -282.35681) (xy 220.858847 -282.33976) (xy 220.807136 -282.314669) (xy 220.759773 -282.282104)
			(xy 220.738446 -282.262834) (xy 220.731588 -282.25623) (xy 220.713554 -282.249118) (xy 220.624654 -282.249118)
			(xy 220.60662 -282.25623) (xy 220.599762 -282.262834) (xy 220.578429 -282.282098) (xy 220.531069 -282.314666)
			(xy 220.479359 -282.339761) (xy 220.424469 -282.356813) (xy 220.367643 -282.365437) (xy 220.338904 -282.365958)
			(xy 220.311649 -282.365541) (xy 220.257694 -282.357783) (xy 220.205392 -282.342425) (xy 220.155809 -282.319779)
			(xy 220.109953 -282.290307) (xy 220.068759 -282.254608) (xy 220.033065 -282.21341) (xy 220.003599 -282.167551)
			(xy 219.980959 -282.117965) (xy 219.965607 -282.065661) (xy 219.957856 -282.011705) (xy 219.957396 -281.98445)
			(xy 219.957396 -281.984196) (xy 219.957872 -281.956485) (xy 219.96589 -281.901645) (xy 219.98177 -281.848547)
			(xy 220.005178 -281.79831) (xy 220.035619 -281.751996) (xy 220.053662 -281.730958) (xy 220.059585 -281.723799)
			(xy 220.066219 -281.70646) (xy 220.066616 -281.697176) (xy 220.066616 -281.620468) (xy 220.059758 -281.602688)
			(xy 220.053662 -281.596084) (xy 220.035589 -281.574997) (xy 220.005082 -281.528592) (xy 219.981619 -281.478257)
			(xy 219.965694 -281.425054) (xy 219.957644 -281.370105) (xy 219.957142 -281.342338) (xy 217.097864 -281.342338)
			(xy 215.430744 -283.009458) (xy 224.751517 -283.009458) (xy 224.751517 -282.954942) (xy 224.759276 -282.900982)
			(xy 224.774636 -282.848675) (xy 224.797284 -282.799087) (xy 224.826759 -282.753227) (xy 224.862462 -282.712029)
			(xy 224.903664 -282.676332) (xy 224.949527 -282.646862) (xy 224.999118 -282.62422) (xy 225.051427 -282.608866)
			(xy 225.105388 -282.601114) (xy 225.132646 -282.600654) (xy 225.161385 -282.601162) (xy 225.218213 -282.60979)
			(xy 225.273103 -282.626845) (xy 225.324815 -282.651939) (xy 225.372177 -282.684507) (xy 225.393504 -282.703778)
			(xy 225.400362 -282.710382) (xy 225.418396 -282.717494) (xy 225.507296 -282.717494) (xy 225.52533 -282.710382)
			(xy 225.532188 -282.703778) (xy 225.553515 -282.684508) (xy 225.600878 -282.651943) (xy 225.652589 -282.626852)
			(xy 225.70748 -282.609802) (xy 225.764307 -282.60118) (xy 225.821785 -282.60118) (xy 225.878612 -282.609802)
			(xy 225.933503 -282.626852) (xy 225.985214 -282.651943) (xy 226.032577 -282.684508) (xy 226.053904 -282.703778)
			(xy 226.060762 -282.710382) (xy 226.078796 -282.717494) (xy 226.167696 -282.717494) (xy 226.18573 -282.710382)
			(xy 226.192588 -282.703778) (xy 226.213902 -282.684492) (xy 226.261267 -282.651926) (xy 226.312982 -282.626836)
			(xy 226.367876 -282.609789) (xy 226.424706 -282.601172) (xy 226.453446 -282.600654) (xy 226.483568 -282.601258)
			(xy 226.543063 -282.610731) (xy 226.60033 -282.629434) (xy 226.653948 -282.656902) (xy 226.702584 -282.692454)
			(xy 226.72421 -282.71343) (xy 226.731609 -282.720271) (xy 226.750209 -282.727989) (xy 226.760278 -282.728416)
			(xy 226.832414 -282.728416) (xy 226.842487 -282.72802) (xy 226.861086 -282.720281) (xy 226.868482 -282.71343)
			(xy 226.890097 -282.692439) (xy 226.938728 -282.65687) (xy 226.992347 -282.629392) (xy 227.049619 -282.610687)
			(xy 227.109121 -282.60122) (xy 227.139246 -282.600654) (xy 227.166492 -282.601219) (xy 227.22043 -282.60898)
			(xy 227.272714 -282.624338) (xy 227.32228 -282.646979) (xy 227.36812 -282.676444) (xy 227.409301 -282.712132)
			(xy 227.444984 -282.753317) (xy 227.474443 -282.79916) (xy 227.497078 -282.84873) (xy 227.512429 -282.901015)
			(xy 227.520184 -282.954954) (xy 227.520184 -283.009446) (xy 227.512429 -283.063385) (xy 227.497078 -283.11567)
			(xy 227.474443 -283.16524) (xy 227.444984 -283.211083) (xy 227.409301 -283.252268) (xy 227.36812 -283.287956)
			(xy 227.32228 -283.317421) (xy 227.272714 -283.340062) (xy 227.22043 -283.35542) (xy 227.166492 -283.363181)
			(xy 227.139246 -283.36367) (xy 227.109124 -283.363065) (xy 227.04963 -283.353591) (xy 226.992362 -283.334888)
			(xy 226.938745 -283.30742) (xy 226.890108 -283.271869) (xy 226.868482 -283.250894) (xy 226.861083 -283.244053)
			(xy 226.842483 -283.236334) (xy 226.832414 -283.235908) (xy 226.760278 -283.235908) (xy 226.750207 -283.23632)
			(xy 226.731609 -283.24405) (xy 226.72421 -283.250894) (xy 226.702603 -283.271894) (xy 226.653969 -283.30746)
			(xy 226.600349 -283.334936) (xy 226.543074 -283.35364) (xy 226.483572 -283.363105) (xy 226.453446 -283.36367)
			(xy 226.424707 -283.36316) (xy 226.36788 -283.354532) (xy 226.312989 -283.337477) (xy 226.261278 -283.312383)
			(xy 226.213915 -283.279817) (xy 226.192588 -283.260546) (xy 226.18573 -283.253942) (xy 226.167696 -283.24683)
			(xy 226.078796 -283.24683) (xy 226.060762 -283.253942) (xy 226.053904 -283.260546) (xy 226.032577 -283.279816)
			(xy 225.985214 -283.312381) (xy 225.933503 -283.337472) (xy 225.878612 -283.354522) (xy 225.821785 -283.363144)
			(xy 225.764307 -283.363144) (xy 225.70748 -283.354522) (xy 225.652589 -283.337472) (xy 225.600878 -283.312381)
			(xy 225.553515 -283.279816) (xy 225.532188 -283.260546) (xy 225.52533 -283.253942) (xy 225.507296 -283.24683)
			(xy 225.418396 -283.24683) (xy 225.400362 -283.253942) (xy 225.393504 -283.260546) (xy 225.372197 -283.27984)
			(xy 225.32483 -283.312403) (xy 225.273113 -283.337492) (xy 225.218218 -283.354537) (xy 225.161386 -283.363153)
			(xy 225.132646 -283.36367) (xy 225.105388 -283.363286) (xy 225.051427 -283.355534) (xy 224.999118 -283.34018)
			(xy 224.949527 -283.317538) (xy 224.903664 -283.288068) (xy 224.862462 -283.252371) (xy 224.826759 -283.211173)
			(xy 224.797284 -283.165313) (xy 224.774636 -283.115725) (xy 224.759276 -283.063418) (xy 224.751517 -283.009458)
			(xy 215.430744 -283.009458) (xy 213.771456 -284.668746) (xy 220.945522 -284.668746) (xy 220.945522 -284.614254)
			(xy 220.953276 -284.560316) (xy 220.968628 -284.508031) (xy 220.991263 -284.458463) (xy 221.020722 -284.41262)
			(xy 221.056404 -284.371435) (xy 221.097584 -284.335748) (xy 221.143424 -284.306284) (xy 221.19299 -284.283643)
			(xy 221.245273 -284.268286) (xy 221.29921 -284.260525) (xy 221.326456 -284.260036) (xy 221.355195 -284.260543)
			(xy 221.412023 -284.269172) (xy 221.466913 -284.286227) (xy 221.518624 -284.311322) (xy 221.565987 -284.343889)
			(xy 221.587314 -284.36316) (xy 221.594172 -284.369764) (xy 221.612206 -284.376876) (xy 221.701106 -284.376876)
			(xy 221.71914 -284.369764) (xy 221.725998 -284.36316) (xy 221.747325 -284.34389) (xy 221.794688 -284.311325)
			(xy 221.846399 -284.286234) (xy 221.90129 -284.269184) (xy 221.958117 -284.260562) (xy 222.015595 -284.260562)
			(xy 222.072422 -284.269184) (xy 222.127313 -284.286234) (xy 222.179024 -284.311325) (xy 222.226387 -284.34389)
			(xy 222.247714 -284.36316) (xy 222.254572 -284.369764) (xy 222.272606 -284.376876) (xy 222.361506 -284.376876)
			(xy 222.37954 -284.369764) (xy 222.386398 -284.36316) (xy 222.407705 -284.343866) (xy 222.455072 -284.311302)
			(xy 222.506789 -284.286214) (xy 222.561684 -284.269169) (xy 222.618516 -284.260553) (xy 222.647256 -284.260036)
			(xy 222.677378 -284.260638) (xy 222.736873 -284.270112) (xy 222.79414 -284.288816) (xy 222.847758 -284.316285)
			(xy 222.896394 -284.351836) (xy 222.91802 -284.372812) (xy 222.925418 -284.379655) (xy 222.944019 -284.387372)
			(xy 222.954088 -284.387798) (xy 223.026224 -284.387798) (xy 223.036298 -284.387412) (xy 223.054897 -284.379667)
			(xy 223.062292 -284.372812) (xy 223.083899 -284.351813) (xy 223.132533 -284.316246) (xy 223.186153 -284.28877)
			(xy 223.243428 -284.270066) (xy 223.30293 -284.260601) (xy 223.333056 -284.260036) (xy 223.360314 -284.260408)
			(xy 223.414276 -284.268161) (xy 223.466585 -284.283515) (xy 223.516177 -284.306157) (xy 223.562041 -284.335628)
			(xy 223.603243 -284.371325) (xy 223.638946 -284.412524) (xy 223.668422 -284.458385) (xy 223.69107 -284.507973)
			(xy 223.70643 -284.560281) (xy 223.714189 -284.614242) (xy 223.714189 -284.668758) (xy 223.70643 -284.722719)
			(xy 223.69107 -284.775027) (xy 223.668422 -284.824615) (xy 223.638946 -284.870476) (xy 223.603243 -284.911675)
			(xy 223.562041 -284.947372) (xy 223.516177 -284.976843) (xy 223.466585 -284.999485) (xy 223.414276 -285.014839)
			(xy 223.360314 -285.022592) (xy 223.333056 -285.023052) (xy 223.302934 -285.022445) (xy 223.243439 -285.012973)
			(xy 223.186172 -284.99427) (xy 223.132554 -284.966802) (xy 223.083918 -284.931251) (xy 223.062292 -284.910276)
			(xy 223.054892 -284.903436) (xy 223.036293 -284.895717) (xy 223.026224 -284.89529) (xy 222.954088 -284.89529)
			(xy 222.944015 -284.895685) (xy 222.925416 -284.903425) (xy 222.91802 -284.910276) (xy 222.896406 -284.931268)
			(xy 222.847774 -284.966835) (xy 222.794155 -284.994314) (xy 222.736883 -285.013019) (xy 222.677381 -285.022486)
			(xy 222.647256 -285.023052) (xy 222.618517 -285.022541) (xy 222.561689 -285.013913) (xy 222.506799 -284.996859)
			(xy 222.455088 -284.971765) (xy 222.407725 -284.939199) (xy 222.386398 -284.919928) (xy 222.37954 -284.913324)
			(xy 222.361506 -284.906212) (xy 222.272606 -284.906212) (xy 222.254572 -284.913324) (xy 222.247714 -284.919928)
			(xy 222.226387 -284.939198) (xy 222.179024 -284.971763) (xy 222.127313 -284.996854) (xy 222.072422 -285.013904)
			(xy 222.015595 -285.022526) (xy 221.958117 -285.022526) (xy 221.90129 -285.013904) (xy 221.846399 -284.996854)
			(xy 221.794688 -284.971763) (xy 221.747325 -284.939198) (xy 221.725998 -284.919928) (xy 221.71914 -284.913324)
			(xy 221.701106 -284.906212) (xy 221.612206 -284.906212) (xy 221.594172 -284.913324) (xy 221.587314 -284.919928)
			(xy 221.566 -284.939214) (xy 221.518635 -284.971779) (xy 221.46692 -284.99687) (xy 221.412026 -285.013916)
			(xy 221.355196 -285.022534) (xy 221.326456 -285.023052) (xy 221.29921 -285.022475) (xy 221.245273 -285.014714)
			(xy 221.19299 -284.999357) (xy 221.143424 -284.976716) (xy 221.097584 -284.947252) (xy 221.056404 -284.911565)
			(xy 221.020722 -284.87038) (xy 220.991263 -284.824537) (xy 220.968628 -284.774969) (xy 220.953276 -284.722684)
			(xy 220.945522 -284.668746) (xy 213.771456 -284.668746) (xy 213.105746 -285.334456) (xy 213.098903 -285.341855)
			(xy 213.091182 -285.360454) (xy 213.09076 -285.370524) (xy 213.09076 -285.473258) (xy 224.751517 -285.473258)
			(xy 224.751517 -285.418742) (xy 224.759276 -285.364782) (xy 224.774636 -285.312475) (xy 224.797284 -285.262887)
			(xy 224.826759 -285.217027) (xy 224.862462 -285.175829) (xy 224.903664 -285.140132) (xy 224.949527 -285.110662)
			(xy 224.999118 -285.08802) (xy 225.051427 -285.072666) (xy 225.105388 -285.064914) (xy 225.132646 -285.064454)
			(xy 225.161385 -285.064962) (xy 225.218213 -285.07359) (xy 225.273103 -285.090645) (xy 225.324815 -285.115739)
			(xy 225.372177 -285.148307) (xy 225.393504 -285.167578) (xy 225.400362 -285.174182) (xy 225.418396 -285.181294)
			(xy 225.507296 -285.181294) (xy 225.52533 -285.174182) (xy 225.532188 -285.167578) (xy 225.553515 -285.148308)
			(xy 225.600878 -285.115743) (xy 225.652589 -285.090652) (xy 225.70748 -285.073602) (xy 225.764307 -285.06498)
			(xy 225.821785 -285.06498) (xy 225.878612 -285.073602) (xy 225.933503 -285.090652) (xy 225.985214 -285.115743)
			(xy 226.032577 -285.148308) (xy 226.053904 -285.167578) (xy 226.060762 -285.174182) (xy 226.078796 -285.181294)
			(xy 226.167696 -285.181294) (xy 226.18573 -285.174182) (xy 226.192588 -285.167578) (xy 226.213902 -285.148292)
			(xy 226.261267 -285.115726) (xy 226.312982 -285.090636) (xy 226.367876 -285.073589) (xy 226.424706 -285.064972)
			(xy 226.453446 -285.064454) (xy 226.483568 -285.065058) (xy 226.543063 -285.074531) (xy 226.60033 -285.093234)
			(xy 226.653948 -285.120702) (xy 226.702584 -285.156254) (xy 226.72421 -285.17723) (xy 226.731609 -285.184071)
			(xy 226.750209 -285.191789) (xy 226.760278 -285.192216) (xy 226.832414 -285.192216) (xy 226.842487 -285.19182)
			(xy 226.861086 -285.184081) (xy 226.868482 -285.17723) (xy 226.890097 -285.156239) (xy 226.938728 -285.12067)
			(xy 226.992347 -285.093192) (xy 227.049619 -285.074487) (xy 227.109121 -285.06502) (xy 227.139246 -285.064454)
			(xy 227.166492 -285.065019) (xy 227.22043 -285.07278) (xy 227.272714 -285.088138) (xy 227.32228 -285.110779)
			(xy 227.36812 -285.140244) (xy 227.409301 -285.175932) (xy 227.444984 -285.217117) (xy 227.474443 -285.26296)
			(xy 227.497078 -285.31253) (xy 227.512429 -285.364815) (xy 227.520184 -285.418754) (xy 227.520184 -285.473246)
			(xy 227.512429 -285.527185) (xy 227.497078 -285.57947) (xy 227.474443 -285.62904) (xy 227.444984 -285.674883)
			(xy 227.409301 -285.716068) (xy 227.36812 -285.751756) (xy 227.32228 -285.781221) (xy 227.272714 -285.803862)
			(xy 227.22043 -285.81922) (xy 227.166492 -285.826981) (xy 227.139246 -285.82747) (xy 227.109124 -285.826865)
			(xy 227.04963 -285.817391) (xy 226.992362 -285.798688) (xy 226.938745 -285.77122) (xy 226.890108 -285.735669)
			(xy 226.868482 -285.714694) (xy 226.861083 -285.707853) (xy 226.842483 -285.700134) (xy 226.832414 -285.699708)
			(xy 226.760278 -285.699708) (xy 226.750207 -285.70012) (xy 226.731609 -285.70785) (xy 226.72421 -285.714694)
			(xy 226.702603 -285.735694) (xy 226.653969 -285.77126) (xy 226.600349 -285.798736) (xy 226.543074 -285.81744)
			(xy 226.483572 -285.826905) (xy 226.453446 -285.82747) (xy 226.424707 -285.82696) (xy 226.36788 -285.818332)
			(xy 226.312989 -285.801277) (xy 226.261278 -285.776183) (xy 226.213915 -285.743617) (xy 226.192588 -285.724346)
			(xy 226.18573 -285.717742) (xy 226.167696 -285.71063) (xy 226.078796 -285.71063) (xy 226.060762 -285.717742)
			(xy 226.053904 -285.724346) (xy 226.032577 -285.743616) (xy 225.985214 -285.776181) (xy 225.933503 -285.801272)
			(xy 225.878612 -285.818322) (xy 225.821785 -285.826944) (xy 225.764307 -285.826944) (xy 225.70748 -285.818322)
			(xy 225.652589 -285.801272) (xy 225.600878 -285.776181) (xy 225.553515 -285.743616) (xy 225.532188 -285.724346)
			(xy 225.52533 -285.717742) (xy 225.507296 -285.71063) (xy 225.418396 -285.71063) (xy 225.400362 -285.717742)
			(xy 225.393504 -285.724346) (xy 225.372197 -285.74364) (xy 225.32483 -285.776203) (xy 225.273113 -285.801292)
			(xy 225.218218 -285.818337) (xy 225.161386 -285.826953) (xy 225.132646 -285.82747) (xy 225.105388 -285.827086)
			(xy 225.051427 -285.819334) (xy 224.999118 -285.80398) (xy 224.949527 -285.781338) (xy 224.903664 -285.751868)
			(xy 224.862462 -285.716171) (xy 224.826759 -285.674973) (xy 224.797284 -285.629113) (xy 224.774636 -285.579525)
			(xy 224.759276 -285.527218) (xy 224.751517 -285.473258) (xy 213.09076 -285.473258) (xy 213.09076 -287.132546)
			(xy 220.945522 -287.132546) (xy 220.945522 -287.078054) (xy 220.953276 -287.024116) (xy 220.968628 -286.971831)
			(xy 220.991263 -286.922263) (xy 221.020722 -286.87642) (xy 221.056404 -286.835235) (xy 221.097584 -286.799548)
			(xy 221.143424 -286.770084) (xy 221.19299 -286.747443) (xy 221.245273 -286.732086) (xy 221.29921 -286.724325)
			(xy 221.326456 -286.723836) (xy 221.355195 -286.724343) (xy 221.412023 -286.732972) (xy 221.466913 -286.750027)
			(xy 221.518624 -286.775122) (xy 221.565987 -286.807689) (xy 221.587314 -286.82696) (xy 221.594172 -286.833564)
			(xy 221.612206 -286.840676) (xy 221.701106 -286.840676) (xy 221.71914 -286.833564) (xy 221.725998 -286.82696)
			(xy 221.747325 -286.80769) (xy 221.794688 -286.775125) (xy 221.846399 -286.750034) (xy 221.90129 -286.732984)
			(xy 221.958117 -286.724362) (xy 222.015595 -286.724362) (xy 222.072422 -286.732984) (xy 222.127313 -286.750034)
			(xy 222.179024 -286.775125) (xy 222.226387 -286.80769) (xy 222.247714 -286.82696) (xy 222.254572 -286.833564)
			(xy 222.272606 -286.840676) (xy 222.361506 -286.840676) (xy 222.37954 -286.833564) (xy 222.386398 -286.82696)
			(xy 222.407705 -286.807666) (xy 222.455072 -286.775102) (xy 222.506789 -286.750014) (xy 222.561684 -286.732969)
			(xy 222.618516 -286.724353) (xy 222.647256 -286.723836) (xy 222.677378 -286.724438) (xy 222.736873 -286.733912)
			(xy 222.79414 -286.752616) (xy 222.847758 -286.780085) (xy 222.896394 -286.815636) (xy 222.91802 -286.836612)
			(xy 222.925418 -286.843455) (xy 222.944019 -286.851172) (xy 222.954088 -286.851598) (xy 223.026224 -286.851598)
			(xy 223.036298 -286.851212) (xy 223.054897 -286.843467) (xy 223.062292 -286.836612) (xy 223.083899 -286.815613)
			(xy 223.132533 -286.780046) (xy 223.186153 -286.75257) (xy 223.243428 -286.733866) (xy 223.30293 -286.724401)
			(xy 223.333056 -286.723836) (xy 223.360314 -286.724208) (xy 223.414276 -286.731961) (xy 223.466585 -286.747315)
			(xy 223.516177 -286.769957) (xy 223.562041 -286.799428) (xy 223.603243 -286.835125) (xy 223.638946 -286.876324)
			(xy 223.668422 -286.922185) (xy 223.69107 -286.971773) (xy 223.70643 -287.024081) (xy 223.714189 -287.078042)
			(xy 223.714189 -287.132558) (xy 223.70643 -287.186519) (xy 223.69107 -287.238827) (xy 223.668422 -287.288415)
			(xy 223.638946 -287.334276) (xy 223.603243 -287.375475) (xy 223.562041 -287.411172) (xy 223.516177 -287.440643)
			(xy 223.466585 -287.463285) (xy 223.414276 -287.478639) (xy 223.360314 -287.486392) (xy 223.333056 -287.486852)
			(xy 223.302934 -287.486245) (xy 223.243439 -287.476773) (xy 223.186172 -287.45807) (xy 223.132554 -287.430602)
			(xy 223.083918 -287.395051) (xy 223.062292 -287.374076) (xy 223.054892 -287.367236) (xy 223.036293 -287.359517)
			(xy 223.026224 -287.35909) (xy 222.954088 -287.35909) (xy 222.944015 -287.359485) (xy 222.925416 -287.367225)
			(xy 222.91802 -287.374076) (xy 222.896406 -287.395068) (xy 222.847774 -287.430635) (xy 222.794155 -287.458114)
			(xy 222.736883 -287.476819) (xy 222.677381 -287.486286) (xy 222.647256 -287.486852) (xy 222.618517 -287.486341)
			(xy 222.561689 -287.477713) (xy 222.506799 -287.460659) (xy 222.455088 -287.435565) (xy 222.407725 -287.402999)
			(xy 222.386398 -287.383728) (xy 222.37954 -287.377124) (xy 222.361506 -287.370012) (xy 222.272606 -287.370012)
			(xy 222.254572 -287.377124) (xy 222.247714 -287.383728) (xy 222.226387 -287.402998) (xy 222.179024 -287.435563)
			(xy 222.127313 -287.460654) (xy 222.072422 -287.477704) (xy 222.015595 -287.486326) (xy 221.958117 -287.486326)
			(xy 221.90129 -287.477704) (xy 221.846399 -287.460654) (xy 221.794688 -287.435563) (xy 221.747325 -287.402998)
			(xy 221.725998 -287.383728) (xy 221.71914 -287.377124) (xy 221.701106 -287.370012) (xy 221.612206 -287.370012)
			(xy 221.594172 -287.377124) (xy 221.587314 -287.383728) (xy 221.566 -287.403014) (xy 221.518635 -287.435579)
			(xy 221.46692 -287.46067) (xy 221.412026 -287.477716) (xy 221.355196 -287.486334) (xy 221.326456 -287.486852)
			(xy 221.29921 -287.486275) (xy 221.245273 -287.478514) (xy 221.19299 -287.463157) (xy 221.143424 -287.440516)
			(xy 221.097584 -287.411052) (xy 221.056404 -287.375365) (xy 221.020722 -287.33418) (xy 220.991263 -287.288337)
			(xy 220.968628 -287.238769) (xy 220.953276 -287.186484) (xy 220.945522 -287.132546) (xy 213.09076 -287.132546)
			(xy 213.09076 -287.77625) (xy 226.333058 -287.77625) (xy 226.333058 -287.72175) (xy 226.340813 -287.667803)
			(xy 226.356167 -287.61551) (xy 226.378805 -287.565933) (xy 226.408269 -287.520083) (xy 226.443957 -287.478892)
			(xy 226.485143 -287.443199) (xy 226.530989 -287.413729) (xy 226.580563 -287.391084) (xy 226.632855 -287.375724)
			(xy 226.6868 -287.367961) (xy 226.71405 -287.367472) (xy 226.744172 -287.368068) (xy 226.803668 -287.377542)
			(xy 226.860936 -287.396247) (xy 226.914553 -287.423717) (xy 226.963188 -287.459271) (xy 226.984814 -287.480248)
			(xy 226.992221 -287.487079) (xy 227.010815 -287.494806) (xy 227.020882 -287.495234) (xy 227.093018 -287.495234)
			(xy 227.103091 -287.494836) (xy 227.121689 -287.487098) (xy 227.129086 -287.480248) (xy 227.150702 -287.459258)
			(xy 227.199332 -287.423689) (xy 227.252951 -287.39621) (xy 227.310223 -287.377504) (xy 227.369725 -287.368037)
			(xy 227.39985 -287.367472) (xy 227.427104 -287.367972) (xy 227.481057 -287.375723) (xy 227.533358 -287.391074)
			(xy 227.582942 -287.413712) (xy 227.628799 -287.443177) (xy 227.669996 -287.478869) (xy 227.705693 -287.520061)
			(xy 227.735164 -287.565914) (xy 227.757809 -287.615495) (xy 227.773167 -287.667794) (xy 227.780925 -287.721746)
			(xy 227.780925 -287.776254) (xy 227.773167 -287.830206) (xy 227.757809 -287.882505) (xy 227.735164 -287.932086)
			(xy 227.705693 -287.977939) (xy 227.669996 -288.019131) (xy 227.628799 -288.054823) (xy 227.582942 -288.084288)
			(xy 227.533358 -288.106926) (xy 227.481057 -288.122277) (xy 227.427104 -288.130028) (xy 227.39985 -288.130488)
			(xy 227.369727 -288.129903) (xy 227.31023 -288.120428) (xy 227.252962 -288.101722) (xy 227.199345 -288.074248)
			(xy 227.150711 -288.038691) (xy 227.129086 -288.017712) (xy 227.121684 -288.010875) (xy 227.103086 -288.003153)
			(xy 227.093018 -288.002726) (xy 227.020882 -288.002726) (xy 227.010811 -288.003135) (xy 226.992213 -288.010867)
			(xy 226.984814 -288.017712) (xy 226.963208 -288.038713) (xy 226.914574 -288.074278) (xy 226.860953 -288.101754)
			(xy 226.803678 -288.120457) (xy 226.744176 -288.129923) (xy 226.71405 -288.130488) (xy 226.6868 -288.130039)
			(xy 226.632855 -288.122276) (xy 226.580563 -288.106916) (xy 226.530989 -288.084271) (xy 226.485143 -288.054801)
			(xy 226.443957 -288.019108) (xy 226.408269 -287.977917) (xy 226.378805 -287.932067) (xy 226.356167 -287.88249)
			(xy 226.340813 -287.830197) (xy 226.333058 -287.77625) (xy 213.09076 -287.77625) (xy 213.09076 -288.652204)
			(xy 227.780594 -288.652204) (xy 227.784665 -288.596582) (xy 227.796791 -288.542145) (xy 227.816714 -288.490054)
			(xy 227.84401 -288.441419) (xy 227.878096 -288.397276) (xy 227.918245 -288.358567) (xy 227.963603 -288.326116)
			(xy 228.013203 -288.300615) (xy 228.065987 -288.282608) (xy 228.12083 -288.272478) (xy 228.176564 -288.270441)
			(xy 228.232001 -288.276541) (xy 228.285958 -288.290647) (xy 228.337287 -288.312459) (xy 228.384893 -288.341513)
			(xy 228.427761 -288.377188) (xy 228.464978 -288.418725) (xy 228.495751 -288.465238) (xy 228.519423 -288.515735)
			(xy 228.535491 -288.569142) (xy 228.543611 -288.624318) (xy 228.54412 -288.652204) (xy 228.543611 -288.68009)
			(xy 228.535491 -288.735266) (xy 228.519423 -288.788673) (xy 228.495751 -288.83917) (xy 228.464978 -288.885683)
			(xy 228.427761 -288.92722) (xy 228.384893 -288.962895) (xy 228.337287 -288.991949) (xy 228.285958 -289.013761)
			(xy 228.232001 -289.027867) (xy 228.176564 -289.033967) (xy 228.12083 -289.03193) (xy 228.065987 -289.0218)
			(xy 228.013203 -289.003793) (xy 227.963603 -288.978292) (xy 227.918245 -288.945841) (xy 227.878096 -288.907132)
			(xy 227.84401 -288.862989) (xy 227.816714 -288.814354) (xy 227.796791 -288.762263) (xy 227.784665 -288.707826)
			(xy 227.780594 -288.652204) (xy 213.09076 -288.652204) (xy 213.09076 -289.418546) (xy 220.259722 -289.418546)
			(xy 220.259722 -289.364054) (xy 220.267476 -289.310116) (xy 220.282828 -289.257831) (xy 220.305463 -289.208263)
			(xy 220.334922 -289.16242) (xy 220.370604 -289.121235) (xy 220.411784 -289.085548) (xy 220.457624 -289.056084)
			(xy 220.50719 -289.033443) (xy 220.559473 -289.018086) (xy 220.61341 -289.010325) (xy 220.640656 -289.009836)
			(xy 220.670778 -289.010438) (xy 220.730273 -289.019912) (xy 220.78754 -289.038616) (xy 220.841158 -289.066085)
			(xy 220.889794 -289.101636) (xy 220.91142 -289.122612) (xy 220.918818 -289.129455) (xy 220.937419 -289.137172)
			(xy 220.947488 -289.137598) (xy 221.019624 -289.137598) (xy 221.029698 -289.137212) (xy 221.048297 -289.129467)
			(xy 221.055692 -289.122612) (xy 221.077299 -289.101613) (xy 221.125933 -289.066046) (xy 221.179553 -289.03857)
			(xy 221.236828 -289.019866) (xy 221.29633 -289.010401) (xy 221.326456 -289.009836) (xy 221.353714 -289.010208)
			(xy 221.407676 -289.017961) (xy 221.459985 -289.033315) (xy 221.509577 -289.055957) (xy 221.555441 -289.085428)
			(xy 221.596643 -289.121125) (xy 221.632346 -289.162324) (xy 221.661822 -289.208185) (xy 221.68447 -289.257773)
			(xy 221.69983 -289.310081) (xy 221.707589 -289.364042) (xy 221.707589 -289.418558) (xy 221.69983 -289.472519)
			(xy 221.68447 -289.524827) (xy 221.661822 -289.574415) (xy 221.632346 -289.620276) (xy 221.596643 -289.661475)
			(xy 221.555441 -289.697172) (xy 221.509577 -289.726643) (xy 221.459985 -289.749285) (xy 221.407676 -289.764639)
			(xy 221.353714 -289.772392) (xy 221.326456 -289.772852) (xy 221.296334 -289.772245) (xy 221.236839 -289.762773)
			(xy 221.179572 -289.74407) (xy 221.125954 -289.716602) (xy 221.077318 -289.681051) (xy 221.055692 -289.660076)
			(xy 221.048292 -289.653236) (xy 221.029693 -289.645517) (xy 221.019624 -289.64509) (xy 220.947488 -289.64509)
			(xy 220.937415 -289.645485) (xy 220.918816 -289.653225) (xy 220.91142 -289.660076) (xy 220.889806 -289.681068)
			(xy 220.841174 -289.716635) (xy 220.787555 -289.744114) (xy 220.730283 -289.762819) (xy 220.670781 -289.772286)
			(xy 220.640656 -289.772852) (xy 220.61341 -289.772275) (xy 220.559473 -289.764514) (xy 220.50719 -289.749157)
			(xy 220.457624 -289.726516) (xy 220.411784 -289.697052) (xy 220.370604 -289.661365) (xy 220.334922 -289.62018)
			(xy 220.305463 -289.574337) (xy 220.282828 -289.524769) (xy 220.267476 -289.472484) (xy 220.259722 -289.418546)
			(xy 213.09076 -289.418546) (xy 213.09076 -290.900153) (xy 227.087881 -290.900153) (xy 227.087881 -290.845647)
			(xy 227.095639 -290.791697) (xy 227.110996 -290.739399) (xy 227.133639 -290.68982) (xy 227.163109 -290.643968)
			(xy 227.198804 -290.602777) (xy 227.239999 -290.567086) (xy 227.285853 -290.537621) (xy 227.335435 -290.514982)
			(xy 227.387734 -290.499631) (xy 227.441685 -290.491879) (xy 227.468938 -290.491418) (xy 227.496307 -290.491916)
			(xy 227.550485 -290.499725) (xy 227.602988 -290.515207) (xy 227.652735 -290.538042) (xy 227.698703 -290.56776)
			(xy 227.719636 -290.585398) (xy 227.71989 -290.585652) (xy 227.726971 -290.591247) (xy 227.743892 -290.597487)
			(xy 227.75291 -290.597844) (xy 227.819966 -290.597844) (xy 227.828983 -290.597483) (xy 227.8459 -290.59124)
			(xy 227.852986 -290.585652) (xy 227.852986 -290.585398) (xy 227.85324 -290.585398) (xy 227.874184 -290.567773)
			(xy 227.920153 -290.538059) (xy 227.969898 -290.515221) (xy 228.022396 -290.499726) (xy 228.07657 -290.491894)
			(xy 228.103938 -290.491418) (xy 228.131189 -290.491854) (xy 228.185137 -290.499616) (xy 228.23743 -290.514975)
			(xy 228.287006 -290.53762) (xy 228.332855 -290.56709) (xy 228.374043 -290.602783) (xy 228.409733 -290.643976)
			(xy 228.439198 -290.689827) (xy 228.461838 -290.739405) (xy 228.477192 -290.791701) (xy 228.484948 -290.845649)
			(xy 228.484948 -290.900151) (xy 228.477192 -290.954099) (xy 228.461838 -291.006395) (xy 228.439198 -291.055973)
			(xy 228.409733 -291.101824) (xy 228.374043 -291.143017) (xy 228.332855 -291.17871) (xy 228.287006 -291.20818)
			(xy 228.23743 -291.230825) (xy 228.185137 -291.246184) (xy 228.131189 -291.253946) (xy 228.103938 -291.254434)
			(xy 228.076568 -291.253962) (xy 228.022388 -291.246148) (xy 227.969885 -291.230661) (xy 227.920138 -291.20782)
			(xy 227.874171 -291.178096) (xy 227.85324 -291.160454) (xy 227.852986 -291.1602) (xy 227.845908 -291.154601)
			(xy 227.828985 -291.148362) (xy 227.819966 -291.148008) (xy 227.75291 -291.148008) (xy 227.743893 -291.148368)
			(xy 227.726976 -291.154613) (xy 227.71989 -291.1602) (xy 227.71989 -291.160454) (xy 227.719636 -291.160454)
			(xy 227.698695 -291.178083) (xy 227.652726 -291.207798) (xy 227.60298 -291.230636) (xy 227.550481 -291.24613)
			(xy 227.496307 -291.253959) (xy 227.468938 -291.254434) (xy 227.441685 -291.253921) (xy 227.387734 -291.246169)
			(xy 227.335435 -291.230818) (xy 227.285853 -291.208179) (xy 227.239999 -291.178714) (xy 227.198804 -291.143023)
			(xy 227.163109 -291.101832) (xy 227.133639 -291.05598) (xy 227.110996 -291.006401) (xy 227.095639 -290.954103)
			(xy 227.087881 -290.900153) (xy 213.09076 -290.900153) (xy 213.09076 -291.639549) (xy 220.096598 -291.639549)
			(xy 220.096598 -291.585051) (xy 220.104354 -291.531107) (xy 220.119708 -291.478816) (xy 220.142347 -291.429242)
			(xy 220.17181 -291.383395) (xy 220.207499 -291.342207) (xy 220.248685 -291.306518) (xy 220.294532 -291.277052)
			(xy 220.344105 -291.254412) (xy 220.396395 -291.239057) (xy 220.450339 -291.231299) (xy 220.477588 -291.230812)
			(xy 220.504958 -291.231282) (xy 220.559137 -291.239099) (xy 220.61164 -291.254587) (xy 220.661387 -291.277427)
			(xy 220.707354 -291.307151) (xy 220.728286 -291.324792) (xy 220.72854 -291.325046) (xy 220.735636 -291.330619)
			(xy 220.752546 -291.336873) (xy 220.76156 -291.337238) (xy 220.828616 -291.337238) (xy 220.837633 -291.336881)
			(xy 220.854549 -291.330632) (xy 220.861636 -291.325046) (xy 220.861636 -291.324792) (xy 220.86189 -291.324792)
			(xy 220.882814 -291.307143) (xy 220.928789 -291.277433) (xy 220.978539 -291.254599) (xy 221.031041 -291.23911)
			(xy 221.085218 -291.231285) (xy 221.112588 -291.230812) (xy 221.139843 -291.231234) (xy 221.193798 -291.23899)
			(xy 221.2461 -291.254346) (xy 221.295684 -291.276989) (xy 221.341541 -291.306458) (xy 221.382738 -291.342154)
			(xy 221.418435 -291.383349) (xy 221.447905 -291.429205) (xy 221.47055 -291.478789) (xy 221.485907 -291.53109)
			(xy 221.493665 -291.585045) (xy 221.493665 -291.639555) (xy 221.485907 -291.69351) (xy 221.47055 -291.745811)
			(xy 221.447905 -291.795395) (xy 221.418435 -291.841251) (xy 221.382738 -291.882446) (xy 221.341541 -291.918142)
			(xy 221.295684 -291.947611) (xy 221.2461 -291.970254) (xy 221.193798 -291.98561) (xy 221.139843 -291.993366)
			(xy 221.112588 -291.993828) (xy 221.085217 -291.993387) (xy 221.031036 -291.985565) (xy 220.978532 -291.970072)
			(xy 220.928785 -291.947224) (xy 220.88282 -291.917493) (xy 220.86189 -291.899848) (xy 220.861636 -291.899594)
			(xy 220.854544 -291.894016) (xy 220.837631 -291.887764) (xy 220.828616 -291.887402) (xy 220.76156 -291.887402)
			(xy 220.752541 -291.88774) (xy 220.735624 -291.894001) (xy 220.72854 -291.899594) (xy 220.72854 -291.899848)
			(xy 220.728286 -291.899848) (xy 220.707326 -291.917452) (xy 220.661361 -291.947171) (xy 220.611621 -291.970015)
			(xy 220.559126 -291.985514) (xy 220.504955 -291.99335) (xy 220.477588 -291.993828) (xy 220.450339 -291.993301)
			(xy 220.396395 -291.985543) (xy 220.344105 -291.970188) (xy 220.294532 -291.947548) (xy 220.248685 -291.918082)
			(xy 220.207499 -291.882393) (xy 220.17181 -291.841205) (xy 220.142347 -291.795358) (xy 220.119708 -291.745784)
			(xy 220.104354 -291.693493) (xy 220.096598 -291.639549) (xy 213.09076 -291.639549) (xy 213.09076 -306.744116)
			(xy 221.949516 -306.744116) (xy 221.953587 -306.688494) (xy 221.965713 -306.634057) (xy 221.985636 -306.581966)
			(xy 222.012932 -306.533331) (xy 222.047018 -306.489188) (xy 222.087167 -306.450479) (xy 222.132525 -306.418028)
			(xy 222.182125 -306.392527) (xy 222.234909 -306.37452) (xy 222.289752 -306.36439) (xy 222.345486 -306.362353)
			(xy 222.400923 -306.368453) (xy 222.45488 -306.382559) (xy 222.506209 -306.404371) (xy 222.553815 -306.433425)
			(xy 222.596683 -306.4691) (xy 222.6339 -306.510637) (xy 222.664673 -306.55715) (xy 222.688345 -306.607647)
			(xy 222.704413 -306.661054) (xy 222.712533 -306.71623) (xy 222.713042 -306.744116) (xy 222.712533 -306.772002)
			(xy 222.71032 -306.787042) (xy 229.223568 -306.787042) (xy 229.227639 -306.73142) (xy 229.239765 -306.676983)
			(xy 229.259688 -306.624892) (xy 229.286984 -306.576257) (xy 229.32107 -306.532114) (xy 229.361219 -306.493405)
			(xy 229.406577 -306.460954) (xy 229.456177 -306.435453) (xy 229.508961 -306.417446) (xy 229.563804 -306.407316)
			(xy 229.619538 -306.405279) (xy 229.674975 -306.411379) (xy 229.728932 -306.425485) (xy 229.780261 -306.447297)
			(xy 229.827867 -306.476351) (xy 229.870735 -306.512026) (xy 229.907952 -306.553563) (xy 229.938725 -306.600076)
			(xy 229.962397 -306.650573) (xy 229.978465 -306.70398) (xy 229.986585 -306.759156) (xy 229.987094 -306.787042)
			(xy 229.986585 -306.814928) (xy 229.978465 -306.870104) (xy 229.962397 -306.923511) (xy 229.938725 -306.974008)
			(xy 229.907952 -307.020521) (xy 229.870735 -307.062058) (xy 229.827867 -307.097733) (xy 229.780261 -307.126787)
			(xy 229.728932 -307.148599) (xy 229.674975 -307.162705) (xy 229.619538 -307.168805) (xy 229.563804 -307.166768)
			(xy 229.508961 -307.156638) (xy 229.456177 -307.138631) (xy 229.406577 -307.11313) (xy 229.361219 -307.080679)
			(xy 229.32107 -307.04197) (xy 229.286984 -306.997827) (xy 229.259688 -306.949192) (xy 229.239765 -306.897101)
			(xy 229.227639 -306.842664) (xy 229.223568 -306.787042) (xy 222.71032 -306.787042) (xy 222.704413 -306.827178)
			(xy 222.688345 -306.880585) (xy 222.664673 -306.931082) (xy 222.6339 -306.977595) (xy 222.596683 -307.019132)
			(xy 222.553815 -307.054807) (xy 222.506209 -307.083861) (xy 222.45488 -307.105673) (xy 222.400923 -307.119779)
			(xy 222.345486 -307.125879) (xy 222.289752 -307.123842) (xy 222.234909 -307.113712) (xy 222.182125 -307.095705)
			(xy 222.132525 -307.070204) (xy 222.087167 -307.037753) (xy 222.047018 -306.999044) (xy 222.012932 -306.954901)
			(xy 221.985636 -306.906266) (xy 221.965713 -306.854175) (xy 221.953587 -306.799738) (xy 221.949516 -306.744116)
			(xy 213.09076 -306.744116) (xy 213.09076 -307.446426) (xy 226.875084 -307.446426) (xy 226.879155 -307.390804)
			(xy 226.891281 -307.336367) (xy 226.911204 -307.284276) (xy 226.9385 -307.235641) (xy 226.972586 -307.191498)
			(xy 227.012735 -307.152789) (xy 227.058093 -307.120338) (xy 227.107693 -307.094837) (xy 227.160477 -307.07683)
			(xy 227.21532 -307.0667) (xy 227.271054 -307.064663) (xy 227.326491 -307.070763) (xy 227.380448 -307.084869)
			(xy 227.431777 -307.106681) (xy 227.479383 -307.135735) (xy 227.522251 -307.17141) (xy 227.559468 -307.212947)
			(xy 227.590241 -307.25946) (xy 227.613913 -307.309957) (xy 227.629981 -307.363364) (xy 227.638101 -307.41854)
			(xy 227.63861 -307.446426) (xy 227.638101 -307.474312) (xy 227.629981 -307.529488) (xy 227.613913 -307.582895)
			(xy 227.590241 -307.633392) (xy 227.559468 -307.679905) (xy 227.522251 -307.721442) (xy 227.479383 -307.757117)
			(xy 227.431777 -307.786171) (xy 227.380448 -307.807983) (xy 227.326491 -307.822089) (xy 227.271054 -307.828189)
			(xy 227.21532 -307.826152) (xy 227.160477 -307.816022) (xy 227.107693 -307.798015) (xy 227.058093 -307.772514)
			(xy 227.012735 -307.740063) (xy 226.972586 -307.701354) (xy 226.9385 -307.657211) (xy 226.911204 -307.608576)
			(xy 226.891281 -307.556485) (xy 226.879155 -307.502048) (xy 226.875084 -307.446426) (xy 213.09076 -307.446426)
			(xy 213.09076 -308.402228) (xy 227.932994 -308.402228) (xy 227.937065 -308.346606) (xy 227.949191 -308.292169)
			(xy 227.969114 -308.240078) (xy 227.99641 -308.191443) (xy 228.030496 -308.1473) (xy 228.070645 -308.108591)
			(xy 228.116003 -308.07614) (xy 228.165603 -308.050639) (xy 228.218387 -308.032632) (xy 228.27323 -308.022502)
			(xy 228.328964 -308.020465) (xy 228.384401 -308.026565) (xy 228.438358 -308.040671) (xy 228.489687 -308.062483)
			(xy 228.537293 -308.091537) (xy 228.580161 -308.127212) (xy 228.617378 -308.168749) (xy 228.648151 -308.215262)
			(xy 228.671823 -308.265759) (xy 228.687891 -308.319166) (xy 228.696011 -308.374342) (xy 228.69652 -308.402228)
			(xy 228.696011 -308.430114) (xy 228.687891 -308.48529) (xy 228.671823 -308.538697) (xy 228.648151 -308.589194)
			(xy 228.617378 -308.635707) (xy 228.580161 -308.677244) (xy 228.537293 -308.712919) (xy 228.489687 -308.741973)
			(xy 228.438358 -308.763785) (xy 228.384401 -308.777891) (xy 228.328964 -308.783991) (xy 228.27323 -308.781954)
			(xy 228.218387 -308.771824) (xy 228.165603 -308.753817) (xy 228.116003 -308.728316) (xy 228.070645 -308.695865)
			(xy 228.030496 -308.657156) (xy 227.99641 -308.613013) (xy 227.969114 -308.564378) (xy 227.949191 -308.512287)
			(xy 227.937065 -308.45785) (xy 227.932994 -308.402228) (xy 213.09076 -308.402228) (xy 213.09076 -309.018178)
			(xy 229.941118 -309.018178) (xy 229.945189 -308.962556) (xy 229.957315 -308.908119) (xy 229.977238 -308.856028)
			(xy 230.004534 -308.807393) (xy 230.03862 -308.76325) (xy 230.078769 -308.724541) (xy 230.124127 -308.69209)
			(xy 230.173727 -308.666589) (xy 230.226511 -308.648582) (xy 230.281354 -308.638452) (xy 230.337088 -308.636415)
			(xy 230.392525 -308.642515) (xy 230.446482 -308.656621) (xy 230.497811 -308.678433) (xy 230.545417 -308.707487)
			(xy 230.588285 -308.743162) (xy 230.625502 -308.784699) (xy 230.656275 -308.831212) (xy 230.679947 -308.881709)
			(xy 230.696015 -308.935116) (xy 230.704135 -308.990292) (xy 230.704644 -309.018178) (xy 230.704135 -309.046064)
			(xy 230.696015 -309.10124) (xy 230.679947 -309.154647) (xy 230.656275 -309.205144) (xy 230.625502 -309.251657)
			(xy 230.588285 -309.293194) (xy 230.545417 -309.328869) (xy 230.497811 -309.357923) (xy 230.446482 -309.379735)
			(xy 230.392525 -309.393841) (xy 230.337088 -309.399941) (xy 230.281354 -309.397904) (xy 230.226511 -309.387774)
			(xy 230.173727 -309.369767) (xy 230.124127 -309.344266) (xy 230.078769 -309.311815) (xy 230.03862 -309.273106)
			(xy 230.004534 -309.228963) (xy 229.977238 -309.180328) (xy 229.957315 -309.128237) (xy 229.945189 -309.0738)
			(xy 229.941118 -309.018178) (xy 213.09076 -309.018178) (xy 213.09076 -309.908448) (xy 226.32111 -309.908448)
			(xy 226.325181 -309.852826) (xy 226.337307 -309.798389) (xy 226.35723 -309.746298) (xy 226.384526 -309.697663)
			(xy 226.418612 -309.65352) (xy 226.458761 -309.614811) (xy 226.504119 -309.58236) (xy 226.553719 -309.556859)
			(xy 226.606503 -309.538852) (xy 226.661346 -309.528722) (xy 226.71708 -309.526685) (xy 226.772517 -309.532785)
			(xy 226.826474 -309.546891) (xy 226.877803 -309.568703) (xy 226.925409 -309.597757) (xy 226.968277 -309.633432)
			(xy 227.005494 -309.674969) (xy 227.036267 -309.721482) (xy 227.047351 -309.745126) (xy 228.036626 -309.745126)
			(xy 228.040697 -309.689504) (xy 228.052823 -309.635067) (xy 228.072746 -309.582976) (xy 228.100042 -309.534341)
			(xy 228.134128 -309.490198) (xy 228.174277 -309.451489) (xy 228.219635 -309.419038) (xy 228.269235 -309.393537)
			(xy 228.322019 -309.37553) (xy 228.376862 -309.3654) (xy 228.432596 -309.363363) (xy 228.488033 -309.369463)
			(xy 228.54199 -309.383569) (xy 228.593319 -309.405381) (xy 228.640925 -309.434435) (xy 228.683793 -309.47011)
			(xy 228.72101 -309.511647) (xy 228.751783 -309.55816) (xy 228.775455 -309.608657) (xy 228.791523 -309.662064)
			(xy 228.799643 -309.71724) (xy 228.800152 -309.745126) (xy 228.799643 -309.773012) (xy 228.791523 -309.828188)
			(xy 228.775455 -309.881595) (xy 228.751783 -309.932092) (xy 228.72101 -309.978605) (xy 228.683793 -310.020142)
			(xy 228.640925 -310.055817) (xy 228.593319 -310.084871) (xy 228.54199 -310.106683) (xy 228.488033 -310.120789)
			(xy 228.432596 -310.126889) (xy 228.376862 -310.124852) (xy 228.322019 -310.114722) (xy 228.269235 -310.096715)
			(xy 228.219635 -310.071214) (xy 228.174277 -310.038763) (xy 228.134128 -310.000054) (xy 228.100042 -309.955911)
			(xy 228.072746 -309.907276) (xy 228.052823 -309.855185) (xy 228.040697 -309.800748) (xy 228.036626 -309.745126)
			(xy 227.047351 -309.745126) (xy 227.059939 -309.771979) (xy 227.076007 -309.825386) (xy 227.084127 -309.880562)
			(xy 227.084636 -309.908448) (xy 227.084127 -309.936334) (xy 227.076007 -309.99151) (xy 227.059939 -310.044917)
			(xy 227.036267 -310.095414) (xy 227.005494 -310.141927) (xy 226.999624 -310.148478) (xy 231.719118 -310.148478)
			(xy 231.723189 -310.092856) (xy 231.735315 -310.038419) (xy 231.755238 -309.986328) (xy 231.782534 -309.937693)
			(xy 231.81662 -309.89355) (xy 231.856769 -309.854841) (xy 231.902127 -309.82239) (xy 231.951727 -309.796889)
			(xy 232.004511 -309.778882) (xy 232.059354 -309.768752) (xy 232.115088 -309.766715) (xy 232.170525 -309.772815)
			(xy 232.224482 -309.786921) (xy 232.275811 -309.808733) (xy 232.323417 -309.837787) (xy 232.366285 -309.873462)
			(xy 232.403502 -309.914999) (xy 232.434275 -309.961512) (xy 232.457947 -310.012009) (xy 232.474015 -310.065416)
			(xy 232.482135 -310.120592) (xy 232.482644 -310.148478) (xy 232.482135 -310.176364) (xy 232.474015 -310.23154)
			(xy 232.457947 -310.284947) (xy 232.434275 -310.335444) (xy 232.403502 -310.381957) (xy 232.366285 -310.423494)
			(xy 232.323417 -310.459169) (xy 232.275811 -310.488223) (xy 232.224482 -310.510035) (xy 232.170525 -310.524141)
			(xy 232.115088 -310.530241) (xy 232.059354 -310.528204) (xy 232.004511 -310.518074) (xy 231.951727 -310.500067)
			(xy 231.902127 -310.474566) (xy 231.856769 -310.442115) (xy 231.81662 -310.403406) (xy 231.782534 -310.359263)
			(xy 231.755238 -310.310628) (xy 231.735315 -310.258537) (xy 231.723189 -310.2041) (xy 231.719118 -310.148478)
			(xy 226.999624 -310.148478) (xy 226.968277 -310.183464) (xy 226.925409 -310.219139) (xy 226.877803 -310.248193)
			(xy 226.826474 -310.270005) (xy 226.772517 -310.284111) (xy 226.71708 -310.290211) (xy 226.661346 -310.288174)
			(xy 226.606503 -310.278044) (xy 226.553719 -310.260037) (xy 226.504119 -310.234536) (xy 226.458761 -310.202085)
			(xy 226.418612 -310.163376) (xy 226.384526 -310.119233) (xy 226.35723 -310.070598) (xy 226.337307 -310.018507)
			(xy 226.325181 -309.96407) (xy 226.32111 -309.908448) (xy 213.09076 -309.908448) (xy 213.09076 -310.590946)
			(xy 230.918764 -310.590946) (xy 230.922835 -310.535324) (xy 230.934961 -310.480887) (xy 230.954884 -310.428796)
			(xy 230.98218 -310.380161) (xy 231.016266 -310.336018) (xy 231.056415 -310.297309) (xy 231.101773 -310.264858)
			(xy 231.151373 -310.239357) (xy 231.204157 -310.22135) (xy 231.259 -310.21122) (xy 231.314734 -310.209183)
			(xy 231.370171 -310.215283) (xy 231.424128 -310.229389) (xy 231.475457 -310.251201) (xy 231.523063 -310.280255)
			(xy 231.565931 -310.31593) (xy 231.603148 -310.357467) (xy 231.633921 -310.40398) (xy 231.657593 -310.454477)
			(xy 231.673661 -310.507884) (xy 231.681781 -310.56306) (xy 231.68229 -310.590946) (xy 231.681781 -310.618832)
			(xy 231.673661 -310.674008) (xy 231.657593 -310.727415) (xy 231.633921 -310.777912) (xy 231.603148 -310.824425)
			(xy 231.565931 -310.865962) (xy 231.523063 -310.901637) (xy 231.475457 -310.930691) (xy 231.424128 -310.952503)
			(xy 231.370171 -310.966609) (xy 231.314734 -310.972709) (xy 231.259 -310.970672) (xy 231.204157 -310.960542)
			(xy 231.151373 -310.942535) (xy 231.101773 -310.917034) (xy 231.056415 -310.884583) (xy 231.016266 -310.845874)
			(xy 230.98218 -310.801731) (xy 230.954884 -310.753096) (xy 230.934961 -310.701005) (xy 230.922835 -310.646568)
			(xy 230.918764 -310.590946) (xy 213.09076 -310.590946) (xy 213.09076 -311.215786) (xy 227.498908 -311.215786)
			(xy 227.502979 -311.160164) (xy 227.515105 -311.105727) (xy 227.535028 -311.053636) (xy 227.562324 -311.005001)
			(xy 227.59641 -310.960858) (xy 227.636559 -310.922149) (xy 227.681917 -310.889698) (xy 227.731517 -310.864197)
			(xy 227.784301 -310.84619) (xy 227.839144 -310.83606) (xy 227.894878 -310.834023) (xy 227.950315 -310.840123)
			(xy 228.004272 -310.854229) (xy 228.055601 -310.876041) (xy 228.103207 -310.905095) (xy 228.146075 -310.94077)
			(xy 228.183292 -310.982307) (xy 228.214065 -311.02882) (xy 228.237737 -311.079317) (xy 228.253805 -311.132724)
			(xy 228.261925 -311.1879) (xy 228.262434 -311.215786) (xy 228.261925 -311.243672) (xy 228.253805 -311.298848)
			(xy 228.237737 -311.352255) (xy 228.214065 -311.402752) (xy 228.183292 -311.449265) (xy 228.146075 -311.490802)
			(xy 228.103207 -311.526477) (xy 228.055601 -311.555531) (xy 228.025463 -311.568338) (xy 229.820468 -311.568338)
			(xy 229.824539 -311.512716) (xy 229.836665 -311.458279) (xy 229.856588 -311.406188) (xy 229.883884 -311.357553)
			(xy 229.91797 -311.31341) (xy 229.958119 -311.274701) (xy 230.003477 -311.24225) (xy 230.053077 -311.216749)
			(xy 230.105861 -311.198742) (xy 230.160704 -311.188612) (xy 230.216438 -311.186575) (xy 230.271875 -311.192675)
			(xy 230.325832 -311.206781) (xy 230.377161 -311.228593) (xy 230.424767 -311.257647) (xy 230.467635 -311.293322)
			(xy 230.504852 -311.334859) (xy 230.535625 -311.381372) (xy 230.559297 -311.431869) (xy 230.575365 -311.485276)
			(xy 230.583485 -311.540452) (xy 230.583994 -311.568338) (xy 230.583485 -311.596224) (xy 230.575365 -311.6514)
			(xy 230.559297 -311.704807) (xy 230.535625 -311.755304) (xy 230.504852 -311.801817) (xy 230.467635 -311.843354)
			(xy 230.424767 -311.879029) (xy 230.377161 -311.908083) (xy 230.325832 -311.929895) (xy 230.271875 -311.944001)
			(xy 230.216438 -311.950101) (xy 230.160704 -311.948064) (xy 230.105861 -311.937934) (xy 230.053077 -311.919927)
			(xy 230.003477 -311.894426) (xy 229.958119 -311.861975) (xy 229.91797 -311.823266) (xy 229.883884 -311.779123)
			(xy 229.856588 -311.730488) (xy 229.836665 -311.678397) (xy 229.824539 -311.62396) (xy 229.820468 -311.568338)
			(xy 228.025463 -311.568338) (xy 228.004272 -311.577343) (xy 227.950315 -311.591449) (xy 227.894878 -311.597549)
			(xy 227.839144 -311.595512) (xy 227.784301 -311.585382) (xy 227.731517 -311.567375) (xy 227.681917 -311.541874)
			(xy 227.636559 -311.509423) (xy 227.59641 -311.470714) (xy 227.562324 -311.426571) (xy 227.535028 -311.377936)
			(xy 227.515105 -311.325845) (xy 227.502979 -311.271408) (xy 227.498908 -311.215786) (xy 213.09076 -311.215786)
			(xy 213.09076 -313.077606) (xy 213.091186 -313.087674) (xy 213.098908 -313.106272) (xy 213.104103 -313.111896)
			(xy 230.52354 -313.111896) (xy 230.527611 -313.056274) (xy 230.539737 -313.001837) (xy 230.55966 -312.949746)
			(xy 230.586956 -312.901111) (xy 230.621042 -312.856968) (xy 230.661191 -312.818259) (xy 230.706549 -312.785808)
			(xy 230.756149 -312.760307) (xy 230.808933 -312.7423) (xy 230.863776 -312.73217) (xy 230.91951 -312.730133)
			(xy 230.974947 -312.736233) (xy 231.028904 -312.750339) (xy 231.080233 -312.772151) (xy 231.127839 -312.801205)
			(xy 231.170707 -312.83688) (xy 231.207924 -312.878417) (xy 231.238697 -312.92493) (xy 231.262369 -312.975427)
			(xy 231.278437 -313.028834) (xy 231.286557 -313.08401) (xy 231.287066 -313.111896) (xy 231.286557 -313.139782)
			(xy 231.278437 -313.194958) (xy 231.262369 -313.248365) (xy 231.238697 -313.298862) (xy 231.207924 -313.345375)
			(xy 231.170707 -313.386912) (xy 231.127839 -313.422587) (xy 231.080233 -313.451641) (xy 231.028904 -313.473453)
			(xy 230.974947 -313.487559) (xy 230.91951 -313.493659) (xy 230.863776 -313.491622) (xy 230.808933 -313.481492)
			(xy 230.756149 -313.463485) (xy 230.706549 -313.437984) (xy 230.661191 -313.405533) (xy 230.621042 -313.366824)
			(xy 230.586956 -313.322681) (xy 230.55966 -313.274046) (xy 230.539737 -313.221955) (xy 230.527611 -313.167518)
			(xy 230.52354 -313.111896) (xy 213.104103 -313.111896) (xy 213.105746 -313.113674) (xy 216.788492 -316.79642)
			(xy 216.811439 -316.819974) (xy 216.852462 -316.871373) (xy 216.887469 -316.927043) (xy 216.916018 -316.986286)
			(xy 216.937751 -317.048353) (xy 216.952393 -317.112465) (xy 216.959761 -317.177813) (xy 216.960196 -317.210694)
			(xy 216.960196 -320.816732) (xy 224.888044 -320.816732) (xy 224.888518 -320.789362) (xy 224.896332 -320.735183)
			(xy 224.911819 -320.682679) (xy 224.934659 -320.632932) (xy 224.964383 -320.586966) (xy 224.982024 -320.566034)
			(xy 224.982278 -320.56578) (xy 224.987888 -320.55871) (xy 224.994119 -320.54178) (xy 224.99447 -320.53276)
			(xy 224.99447 -320.465704) (xy 224.994118 -320.456686) (xy 224.987868 -320.439769) (xy 224.982278 -320.432684)
			(xy 224.982024 -320.432684) (xy 224.982024 -320.43243) (xy 224.964389 -320.411494) (xy 224.934676 -320.365523)
			(xy 224.911839 -320.315776) (xy 224.896347 -320.263276) (xy 224.888518 -320.209101) (xy 224.888044 -320.181732)
			(xy 224.888608 -320.154484) (xy 224.896359 -320.100541) (xy 224.911707 -320.048251) (xy 224.934341 -319.998677)
			(xy 224.9638 -319.952829) (xy 224.999483 -319.91164) (xy 225.040665 -319.875948) (xy 225.086507 -319.84648)
			(xy 225.136076 -319.823835) (xy 225.188363 -319.808476) (xy 225.242304 -319.800714) (xy 225.269552 -319.800224)
			(xy 225.296921 -319.800712) (xy 225.3511 -319.808524) (xy 225.403603 -319.824007) (xy 225.45335 -319.846844)
			(xy 225.499318 -319.876565) (xy 225.52025 -319.894204) (xy 225.520504 -319.894458) (xy 225.52758 -319.900059)
			(xy 225.544505 -319.906296) (xy 225.553524 -319.90665) (xy 225.62058 -319.90665) (xy 225.629597 -319.906294)
			(xy 225.646515 -319.900047) (xy 225.6536 -319.894458) (xy 225.6536 -319.894204) (xy 225.653854 -319.894204)
			(xy 225.674787 -319.876563) (xy 225.720755 -319.846839) (xy 225.770501 -319.823993) (xy 225.823003 -319.808497)
			(xy 225.877181 -319.800668) (xy 225.931923 -319.800668) (xy 225.986101 -319.808497) (xy 226.038603 -319.823993)
			(xy 226.088349 -319.846839) (xy 226.134317 -319.876563) (xy 226.15525 -319.894204) (xy 226.155504 -319.894458)
			(xy 226.16258 -319.900059) (xy 226.179505 -319.906296) (xy 226.188524 -319.90665) (xy 226.25558 -319.90665)
			(xy 226.264597 -319.906294) (xy 226.281515 -319.900047) (xy 226.2886 -319.894458) (xy 226.2886 -319.894204)
			(xy 226.288854 -319.894204) (xy 226.309793 -319.876574) (xy 226.355764 -319.84686) (xy 226.40551 -319.824023)
			(xy 226.458009 -319.80853) (xy 226.512183 -319.800699) (xy 226.539552 -319.800224) (xy 226.566805 -319.8007)
			(xy 226.620757 -319.808451) (xy 226.673057 -319.823803) (xy 226.722639 -319.846442) (xy 226.768494 -319.875908)
			(xy 226.809688 -319.911601) (xy 226.845382 -319.952793) (xy 226.87485 -319.998647) (xy 226.897492 -320.048228)
			(xy 226.912845 -320.100527) (xy 226.920599 -320.154479) (xy 226.92106 -320.181732) (xy 226.920622 -320.209103)
			(xy 226.912799 -320.263284) (xy 226.897304 -320.315788) (xy 226.874456 -320.365534) (xy 226.844725 -320.4115)
			(xy 226.82708 -320.43243) (xy 226.826826 -320.432684) (xy 226.821231 -320.439765) (xy 226.814991 -320.456686)
			(xy 226.814634 -320.465704) (xy 226.814634 -320.53276) (xy 226.815003 -320.541776) (xy 226.821241 -320.558693)
			(xy 226.826826 -320.56578) (xy 226.82708 -320.56578) (xy 226.82708 -320.566034) (xy 226.844699 -320.586983)
			(xy 226.874414 -320.632951) (xy 226.897254 -320.682694) (xy 226.91275 -320.735191) (xy 226.920583 -320.789364)
			(xy 226.92106 -320.816732) (xy 226.920675 -320.843988) (xy 226.912912 -320.897944) (xy 226.89755 -320.950246)
			(xy 226.8749 -320.99983) (xy 226.845424 -321.045685) (xy 226.809722 -321.086879) (xy 226.768521 -321.122572)
			(xy 226.72266 -321.152038) (xy 226.673071 -321.174678) (xy 226.620766 -321.190029) (xy 226.566808 -321.19778)
			(xy 226.539552 -321.19824) (xy 226.512182 -321.197758) (xy 226.458003 -321.189946) (xy 226.4055 -321.174462)
			(xy 226.355752 -321.151623) (xy 226.309786 -321.121901) (xy 226.288854 -321.10426) (xy 226.2886 -321.104006)
			(xy 226.281517 -321.098414) (xy 226.264598 -321.09217) (xy 226.25558 -321.091814) (xy 226.188524 -321.091814)
			(xy 226.179508 -321.092179) (xy 226.162591 -321.098421) (xy 226.155504 -321.104006) (xy 226.15525 -321.10426)
			(xy 226.134317 -321.121901) (xy 226.088349 -321.151625) (xy 226.038603 -321.174471) (xy 225.986101 -321.189967)
			(xy 225.931923 -321.197796) (xy 225.877181 -321.197796) (xy 225.823003 -321.189967) (xy 225.770501 -321.174471)
			(xy 225.720755 -321.151625) (xy 225.674787 -321.121901) (xy 225.653854 -321.10426) (xy 225.6536 -321.104006)
			(xy 225.646517 -321.098414) (xy 225.629598 -321.09217) (xy 225.62058 -321.091814) (xy 225.553524 -321.091814)
			(xy 225.544508 -321.092179) (xy 225.527591 -321.098421) (xy 225.520504 -321.104006) (xy 225.520504 -321.10426)
			(xy 225.52025 -321.10426) (xy 225.499305 -321.121883) (xy 225.453336 -321.151599) (xy 225.403592 -321.174438)
			(xy 225.351094 -321.189933) (xy 225.29692 -321.197764) (xy 225.269552 -321.19824) (xy 225.242301 -321.197767)
			(xy 225.188355 -321.190005) (xy 225.136062 -321.174645) (xy 225.086486 -321.152001) (xy 225.040638 -321.122532)
			(xy 224.999449 -321.08684) (xy 224.963758 -321.04565) (xy 224.934292 -320.9998) (xy 224.911649 -320.950223)
			(xy 224.896292 -320.89793) (xy 224.888532 -320.843983) (xy 224.888044 -320.816732) (xy 216.960196 -320.816732)
			(xy 216.960196 -321.317366) (xy 216.960631 -321.327431) (xy 216.968362 -321.346018) (xy 216.975182 -321.353434)
			(xy 217.854784 -322.23329) (xy 217.862187 -322.240124) (xy 217.880785 -322.24783) (xy 217.890852 -322.248276)
			(xy 224.358454 -322.248276) (xy 224.391309 -322.248734) (xy 224.456606 -322.256085) (xy 224.520669 -322.270701)
			(xy 224.582693 -322.292398) (xy 224.641898 -322.320902) (xy 224.69754 -322.355855) (xy 224.748918 -322.396819)
			(xy 224.772474 -322.419726) (xy 228.16947 -325.816722) (xy 228.176826 -325.823373) (xy 228.195126 -325.830961)
			(xy 228.20503 -325.831454) (xy 228.235764 -325.831708) (xy 228.245048 -325.831312) (xy 228.26239 -325.82468)
			(xy 228.269546 -325.818754) (xy 228.290636 -325.800629) (xy 228.337075 -325.770044) (xy 228.38746 -325.746518)
			(xy 228.440725 -325.730549) (xy 228.495743 -325.722475) (xy 228.523546 -325.72198) (xy 228.550795 -325.722469)
			(xy 228.604739 -325.730231) (xy 228.657029 -325.74559) (xy 228.706601 -325.768233) (xy 228.752446 -325.797701)
			(xy 228.793632 -325.833392) (xy 228.82932 -325.874581) (xy 228.858783 -325.920429) (xy 228.881422 -325.970003)
			(xy 228.896777 -326.022294) (xy 228.904534 -326.076239) (xy 228.905054 -326.103488) (xy 228.904489 -326.133179)
			(xy 228.895286 -326.191844) (xy 228.877101 -326.248374) (xy 228.850374 -326.301402) (xy 228.81575 -326.349645)
			(xy 228.795326 -326.371204) (xy 228.795072 -326.371458) (xy 228.788508 -326.378911) (xy 228.78113 -326.397329)
			(xy 228.781267 -326.41717) (xy 228.7889 -326.435484) (xy 228.79558 -326.442832) (xy 231.224074 -328.871326)
			(xy 231.250224 -328.898339) (xy 231.296144 -328.95787) (xy 231.334081 -329.022781) (xy 231.363412 -329.092008)
			(xy 231.383657 -329.164415) (xy 231.389682 -329.201526) (xy 231.390698 -329.209654) (xy 231.398064 -329.224386)
			(xy 231.538526 -329.364848) (xy 231.545373 -329.372245) (xy 231.553102 -329.390845) (xy 231.553512 -329.400916)
			(xy 231.553512 -329.719686) (xy 231.554084 -329.731351) (xy 231.564415 -329.752265) (xy 231.573324 -329.759818)
			(xy 231.594273 -329.776566) (xy 231.63172 -329.814964) (xy 231.663419 -329.858228) (xy 231.688745 -329.905506)
			(xy 231.707201 -329.955865) (xy 231.718421 -330.008313) (xy 231.722184 -330.061815) (xy 231.718417 -330.115316)
			(xy 231.707193 -330.167763) (xy 231.688733 -330.218121) (xy 231.663403 -330.265397) (xy 231.631701 -330.308659)
			(xy 231.594251 -330.347054) (xy 231.573324 -330.36383) (xy 231.564454 -330.371412) (xy 231.554127 -330.39231)
			(xy 231.553512 -330.403962) (xy 231.553512 -332.883256) (xy 236.029498 -332.883256) (xy 236.033569 -332.827634)
			(xy 236.045695 -332.773197) (xy 236.065618 -332.721106) (xy 236.092914 -332.672471) (xy 236.127 -332.628328)
			(xy 236.167149 -332.589619) (xy 236.212507 -332.557168) (xy 236.262107 -332.531667) (xy 236.314891 -332.51366)
			(xy 236.369734 -332.50353) (xy 236.425468 -332.501493) (xy 236.480905 -332.507593) (xy 236.534862 -332.521699)
			(xy 236.586191 -332.543511) (xy 236.633797 -332.572565) (xy 236.676665 -332.60824) (xy 236.713882 -332.649777)
			(xy 236.744655 -332.69629) (xy 236.768327 -332.746787) (xy 236.784395 -332.800194) (xy 236.792515 -332.85537)
			(xy 236.793024 -332.883256) (xy 236.792515 -332.911142) (xy 236.784395 -332.966318) (xy 236.768327 -333.019725)
			(xy 236.744655 -333.070222) (xy 236.713882 -333.116735) (xy 236.676665 -333.158272) (xy 236.633797 -333.193947)
			(xy 236.586191 -333.223001) (xy 236.534862 -333.244813) (xy 236.480905 -333.258919) (xy 236.425468 -333.265019)
			(xy 236.369734 -333.262982) (xy 236.314891 -333.252852) (xy 236.262107 -333.234845) (xy 236.212507 -333.209344)
			(xy 236.167149 -333.176893) (xy 236.127 -333.138184) (xy 236.092914 -333.094041) (xy 236.065618 -333.045406)
			(xy 236.045695 -332.993315) (xy 236.033569 -332.938878) (xy 236.029498 -332.883256) (xy 231.553512 -332.883256)
			(xy 231.553512 -333.411322) (xy 231.569514 -333.436214) (xy 231.582976 -333.44231) (xy 231.607491 -333.454103)
			(xy 231.653195 -333.483604) (xy 231.694246 -333.519297) (xy 231.729811 -333.560459) (xy 231.759169 -333.606256)
			(xy 231.781725 -333.655758) (xy 231.79702 -333.707962) (xy 231.804746 -333.761809) (xy 231.804744 -333.816208)
			(xy 231.797016 -333.870055) (xy 231.781719 -333.922258) (xy 231.759161 -333.971759) (xy 231.729801 -334.017554)
			(xy 231.694234 -334.058715) (xy 231.653182 -334.094406) (xy 231.607476 -334.123905) (xy 231.582976 -334.13573)
			(xy 231.569514 -334.141826) (xy 231.553512 -334.166718) (xy 231.553512 -334.831436) (xy 231.553083 -334.841504)
			(xy 231.545361 -334.8601) (xy 231.538526 -334.867504) (xy 231.252776 -335.153254) (xy 231.246081 -335.160664)
			(xy 231.238465 -335.179103) (xy 231.238456 -335.199052) (xy 231.246056 -335.217498) (xy 231.252776 -335.224882)
			(xy 234.443524 -338.41563) (xy 234.45092 -338.42248) (xy 234.469519 -338.430217) (xy 234.479592 -338.430616)
		)
		(stroke
			(width 0)
			(type solid)
		)
		(fill yes)
		(layer "In9.Cu")
		(net "GND")
	)
	(gr_poly
		(pts
			(xy 330.396088 -248.54027) (xy 332.626208 -246.31015) (xy 332.634013 -246.283666) (xy 332.656201 -246.233108)
			(xy 332.685444 -246.186277) (xy 332.721133 -246.14415) (xy 332.762523 -246.107608) (xy 332.808747 -246.077414)
			(xy 332.858841 -246.054199) (xy 332.911759 -246.038447) (xy 332.966394 -246.030488) (xy 332.994 -246.029988)
			(xy 333.021251 -246.030474) (xy 333.075199 -246.03823) (xy 333.127494 -246.053585) (xy 333.177072 -246.076226)
			(xy 333.222922 -246.105693) (xy 333.264113 -246.141384) (xy 333.299805 -246.182574) (xy 333.329272 -246.228425)
			(xy 333.351913 -246.278002) (xy 333.367269 -246.330297) (xy 333.375026 -246.384245) (xy 333.375508 -246.411496)
			(xy 333.37491 -246.44106) (xy 333.365718 -246.499471) (xy 333.347644 -246.55577) (xy 333.334868 -246.582438)
			(xy 333.334868 -246.582692) (xy 333.334614 -246.5832) (xy 333.331193 -246.591052) (xy 333.329229 -246.608058)
			(xy 333.332931 -246.624771) (xy 333.337154 -246.632222) (xy 333.382366 -246.705628) (xy 333.384974 -246.709712)
			(xy 333.391498 -246.716873) (xy 333.39532 -246.719852) (xy 334.064356 -246.719852) (xy 335.398618 -245.38559)
			(xy 335.390744 -245.323106) (xy 335.388725 -245.311659) (xy 335.376032 -245.292214) (xy 335.36636 -245.285768)
			(xy 335.366106 -245.285514) (xy 335.342055 -245.270667) (xy 335.29821 -245.234998) (xy 335.260102 -245.193257)
			(xy 335.228563 -245.146354) (xy 335.204281 -245.095314) (xy 335.187788 -245.041254) (xy 335.179444 -244.985352)
			(xy 335.178908 -244.957092) (xy 335.179372 -244.92984) (xy 335.18713 -244.875891) (xy 335.202487 -244.823595)
			(xy 335.22513 -244.774017) (xy 335.254598 -244.728166) (xy 335.290292 -244.686975) (xy 335.331485 -244.651284)
			(xy 335.377338 -244.621818) (xy 335.426917 -244.599178) (xy 335.479214 -244.583825) (xy 335.533164 -244.57607)
			(xy 335.560416 -244.575584) (xy 335.588681 -244.576089) (xy 335.644593 -244.584416) (xy 335.698665 -244.6009)
			(xy 335.749714 -244.62518) (xy 335.796623 -244.656725) (xy 335.838365 -244.694844) (xy 335.874027 -244.738704)
			(xy 335.888838 -244.762782) (xy 335.889092 -244.763036) (xy 335.895501 -244.772748) (xy 335.914961 -244.785456)
			(xy 335.92643 -244.78742) (xy 335.988914 -244.795294) (xy 336.357976 -244.426232) (xy 336.357976 -244.141244)
			(xy 336.346151 -244.11965) (xy 336.327544 -244.074067) (xy 336.314959 -244.026469) (xy 336.308605 -243.977647)
			(xy 336.308192 -243.95303) (xy 336.308653 -243.925776) (xy 336.316407 -243.871822) (xy 336.33176 -243.81952)
			(xy 336.354401 -243.769936) (xy 336.383868 -243.724079) (xy 336.419562 -243.682883) (xy 336.460755 -243.647186)
			(xy 336.50661 -243.617715) (xy 336.556192 -243.595071) (xy 336.608492 -243.579713) (xy 336.662446 -243.571955)
			(xy 336.6897 -243.571522) (xy 336.717445 -243.572016) (xy 336.77235 -243.580056) (xy 336.825507 -243.59598)
			(xy 336.875789 -243.619451) (xy 336.922131 -243.649972) (xy 336.943192 -243.668042) (xy 336.943954 -243.668804)
			(xy 336.948136 -243.672203) (xy 336.957616 -243.677325) (xy 336.96275 -243.678964) (xy 336.973926 -243.682266)
			(xy 337.074256 -243.666518) (xy 337.093052 -243.653818) (xy 337.098894 -243.643658) (xy 337.113687 -243.619434)
			(xy 337.149313 -243.575251) (xy 337.191092 -243.536833) (xy 337.238101 -243.505028) (xy 337.289303 -243.480538)
			(xy 337.343569 -243.463904) (xy 337.399699 -243.455493) (xy 337.428078 -243.454936) (xy 337.455329 -243.455398)
			(xy 337.509276 -243.463151) (xy 337.56157 -243.478504) (xy 337.611147 -243.501142) (xy 337.627387 -243.511578)
			(xy 354.422708 -243.511578) (xy 354.426779 -243.455956) (xy 354.438905 -243.401519) (xy 354.458828 -243.349428)
			(xy 354.486124 -243.300793) (xy 354.52021 -243.25665) (xy 354.560359 -243.217941) (xy 354.605717 -243.18549)
			(xy 354.655317 -243.159989) (xy 354.708101 -243.141982) (xy 354.762944 -243.131852) (xy 354.818678 -243.129815)
			(xy 354.874115 -243.135915) (xy 354.928072 -243.150021) (xy 354.979401 -243.171833) (xy 355.027007 -243.200887)
			(xy 355.069875 -243.236562) (xy 355.107092 -243.278099) (xy 355.137865 -243.324612) (xy 355.161537 -243.375109)
			(xy 355.177605 -243.428516) (xy 355.185725 -243.483692) (xy 355.186234 -243.511578) (xy 355.185725 -243.539464)
			(xy 355.182315 -243.562632) (xy 358.60177 -243.562632) (xy 358.605841 -243.50701) (xy 358.617967 -243.452573)
			(xy 358.63789 -243.400482) (xy 358.665186 -243.351847) (xy 358.699272 -243.307704) (xy 358.739421 -243.268995)
			(xy 358.784779 -243.236544) (xy 358.834379 -243.211043) (xy 358.887163 -243.193036) (xy 358.942006 -243.182906)
			(xy 358.99774 -243.180869) (xy 359.053177 -243.186969) (xy 359.107134 -243.201075) (xy 359.158463 -243.222887)
			(xy 359.206069 -243.251941) (xy 359.248937 -243.287616) (xy 359.286154 -243.329153) (xy 359.316927 -243.375666)
			(xy 359.340599 -243.426163) (xy 359.356667 -243.47957) (xy 359.364787 -243.534746) (xy 359.365296 -243.562632)
			(xy 359.364787 -243.590518) (xy 359.356667 -243.645694) (xy 359.340599 -243.699101) (xy 359.316927 -243.749598)
			(xy 359.286154 -243.796111) (xy 359.248937 -243.837648) (xy 359.206069 -243.873323) (xy 359.158463 -243.902377)
			(xy 359.107134 -243.924189) (xy 359.053177 -243.938295) (xy 358.99774 -243.944395) (xy 358.942006 -243.942358)
			(xy 358.887163 -243.932228) (xy 358.834379 -243.914221) (xy 358.784779 -243.88872) (xy 358.739421 -243.856269)
			(xy 358.699272 -243.81756) (xy 358.665186 -243.773417) (xy 358.63789 -243.724782) (xy 358.617967 -243.672691)
			(xy 358.605841 -243.618254) (xy 358.60177 -243.562632) (xy 355.182315 -243.562632) (xy 355.177605 -243.59464)
			(xy 355.161537 -243.648047) (xy 355.137865 -243.698544) (xy 355.107092 -243.745057) (xy 355.069875 -243.786594)
			(xy 355.027007 -243.822269) (xy 354.979401 -243.851323) (xy 354.928072 -243.873135) (xy 354.874115 -243.887241)
			(xy 354.818678 -243.893341) (xy 354.762944 -243.891304) (xy 354.708101 -243.881174) (xy 354.655317 -243.863167)
			(xy 354.605717 -243.837666) (xy 354.560359 -243.805215) (xy 354.52021 -243.766506) (xy 354.486124 -243.722363)
			(xy 354.458828 -243.673728) (xy 354.438905 -243.621637) (xy 354.426779 -243.5672) (xy 354.422708 -243.511578)
			(xy 337.627387 -243.511578) (xy 337.656998 -243.530606) (xy 337.698189 -243.566296) (xy 337.733881 -243.607484)
			(xy 337.763347 -243.653333) (xy 337.785989 -243.702909) (xy 337.801344 -243.755203) (xy 337.809101 -243.809149)
			(xy 337.809101 -243.863651) (xy 337.801344 -243.917597) (xy 337.785989 -243.969891) (xy 337.763347 -244.019467)
			(xy 337.733881 -244.065316) (xy 337.698189 -244.106504) (xy 337.656998 -244.142194) (xy 337.611147 -244.171658)
			(xy 337.56157 -244.194296) (xy 337.509276 -244.209649) (xy 337.455329 -244.217402) (xy 337.428078 -244.217952)
			(xy 337.400331 -244.217463) (xy 337.345421 -244.209433) (xy 337.292259 -244.193516) (xy 337.24197 -244.170051)
			(xy 337.19562 -244.139534) (xy 337.174586 -244.121432) (xy 337.173824 -244.12067) (xy 337.169644 -244.117267)
			(xy 337.160168 -244.112134) (xy 337.155028 -244.11051) (xy 337.143852 -244.107208) (xy 337.043522 -244.122956)
			(xy 337.024472 -244.13591) (xy 337.021424 -244.141244) (xy 337.021424 -244.221) (xy 338.072982 -244.221)
			(xy 338.077053 -244.165378) (xy 338.089179 -244.110941) (xy 338.109102 -244.05885) (xy 338.136398 -244.010215)
			(xy 338.170484 -243.966072) (xy 338.210633 -243.927363) (xy 338.255991 -243.894912) (xy 338.305591 -243.869411)
			(xy 338.358375 -243.851404) (xy 338.413218 -243.841274) (xy 338.468952 -243.839237) (xy 338.524389 -243.845337)
			(xy 338.578346 -243.859443) (xy 338.629675 -243.881255) (xy 338.677281 -243.910309) (xy 338.720149 -243.945984)
			(xy 338.757366 -243.987521) (xy 338.788139 -244.034034) (xy 338.811811 -244.084531) (xy 338.827879 -244.137938)
			(xy 338.835999 -244.193114) (xy 338.836508 -244.221) (xy 338.835999 -244.248886) (xy 338.827879 -244.304062)
			(xy 338.811811 -244.357469) (xy 338.788139 -244.407966) (xy 338.757366 -244.454479) (xy 338.720149 -244.496016)
			(xy 338.677281 -244.531691) (xy 338.629675 -244.560745) (xy 338.578346 -244.582557) (xy 338.524389 -244.596663)
			(xy 338.468952 -244.602763) (xy 338.413218 -244.600726) (xy 338.358375 -244.590596) (xy 338.305591 -244.572589)
			(xy 338.255991 -244.547088) (xy 338.210633 -244.514637) (xy 338.170484 -244.475928) (xy 338.136398 -244.431785)
			(xy 338.109102 -244.38315) (xy 338.089179 -244.331059) (xy 338.077053 -244.276622) (xy 338.072982 -244.221)
			(xy 337.021424 -244.221) (xy 337.021424 -244.70106) (xy 336.972148 -244.750336) (xy 336.96078 -244.770333)
			(xy 336.933242 -244.807175) (xy 336.917284 -244.823742) (xy 336.413094 -245.327678) (xy 336.405974 -245.335648)
			(xy 336.403593 -245.341902) (xy 355.742238 -245.341902) (xy 355.746309 -245.28628) (xy 355.758435 -245.231843)
			(xy 355.778358 -245.179752) (xy 355.805654 -245.131117) (xy 355.83974 -245.086974) (xy 355.879889 -245.048265)
			(xy 355.925247 -245.015814) (xy 355.974847 -244.990313) (xy 356.027631 -244.972306) (xy 356.082474 -244.962176)
			(xy 356.138208 -244.960139) (xy 356.193645 -244.966239) (xy 356.247602 -244.980345) (xy 356.298931 -245.002157)
			(xy 356.346537 -245.031211) (xy 356.389405 -245.066886) (xy 356.426622 -245.108423) (xy 356.457395 -245.154936)
			(xy 356.481067 -245.205433) (xy 356.497135 -245.25884) (xy 356.505255 -245.314016) (xy 356.505764 -245.341902)
			(xy 356.505255 -245.369788) (xy 356.497135 -245.424964) (xy 356.481067 -245.478371) (xy 356.457395 -245.528868)
			(xy 356.426622 -245.575381) (xy 356.389405 -245.616918) (xy 356.346537 -245.652593) (xy 356.298931 -245.681647)
			(xy 356.247602 -245.703459) (xy 356.193645 -245.717565) (xy 356.138208 -245.723665) (xy 356.082474 -245.721628)
			(xy 356.027631 -245.711498) (xy 355.974847 -245.693491) (xy 355.925247 -245.66799) (xy 355.879889 -245.635539)
			(xy 355.83974 -245.59683) (xy 355.805654 -245.552687) (xy 355.778358 -245.504052) (xy 355.758435 -245.451961)
			(xy 355.746309 -245.397524) (xy 355.742238 -245.341902) (xy 336.403593 -245.341902) (xy 336.39838 -245.355597)
			(xy 336.398362 -245.366286) (xy 336.403188 -245.452646) (xy 336.41284 -245.471696) (xy 336.421476 -245.478554)
			(xy 336.443342 -245.496785) (xy 336.481947 -245.538623) (xy 336.51391 -245.58573) (xy 336.538523 -245.637062)
			(xy 336.555239 -245.691481) (xy 336.563687 -245.747778) (xy 336.564224 -245.776242) (xy 336.563735 -245.803492)
			(xy 336.555974 -245.857436) (xy 336.540615 -245.909726) (xy 336.517972 -245.959299) (xy 336.488505 -246.005146)
			(xy 336.452814 -246.046332) (xy 336.411625 -246.082021) (xy 336.365776 -246.111485) (xy 336.316202 -246.134125)
			(xy 336.26391 -246.14948) (xy 336.209966 -246.157237) (xy 336.182716 -246.15775) (xy 336.154252 -246.157225)
			(xy 336.097954 -246.148773) (xy 336.043535 -246.132055) (xy 335.992203 -246.10744) (xy 335.945095 -246.075476)
			(xy 335.903257 -246.03687) (xy 335.885028 -246.015002) (xy 335.87817 -246.006366) (xy 335.85912 -245.996714)
			(xy 335.77276 -245.991888) (xy 335.762049 -245.991762) (xy 335.74205 -245.999385) (xy 335.734152 -246.00662)
			(xy 334.461866 -247.27916) (xy 334.445317 -247.295139) (xy 334.408473 -247.322681) (xy 334.38846 -247.334024)
			(xy 334.339184 -247.3833) (xy 333.242666 -247.3833) (xy 332.236572 -248.389394) (xy 332.235913 -248.394082)
			(xy 332.236162 -248.403546) (xy 332.23708 -248.40819) (xy 332.258416 -248.504202) (xy 332.275434 -248.52376)
			(xy 332.287626 -248.528332) (xy 332.308454 -248.53646) (xy 332.318106 -248.540778) (xy 359.860342 -248.540778)
			(xy 359.870217 -248.540313) (xy 359.888507 -248.532861) (xy 359.895902 -248.5263) (xy 360.152442 -248.26976)
			(xy 360.160062 -248.249186) (xy 360.159046 -248.237756) (xy 360.157776 -248.206768) (xy 360.158264 -248.179518)
			(xy 360.166024 -248.125573) (xy 360.181382 -248.073281) (xy 360.204025 -248.023707) (xy 360.233491 -247.977859)
			(xy 360.269183 -247.936671) (xy 360.310372 -247.900982) (xy 360.356221 -247.871517) (xy 360.405796 -247.848876)
			(xy 360.458088 -247.833521) (xy 360.512034 -247.825763) (xy 360.539284 -247.82526) (xy 360.570272 -247.82653)
			(xy 360.581702 -247.827546) (xy 360.602276 -247.819926) (xy 360.922062 -247.50014) (xy 360.92257 -247.499632)
			(xy 360.929148 -247.492249) (xy 360.936591 -247.47395) (xy 360.937048 -247.464072) (xy 360.937048 -245.73357)
			(xy 360.937169 -245.728616) (xy 360.939092 -245.718896) (xy 360.940858 -245.714266) (xy 360.952034 -245.68785)
			(xy 360.952034 -243.816632) (xy 360.92881 -243.822203) (xy 360.881426 -243.828196) (xy 360.857546 -243.82857)
			(xy 360.830273 -243.82811) (xy 360.77628 -243.820353) (xy 360.723942 -243.804991) (xy 360.674322 -243.782336)
			(xy 360.628432 -243.75285) (xy 360.587206 -243.717132) (xy 360.551483 -243.675911) (xy 360.52199 -243.630025)
			(xy 360.499328 -243.580409) (xy 360.483959 -243.528072) (xy 360.476194 -243.474081) (xy 360.475784 -243.446808)
			(xy 360.476546 -243.421408) (xy 360.475784 -243.396008) (xy 360.476247 -243.368738) (xy 360.484008 -243.314753)
			(xy 360.499374 -243.262422) (xy 360.522032 -243.21281) (xy 360.55152 -243.166929) (xy 360.587239 -243.125712)
			(xy 360.628459 -243.089998) (xy 360.674344 -243.060514) (xy 360.723957 -243.037861) (xy 360.77629 -243.0225)
			(xy 360.830276 -243.014744) (xy 360.857546 -243.014246) (xy 360.881426 -243.01463) (xy 360.92881 -243.020614)
			(xy 360.952034 -243.026184) (xy 360.952034 -239.685068) (xy 360.951519 -239.670131) (xy 360.942892 -239.641531)
			(xy 360.926358 -239.616651) (xy 360.90333 -239.597622) (xy 360.87578 -239.586071) (xy 360.846066 -239.582989)
			(xy 360.816732 -239.588638) (xy 360.790288 -239.602535) (xy 360.779314 -239.612678) (xy 360.757746 -239.633072)
			(xy 360.709474 -239.667612) (xy 360.65644 -239.694267) (xy 360.59992 -239.712396) (xy 360.541276 -239.721564)
			(xy 360.511598 -239.722152) (xy 360.485725 -239.721721) (xy 360.434455 -239.714729) (xy 360.384599 -239.700874)
			(xy 360.337073 -239.68041) (xy 360.292747 -239.653713) (xy 360.252435 -239.621271) (xy 360.216875 -239.58368)
			(xy 360.201464 -239.562894) (xy 360.193035 -239.551951) (xy 360.17151 -239.534658) (xy 360.146145 -239.523751)
			(xy 360.118787 -239.520025) (xy 360.091429 -239.523751) (xy 360.066064 -239.534658) (xy 360.044539 -239.551951)
			(xy 360.03611 -239.562894) (xy 360.02069 -239.583675) (xy 359.985142 -239.62128) (xy 359.944836 -239.653732)
			(xy 359.900511 -239.680436) (xy 359.852983 -239.700901) (xy 359.803124 -239.714751) (xy 359.75185 -239.721732)
			(xy 359.725976 -239.722152) (xy 359.698708 -239.721664) (xy 359.644729 -239.7139) (xy 359.592404 -239.698533)
			(xy 359.542798 -239.675876) (xy 359.496921 -239.64639) (xy 359.455707 -239.610676) (xy 359.419996 -239.56946)
			(xy 359.390513 -239.523581) (xy 359.367859 -239.473974) (xy 359.352495 -239.421648) (xy 359.344734 -239.367668)
			(xy 359.344734 -239.313132) (xy 359.352495 -239.259152) (xy 359.367859 -239.206826) (xy 359.390513 -239.157219)
			(xy 359.419996 -239.11134) (xy 359.455707 -239.070124) (xy 359.496921 -239.03441) (xy 359.542798 -239.004924)
			(xy 359.592404 -238.982267) (xy 359.644729 -238.9669) (xy 359.698708 -238.959136) (xy 359.725976 -238.958628)
			(xy 359.751846 -238.959064) (xy 359.803112 -238.966064) (xy 359.852961 -238.979926) (xy 359.900481 -239.000395)
			(xy 359.9448 -239.027096) (xy 359.985106 -239.05954) (xy 360.020659 -239.097131) (xy 360.03611 -239.117886)
			(xy 360.044511 -239.128873) (xy 360.066015 -239.14625) (xy 360.091395 -239.157214) (xy 360.118787 -239.16096)
			(xy 360.146179 -239.157214) (xy 360.171559 -239.14625) (xy 360.193063 -239.128873) (xy 360.201464 -239.117886)
			(xy 360.216884 -239.097104) (xy 360.252432 -239.059499) (xy 360.292738 -239.027046) (xy 360.337063 -239.000341)
			(xy 360.384591 -238.979874) (xy 360.43445 -238.966021) (xy 360.485724 -238.959037) (xy 360.511598 -238.958628)
			(xy 360.541278 -238.959189) (xy 360.599923 -238.968367) (xy 360.656444 -238.986501) (xy 360.709482 -239.013156)
			(xy 360.75776 -239.047691) (xy 360.779314 -239.068102) (xy 360.790332 -239.078188) (xy 360.816773 -239.092054)
			(xy 360.846094 -239.097686) (xy 360.87579 -239.094602) (xy 360.903328 -239.083065) (xy 360.926355 -239.064061)
			(xy 360.942906 -239.039212) (xy 360.951568 -239.01064) (xy 360.952034 -238.995712) (xy 360.952034 -230.702612)
			(xy 360.944414 -230.683816) (xy 360.937048 -230.676704) (xy 360.404664 -230.14432) (xy 360.397265 -230.137477)
			(xy 360.378666 -230.129752) (xy 360.368596 -230.129334) (xy 358.207056 -230.129334) (xy 358.18826 -230.136954)
			(xy 358.181148 -230.14432) (xy 357.15575 -231.169718) (xy 357.149135 -231.176996) (xy 357.141498 -231.195101)
			(xy 357.141196 -231.214748) (xy 357.14432 -231.224074) (xy 357.144574 -231.224582) (xy 357.144574 -231.224836)
			(xy 357.153395 -231.247635) (xy 357.165821 -231.294915) (xy 357.172103 -231.343395) (xy 357.172514 -231.367838)
			(xy 357.172026 -231.395088) (xy 357.171854 -231.396286) (xy 359.607864 -231.396286) (xy 359.611937 -231.340627)
			(xy 359.624072 -231.286154) (xy 359.644008 -231.234028) (xy 359.671322 -231.18536) (xy 359.70543 -231.141188)
			(xy 359.745607 -231.102453) (xy 359.790995 -231.069981) (xy 359.840627 -231.044463) (xy 359.893447 -231.026444)
			(xy 359.948326 -231.016307) (xy 360.004097 -231.014269) (xy 360.059571 -231.020372) (xy 360.113564 -231.034488)
			(xy 360.164927 -231.056315) (xy 360.212565 -231.085388) (xy 360.255461 -231.121087) (xy 360.292703 -231.162651)
			(xy 360.323497 -231.209195) (xy 360.347185 -231.259726) (xy 360.363263 -231.313168) (xy 360.371389 -231.368382)
			(xy 360.371898 -231.396286) (xy 360.371389 -231.42419) (xy 360.363263 -231.479404) (xy 360.347185 -231.532846)
			(xy 360.323497 -231.583377) (xy 360.292703 -231.629921) (xy 360.255461 -231.671485) (xy 360.212565 -231.707184)
			(xy 360.164927 -231.736257) (xy 360.113564 -231.758084) (xy 360.059571 -231.7722) (xy 360.004097 -231.778303)
			(xy 359.948326 -231.776265) (xy 359.893447 -231.766128) (xy 359.840627 -231.748109) (xy 359.790995 -231.722591)
			(xy 359.745607 -231.690119) (xy 359.70543 -231.651384) (xy 359.671322 -231.607212) (xy 359.644008 -231.558544)
			(xy 359.624072 -231.506418) (xy 359.611937 -231.451945) (xy 359.607864 -231.396286) (xy 357.171854 -231.396286)
			(xy 357.164265 -231.449032) (xy 357.148906 -231.501322) (xy 357.126263 -231.550895) (xy 357.096796 -231.596741)
			(xy 357.061105 -231.637927) (xy 357.019915 -231.673615) (xy 356.974067 -231.703079) (xy 356.924492 -231.725718)
			(xy 356.8722 -231.741072) (xy 356.818256 -231.748828) (xy 356.791006 -231.749346) (xy 356.762872 -231.748844)
			(xy 356.707213 -231.740581) (xy 356.653372 -231.724233) (xy 356.602515 -231.700154) (xy 356.555746 -231.668867)
			(xy 356.51408 -231.631051) (xy 356.478419 -231.587525) (xy 356.449538 -231.539234) (xy 356.428063 -231.487225)
			(xy 356.414458 -231.432626) (xy 356.411276 -231.404668) (xy 356.409498 -231.38511) (xy 356.380288 -231.358694)
			(xy 352.824796 -231.358694) (xy 352.809682 -231.359243) (xy 352.780774 -231.36808) (xy 352.755711 -231.384981)
			(xy 352.736683 -231.40847) (xy 352.725352 -231.436495) (xy 352.722708 -231.466607) (xy 352.728981 -231.496178)
			(xy 352.743624 -231.522624) (xy 352.754184 -231.533446) (xy 352.772273 -231.551466) (xy 352.80396 -231.591503)
			(xy 352.830021 -231.635409) (xy 352.849991 -231.682401) (xy 352.863512 -231.731637) (xy 352.870342 -231.782237)
			(xy 352.87077 -231.807766) (xy 352.870284 -231.835017) (xy 352.862528 -231.888965) (xy 352.847173 -231.94126)
			(xy 352.824531 -231.990837) (xy 352.795065 -232.036687) (xy 352.759374 -232.077878) (xy 352.718183 -232.113569)
			(xy 352.672333 -232.143035) (xy 352.622756 -232.165677) (xy 352.570461 -232.181032) (xy 352.516513 -232.188788)
			(xy 352.462011 -232.188788) (xy 352.408063 -232.181032) (xy 352.355768 -232.165677) (xy 352.306191 -232.143035)
			(xy 352.260341 -232.113569) (xy 352.21915 -232.077878) (xy 352.183459 -232.036687) (xy 352.153993 -231.990837)
			(xy 352.131351 -231.94126) (xy 352.115996 -231.888965) (xy 352.10824 -231.835017) (xy 352.107754 -231.807766)
			(xy 352.108245 -231.779817) (xy 352.116403 -231.724519) (xy 352.132541 -231.671002) (xy 352.156312 -231.620411)
			(xy 352.187208 -231.573829) (xy 352.224569 -231.532252) (xy 352.267595 -231.496569) (xy 352.315365 -231.467544)
			(xy 352.340926 -231.45623) (xy 352.35515 -231.450388) (xy 352.371914 -231.424988) (xy 352.371914 -231.409494)
			(xy 352.371425 -231.399486) (xy 352.363765 -231.380994) (xy 352.349613 -231.366839) (xy 352.331122 -231.359176)
			(xy 352.321114 -231.358694) (xy 352.227896 -231.358694) (xy 352.217826 -231.359117) (xy 352.199222 -231.366832)
			(xy 352.191828 -231.37368) (xy 352.048318 -231.51719) (xy 352.040915 -231.524025) (xy 352.022317 -231.531731)
			(xy 352.01225 -231.532176) (xy 346.0115 -231.532176) (xy 346.001429 -231.532598) (xy 345.982823 -231.54031)
			(xy 345.975432 -231.547162) (xy 345.379548 -232.143046) (xy 345.372149 -232.14989) (xy 345.35355 -232.157614)
			(xy 345.34348 -232.158032) (xy 342.521286 -232.158032) (xy 342.511218 -232.158458) (xy 342.49262 -232.16618)
			(xy 342.485218 -232.173018) (xy 342.303335 -232.354882) (xy 353.920296 -232.354882) (xy 353.924367 -232.29926)
			(xy 353.936493 -232.244823) (xy 353.956416 -232.192732) (xy 353.983712 -232.144097) (xy 354.017798 -232.099954)
			(xy 354.057947 -232.061245) (xy 354.103305 -232.028794) (xy 354.152905 -232.003293) (xy 354.205689 -231.985286)
			(xy 354.260532 -231.975156) (xy 354.316266 -231.973119) (xy 354.371703 -231.979219) (xy 354.42566 -231.993325)
			(xy 354.476989 -232.015137) (xy 354.524595 -232.044191) (xy 354.567463 -232.079866) (xy 354.60468 -232.121403)
			(xy 354.635453 -232.167916) (xy 354.659125 -232.218413) (xy 354.675193 -232.27182) (xy 354.683313 -232.326996)
			(xy 354.683822 -232.354882) (xy 354.683313 -232.382768) (xy 354.675193 -232.437944) (xy 354.669386 -232.457244)
			(xy 356.427022 -232.457244) (xy 356.431093 -232.401622) (xy 356.443219 -232.347185) (xy 356.463142 -232.295094)
			(xy 356.490438 -232.246459) (xy 356.524524 -232.202316) (xy 356.564673 -232.163607) (xy 356.610031 -232.131156)
			(xy 356.659631 -232.105655) (xy 356.712415 -232.087648) (xy 356.767258 -232.077518) (xy 356.822992 -232.075481)
			(xy 356.878429 -232.081581) (xy 356.932386 -232.095687) (xy 356.983715 -232.117499) (xy 357.031321 -232.146553)
			(xy 357.074189 -232.182228) (xy 357.111406 -232.223765) (xy 357.142179 -232.270278) (xy 357.165851 -232.320775)
			(xy 357.181919 -232.374182) (xy 357.190039 -232.429358) (xy 357.190548 -232.457244) (xy 358.666032 -232.457244)
			(xy 358.670103 -232.401622) (xy 358.682229 -232.347185) (xy 358.702152 -232.295094) (xy 358.729448 -232.246459)
			(xy 358.763534 -232.202316) (xy 358.803683 -232.163607) (xy 358.849041 -232.131156) (xy 358.898641 -232.105655)
			(xy 358.951425 -232.087648) (xy 359.006268 -232.077518) (xy 359.062002 -232.075481) (xy 359.117439 -232.081581)
			(xy 359.171396 -232.095687) (xy 359.222725 -232.117499) (xy 359.270331 -232.146553) (xy 359.313199 -232.182228)
			(xy 359.350416 -232.223765) (xy 359.381189 -232.270278) (xy 359.404861 -232.320775) (xy 359.420929 -232.374182)
			(xy 359.429049 -232.429358) (xy 359.429558 -232.457244) (xy 359.429049 -232.48513) (xy 359.420929 -232.540306)
			(xy 359.404861 -232.593713) (xy 359.381189 -232.64421) (xy 359.350416 -232.690723) (xy 359.313199 -232.73226)
			(xy 359.270331 -232.767935) (xy 359.222725 -232.796989) (xy 359.171396 -232.818801) (xy 359.117439 -232.832907)
			(xy 359.062002 -232.839007) (xy 359.006268 -232.83697) (xy 358.951425 -232.82684) (xy 358.898641 -232.808833)
			(xy 358.849041 -232.783332) (xy 358.803683 -232.750881) (xy 358.763534 -232.712172) (xy 358.729448 -232.668029)
			(xy 358.702152 -232.619394) (xy 358.682229 -232.567303) (xy 358.670103 -232.512866) (xy 358.666032 -232.457244)
			(xy 357.190548 -232.457244) (xy 357.190039 -232.48513) (xy 357.181919 -232.540306) (xy 357.165851 -232.593713)
			(xy 357.142179 -232.64421) (xy 357.111406 -232.690723) (xy 357.074189 -232.73226) (xy 357.031321 -232.767935)
			(xy 356.983715 -232.796989) (xy 356.932386 -232.818801) (xy 356.878429 -232.832907) (xy 356.822992 -232.839007)
			(xy 356.767258 -232.83697) (xy 356.712415 -232.82684) (xy 356.659631 -232.808833) (xy 356.610031 -232.783332)
			(xy 356.564673 -232.750881) (xy 356.524524 -232.712172) (xy 356.490438 -232.668029) (xy 356.463142 -232.619394)
			(xy 356.443219 -232.567303) (xy 356.431093 -232.512866) (xy 356.427022 -232.457244) (xy 354.669386 -232.457244)
			(xy 354.659125 -232.491351) (xy 354.635453 -232.541848) (xy 354.60468 -232.588361) (xy 354.567463 -232.629898)
			(xy 354.524595 -232.665573) (xy 354.476989 -232.694627) (xy 354.42566 -232.716439) (xy 354.371703 -232.730545)
			(xy 354.316266 -232.736645) (xy 354.260532 -232.734608) (xy 354.205689 -232.724478) (xy 354.152905 -232.706471)
			(xy 354.103305 -232.68097) (xy 354.057947 -232.648519) (xy 354.017798 -232.60981) (xy 353.983712 -232.565667)
			(xy 353.956416 -232.517032) (xy 353.936493 -232.464941) (xy 353.924367 -232.410504) (xy 353.920296 -232.354882)
			(xy 342.303335 -232.354882) (xy 340.09711 -234.560872) (xy 340.088759 -234.570143) (xy 340.081455 -234.593973)
			(xy 340.08314 -234.606338) (xy 340.099142 -234.689142) (xy 340.102033 -234.701231) (xy 340.117488 -234.720664)
			(xy 340.128606 -234.726226) (xy 340.12886 -234.726226) (xy 340.154261 -234.737628) (xy 340.201738 -234.76671)
			(xy 340.244486 -234.802382) (xy 340.281597 -234.843886) (xy 340.312284 -234.890342) (xy 340.335896 -234.940764)
			(xy 340.351931 -234.994081) (xy 340.360049 -235.049162) (xy 340.360508 -235.077) (xy 340.612982 -235.077)
			(xy 340.617053 -235.021378) (xy 340.629179 -234.966941) (xy 340.649102 -234.91485) (xy 340.676398 -234.866215)
			(xy 340.710484 -234.822072) (xy 340.750633 -234.783363) (xy 340.795991 -234.750912) (xy 340.845591 -234.725411)
			(xy 340.898375 -234.707404) (xy 340.953218 -234.697274) (xy 341.008952 -234.695237) (xy 341.064389 -234.701337)
			(xy 341.118346 -234.715443) (xy 341.169675 -234.737255) (xy 341.217281 -234.766309) (xy 341.260149 -234.801984)
			(xy 341.297366 -234.843521) (xy 341.328139 -234.890034) (xy 341.351811 -234.940531) (xy 341.367879 -234.993938)
			(xy 341.375999 -235.049114) (xy 341.376508 -235.077) (xy 341.628982 -235.077) (xy 341.633053 -235.021378)
			(xy 341.645179 -234.966941) (xy 341.665102 -234.91485) (xy 341.692398 -234.866215) (xy 341.726484 -234.822072)
			(xy 341.766633 -234.783363) (xy 341.811991 -234.750912) (xy 341.861591 -234.725411) (xy 341.914375 -234.707404)
			(xy 341.969218 -234.697274) (xy 342.024952 -234.695237) (xy 342.080389 -234.701337) (xy 342.134346 -234.715443)
			(xy 342.185675 -234.737255) (xy 342.233281 -234.766309) (xy 342.276149 -234.801984) (xy 342.313366 -234.843521)
			(xy 342.344139 -234.890034) (xy 342.367811 -234.940531) (xy 342.383879 -234.993938) (xy 342.391999 -235.049114)
			(xy 342.392508 -235.077) (xy 342.644982 -235.077) (xy 342.649053 -235.021378) (xy 342.661179 -234.966941)
			(xy 342.681102 -234.91485) (xy 342.708398 -234.866215) (xy 342.742484 -234.822072) (xy 342.782633 -234.783363)
			(xy 342.827991 -234.750912) (xy 342.877591 -234.725411) (xy 342.930375 -234.707404) (xy 342.985218 -234.697274)
			(xy 343.040952 -234.695237) (xy 343.096389 -234.701337) (xy 343.150346 -234.715443) (xy 343.201675 -234.737255)
			(xy 343.249281 -234.766309) (xy 343.292149 -234.801984) (xy 343.329366 -234.843521) (xy 343.360139 -234.890034)
			(xy 343.383811 -234.940531) (xy 343.399879 -234.993938) (xy 343.407999 -235.049114) (xy 343.408508 -235.077)
			(xy 343.660982 -235.077) (xy 343.665053 -235.021378) (xy 343.677179 -234.966941) (xy 343.697102 -234.91485)
			(xy 343.724398 -234.866215) (xy 343.758484 -234.822072) (xy 343.798633 -234.783363) (xy 343.843991 -234.750912)
			(xy 343.893591 -234.725411) (xy 343.946375 -234.707404) (xy 344.001218 -234.697274) (xy 344.056952 -234.695237)
			(xy 344.112389 -234.701337) (xy 344.166346 -234.715443) (xy 344.217675 -234.737255) (xy 344.265281 -234.766309)
			(xy 344.308149 -234.801984) (xy 344.345366 -234.843521) (xy 344.376139 -234.890034) (xy 344.399811 -234.940531)
			(xy 344.415879 -234.993938) (xy 344.423999 -235.049114) (xy 344.424508 -235.077) (xy 344.676982 -235.077)
			(xy 344.681053 -235.021378) (xy 344.693179 -234.966941) (xy 344.713102 -234.91485) (xy 344.740398 -234.866215)
			(xy 344.774484 -234.822072) (xy 344.814633 -234.783363) (xy 344.859991 -234.750912) (xy 344.909591 -234.725411)
			(xy 344.962375 -234.707404) (xy 345.017218 -234.697274) (xy 345.072952 -234.695237) (xy 345.128389 -234.701337)
			(xy 345.182346 -234.715443) (xy 345.233675 -234.737255) (xy 345.281281 -234.766309) (xy 345.324149 -234.801984)
			(xy 345.361366 -234.843521) (xy 345.392139 -234.890034) (xy 345.415811 -234.940531) (xy 345.431879 -234.993938)
			(xy 345.439999 -235.049114) (xy 345.440508 -235.077) (xy 345.692982 -235.077) (xy 345.697053 -235.021378)
			(xy 345.709179 -234.966941) (xy 345.729102 -234.91485) (xy 345.756398 -234.866215) (xy 345.790484 -234.822072)
			(xy 345.830633 -234.783363) (xy 345.875991 -234.750912) (xy 345.925591 -234.725411) (xy 345.978375 -234.707404)
			(xy 346.033218 -234.697274) (xy 346.088952 -234.695237) (xy 346.144389 -234.701337) (xy 346.198346 -234.715443)
			(xy 346.249675 -234.737255) (xy 346.297281 -234.766309) (xy 346.340149 -234.801984) (xy 346.377366 -234.843521)
			(xy 346.408139 -234.890034) (xy 346.431811 -234.940531) (xy 346.447879 -234.993938) (xy 346.455999 -235.049114)
			(xy 346.456508 -235.077) (xy 346.708982 -235.077) (xy 346.713053 -235.021378) (xy 346.725179 -234.966941)
			(xy 346.745102 -234.91485) (xy 346.772398 -234.866215) (xy 346.806484 -234.822072) (xy 346.846633 -234.783363)
			(xy 346.891991 -234.750912) (xy 346.941591 -234.725411) (xy 346.994375 -234.707404) (xy 347.049218 -234.697274)
			(xy 347.104952 -234.695237) (xy 347.160389 -234.701337) (xy 347.214346 -234.715443) (xy 347.265675 -234.737255)
			(xy 347.313281 -234.766309) (xy 347.356149 -234.801984) (xy 347.393366 -234.843521) (xy 347.424139 -234.890034)
			(xy 347.447811 -234.940531) (xy 347.463879 -234.993938) (xy 347.471999 -235.049114) (xy 347.472508 -235.077)
			(xy 347.724982 -235.077) (xy 347.729053 -235.021378) (xy 347.741179 -234.966941) (xy 347.761102 -234.91485)
			(xy 347.788398 -234.866215) (xy 347.822484 -234.822072) (xy 347.862633 -234.783363) (xy 347.907991 -234.750912)
			(xy 347.957591 -234.725411) (xy 348.010375 -234.707404) (xy 348.065218 -234.697274) (xy 348.120952 -234.695237)
			(xy 348.176389 -234.701337) (xy 348.230346 -234.715443) (xy 348.281675 -234.737255) (xy 348.329281 -234.766309)
			(xy 348.372149 -234.801984) (xy 348.409366 -234.843521) (xy 348.440139 -234.890034) (xy 348.463811 -234.940531)
			(xy 348.479879 -234.993938) (xy 348.487999 -235.049114) (xy 348.488508 -235.077) (xy 348.488016 -235.103969)
			(xy 348.708447 -235.103969) (xy 348.708447 -235.049431) (xy 348.716209 -234.995448) (xy 348.731575 -234.94312)
			(xy 348.754232 -234.893511) (xy 348.783718 -234.847632) (xy 348.819434 -234.806416) (xy 348.860653 -234.770703)
			(xy 348.906534 -234.741219) (xy 348.956144 -234.718566) (xy 349.008474 -234.703204) (xy 349.062457 -234.695446)
			(xy 349.089726 -234.694984) (xy 349.112078 -234.695746) (xy 349.123 -234.695492) (xy 349.150251 -234.695978)
			(xy 349.204199 -234.703734) (xy 349.256494 -234.719089) (xy 349.306071 -234.741731) (xy 349.351921 -234.771197)
			(xy 349.393112 -234.806888) (xy 349.428803 -234.848079) (xy 349.458269 -234.893929) (xy 349.480911 -234.943506)
			(xy 349.496266 -234.995801) (xy 349.504022 -235.049749) (xy 349.504022 -235.077) (xy 349.756982 -235.077)
			(xy 349.761053 -235.021378) (xy 349.773179 -234.966941) (xy 349.793102 -234.91485) (xy 349.820398 -234.866215)
			(xy 349.854484 -234.822072) (xy 349.894633 -234.783363) (xy 349.939991 -234.750912) (xy 349.989591 -234.725411)
			(xy 350.042375 -234.707404) (xy 350.097218 -234.697274) (xy 350.152952 -234.695237) (xy 350.208389 -234.701337)
			(xy 350.262346 -234.715443) (xy 350.313675 -234.737255) (xy 350.361281 -234.766309) (xy 350.404149 -234.801984)
			(xy 350.441366 -234.843521) (xy 350.472139 -234.890034) (xy 350.495811 -234.940531) (xy 350.511879 -234.993938)
			(xy 350.519999 -235.049114) (xy 350.520508 -235.077) (xy 350.772982 -235.077) (xy 350.777053 -235.021378)
			(xy 350.789179 -234.966941) (xy 350.809102 -234.91485) (xy 350.836398 -234.866215) (xy 350.870484 -234.822072)
			(xy 350.910633 -234.783363) (xy 350.955991 -234.750912) (xy 351.005591 -234.725411) (xy 351.058375 -234.707404)
			(xy 351.113218 -234.697274) (xy 351.168952 -234.695237) (xy 351.224389 -234.701337) (xy 351.278346 -234.715443)
			(xy 351.329675 -234.737255) (xy 351.377281 -234.766309) (xy 351.420149 -234.801984) (xy 351.457366 -234.843521)
			(xy 351.488139 -234.890034) (xy 351.511811 -234.940531) (xy 351.527879 -234.993938) (xy 351.535999 -235.049114)
			(xy 351.536508 -235.077) (xy 351.535999 -235.104886) (xy 351.527879 -235.160062) (xy 351.511811 -235.213469)
			(xy 351.488139 -235.263966) (xy 351.465917 -235.297555) (xy 354.773649 -235.297555) (xy 354.773649 -235.243045)
			(xy 354.781408 -235.18909) (xy 354.796766 -235.136788) (xy 354.819411 -235.087205) (xy 354.848883 -235.041349)
			(xy 354.884582 -235.000155) (xy 354.92578 -234.964461) (xy 354.971638 -234.934993) (xy 355.021224 -234.912352)
			(xy 355.073527 -234.896999) (xy 355.127483 -234.889247) (xy 355.154738 -234.888786) (xy 355.179705 -234.889166)
			(xy 355.229214 -234.895676) (xy 355.277449 -234.908592) (xy 355.323586 -234.927694) (xy 355.366835 -234.952654)
			(xy 355.386894 -234.967526) (xy 355.39553 -234.97413) (xy 355.41585 -234.97921) (xy 355.510846 -234.962954)
			(xy 355.528372 -234.951524) (xy 355.534214 -234.94238) (xy 355.549413 -234.919939) (xy 355.585092 -234.87914)
			(xy 355.626187 -234.843803) (xy 355.67187 -234.81464) (xy 355.721222 -234.792237) (xy 355.773248 -234.777046)
			(xy 355.826901 -234.769374) (xy 355.854 -234.768898) (xy 355.881252 -234.769372) (xy 355.9352 -234.777128)
			(xy 355.987496 -234.792484) (xy 356.037074 -234.815125) (xy 356.082925 -234.844592) (xy 356.124116 -234.880284)
			(xy 356.159808 -234.921475) (xy 356.189275 -234.967326) (xy 356.211916 -235.016904) (xy 356.227272 -235.0692)
			(xy 356.235028 -235.123148) (xy 356.235028 -235.177652) (xy 356.227272 -235.2316) (xy 356.211916 -235.283896)
			(xy 356.189275 -235.333474) (xy 356.159808 -235.379325) (xy 356.124116 -235.420516) (xy 356.082925 -235.456208)
			(xy 356.037074 -235.485675) (xy 355.987496 -235.508316) (xy 355.9352 -235.523672) (xy 355.881252 -235.531428)
			(xy 355.854 -235.531914) (xy 355.829032 -235.53153) (xy 355.779522 -235.525025) (xy 355.731285 -235.512113)
			(xy 355.685145 -235.493015) (xy 355.641894 -235.468058) (xy 355.621844 -235.453174) (xy 355.613208 -235.44657)
			(xy 355.592888 -235.44149) (xy 355.497892 -235.457746) (xy 355.480366 -235.469176) (xy 355.474524 -235.47832)
			(xy 355.459365 -235.50079) (xy 355.42368 -235.541588) (xy 355.382578 -235.576923) (xy 355.336888 -235.606083)
			(xy 355.287529 -235.628481) (xy 355.235497 -235.643666) (xy 355.181839 -235.651331) (xy 355.154738 -235.651802)
			(xy 355.127483 -235.651353) (xy 355.073527 -235.643601) (xy 355.021224 -235.628248) (xy 354.971638 -235.605607)
			(xy 354.92578 -235.576139) (xy 354.884582 -235.540445) (xy 354.848883 -235.499251) (xy 354.819411 -235.453395)
			(xy 354.796766 -235.403812) (xy 354.781408 -235.35151) (xy 354.773649 -235.297555) (xy 351.465917 -235.297555)
			(xy 351.457366 -235.310479) (xy 351.420149 -235.352016) (xy 351.377281 -235.387691) (xy 351.329675 -235.416745)
			(xy 351.278346 -235.438557) (xy 351.224389 -235.452663) (xy 351.168952 -235.458763) (xy 351.113218 -235.456726)
			(xy 351.058375 -235.446596) (xy 351.005591 -235.428589) (xy 350.955991 -235.403088) (xy 350.910633 -235.370637)
			(xy 350.870484 -235.331928) (xy 350.836398 -235.287785) (xy 350.809102 -235.23915) (xy 350.789179 -235.187059)
			(xy 350.777053 -235.132622) (xy 350.772982 -235.077) (xy 350.520508 -235.077) (xy 350.519999 -235.104886)
			(xy 350.511879 -235.160062) (xy 350.495811 -235.213469) (xy 350.472139 -235.263966) (xy 350.441366 -235.310479)
			(xy 350.404149 -235.352016) (xy 350.361281 -235.387691) (xy 350.313675 -235.416745) (xy 350.262346 -235.438557)
			(xy 350.208389 -235.452663) (xy 350.152952 -235.458763) (xy 350.097218 -235.456726) (xy 350.042375 -235.446596)
			(xy 349.989591 -235.428589) (xy 349.939991 -235.403088) (xy 349.894633 -235.370637) (xy 349.854484 -235.331928)
			(xy 349.820398 -235.287785) (xy 349.793102 -235.23915) (xy 349.773179 -235.187059) (xy 349.761053 -235.132622)
			(xy 349.756982 -235.077) (xy 349.504022 -235.077) (xy 349.504022 -235.104251) (xy 349.496266 -235.158199)
			(xy 349.480911 -235.210494) (xy 349.458269 -235.260071) (xy 349.428803 -235.305921) (xy 349.393112 -235.347112)
			(xy 349.351921 -235.382803) (xy 349.306071 -235.412269) (xy 349.256494 -235.434911) (xy 349.204199 -235.450266)
			(xy 349.150251 -235.458022) (xy 349.123 -235.458508) (xy 349.10649 -235.458254) (xy 349.089726 -235.458508)
			(xy 349.062457 -235.457954) (xy 349.008474 -235.450196) (xy 348.956144 -235.434834) (xy 348.906534 -235.412181)
			(xy 348.860653 -235.382697) (xy 348.819434 -235.346984) (xy 348.783718 -235.305768) (xy 348.754232 -235.259889)
			(xy 348.731575 -235.21028) (xy 348.716209 -235.157952) (xy 348.708447 -235.103969) (xy 348.488016 -235.103969)
			(xy 348.487999 -235.104886) (xy 348.479879 -235.160062) (xy 348.463811 -235.213469) (xy 348.440139 -235.263966)
			(xy 348.409366 -235.310479) (xy 348.372149 -235.352016) (xy 348.329281 -235.387691) (xy 348.281675 -235.416745)
			(xy 348.230346 -235.438557) (xy 348.176389 -235.452663) (xy 348.120952 -235.458763) (xy 348.065218 -235.456726)
			(xy 348.010375 -235.446596) (xy 347.957591 -235.428589) (xy 347.907991 -235.403088) (xy 347.862633 -235.370637)
			(xy 347.822484 -235.331928) (xy 347.788398 -235.287785) (xy 347.761102 -235.23915) (xy 347.741179 -235.187059)
			(xy 347.729053 -235.132622) (xy 347.724982 -235.077) (xy 347.472508 -235.077) (xy 347.471999 -235.104886)
			(xy 347.463879 -235.160062) (xy 347.447811 -235.213469) (xy 347.424139 -235.263966) (xy 347.393366 -235.310479)
			(xy 347.356149 -235.352016) (xy 347.313281 -235.387691) (xy 347.265675 -235.416745) (xy 347.214346 -235.438557)
			(xy 347.160389 -235.452663) (xy 347.104952 -235.458763) (xy 347.049218 -235.456726) (xy 346.994375 -235.446596)
			(xy 346.941591 -235.428589) (xy 346.891991 -235.403088) (xy 346.846633 -235.370637) (xy 346.806484 -235.331928)
			(xy 346.772398 -235.287785) (xy 346.745102 -235.23915) (xy 346.725179 -235.187059) (xy 346.713053 -235.132622)
			(xy 346.708982 -235.077) (xy 346.456508 -235.077) (xy 346.455999 -235.104886) (xy 346.447879 -235.160062)
			(xy 346.431811 -235.213469) (xy 346.408139 -235.263966) (xy 346.377366 -235.310479) (xy 346.340149 -235.352016)
			(xy 346.297281 -235.387691) (xy 346.249675 -235.416745) (xy 346.198346 -235.438557) (xy 346.144389 -235.452663)
			(xy 346.088952 -235.458763) (xy 346.033218 -235.456726) (xy 345.978375 -235.446596) (xy 345.925591 -235.428589)
			(xy 345.875991 -235.403088) (xy 345.830633 -235.370637) (xy 345.790484 -235.331928) (xy 345.756398 -235.287785)
			(xy 345.729102 -235.23915) (xy 345.709179 -235.187059) (xy 345.697053 -235.132622) (xy 345.692982 -235.077)
			(xy 345.440508 -235.077) (xy 345.439999 -235.104886) (xy 345.431879 -235.160062) (xy 345.415811 -235.213469)
			(xy 345.392139 -235.263966) (xy 345.361366 -235.310479) (xy 345.324149 -235.352016) (xy 345.281281 -235.387691)
			(xy 345.233675 -235.416745) (xy 345.182346 -235.438557) (xy 345.128389 -235.452663) (xy 345.072952 -235.458763)
			(xy 345.017218 -235.456726) (xy 344.962375 -235.446596) (xy 344.909591 -235.428589) (xy 344.859991 -235.403088)
			(xy 344.814633 -235.370637) (xy 344.774484 -235.331928) (xy 344.740398 -235.287785) (xy 344.713102 -235.23915)
			(xy 344.693179 -235.187059) (xy 344.681053 -235.132622) (xy 344.676982 -235.077) (xy 344.424508 -235.077)
			(xy 344.423999 -235.104886) (xy 344.415879 -235.160062) (xy 344.399811 -235.213469) (xy 344.376139 -235.263966)
			(xy 344.345366 -235.310479) (xy 344.308149 -235.352016) (xy 344.265281 -235.387691) (xy 344.217675 -235.416745)
			(xy 344.166346 -235.438557) (xy 344.112389 -235.452663) (xy 344.056952 -235.458763) (xy 344.001218 -235.456726)
			(xy 343.946375 -235.446596) (xy 343.893591 -235.428589) (xy 343.843991 -235.403088) (xy 343.798633 -235.370637)
			(xy 343.758484 -235.331928) (xy 343.724398 -235.287785) (xy 343.697102 -235.23915) (xy 343.677179 -235.187059)
			(xy 343.665053 -235.132622) (xy 343.660982 -235.077) (xy 343.408508 -235.077) (xy 343.407999 -235.104886)
			(xy 343.399879 -235.160062) (xy 343.383811 -235.213469) (xy 343.360139 -235.263966) (xy 343.329366 -235.310479)
			(xy 343.292149 -235.352016) (xy 343.249281 -235.387691) (xy 343.201675 -235.416745) (xy 343.150346 -235.438557)
			(xy 343.096389 -235.452663) (xy 343.040952 -235.458763) (xy 342.985218 -235.456726) (xy 342.930375 -235.446596)
			(xy 342.877591 -235.428589) (xy 342.827991 -235.403088) (xy 342.782633 -235.370637) (xy 342.742484 -235.331928)
			(xy 342.708398 -235.287785) (xy 342.681102 -235.23915) (xy 342.661179 -235.187059) (xy 342.649053 -235.132622)
			(xy 342.644982 -235.077) (xy 342.392508 -235.077) (xy 342.391999 -235.104886) (xy 342.383879 -235.160062)
			(xy 342.367811 -235.213469) (xy 342.344139 -235.263966) (xy 342.313366 -235.310479) (xy 342.276149 -235.352016)
			(xy 342.233281 -235.387691) (xy 342.185675 -235.416745) (xy 342.134346 -235.438557) (xy 342.080389 -235.452663)
			(xy 342.024952 -235.458763) (xy 341.969218 -235.456726) (xy 341.914375 -235.446596) (xy 341.861591 -235.428589)
			(xy 341.811991 -235.403088) (xy 341.766633 -235.370637) (xy 341.726484 -235.331928) (xy 341.692398 -235.287785)
			(xy 341.665102 -235.23915) (xy 341.645179 -235.187059) (xy 341.633053 -235.132622) (xy 341.628982 -235.077)
			(xy 341.376508 -235.077) (xy 341.375999 -235.104886) (xy 341.367879 -235.160062) (xy 341.351811 -235.213469)
			(xy 341.328139 -235.263966) (xy 341.297366 -235.310479) (xy 341.260149 -235.352016) (xy 341.217281 -235.387691)
			(xy 341.169675 -235.416745) (xy 341.118346 -235.438557) (xy 341.064389 -235.452663) (xy 341.008952 -235.458763)
			(xy 340.953218 -235.456726) (xy 340.898375 -235.446596) (xy 340.845591 -235.428589) (xy 340.795991 -235.403088)
			(xy 340.750633 -235.370637) (xy 340.710484 -235.331928) (xy 340.676398 -235.287785) (xy 340.649102 -235.23915)
			(xy 340.629179 -235.187059) (xy 340.617053 -235.132622) (xy 340.612982 -235.077) (xy 340.360508 -235.077)
			(xy 340.360022 -235.104251) (xy 340.352266 -235.158199) (xy 340.336911 -235.210494) (xy 340.314269 -235.260071)
			(xy 340.284803 -235.305921) (xy 340.249112 -235.347112) (xy 340.207921 -235.382803) (xy 340.162071 -235.412269)
			(xy 340.112494 -235.434911) (xy 340.060199 -235.450266) (xy 340.006251 -235.458022) (xy 339.979 -235.458508)
			(xy 339.951173 -235.458004) (xy 339.89611 -235.44992) (xy 339.842805 -235.433923) (xy 339.792389 -235.410353)
			(xy 339.745932 -235.37971) (xy 339.704418 -235.342643) (xy 339.668729 -235.29994) (xy 339.639622 -235.252505)
			(xy 339.628226 -235.227114) (xy 339.628226 -235.226606) (xy 339.622529 -235.2156) (xy 339.603148 -235.20022)
			(xy 339.591142 -235.197142) (xy 339.508338 -235.18114) (xy 339.495973 -235.179393) (xy 339.472138 -235.186736)
			(xy 339.462872 -235.19511) (xy 338.863178 -235.794804) (xy 338.855778 -235.801646) (xy 338.83718 -235.809372)
			(xy 338.82711 -235.80979) (xy 335.775808 -235.80979) (xy 335.667096 -235.918502) (xy 335.625694 -235.918502)
			(xy 335.576672 -235.967524) (xy 333.45755 -235.967524) (xy 333.455326 -235.996316) (xy 333.443292 -236.052794)
			(xy 333.422891 -236.106816) (xy 333.394587 -236.157149) (xy 333.359026 -236.202646) (xy 333.31702 -236.24227)
			(xy 333.269525 -236.275116) (xy 333.217626 -236.300435) (xy 333.162506 -236.31765) (xy 333.105423 -236.326368)
			(xy 333.07655 -236.326934) (xy 333.049284 -236.326444) (xy 332.995307 -236.318677) (xy 332.942985 -236.303307)
			(xy 332.893383 -236.280647) (xy 332.84751 -236.251159) (xy 332.806301 -236.215444) (xy 332.770594 -236.174227)
			(xy 332.741115 -236.128349) (xy 332.718466 -236.078742) (xy 332.703107 -236.026417) (xy 332.69535 -235.972438)
			(xy 332.694788 -235.945172) (xy 332.695804 -235.918502) (xy 332.696347 -235.904589) (xy 332.690721 -235.87733)
			(xy 332.67794 -235.852604) (xy 332.658955 -235.83225) (xy 332.635177 -235.817781) (xy 332.608375 -235.810273)
			(xy 332.594458 -235.80979) (xy 331.868526 -235.80979) (xy 331.839062 -235.838492) (xy 331.838554 -235.85932)
			(xy 331.837495 -235.88617) (xy 331.828767 -235.939191) (xy 331.812685 -235.990462) (xy 331.789567 -236.038969)
			(xy 331.759869 -236.083752) (xy 331.724181 -236.123923) (xy 331.683209 -236.158688) (xy 331.637763 -236.18736)
			(xy 331.588743 -236.209369) (xy 331.537119 -236.224281) (xy 331.483913 -236.231801) (xy 331.457046 -236.232192)
			(xy 331.430451 -236.231734) (xy 331.377775 -236.224353) (xy 331.326634 -236.209728) (xy 331.27802 -236.188142)
			(xy 331.232876 -236.160013) (xy 331.21219 -236.143292) (xy 331.179678 -236.131354) (xy 331.169611 -236.131783)
			(xy 331.151017 -236.139509) (xy 331.14361 -236.14634) (xy 330.94295 -236.347) (xy 339.596982 -236.347)
			(xy 339.601053 -236.291378) (xy 339.613179 -236.236941) (xy 339.633102 -236.18485) (xy 339.660398 -236.136215)
			(xy 339.694484 -236.092072) (xy 339.734633 -236.053363) (xy 339.779991 -236.020912) (xy 339.829591 -235.995411)
			(xy 339.882375 -235.977404) (xy 339.937218 -235.967274) (xy 339.992952 -235.965237) (xy 340.048389 -235.971337)
			(xy 340.102346 -235.985443) (xy 340.153675 -236.007255) (xy 340.201281 -236.036309) (xy 340.244149 -236.071984)
			(xy 340.281366 -236.113521) (xy 340.312139 -236.160034) (xy 340.335811 -236.210531) (xy 340.351879 -236.263938)
			(xy 340.359999 -236.319114) (xy 340.360508 -236.347) (xy 340.612982 -236.347) (xy 340.617053 -236.291378)
			(xy 340.629179 -236.236941) (xy 340.649102 -236.18485) (xy 340.676398 -236.136215) (xy 340.710484 -236.092072)
			(xy 340.750633 -236.053363) (xy 340.795991 -236.020912) (xy 340.845591 -235.995411) (xy 340.898375 -235.977404)
			(xy 340.953218 -235.967274) (xy 341.008952 -235.965237) (xy 341.064389 -235.971337) (xy 341.118346 -235.985443)
			(xy 341.169675 -236.007255) (xy 341.217281 -236.036309) (xy 341.260149 -236.071984) (xy 341.297366 -236.113521)
			(xy 341.328139 -236.160034) (xy 341.351811 -236.210531) (xy 341.367879 -236.263938) (xy 341.375999 -236.319114)
			(xy 341.376508 -236.347) (xy 341.628982 -236.347) (xy 341.633053 -236.291378) (xy 341.645179 -236.236941)
			(xy 341.665102 -236.18485) (xy 341.692398 -236.136215) (xy 341.726484 -236.092072) (xy 341.766633 -236.053363)
			(xy 341.811991 -236.020912) (xy 341.861591 -235.995411) (xy 341.914375 -235.977404) (xy 341.969218 -235.967274)
			(xy 342.024952 -235.965237) (xy 342.080389 -235.971337) (xy 342.134346 -235.985443) (xy 342.185675 -236.007255)
			(xy 342.233281 -236.036309) (xy 342.276149 -236.071984) (xy 342.313366 -236.113521) (xy 342.344139 -236.160034)
			(xy 342.367811 -236.210531) (xy 342.383879 -236.263938) (xy 342.391999 -236.319114) (xy 342.392508 -236.347)
			(xy 342.644982 -236.347) (xy 342.649053 -236.291378) (xy 342.661179 -236.236941) (xy 342.681102 -236.18485)
			(xy 342.708398 -236.136215) (xy 342.742484 -236.092072) (xy 342.782633 -236.053363) (xy 342.827991 -236.020912)
			(xy 342.877591 -235.995411) (xy 342.930375 -235.977404) (xy 342.985218 -235.967274) (xy 343.040952 -235.965237)
			(xy 343.096389 -235.971337) (xy 343.150346 -235.985443) (xy 343.201675 -236.007255) (xy 343.249281 -236.036309)
			(xy 343.292149 -236.071984) (xy 343.329366 -236.113521) (xy 343.360139 -236.160034) (xy 343.383811 -236.210531)
			(xy 343.399879 -236.263938) (xy 343.407999 -236.319114) (xy 343.408508 -236.347) (xy 343.660982 -236.347)
			(xy 343.665053 -236.291378) (xy 343.677179 -236.236941) (xy 343.697102 -236.18485) (xy 343.724398 -236.136215)
			(xy 343.758484 -236.092072) (xy 343.798633 -236.053363) (xy 343.843991 -236.020912) (xy 343.893591 -235.995411)
			(xy 343.946375 -235.977404) (xy 344.001218 -235.967274) (xy 344.056952 -235.965237) (xy 344.112389 -235.971337)
			(xy 344.166346 -235.985443) (xy 344.217675 -236.007255) (xy 344.265281 -236.036309) (xy 344.308149 -236.071984)
			(xy 344.345366 -236.113521) (xy 344.376139 -236.160034) (xy 344.399811 -236.210531) (xy 344.415879 -236.263938)
			(xy 344.423999 -236.319114) (xy 344.424508 -236.347) (xy 344.676982 -236.347) (xy 344.681053 -236.291378)
			(xy 344.693179 -236.236941) (xy 344.713102 -236.18485) (xy 344.740398 -236.136215) (xy 344.774484 -236.092072)
			(xy 344.814633 -236.053363) (xy 344.859991 -236.020912) (xy 344.909591 -235.995411) (xy 344.962375 -235.977404)
			(xy 345.017218 -235.967274) (xy 345.072952 -235.965237) (xy 345.128389 -235.971337) (xy 345.182346 -235.985443)
			(xy 345.233675 -236.007255) (xy 345.281281 -236.036309) (xy 345.324149 -236.071984) (xy 345.361366 -236.113521)
			(xy 345.392139 -236.160034) (xy 345.415811 -236.210531) (xy 345.431879 -236.263938) (xy 345.439999 -236.319114)
			(xy 345.440508 -236.347) (xy 345.692982 -236.347) (xy 345.697053 -236.291378) (xy 345.709179 -236.236941)
			(xy 345.729102 -236.18485) (xy 345.756398 -236.136215) (xy 345.790484 -236.092072) (xy 345.830633 -236.053363)
			(xy 345.875991 -236.020912) (xy 345.925591 -235.995411) (xy 345.978375 -235.977404) (xy 346.033218 -235.967274)
			(xy 346.088952 -235.965237) (xy 346.144389 -235.971337) (xy 346.198346 -235.985443) (xy 346.249675 -236.007255)
			(xy 346.297281 -236.036309) (xy 346.340149 -236.071984) (xy 346.377366 -236.113521) (xy 346.408139 -236.160034)
			(xy 346.431811 -236.210531) (xy 346.447879 -236.263938) (xy 346.455999 -236.319114) (xy 346.456508 -236.347)
			(xy 346.708982 -236.347) (xy 346.713053 -236.291378) (xy 346.725179 -236.236941) (xy 346.745102 -236.18485)
			(xy 346.772398 -236.136215) (xy 346.806484 -236.092072) (xy 346.846633 -236.053363) (xy 346.891991 -236.020912)
			(xy 346.941591 -235.995411) (xy 346.994375 -235.977404) (xy 347.049218 -235.967274) (xy 347.104952 -235.965237)
			(xy 347.160389 -235.971337) (xy 347.214346 -235.985443) (xy 347.265675 -236.007255) (xy 347.313281 -236.036309)
			(xy 347.356149 -236.071984) (xy 347.393366 -236.113521) (xy 347.424139 -236.160034) (xy 347.447811 -236.210531)
			(xy 347.463879 -236.263938) (xy 347.471999 -236.319114) (xy 347.472508 -236.347) (xy 347.724982 -236.347)
			(xy 347.729053 -236.291378) (xy 347.741179 -236.236941) (xy 347.761102 -236.18485) (xy 347.788398 -236.136215)
			(xy 347.822484 -236.092072) (xy 347.862633 -236.053363) (xy 347.907991 -236.020912) (xy 347.957591 -235.995411)
			(xy 348.010375 -235.977404) (xy 348.065218 -235.967274) (xy 348.120952 -235.965237) (xy 348.176389 -235.971337)
			(xy 348.230346 -235.985443) (xy 348.281675 -236.007255) (xy 348.329281 -236.036309) (xy 348.372149 -236.071984)
			(xy 348.409366 -236.113521) (xy 348.440139 -236.160034) (xy 348.463811 -236.210531) (xy 348.479879 -236.263938)
			(xy 348.487999 -236.319114) (xy 348.488508 -236.347) (xy 348.740982 -236.347) (xy 348.745053 -236.291378)
			(xy 348.757179 -236.236941) (xy 348.777102 -236.18485) (xy 348.804398 -236.136215) (xy 348.838484 -236.092072)
			(xy 348.878633 -236.053363) (xy 348.923991 -236.020912) (xy 348.973591 -235.995411) (xy 349.026375 -235.977404)
			(xy 349.081218 -235.967274) (xy 349.136952 -235.965237) (xy 349.192389 -235.971337) (xy 349.246346 -235.985443)
			(xy 349.297675 -236.007255) (xy 349.345281 -236.036309) (xy 349.388149 -236.071984) (xy 349.425366 -236.113521)
			(xy 349.456139 -236.160034) (xy 349.479811 -236.210531) (xy 349.495879 -236.263938) (xy 349.503999 -236.319114)
			(xy 349.504508 -236.347) (xy 349.756982 -236.347) (xy 349.761053 -236.291378) (xy 349.773179 -236.236941)
			(xy 349.793102 -236.18485) (xy 349.820398 -236.136215) (xy 349.854484 -236.092072) (xy 349.894633 -236.053363)
			(xy 349.939991 -236.020912) (xy 349.989591 -235.995411) (xy 350.042375 -235.977404) (xy 350.097218 -235.967274)
			(xy 350.152952 -235.965237) (xy 350.208389 -235.971337) (xy 350.262346 -235.985443) (xy 350.313675 -236.007255)
			(xy 350.361281 -236.036309) (xy 350.404149 -236.071984) (xy 350.441366 -236.113521) (xy 350.472139 -236.160034)
			(xy 350.495811 -236.210531) (xy 350.511879 -236.263938) (xy 350.515917 -236.291374) (xy 350.842832 -236.291374)
			(xy 350.846903 -236.235752) (xy 350.859029 -236.181315) (xy 350.878952 -236.129224) (xy 350.906248 -236.080589)
			(xy 350.940334 -236.036446) (xy 350.980483 -235.997737) (xy 351.025841 -235.965286) (xy 351.075441 -235.939785)
			(xy 351.128225 -235.921778) (xy 351.183068 -235.911648) (xy 351.238802 -235.909611) (xy 351.294239 -235.915711)
			(xy 351.348196 -235.929817) (xy 351.399525 -235.951629) (xy 351.447131 -235.980683) (xy 351.489999 -236.016358)
			(xy 351.527216 -236.057895) (xy 351.557989 -236.104408) (xy 351.581661 -236.154905) (xy 351.597729 -236.208312)
			(xy 351.605849 -236.263488) (xy 351.606358 -236.291374) (xy 351.605849 -236.31926) (xy 351.597729 -236.374436)
			(xy 351.581661 -236.427843) (xy 351.557989 -236.47834) (xy 351.527216 -236.524853) (xy 351.489999 -236.56639)
			(xy 351.447131 -236.602065) (xy 351.399525 -236.631119) (xy 351.348196 -236.652931) (xy 351.294239 -236.667037)
			(xy 351.238802 -236.673137) (xy 351.183068 -236.6711) (xy 351.128225 -236.66097) (xy 351.075441 -236.642963)
			(xy 351.025841 -236.617462) (xy 350.980483 -236.585011) (xy 350.940334 -236.546302) (xy 350.906248 -236.502159)
			(xy 350.878952 -236.453524) (xy 350.859029 -236.401433) (xy 350.846903 -236.346996) (xy 350.842832 -236.291374)
			(xy 350.515917 -236.291374) (xy 350.519999 -236.319114) (xy 350.520508 -236.347) (xy 350.519999 -236.374886)
			(xy 350.511879 -236.430062) (xy 350.495811 -236.483469) (xy 350.472139 -236.533966) (xy 350.441366 -236.580479)
			(xy 350.404149 -236.622016) (xy 350.361281 -236.657691) (xy 350.313675 -236.686745) (xy 350.262346 -236.708557)
			(xy 350.208389 -236.722663) (xy 350.152952 -236.728763) (xy 350.097218 -236.726726) (xy 350.042375 -236.716596)
			(xy 349.989591 -236.698589) (xy 349.939991 -236.673088) (xy 349.894633 -236.640637) (xy 349.854484 -236.601928)
			(xy 349.820398 -236.557785) (xy 349.793102 -236.50915) (xy 349.773179 -236.457059) (xy 349.761053 -236.402622)
			(xy 349.756982 -236.347) (xy 349.504508 -236.347) (xy 349.503999 -236.374886) (xy 349.495879 -236.430062)
			(xy 349.479811 -236.483469) (xy 349.456139 -236.533966) (xy 349.425366 -236.580479) (xy 349.388149 -236.622016)
			(xy 349.345281 -236.657691) (xy 349.297675 -236.686745) (xy 349.246346 -236.708557) (xy 349.192389 -236.722663)
			(xy 349.136952 -236.728763) (xy 349.081218 -236.726726) (xy 349.026375 -236.716596) (xy 348.973591 -236.698589)
			(xy 348.923991 -236.673088) (xy 348.878633 -236.640637) (xy 348.838484 -236.601928) (xy 348.804398 -236.557785)
			(xy 348.777102 -236.50915) (xy 348.757179 -236.457059) (xy 348.745053 -236.402622) (xy 348.740982 -236.347)
			(xy 348.488508 -236.347) (xy 348.487999 -236.374886) (xy 348.479879 -236.430062) (xy 348.463811 -236.483469)
			(xy 348.440139 -236.533966) (xy 348.409366 -236.580479) (xy 348.372149 -236.622016) (xy 348.329281 -236.657691)
			(xy 348.281675 -236.686745) (xy 348.230346 -236.708557) (xy 348.176389 -236.722663) (xy 348.120952 -236.728763)
			(xy 348.065218 -236.726726) (xy 348.010375 -236.716596) (xy 347.957591 -236.698589) (xy 347.907991 -236.673088)
			(xy 347.862633 -236.640637) (xy 347.822484 -236.601928) (xy 347.788398 -236.557785) (xy 347.761102 -236.50915)
			(xy 347.741179 -236.457059) (xy 347.729053 -236.402622) (xy 347.724982 -236.347) (xy 347.472508 -236.347)
			(xy 347.471999 -236.374886) (xy 347.463879 -236.430062) (xy 347.447811 -236.483469) (xy 347.424139 -236.533966)
			(xy 347.393366 -236.580479) (xy 347.356149 -236.622016) (xy 347.313281 -236.657691) (xy 347.265675 -236.686745)
			(xy 347.214346 -236.708557) (xy 347.160389 -236.722663) (xy 347.104952 -236.728763) (xy 347.049218 -236.726726)
			(xy 346.994375 -236.716596) (xy 346.941591 -236.698589) (xy 346.891991 -236.673088) (xy 346.846633 -236.640637)
			(xy 346.806484 -236.601928) (xy 346.772398 -236.557785) (xy 346.745102 -236.50915) (xy 346.725179 -236.457059)
			(xy 346.713053 -236.402622) (xy 346.708982 -236.347) (xy 346.456508 -236.347) (xy 346.455999 -236.374886)
			(xy 346.447879 -236.430062) (xy 346.431811 -236.483469) (xy 346.408139 -236.533966) (xy 346.377366 -236.580479)
			(xy 346.340149 -236.622016) (xy 346.297281 -236.657691) (xy 346.249675 -236.686745) (xy 346.198346 -236.708557)
			(xy 346.144389 -236.722663) (xy 346.088952 -236.728763) (xy 346.033218 -236.726726) (xy 345.978375 -236.716596)
			(xy 345.925591 -236.698589) (xy 345.875991 -236.673088) (xy 345.830633 -236.640637) (xy 345.790484 -236.601928)
			(xy 345.756398 -236.557785) (xy 345.729102 -236.50915) (xy 345.709179 -236.457059) (xy 345.697053 -236.402622)
			(xy 345.692982 -236.347) (xy 345.440508 -236.347) (xy 345.439999 -236.374886) (xy 345.431879 -236.430062)
			(xy 345.415811 -236.483469) (xy 345.392139 -236.533966) (xy 345.361366 -236.580479) (xy 345.324149 -236.622016)
			(xy 345.281281 -236.657691) (xy 345.233675 -236.686745) (xy 345.182346 -236.708557) (xy 345.128389 -236.722663)
			(xy 345.072952 -236.728763) (xy 345.017218 -236.726726) (xy 344.962375 -236.716596) (xy 344.909591 -236.698589)
			(xy 344.859991 -236.673088) (xy 344.814633 -236.640637) (xy 344.774484 -236.601928) (xy 344.740398 -236.557785)
			(xy 344.713102 -236.50915) (xy 344.693179 -236.457059) (xy 344.681053 -236.402622) (xy 344.676982 -236.347)
			(xy 344.424508 -236.347) (xy 344.423999 -236.374886) (xy 344.415879 -236.430062) (xy 344.399811 -236.483469)
			(xy 344.376139 -236.533966) (xy 344.345366 -236.580479) (xy 344.308149 -236.622016) (xy 344.265281 -236.657691)
			(xy 344.217675 -236.686745) (xy 344.166346 -236.708557) (xy 344.112389 -236.722663) (xy 344.056952 -236.728763)
			(xy 344.001218 -236.726726) (xy 343.946375 -236.716596) (xy 343.893591 -236.698589) (xy 343.843991 -236.673088)
			(xy 343.798633 -236.640637) (xy 343.758484 -236.601928) (xy 343.724398 -236.557785) (xy 343.697102 -236.50915)
			(xy 343.677179 -236.457059) (xy 343.665053 -236.402622) (xy 343.660982 -236.347) (xy 343.408508 -236.347)
			(xy 343.407999 -236.374886) (xy 343.399879 -236.430062) (xy 343.383811 -236.483469) (xy 343.360139 -236.533966)
			(xy 343.329366 -236.580479) (xy 343.292149 -236.622016) (xy 343.249281 -236.657691) (xy 343.201675 -236.686745)
			(xy 343.150346 -236.708557) (xy 343.096389 -236.722663) (xy 343.040952 -236.728763) (xy 342.985218 -236.726726)
			(xy 342.930375 -236.716596) (xy 342.877591 -236.698589) (xy 342.827991 -236.673088) (xy 342.782633 -236.640637)
			(xy 342.742484 -236.601928) (xy 342.708398 -236.557785) (xy 342.681102 -236.50915) (xy 342.661179 -236.457059)
			(xy 342.649053 -236.402622) (xy 342.644982 -236.347) (xy 342.392508 -236.347) (xy 342.391999 -236.374886)
			(xy 342.383879 -236.430062) (xy 342.367811 -236.483469) (xy 342.344139 -236.533966) (xy 342.313366 -236.580479)
			(xy 342.276149 -236.622016) (xy 342.233281 -236.657691) (xy 342.185675 -236.686745) (xy 342.134346 -236.708557)
			(xy 342.080389 -236.722663) (xy 342.024952 -236.728763) (xy 341.969218 -236.726726) (xy 341.914375 -236.716596)
			(xy 341.861591 -236.698589) (xy 341.811991 -236.673088) (xy 341.766633 -236.640637) (xy 341.726484 -236.601928)
			(xy 341.692398 -236.557785) (xy 341.665102 -236.50915) (xy 341.645179 -236.457059) (xy 341.633053 -236.402622)
			(xy 341.628982 -236.347) (xy 341.376508 -236.347) (xy 341.375999 -236.374886) (xy 341.367879 -236.430062)
			(xy 341.351811 -236.483469) (xy 341.328139 -236.533966) (xy 341.297366 -236.580479) (xy 341.260149 -236.622016)
			(xy 341.217281 -236.657691) (xy 341.169675 -236.686745) (xy 341.118346 -236.708557) (xy 341.064389 -236.722663)
			(xy 341.008952 -236.728763) (xy 340.953218 -236.726726) (xy 340.898375 -236.716596) (xy 340.845591 -236.698589)
			(xy 340.795991 -236.673088) (xy 340.750633 -236.640637) (xy 340.710484 -236.601928) (xy 340.676398 -236.557785)
			(xy 340.649102 -236.50915) (xy 340.629179 -236.457059) (xy 340.617053 -236.402622) (xy 340.612982 -236.347)
			(xy 340.360508 -236.347) (xy 340.359999 -236.374886) (xy 340.351879 -236.430062) (xy 340.335811 -236.483469)
			(xy 340.312139 -236.533966) (xy 340.281366 -236.580479) (xy 340.244149 -236.622016) (xy 340.201281 -236.657691)
			(xy 340.153675 -236.686745) (xy 340.102346 -236.708557) (xy 340.048389 -236.722663) (xy 339.992952 -236.728763)
			(xy 339.937218 -236.726726) (xy 339.882375 -236.716596) (xy 339.829591 -236.698589) (xy 339.779991 -236.673088)
			(xy 339.734633 -236.640637) (xy 339.694484 -236.601928) (xy 339.660398 -236.557785) (xy 339.633102 -236.50915)
			(xy 339.613179 -236.457059) (xy 339.601053 -236.402622) (xy 339.596982 -236.347) (xy 330.94295 -236.347)
			(xy 330.069952 -237.219998) (xy 330.069952 -237.25505) (xy 335.659982 -237.25505) (xy 335.664053 -237.199428)
			(xy 335.676179 -237.144991) (xy 335.696102 -237.0929) (xy 335.723398 -237.044265) (xy 335.757484 -237.000122)
			(xy 335.797633 -236.961413) (xy 335.842991 -236.928962) (xy 335.892591 -236.903461) (xy 335.945375 -236.885454)
			(xy 336.000218 -236.875324) (xy 336.055952 -236.873287) (xy 336.111389 -236.879387) (xy 336.165346 -236.893493)
			(xy 336.216675 -236.915305) (xy 336.264281 -236.944359) (xy 336.307149 -236.980034) (xy 336.344366 -237.021571)
			(xy 336.375139 -237.068084) (xy 336.398811 -237.118581) (xy 336.414879 -237.171988) (xy 336.417758 -237.19155)
			(xy 337.234528 -237.19155) (xy 337.238599 -237.135928) (xy 337.250725 -237.081491) (xy 337.270648 -237.0294)
			(xy 337.297944 -236.980765) (xy 337.33203 -236.936622) (xy 337.372179 -236.897913) (xy 337.417537 -236.865462)
			(xy 337.467137 -236.839961) (xy 337.519921 -236.821954) (xy 337.574764 -236.811824) (xy 337.630498 -236.809787)
			(xy 337.685935 -236.815887) (xy 337.739892 -236.829993) (xy 337.791221 -236.851805) (xy 337.838827 -236.880859)
			(xy 337.881695 -236.916534) (xy 337.918912 -236.958071) (xy 337.949685 -237.004584) (xy 337.973357 -237.055081)
			(xy 337.989425 -237.108488) (xy 337.997545 -237.163664) (xy 337.99785 -237.180374) (xy 338.23351 -237.180374)
			(xy 338.237581 -237.124752) (xy 338.249707 -237.070315) (xy 338.26963 -237.018224) (xy 338.296926 -236.969589)
			(xy 338.331012 -236.925446) (xy 338.371161 -236.886737) (xy 338.416519 -236.854286) (xy 338.466119 -236.828785)
			(xy 338.518903 -236.810778) (xy 338.573746 -236.800648) (xy 338.62948 -236.798611) (xy 338.684917 -236.804711)
			(xy 338.738874 -236.818817) (xy 338.790203 -236.840629) (xy 338.837809 -236.869683) (xy 338.880677 -236.905358)
			(xy 338.917894 -236.946895) (xy 338.948667 -236.993408) (xy 338.972339 -237.043905) (xy 338.988407 -237.097312)
			(xy 338.996527 -237.152488) (xy 338.997036 -237.180374) (xy 338.996527 -237.20826) (xy 338.988407 -237.263436)
			(xy 338.972339 -237.316843) (xy 338.948667 -237.36734) (xy 338.917894 -237.413853) (xy 338.880677 -237.45539)
			(xy 338.837809 -237.491065) (xy 338.790203 -237.520119) (xy 338.738874 -237.541931) (xy 338.684917 -237.556037)
			(xy 338.62948 -237.562137) (xy 338.573746 -237.5601) (xy 338.518903 -237.54997) (xy 338.466119 -237.531963)
			(xy 338.416519 -237.506462) (xy 338.371161 -237.474011) (xy 338.331012 -237.435302) (xy 338.296926 -237.391159)
			(xy 338.26963 -237.342524) (xy 338.249707 -237.290433) (xy 338.237581 -237.235996) (xy 338.23351 -237.180374)
			(xy 337.99785 -237.180374) (xy 337.998054 -237.19155) (xy 337.997545 -237.219436) (xy 337.989425 -237.274612)
			(xy 337.973357 -237.328019) (xy 337.949685 -237.378516) (xy 337.918912 -237.425029) (xy 337.881695 -237.466566)
			(xy 337.838827 -237.502241) (xy 337.791221 -237.531295) (xy 337.739892 -237.553107) (xy 337.685935 -237.567213)
			(xy 337.630498 -237.573313) (xy 337.574764 -237.571276) (xy 337.519921 -237.561146) (xy 337.467137 -237.543139)
			(xy 337.417537 -237.517638) (xy 337.372179 -237.485187) (xy 337.33203 -237.446478) (xy 337.297944 -237.402335)
			(xy 337.270648 -237.3537) (xy 337.250725 -237.301609) (xy 337.238599 -237.247172) (xy 337.234528 -237.19155)
			(xy 336.417758 -237.19155) (xy 336.422999 -237.227164) (xy 336.423508 -237.25505) (xy 336.422999 -237.282936)
			(xy 336.414879 -237.338112) (xy 336.398811 -237.391519) (xy 336.375139 -237.442016) (xy 336.344366 -237.488529)
			(xy 336.307149 -237.530066) (xy 336.264281 -237.565741) (xy 336.216675 -237.594795) (xy 336.165346 -237.616607)
			(xy 336.111389 -237.630713) (xy 336.055952 -237.636813) (xy 336.000218 -237.634776) (xy 335.945375 -237.624646)
			(xy 335.892591 -237.606639) (xy 335.842991 -237.581138) (xy 335.797633 -237.548687) (xy 335.757484 -237.509978)
			(xy 335.723398 -237.465835) (xy 335.696102 -237.4172) (xy 335.676179 -237.365109) (xy 335.664053 -237.310672)
			(xy 335.659982 -237.25505) (xy 330.069952 -237.25505) (xy 330.069952 -237.84179) (xy 330.076048 -237.847886)
			(xy 330.091034 -237.847886) (xy 330.105641 -237.822928) (xy 330.141207 -237.777334) (xy 330.183244 -237.737625)
			(xy 330.230789 -237.704711) (xy 330.282753 -237.679344) (xy 330.33795 -237.662105) (xy 330.395115 -237.653387)
			(xy 330.424028 -237.652814) (xy 330.451511 -237.653287) (xy 330.505909 -237.661159) (xy 330.558616 -237.676751)
			(xy 330.608543 -237.69974) (xy 330.654657 -237.72965) (xy 330.696005 -237.765865) (xy 330.731732 -237.807635)
			(xy 330.7611 -237.854096) (xy 330.780548 -237.89767) (xy 333.15859 -237.89767) (xy 333.162661 -237.842048)
			(xy 333.174787 -237.787611) (xy 333.19471 -237.73552) (xy 333.222006 -237.686885) (xy 333.256092 -237.642742)
			(xy 333.296241 -237.604033) (xy 333.341599 -237.571582) (xy 333.391199 -237.546081) (xy 333.443983 -237.528074)
			(xy 333.498826 -237.517944) (xy 333.55456 -237.515907) (xy 333.609997 -237.522007) (xy 333.663954 -237.536113)
			(xy 333.715283 -237.557925) (xy 333.762889 -237.586979) (xy 333.805757 -237.622654) (xy 333.842974 -237.664191)
			(xy 333.873747 -237.710704) (xy 333.897419 -237.761201) (xy 333.913487 -237.814608) (xy 333.921607 -237.869784)
			(xy 333.922116 -237.89767) (xy 333.921607 -237.925556) (xy 333.913487 -237.980732) (xy 333.897419 -238.034139)
			(xy 333.873747 -238.084636) (xy 333.842974 -238.131149) (xy 333.805757 -238.172686) (xy 333.762889 -238.208361)
			(xy 333.722599 -238.23295) (xy 338.199982 -238.23295) (xy 338.204053 -238.177328) (xy 338.216179 -238.122891)
			(xy 338.236102 -238.0708) (xy 338.263398 -238.022165) (xy 338.297484 -237.978022) (xy 338.337633 -237.939313)
			(xy 338.382991 -237.906862) (xy 338.432591 -237.881361) (xy 338.485375 -237.863354) (xy 338.540218 -237.853224)
			(xy 338.595952 -237.851187) (xy 338.651389 -237.857287) (xy 338.705346 -237.871393) (xy 338.756675 -237.893205)
			(xy 338.804281 -237.922259) (xy 338.820516 -237.93577) (xy 342.479374 -237.93577) (xy 342.483445 -237.880148)
			(xy 342.495571 -237.825711) (xy 342.515494 -237.77362) (xy 342.54279 -237.724985) (xy 342.576876 -237.680842)
			(xy 342.617025 -237.642133) (xy 342.662383 -237.609682) (xy 342.711983 -237.584181) (xy 342.764767 -237.566174)
			(xy 342.81961 -237.556044) (xy 342.875344 -237.554007) (xy 342.930781 -237.560107) (xy 342.984738 -237.574213)
			(xy 343.036067 -237.596025) (xy 343.083673 -237.625079) (xy 343.126541 -237.660754) (xy 343.163758 -237.702291)
			(xy 343.194531 -237.748804) (xy 343.218203 -237.799301) (xy 343.234271 -237.852708) (xy 343.242391 -237.907884)
			(xy 343.2429 -237.93577) (xy 343.242483 -237.95863) (xy 359.485436 -237.95863) (xy 359.489509 -237.902971)
			(xy 359.501644 -237.848498) (xy 359.52158 -237.796372) (xy 359.548894 -237.747704) (xy 359.583002 -237.703532)
			(xy 359.623179 -237.664797) (xy 359.668567 -237.632325) (xy 359.718199 -237.606807) (xy 359.771019 -237.588788)
			(xy 359.825898 -237.578651) (xy 359.881669 -237.576613) (xy 359.937143 -237.582716) (xy 359.991136 -237.596832)
			(xy 360.042499 -237.618659) (xy 360.090137 -237.647732) (xy 360.133033 -237.683431) (xy 360.170275 -237.724995)
			(xy 360.201069 -237.771539) (xy 360.224757 -237.82207) (xy 360.240835 -237.875512) (xy 360.248961 -237.930726)
			(xy 360.24947 -237.95863) (xy 360.248961 -237.986534) (xy 360.240835 -238.041748) (xy 360.224757 -238.09519)
			(xy 360.201069 -238.145721) (xy 360.170275 -238.192265) (xy 360.133033 -238.233829) (xy 360.090137 -238.269528)
			(xy 360.042499 -238.298601) (xy 359.991136 -238.320428) (xy 359.937143 -238.334544) (xy 359.881669 -238.340647)
			(xy 359.825898 -238.338609) (xy 359.771019 -238.328472) (xy 359.718199 -238.310453) (xy 359.668567 -238.284935)
			(xy 359.623179 -238.252463) (xy 359.583002 -238.213728) (xy 359.548894 -238.169556) (xy 359.52158 -238.120888)
			(xy 359.501644 -238.068762) (xy 359.489509 -238.014289) (xy 359.485436 -237.95863) (xy 343.242483 -237.95863)
			(xy 343.242391 -237.963656) (xy 343.234271 -238.018832) (xy 343.218203 -238.072239) (xy 343.194531 -238.122736)
			(xy 343.163758 -238.169249) (xy 343.126541 -238.210786) (xy 343.083673 -238.246461) (xy 343.036067 -238.275515)
			(xy 342.984738 -238.297327) (xy 342.930781 -238.311433) (xy 342.875344 -238.317533) (xy 342.81961 -238.315496)
			(xy 342.764767 -238.305366) (xy 342.711983 -238.287359) (xy 342.662383 -238.261858) (xy 342.617025 -238.229407)
			(xy 342.576876 -238.190698) (xy 342.54279 -238.146555) (xy 342.515494 -238.09792) (xy 342.495571 -238.045829)
			(xy 342.483445 -237.991392) (xy 342.479374 -237.93577) (xy 338.820516 -237.93577) (xy 338.847149 -237.957934)
			(xy 338.884366 -237.999471) (xy 338.915139 -238.045984) (xy 338.938811 -238.096481) (xy 338.954879 -238.149888)
			(xy 338.962999 -238.205064) (xy 338.963508 -238.23295) (xy 338.962999 -238.260836) (xy 338.954879 -238.316012)
			(xy 338.938811 -238.369419) (xy 338.915139 -238.419916) (xy 338.884737 -238.465868) (xy 344.536774 -238.465868)
			(xy 344.540845 -238.410246) (xy 344.552971 -238.355809) (xy 344.572894 -238.303718) (xy 344.60019 -238.255083)
			(xy 344.634276 -238.21094) (xy 344.674425 -238.172231) (xy 344.719783 -238.13978) (xy 344.769383 -238.114279)
			(xy 344.822167 -238.096272) (xy 344.87701 -238.086142) (xy 344.932744 -238.084105) (xy 344.988181 -238.090205)
			(xy 345.042138 -238.104311) (xy 345.093467 -238.126123) (xy 345.141073 -238.155177) (xy 345.183941 -238.190852)
			(xy 345.221158 -238.232389) (xy 345.251931 -238.278902) (xy 345.275603 -238.329399) (xy 345.291671 -238.382806)
			(xy 345.299791 -238.437982) (xy 345.3003 -238.465868) (xy 345.299791 -238.493754) (xy 345.291671 -238.54893)
			(xy 345.275603 -238.602337) (xy 345.264206 -238.62665) (xy 346.568774 -238.62665) (xy 346.572845 -238.571028)
			(xy 346.584971 -238.516591) (xy 346.604894 -238.4645) (xy 346.63219 -238.415865) (xy 346.666276 -238.371722)
			(xy 346.706425 -238.333013) (xy 346.751783 -238.300562) (xy 346.801383 -238.275061) (xy 346.854167 -238.257054)
			(xy 346.90901 -238.246924) (xy 346.964744 -238.244887) (xy 347.020181 -238.250987) (xy 347.074138 -238.265093)
			(xy 347.125467 -238.286905) (xy 347.173073 -238.315959) (xy 347.215941 -238.351634) (xy 347.253158 -238.393171)
			(xy 347.283931 -238.439684) (xy 347.307603 -238.490181) (xy 347.323671 -238.543588) (xy 347.331791 -238.598764)
			(xy 347.3323 -238.62665) (xy 347.331791 -238.654536) (xy 347.323671 -238.709712) (xy 347.307603 -238.763119)
			(xy 347.296801 -238.786162) (xy 348.600774 -238.786162) (xy 348.604845 -238.73054) (xy 348.616971 -238.676103)
			(xy 348.636894 -238.624012) (xy 348.66419 -238.575377) (xy 348.698276 -238.531234) (xy 348.738425 -238.492525)
			(xy 348.783783 -238.460074) (xy 348.833383 -238.434573) (xy 348.886167 -238.416566) (xy 348.94101 -238.406436)
			(xy 348.996744 -238.404399) (xy 349.052181 -238.410499) (xy 349.106138 -238.424605) (xy 349.157467 -238.446417)
			(xy 349.205073 -238.475471) (xy 349.247941 -238.511146) (xy 349.285158 -238.552683) (xy 349.315931 -238.599196)
			(xy 349.339603 -238.649693) (xy 349.355671 -238.7031) (xy 349.363791 -238.758276) (xy 349.3643 -238.786162)
			(xy 349.363791 -238.814048) (xy 349.355671 -238.869224) (xy 349.339603 -238.922631) (xy 349.315931 -238.973128)
			(xy 349.285158 -239.019641) (xy 349.247941 -239.061178) (xy 349.205073 -239.096853) (xy 349.157467 -239.125907)
			(xy 349.106138 -239.147719) (xy 349.052181 -239.161825) (xy 348.996744 -239.167925) (xy 348.94101 -239.165888)
			(xy 348.886167 -239.155758) (xy 348.833383 -239.137751) (xy 348.783783 -239.11225) (xy 348.738425 -239.079799)
			(xy 348.698276 -239.04109) (xy 348.66419 -238.996947) (xy 348.636894 -238.948312) (xy 348.616971 -238.896221)
			(xy 348.604845 -238.841784) (xy 348.600774 -238.786162) (xy 347.296801 -238.786162) (xy 347.283931 -238.813616)
			(xy 347.253158 -238.860129) (xy 347.215941 -238.901666) (xy 347.173073 -238.937341) (xy 347.125467 -238.966395)
			(xy 347.074138 -238.988207) (xy 347.020181 -239.002313) (xy 346.964744 -239.008413) (xy 346.90901 -239.006376)
			(xy 346.854167 -238.996246) (xy 346.801383 -238.978239) (xy 346.751783 -238.952738) (xy 346.706425 -238.920287)
			(xy 346.666276 -238.881578) (xy 346.63219 -238.837435) (xy 346.604894 -238.7888) (xy 346.584971 -238.736709)
			(xy 346.572845 -238.682272) (xy 346.568774 -238.62665) (xy 345.264206 -238.62665) (xy 345.251931 -238.652834)
			(xy 345.221158 -238.699347) (xy 345.183941 -238.740884) (xy 345.141073 -238.776559) (xy 345.093467 -238.805613)
			(xy 345.042138 -238.827425) (xy 344.988181 -238.841531) (xy 344.932744 -238.847631) (xy 344.87701 -238.845594)
			(xy 344.822167 -238.835464) (xy 344.769383 -238.817457) (xy 344.719783 -238.791956) (xy 344.674425 -238.759505)
			(xy 344.634276 -238.720796) (xy 344.60019 -238.676653) (xy 344.572894 -238.628018) (xy 344.552971 -238.575927)
			(xy 344.540845 -238.52149) (xy 344.536774 -238.465868) (xy 338.884737 -238.465868) (xy 338.884366 -238.466429)
			(xy 338.847149 -238.507966) (xy 338.804281 -238.543641) (xy 338.756675 -238.572695) (xy 338.705346 -238.594507)
			(xy 338.651389 -238.608613) (xy 338.595952 -238.614713) (xy 338.540218 -238.612676) (xy 338.485375 -238.602546)
			(xy 338.432591 -238.584539) (xy 338.382991 -238.559038) (xy 338.337633 -238.526587) (xy 338.297484 -238.487878)
			(xy 338.263398 -238.443735) (xy 338.236102 -238.3951) (xy 338.216179 -238.343009) (xy 338.204053 -238.288572)
			(xy 338.199982 -238.23295) (xy 333.722599 -238.23295) (xy 333.715283 -238.237415) (xy 333.663954 -238.259227)
			(xy 333.609997 -238.273333) (xy 333.55456 -238.279433) (xy 333.498826 -238.277396) (xy 333.443983 -238.267266)
			(xy 333.391199 -238.249259) (xy 333.341599 -238.223758) (xy 333.296241 -238.191307) (xy 333.256092 -238.152598)
			(xy 333.222006 -238.108455) (xy 333.19471 -238.05982) (xy 333.174787 -238.007729) (xy 333.162661 -237.953292)
			(xy 333.15859 -237.89767) (xy 330.780548 -237.89767) (xy 330.783502 -237.904289) (xy 330.798474 -237.957175)
			(xy 330.805708 -238.011662) (xy 330.805053 -238.066623) (xy 330.796523 -238.120922) (xy 330.780295 -238.173437)
			(xy 330.756704 -238.223082) (xy 330.726237 -238.26883) (xy 330.689525 -238.309737) (xy 330.647326 -238.344956)
			(xy 330.600512 -238.37376) (xy 330.550052 -238.395553) (xy 330.496988 -238.409884) (xy 330.469748 -238.413544)
			(xy 330.436728 -238.446564) (xy 330.568554 -238.578644) (xy 330.568554 -239.369346) (xy 330.168504 -239.769396)
			(xy 333.012032 -239.769396) (xy 333.016103 -239.713774) (xy 333.028229 -239.659337) (xy 333.048152 -239.607246)
			(xy 333.075448 -239.558611) (xy 333.109534 -239.514468) (xy 333.149683 -239.475759) (xy 333.195041 -239.443308)
			(xy 333.244641 -239.417807) (xy 333.297425 -239.3998) (xy 333.352268 -239.38967) (xy 333.408002 -239.387633)
			(xy 333.463439 -239.393733) (xy 333.517396 -239.407839) (xy 333.568725 -239.429651) (xy 333.616331 -239.458705)
			(xy 333.659199 -239.49438) (xy 333.696416 -239.535917) (xy 333.727189 -239.58243) (xy 333.750861 -239.632927)
			(xy 333.766929 -239.686334) (xy 333.775049 -239.74151) (xy 333.775558 -239.769396) (xy 333.775166 -239.790852)
			(xy 334.486232 -239.790852) (xy 334.486232 -239.736348) (xy 334.493988 -239.682398) (xy 334.509342 -239.630101)
			(xy 334.531983 -239.580521) (xy 334.561448 -239.534667) (xy 334.597138 -239.493474) (xy 334.638327 -239.457778)
			(xy 334.684177 -239.428307) (xy 334.733754 -239.40566) (xy 334.786049 -239.390299) (xy 334.839998 -239.382535)
			(xy 334.86725 -239.382046) (xy 334.893113 -239.382459) (xy 334.944365 -239.389448) (xy 334.994201 -239.403303)
			(xy 335.041706 -239.42377) (xy 335.086006 -239.450474) (xy 335.126288 -239.482923) (xy 335.144364 -239.501426)
			(xy 335.151984 -239.509554) (xy 335.172558 -239.517936) (xy 335.260696 -239.513618) (xy 335.271609 -239.512586)
			(xy 335.29109 -239.502582) (xy 335.298288 -239.494314) (xy 335.316517 -239.471907) (xy 335.358525 -239.432265)
			(xy 335.406022 -239.399397) (xy 335.457925 -239.374053) (xy 335.513051 -239.35681) (xy 335.570145 -239.34806)
			(xy 335.599024 -239.347502) (xy 335.626275 -239.347969) (xy 335.680221 -239.355729) (xy 335.732515 -239.371087)
			(xy 335.78209 -239.39373) (xy 335.827939 -239.423197) (xy 335.869127 -239.45889) (xy 335.904817 -239.500081)
			(xy 335.934282 -239.545931) (xy 335.956922 -239.595508) (xy 335.972276 -239.647802) (xy 335.972448 -239.649)
			(xy 336.548982 -239.649) (xy 336.553053 -239.593378) (xy 336.565179 -239.538941) (xy 336.585102 -239.48685)
			(xy 336.612398 -239.438215) (xy 336.646484 -239.394072) (xy 336.686633 -239.355363) (xy 336.731991 -239.322912)
			(xy 336.781591 -239.297411) (xy 336.834375 -239.279404) (xy 336.889218 -239.269274) (xy 336.944952 -239.267237)
			(xy 337.000389 -239.273337) (xy 337.054346 -239.287443) (xy 337.105675 -239.309255) (xy 337.153281 -239.338309)
			(xy 337.196149 -239.373984) (xy 337.233366 -239.415521) (xy 337.264139 -239.462034) (xy 337.287811 -239.512531)
			(xy 337.303879 -239.565938) (xy 337.311999 -239.621114) (xy 337.312508 -239.649) (xy 338.961982 -239.649)
			(xy 338.966053 -239.593378) (xy 338.978179 -239.538941) (xy 338.998102 -239.48685) (xy 339.025398 -239.438215)
			(xy 339.059484 -239.394072) (xy 339.099633 -239.355363) (xy 339.144991 -239.322912) (xy 339.194591 -239.297411)
			(xy 339.247375 -239.279404) (xy 339.302218 -239.269274) (xy 339.357952 -239.267237) (xy 339.413389 -239.273337)
			(xy 339.467346 -239.287443) (xy 339.518675 -239.309255) (xy 339.566281 -239.338309) (xy 339.609149 -239.373984)
			(xy 339.646366 -239.415521) (xy 339.677139 -239.462034) (xy 339.700811 -239.512531) (xy 339.716879 -239.565938)
			(xy 339.724999 -239.621114) (xy 339.725508 -239.649) (xy 339.72503 -239.675162) (xy 341.488774 -239.675162)
			(xy 341.492845 -239.61954) (xy 341.504971 -239.565103) (xy 341.524894 -239.513012) (xy 341.55219 -239.464377)
			(xy 341.586276 -239.420234) (xy 341.626425 -239.381525) (xy 341.671783 -239.349074) (xy 341.721383 -239.323573)
			(xy 341.774167 -239.305566) (xy 341.82901 -239.295436) (xy 341.884744 -239.293399) (xy 341.940181 -239.299499)
			(xy 341.994138 -239.313605) (xy 342.045467 -239.335417) (xy 342.093073 -239.364471) (xy 342.135941 -239.400146)
			(xy 342.173158 -239.441683) (xy 342.203931 -239.488196) (xy 342.227603 -239.538693) (xy 342.243671 -239.5921)
			(xy 342.251791 -239.647276) (xy 342.2523 -239.675162) (xy 343.520774 -239.675162) (xy 343.524845 -239.61954)
			(xy 343.536971 -239.565103) (xy 343.556894 -239.513012) (xy 343.58419 -239.464377) (xy 343.618276 -239.420234)
			(xy 343.658425 -239.381525) (xy 343.703783 -239.349074) (xy 343.753383 -239.323573) (xy 343.806167 -239.305566)
			(xy 343.86101 -239.295436) (xy 343.916744 -239.293399) (xy 343.972181 -239.299499) (xy 344.026138 -239.313605)
			(xy 344.077467 -239.335417) (xy 344.125073 -239.364471) (xy 344.167941 -239.400146) (xy 344.205158 -239.441683)
			(xy 344.235931 -239.488196) (xy 344.259603 -239.538693) (xy 344.275671 -239.5921) (xy 344.283791 -239.647276)
			(xy 344.2843 -239.675162) (xy 345.552774 -239.675162) (xy 345.556845 -239.61954) (xy 345.568971 -239.565103)
			(xy 345.588894 -239.513012) (xy 345.61619 -239.464377) (xy 345.650276 -239.420234) (xy 345.690425 -239.381525)
			(xy 345.735783 -239.349074) (xy 345.785383 -239.323573) (xy 345.838167 -239.305566) (xy 345.89301 -239.295436)
			(xy 345.948744 -239.293399) (xy 346.004181 -239.299499) (xy 346.058138 -239.313605) (xy 346.109467 -239.335417)
			(xy 346.157073 -239.364471) (xy 346.199941 -239.400146) (xy 346.237158 -239.441683) (xy 346.267931 -239.488196)
			(xy 346.291603 -239.538693) (xy 346.307671 -239.5921) (xy 346.315791 -239.647276) (xy 346.3163 -239.675162)
			(xy 347.584774 -239.675162) (xy 347.588845 -239.61954) (xy 347.600971 -239.565103) (xy 347.620894 -239.513012)
			(xy 347.64819 -239.464377) (xy 347.682276 -239.420234) (xy 347.722425 -239.381525) (xy 347.767783 -239.349074)
			(xy 347.817383 -239.323573) (xy 347.870167 -239.305566) (xy 347.92501 -239.295436) (xy 347.980744 -239.293399)
			(xy 348.036181 -239.299499) (xy 348.090138 -239.313605) (xy 348.141467 -239.335417) (xy 348.189073 -239.364471)
			(xy 348.231941 -239.400146) (xy 348.269158 -239.441683) (xy 348.299931 -239.488196) (xy 348.323603 -239.538693)
			(xy 348.339671 -239.5921) (xy 348.347791 -239.647276) (xy 348.3483 -239.675162) (xy 348.347791 -239.703048)
			(xy 348.339671 -239.758224) (xy 348.323603 -239.811631) (xy 348.299931 -239.862128) (xy 348.269158 -239.908641)
			(xy 348.231941 -239.950178) (xy 348.189073 -239.985853) (xy 348.141467 -240.014907) (xy 348.090138 -240.036719)
			(xy 348.036181 -240.050825) (xy 347.980744 -240.056925) (xy 347.92501 -240.054888) (xy 347.870167 -240.044758)
			(xy 347.817383 -240.026751) (xy 347.767783 -240.00125) (xy 347.722425 -239.968799) (xy 347.682276 -239.93009)
			(xy 347.64819 -239.885947) (xy 347.620894 -239.837312) (xy 347.600971 -239.785221) (xy 347.588845 -239.730784)
			(xy 347.584774 -239.675162) (xy 346.3163 -239.675162) (xy 346.315791 -239.703048) (xy 346.307671 -239.758224)
			(xy 346.291603 -239.811631) (xy 346.267931 -239.862128) (xy 346.237158 -239.908641) (xy 346.199941 -239.950178)
			(xy 346.157073 -239.985853) (xy 346.109467 -240.014907) (xy 346.058138 -240.036719) (xy 346.004181 -240.050825)
			(xy 345.948744 -240.056925) (xy 345.89301 -240.054888) (xy 345.838167 -240.044758) (xy 345.785383 -240.026751)
			(xy 345.735783 -240.00125) (xy 345.690425 -239.968799) (xy 345.650276 -239.93009) (xy 345.61619 -239.885947)
			(xy 345.588894 -239.837312) (xy 345.568971 -239.785221) (xy 345.556845 -239.730784) (xy 345.552774 -239.675162)
			(xy 344.2843 -239.675162) (xy 344.283791 -239.703048) (xy 344.275671 -239.758224) (xy 344.259603 -239.811631)
			(xy 344.235931 -239.862128) (xy 344.205158 -239.908641) (xy 344.167941 -239.950178) (xy 344.125073 -239.985853)
			(xy 344.077467 -240.014907) (xy 344.026138 -240.036719) (xy 343.972181 -240.050825) (xy 343.916744 -240.056925)
			(xy 343.86101 -240.054888) (xy 343.806167 -240.044758) (xy 343.753383 -240.026751) (xy 343.703783 -240.00125)
			(xy 343.658425 -239.968799) (xy 343.618276 -239.93009) (xy 343.58419 -239.885947) (xy 343.556894 -239.837312)
			(xy 343.536971 -239.785221) (xy 343.524845 -239.730784) (xy 343.520774 -239.675162) (xy 342.2523 -239.675162)
			(xy 342.251791 -239.703048) (xy 342.243671 -239.758224) (xy 342.227603 -239.811631) (xy 342.203931 -239.862128)
			(xy 342.173158 -239.908641) (xy 342.135941 -239.950178) (xy 342.093073 -239.985853) (xy 342.045467 -240.014907)
			(xy 341.994138 -240.036719) (xy 341.940181 -240.050825) (xy 341.884744 -240.056925) (xy 341.82901 -240.054888)
			(xy 341.774167 -240.044758) (xy 341.721383 -240.026751) (xy 341.671783 -240.00125) (xy 341.626425 -239.968799)
			(xy 341.586276 -239.93009) (xy 341.55219 -239.885947) (xy 341.524894 -239.837312) (xy 341.504971 -239.785221)
			(xy 341.492845 -239.730784) (xy 341.488774 -239.675162) (xy 339.72503 -239.675162) (xy 339.724999 -239.676886)
			(xy 339.716879 -239.732062) (xy 339.700811 -239.785469) (xy 339.677139 -239.835966) (xy 339.646366 -239.882479)
			(xy 339.609149 -239.924016) (xy 339.566281 -239.959691) (xy 339.518675 -239.988745) (xy 339.467346 -240.010557)
			(xy 339.413389 -240.024663) (xy 339.357952 -240.030763) (xy 339.302218 -240.028726) (xy 339.247375 -240.018596)
			(xy 339.194591 -240.000589) (xy 339.144991 -239.975088) (xy 339.099633 -239.942637) (xy 339.059484 -239.903928)
			(xy 339.025398 -239.859785) (xy 338.998102 -239.81115) (xy 338.978179 -239.759059) (xy 338.966053 -239.704622)
			(xy 338.961982 -239.649) (xy 337.312508 -239.649) (xy 337.311999 -239.676886) (xy 337.303879 -239.732062)
			(xy 337.287811 -239.785469) (xy 337.264139 -239.835966) (xy 337.233366 -239.882479) (xy 337.196149 -239.924016)
			(xy 337.153281 -239.959691) (xy 337.105675 -239.988745) (xy 337.054346 -240.010557) (xy 337.000389 -240.024663)
			(xy 336.944952 -240.030763) (xy 336.889218 -240.028726) (xy 336.834375 -240.018596) (xy 336.781591 -240.000589)
			(xy 336.731991 -239.975088) (xy 336.686633 -239.942637) (xy 336.646484 -239.903928) (xy 336.612398 -239.859785)
			(xy 336.585102 -239.81115) (xy 336.565179 -239.759059) (xy 336.553053 -239.704622) (xy 336.548982 -239.649)
			(xy 335.972448 -239.649) (xy 335.980032 -239.701749) (xy 335.980032 -239.756251) (xy 335.972276 -239.810198)
			(xy 335.956922 -239.862492) (xy 335.934282 -239.912069) (xy 335.904817 -239.957919) (xy 335.869127 -239.99911)
			(xy 335.827939 -240.034803) (xy 335.78209 -240.06427) (xy 335.732515 -240.086913) (xy 335.680221 -240.102271)
			(xy 335.626275 -240.110031) (xy 335.599024 -240.110518) (xy 335.57316 -240.110133) (xy 335.521906 -240.103141)
			(xy 335.472069 -240.089281) (xy 335.424564 -240.068808) (xy 335.380265 -240.042099) (xy 335.339985 -240.009644)
			(xy 335.32191 -239.991138) (xy 335.31429 -239.98301) (xy 335.293716 -239.974628) (xy 335.205578 -239.978946)
			(xy 335.194665 -239.979976) (xy 335.175185 -239.989983) (xy 335.167986 -239.99825) (xy 335.149763 -240.020662)
			(xy 335.107754 -240.060306) (xy 335.060256 -240.093174) (xy 335.008352 -240.118517) (xy 334.953225 -240.135759)
			(xy 334.89613 -240.144506) (xy 334.86725 -240.145062) (xy 334.839998 -240.144665) (xy 334.786049 -240.136901)
			(xy 334.733754 -240.12154) (xy 334.684177 -240.098893) (xy 334.638327 -240.069422) (xy 334.597138 -240.033726)
			(xy 334.561448 -239.992533) (xy 334.531983 -239.946679) (xy 334.509342 -239.897099) (xy 334.493988 -239.844802)
			(xy 334.486232 -239.790852) (xy 333.775166 -239.790852) (xy 333.775049 -239.797282) (xy 333.766929 -239.852458)
			(xy 333.750861 -239.905865) (xy 333.727189 -239.956362) (xy 333.696416 -240.002875) (xy 333.659199 -240.044412)
			(xy 333.616331 -240.080087) (xy 333.568725 -240.109141) (xy 333.517396 -240.130953) (xy 333.463439 -240.145059)
			(xy 333.408002 -240.151159) (xy 333.352268 -240.149122) (xy 333.297425 -240.138992) (xy 333.244641 -240.120985)
			(xy 333.195041 -240.095484) (xy 333.149683 -240.063033) (xy 333.109534 -240.024324) (xy 333.075448 -239.980181)
			(xy 333.048152 -239.931546) (xy 333.028229 -239.879455) (xy 333.016103 -239.825018) (xy 333.012032 -239.769396)
			(xy 330.168504 -239.769396) (xy 330.153518 -239.784382) (xy 329.430888 -239.784382) (xy 329.289664 -239.925606)
			(xy 329.289664 -240.641378) (xy 340.440262 -240.641378) (xy 340.444333 -240.585756) (xy 340.456459 -240.531319)
			(xy 340.476382 -240.479228) (xy 340.503678 -240.430593) (xy 340.537764 -240.38645) (xy 340.577913 -240.347741)
			(xy 340.623271 -240.31529) (xy 340.672871 -240.289789) (xy 340.725655 -240.271782) (xy 340.780498 -240.261652)
			(xy 340.836232 -240.259615) (xy 340.891669 -240.265715) (xy 340.945626 -240.279821) (xy 340.996955 -240.301633)
			(xy 341.044561 -240.330687) (xy 341.087429 -240.366362) (xy 341.124646 -240.407899) (xy 341.155419 -240.454412)
			(xy 341.179091 -240.504909) (xy 341.195159 -240.558316) (xy 341.203279 -240.613492) (xy 341.203788 -240.641378)
			(xy 341.203279 -240.669264) (xy 341.195159 -240.72444) (xy 341.179091 -240.777847) (xy 341.155419 -240.828344)
			(xy 341.124646 -240.874857) (xy 341.087429 -240.916394) (xy 341.044561 -240.952069) (xy 340.996955 -240.981123)
			(xy 340.945626 -241.002935) (xy 340.891669 -241.017041) (xy 340.836232 -241.023141) (xy 340.780498 -241.021104)
			(xy 340.725655 -241.010974) (xy 340.672871 -240.992967) (xy 340.623271 -240.967466) (xy 340.577913 -240.935015)
			(xy 340.537764 -240.896306) (xy 340.503678 -240.852163) (xy 340.476382 -240.803528) (xy 340.456459 -240.751437)
			(xy 340.444333 -240.697) (xy 340.440262 -240.641378) (xy 329.289664 -240.641378) (xy 329.289664 -242.127024)
			(xy 329.099164 -242.317524) (xy 329.099164 -243.84) (xy 329.944982 -243.84) (xy 329.949053 -243.784378)
			(xy 329.961179 -243.729941) (xy 329.981102 -243.67785) (xy 330.008398 -243.629215) (xy 330.042484 -243.585072)
			(xy 330.082633 -243.546363) (xy 330.127991 -243.513912) (xy 330.177591 -243.488411) (xy 330.230375 -243.470404)
			(xy 330.285218 -243.460274) (xy 330.340952 -243.458237) (xy 330.396389 -243.464337) (xy 330.450346 -243.478443)
			(xy 330.501675 -243.500255) (xy 330.549281 -243.529309) (xy 330.592149 -243.564984) (xy 330.629366 -243.606521)
			(xy 330.660139 -243.653034) (xy 330.683811 -243.703531) (xy 330.699879 -243.756938) (xy 330.707999 -243.812114)
			(xy 330.708508 -243.84) (xy 330.707999 -243.867886) (xy 330.70462 -243.890849) (xy 330.8114 -243.890849)
			(xy 330.8114 -243.836351) (xy 330.819156 -243.782409) (xy 330.834509 -243.730119) (xy 330.857147 -243.680546)
			(xy 330.886609 -243.634699) (xy 330.922297 -243.593512) (xy 330.963482 -243.557823) (xy 331.009327 -243.528358)
			(xy 331.058898 -243.505716) (xy 331.111187 -243.49036) (xy 331.165129 -243.482602) (xy 331.192378 -243.482114)
			(xy 331.218436 -243.482575) (xy 331.270067 -243.489671) (xy 331.320249 -243.503734) (xy 331.368049 -243.524501)
			(xy 331.412574 -243.551585) (xy 331.452995 -243.584482) (xy 331.488559 -243.622578) (xy 331.518602 -243.665163)
			(xy 331.53096 -243.688108) (xy 331.537732 -243.700374) (xy 331.556893 -243.720808) (xy 331.580886 -243.735267)
			(xy 331.607904 -243.742662) (xy 331.635916 -243.742438) (xy 331.662813 -243.734611) (xy 331.686571 -243.71977)
			(xy 331.696314 -243.709698) (xy 331.714465 -243.690498) (xy 331.755142 -243.656777) (xy 331.800082 -243.628992)
			(xy 331.848427 -243.607674) (xy 331.899251 -243.593232) (xy 331.951582 -243.585941) (xy 331.978 -243.585492)
			(xy 332.005251 -243.585978) (xy 332.059199 -243.593734) (xy 332.111494 -243.609089) (xy 332.161071 -243.631731)
			(xy 332.206921 -243.661197) (xy 332.248112 -243.696888) (xy 332.283803 -243.738079) (xy 332.313269 -243.783929)
			(xy 332.335911 -243.833506) (xy 332.337818 -243.84) (xy 333.739996 -243.84) (xy 333.744067 -243.784378)
			(xy 333.756193 -243.729941) (xy 333.776116 -243.67785) (xy 333.803412 -243.629215) (xy 333.837498 -243.585072)
			(xy 333.877647 -243.546363) (xy 333.923005 -243.513912) (xy 333.972605 -243.488411) (xy 334.025389 -243.470404)
			(xy 334.080232 -243.460274) (xy 334.135966 -243.458237) (xy 334.191403 -243.464337) (xy 334.24536 -243.478443)
			(xy 334.296689 -243.500255) (xy 334.344295 -243.529309) (xy 334.387163 -243.564984) (xy 334.42438 -243.606521)
			(xy 334.455153 -243.653034) (xy 334.478825 -243.703531) (xy 334.494893 -243.756938) (xy 334.503013 -243.812114)
			(xy 334.503522 -243.84) (xy 334.503013 -243.867886) (xy 334.494893 -243.923062) (xy 334.478825 -243.976469)
			(xy 334.455153 -244.026966) (xy 334.42438 -244.073479) (xy 334.387163 -244.115016) (xy 334.344295 -244.150691)
			(xy 334.296689 -244.179745) (xy 334.24536 -244.201557) (xy 334.191403 -244.215663) (xy 334.135966 -244.221763)
			(xy 334.080232 -244.219726) (xy 334.025389 -244.209596) (xy 333.972605 -244.191589) (xy 333.923005 -244.166088)
			(xy 333.877647 -244.133637) (xy 333.837498 -244.094928) (xy 333.803412 -244.050785) (xy 333.776116 -244.00215)
			(xy 333.756193 -243.950059) (xy 333.744067 -243.895622) (xy 333.739996 -243.84) (xy 332.337818 -243.84)
			(xy 332.351266 -243.885801) (xy 332.359022 -243.939749) (xy 332.359022 -243.994251) (xy 332.351266 -244.048199)
			(xy 332.335911 -244.100494) (xy 332.313269 -244.150071) (xy 332.283803 -244.195921) (xy 332.248112 -244.237112)
			(xy 332.206921 -244.272803) (xy 332.161071 -244.302269) (xy 332.111494 -244.324911) (xy 332.059199 -244.340266)
			(xy 332.005251 -244.348022) (xy 331.978 -244.348508) (xy 331.95194 -244.348107) (xy 331.900305 -244.341006)
			(xy 331.850118 -244.326938) (xy 331.802317 -244.306163) (xy 331.757791 -244.27907) (xy 331.717371 -244.246164)
			(xy 331.681811 -244.208058) (xy 331.651773 -244.165464) (xy 331.639418 -244.142514) (xy 331.63254 -244.130312)
			(xy 331.613401 -244.109881) (xy 331.589431 -244.095419) (xy 331.562432 -244.088016) (xy 331.534438 -244.088228)
			(xy 331.507554 -244.096039) (xy 331.483805 -244.110862) (xy 331.474064 -244.120924) (xy 331.455928 -244.140139)
			(xy 331.415248 -244.173858) (xy 331.370304 -244.20164) (xy 331.321956 -244.222955) (xy 331.27113 -244.237395)
			(xy 331.218797 -244.244683) (xy 331.192378 -244.24513) (xy 331.165129 -244.244598) (xy 331.111187 -244.23684)
			(xy 331.058898 -244.221484) (xy 331.009327 -244.198842) (xy 330.963482 -244.169377) (xy 330.922297 -244.133688)
			(xy 330.886609 -244.092501) (xy 330.857147 -244.046654) (xy 330.834509 -243.997081) (xy 330.819156 -243.944791)
			(xy 330.8114 -243.890849) (xy 330.70462 -243.890849) (xy 330.699879 -243.923062) (xy 330.683811 -243.976469)
			(xy 330.660139 -244.026966) (xy 330.629366 -244.073479) (xy 330.592149 -244.115016) (xy 330.549281 -244.150691)
			(xy 330.501675 -244.179745) (xy 330.450346 -244.201557) (xy 330.396389 -244.215663) (xy 330.340952 -244.221763)
			(xy 330.285218 -244.219726) (xy 330.230375 -244.209596) (xy 330.177591 -244.191589) (xy 330.127991 -244.166088)
			(xy 330.082633 -244.133637) (xy 330.042484 -244.094928) (xy 330.008398 -244.050785) (xy 329.981102 -244.00215)
			(xy 329.961179 -243.950059) (xy 329.949053 -243.895622) (xy 329.944982 -243.84) (xy 329.099164 -243.84)
			(xy 329.099164 -246.28729) (xy 329.098729 -246.318438) (xy 329.091975 -246.380368) (xy 329.079973 -246.434864)
			(xy 329.197714 -246.434864) (xy 329.201785 -246.379242) (xy 329.213911 -246.324805) (xy 329.233834 -246.272714)
			(xy 329.26113 -246.224079) (xy 329.295216 -246.179936) (xy 329.335365 -246.141227) (xy 329.380723 -246.108776)
			(xy 329.430323 -246.083275) (xy 329.483107 -246.065268) (xy 329.53795 -246.055138) (xy 329.593684 -246.053101)
			(xy 329.649121 -246.059201) (xy 329.703078 -246.073307) (xy 329.754407 -246.095119) (xy 329.802013 -246.124173)
			(xy 329.844881 -246.159848) (xy 329.882098 -246.201385) (xy 329.912871 -246.247898) (xy 329.936543 -246.298395)
			(xy 329.952611 -246.351802) (xy 329.960731 -246.406978) (xy 329.96124 -246.434864) (xy 329.960731 -246.46275)
			(xy 329.952611 -246.517926) (xy 329.936543 -246.571333) (xy 329.912871 -246.62183) (xy 329.882098 -246.668343)
			(xy 329.844881 -246.70988) (xy 329.802013 -246.745555) (xy 329.754407 -246.774609) (xy 329.703078 -246.796421)
			(xy 329.649121 -246.810527) (xy 329.593684 -246.816627) (xy 329.53795 -246.81459) (xy 329.483107 -246.80446)
			(xy 329.430323 -246.786453) (xy 329.380723 -246.760952) (xy 329.335365 -246.728501) (xy 329.295216 -246.689792)
			(xy 329.26113 -246.645649) (xy 329.233834 -246.597014) (xy 329.213911 -246.544923) (xy 329.201785 -246.490486)
			(xy 329.197714 -246.434864) (xy 329.079973 -246.434864) (xy 329.078576 -246.441207) (xy 329.05869 -246.500244)
			(xy 329.032548 -246.556791) (xy 329.016868 -246.583708) (xy 329.013312 -246.58955) (xy 329.007724 -246.609108)
			(xy 329.005692 -246.623078) (xy 329.005692 -248.215658) (xy 329.006159 -248.225532) (xy 329.013612 -248.243821)
			(xy 329.02017 -248.251218) (xy 329.294744 -248.525792) (xy 329.295252 -248.5263) (xy 329.302631 -248.532888)
			(xy 329.32093 -248.540347) (xy 329.330812 -248.540778) (xy 330.388722 -248.540778)
		)
		(stroke
			(width 0)
			(type solid)
		)
		(fill yes)
		(layer "In9.Cu")
		(net "P3V3_AUX")
	)
	(gr_poly
		(pts
			(xy 247.042178 -253.615444) (xy 247.052051 -253.614974) (xy 247.070338 -253.607521) (xy 247.077738 -253.600966)
			(xy 247.077992 -253.600712) (xy 247.261634 -253.41707) (xy 247.262142 -253.416562) (xy 247.268728 -253.409182)
			(xy 247.276185 -253.390883) (xy 247.27662 -253.381002) (xy 247.27662 -253.30531) (xy 247.270524 -253.299214)
			(xy 247.270524 -251.876814) (xy 247.270524 -251.87656) (xy 247.270646 -251.871606) (xy 247.272569 -251.861887)
			(xy 247.274334 -251.857256) (xy 247.28551 -251.83084) (xy 247.28551 -238.348012) (xy 247.284973 -238.337651)
			(xy 247.276722 -238.318637) (xy 247.269508 -238.311182) (xy 247.247156 -238.2901) (xy 247.239778 -238.283691)
			(xy 247.221617 -238.27652) (xy 247.21185 -238.27613) (xy 247.209818 -238.27613) (xy 247.187466 -238.275368)
			(xy 247.175408 -238.275436) (xy 247.153416 -238.285244) (xy 247.145302 -238.294164) (xy 247.124982 -238.319056)
			(xy 247.117872 -238.328761) (xy 247.112699 -238.352222) (xy 247.115076 -238.364014) (xy 247.12111 -238.38814)
			(xy 247.127604 -238.437446) (xy 247.12803 -238.462312) (xy 247.127544 -238.489563) (xy 247.119788 -238.543511)
			(xy 247.104433 -238.595806) (xy 247.081791 -238.645383) (xy 247.052325 -238.691233) (xy 247.016634 -238.732424)
			(xy 246.975443 -238.768115) (xy 246.929593 -238.797581) (xy 246.880016 -238.820223) (xy 246.827721 -238.835578)
			(xy 246.773773 -238.843334) (xy 246.719271 -238.843334) (xy 246.665323 -238.835578) (xy 246.613028 -238.820223)
			(xy 246.563451 -238.797581) (xy 246.517601 -238.768115) (xy 246.47641 -238.732424) (xy 246.440719 -238.691233)
			(xy 246.411253 -238.645383) (xy 246.388611 -238.595806) (xy 246.373256 -238.543511) (xy 246.3655 -238.489563)
			(xy 246.365014 -238.462312) (xy 246.365474 -238.435498) (xy 246.372993 -238.382401) (xy 246.38787 -238.330878)
			(xy 246.409813 -238.281946) (xy 246.438389 -238.236566) (xy 246.473036 -238.195633) (xy 246.513071 -238.159953)
			(xy 246.557707 -238.130228) (xy 246.606063 -238.107044) (xy 246.657189 -238.090857) (xy 246.710078 -238.081985)
			(xy 246.73687 -238.080804) (xy 246.748046 -238.08055) (xy 246.767858 -238.070898) (xy 246.830596 -237.993936)
			(xy 246.836184 -237.9726) (xy 246.834152 -237.961424) (xy 246.831403 -237.944861) (xy 246.828478 -237.911411)
			(xy 246.82831 -237.894622) (xy 246.828797 -237.866387) (xy 246.837079 -237.810527) (xy 246.84482 -237.78337)
			(xy 246.847156 -237.774399) (xy 246.84597 -237.755913) (xy 246.842534 -237.747302) (xy 246.82958 -237.719108)
			(xy 246.825372 -237.710856) (xy 246.812219 -237.697834) (xy 246.803926 -237.693708) (xy 246.778972 -237.682112)
			(xy 246.732401 -237.652806) (xy 246.690524 -237.617113) (xy 246.654209 -237.575774) (xy 246.62421 -237.529646)
			(xy 246.601151 -237.479687) (xy 246.585508 -237.426933) (xy 246.577607 -237.372478) (xy 246.577104 -237.344966)
			(xy 246.577593 -237.317717) (xy 246.585353 -237.263773) (xy 246.600711 -237.211483) (xy 246.623355 -237.161911)
			(xy 246.652822 -237.116066) (xy 246.688514 -237.074881) (xy 246.729703 -237.039194) (xy 246.775552 -237.009732)
			(xy 246.825127 -236.987095) (xy 246.877418 -236.971743) (xy 246.931363 -236.963989) (xy 246.958612 -236.963458)
			(xy 246.989457 -236.964051) (xy 247.050342 -236.973975) (xy 247.108839 -236.993563) (xy 247.136412 -237.0074)
			(xy 247.14835 -237.01375) (xy 247.17502 -237.012988) (xy 247.260872 -236.961172) (xy 247.268145 -236.956355)
			(xy 247.279181 -236.942859) (xy 247.285078 -236.926453) (xy 247.28551 -236.917738) (xy 247.28551 -235.163106)
			(xy 247.27789 -235.14431) (xy 247.270524 -235.137198) (xy 241.984022 -229.850696) (xy 241.976619 -229.843862)
			(xy 241.958021 -229.836157) (xy 241.947954 -229.83571) (xy 236.89945 -229.83571) (xy 236.887027 -229.836317)
			(xy 236.86504 -229.847888) (xy 236.85754 -229.857808) (xy 236.810296 -229.926896) (xy 236.803918 -229.937516)
			(xy 236.800978 -229.962075) (xy 236.804708 -229.973886) (xy 236.812824 -229.995833) (xy 236.824242 -230.041212)
			(xy 236.830004 -230.087649) (xy 236.830362 -230.111046) (xy 236.830362 -230.111808) (xy 236.829876 -230.139059)
			(xy 236.82212 -230.193007) (xy 236.806765 -230.245302) (xy 236.784123 -230.294879) (xy 236.754657 -230.340729)
			(xy 236.718966 -230.38192) (xy 236.677775 -230.417611) (xy 236.631925 -230.447077) (xy 236.582348 -230.469719)
			(xy 236.530053 -230.485074) (xy 236.476105 -230.49283) (xy 236.421603 -230.49283) (xy 236.367655 -230.485074)
			(xy 236.31536 -230.469719) (xy 236.265783 -230.447077) (xy 236.219933 -230.417611) (xy 236.178742 -230.38192)
			(xy 236.143051 -230.340729) (xy 236.113585 -230.294879) (xy 236.090943 -230.245302) (xy 236.075588 -230.193007)
			(xy 236.067832 -230.139059) (xy 236.067346 -230.111808) (xy 236.067346 -230.111046) (xy 236.067697 -230.087952)
			(xy 236.073297 -230.042104) (xy 236.078522 -230.019606) (xy 236.080247 -230.011306) (xy 236.078675 -229.994437)
			(xy 236.075474 -229.986586) (xy 236.06448 -229.960995) (xy 236.049181 -229.907442) (xy 236.044994 -229.879906)
			(xy 236.042454 -229.860602) (xy 236.014006 -229.83571) (xy 234.45978 -229.83571) (xy 234.43057 -229.863396)
			(xy 234.429554 -229.883716) (xy 234.427582 -229.911223) (xy 234.416712 -229.965287) (xy 234.398173 -230.017223)
			(xy 234.37235 -230.065949) (xy 234.339781 -230.11045) (xy 234.301145 -230.149799) (xy 234.257247 -230.183176)
			(xy 234.209001 -230.209885) (xy 234.157412 -230.229371) (xy 234.103556 -230.241228) (xy 234.048554 -230.245208)
			(xy 233.993552 -230.241228) (xy 233.939696 -230.229371) (xy 233.888107 -230.209885) (xy 233.839861 -230.183176)
			(xy 233.795963 -230.149799) (xy 233.757327 -230.11045) (xy 233.724758 -230.065949) (xy 233.698935 -230.017223)
			(xy 233.680396 -229.965287) (xy 233.669526 -229.911223) (xy 233.667554 -229.883716) (xy 233.666538 -229.863396)
			(xy 233.637328 -229.83571) (xy 231.328214 -229.83571) (xy 231.307894 -229.845362) (xy 231.300528 -229.854252)
			(xy 231.243378 -229.923594) (xy 231.23779 -229.945438) (xy 231.240076 -229.956614) (xy 231.243365 -229.974468)
			(xy 231.246927 -230.010598) (xy 231.247188 -230.02875) (xy 231.247188 -230.031036) (xy 231.246633 -230.05824)
			(xy 231.238759 -230.112078) (xy 231.223316 -230.16425) (xy 231.200618 -230.2137) (xy 231.171124 -230.259423)
			(xy 231.135433 -230.300492) (xy 231.094269 -230.336073) (xy 231.048467 -230.365446) (xy 230.998958 -230.388013)
			(xy 230.946744 -230.403316) (xy 230.892885 -230.411047) (xy 230.838475 -230.411047) (xy 230.784616 -230.403316)
			(xy 230.732402 -230.388013) (xy 230.682893 -230.365446) (xy 230.637091 -230.336073) (xy 230.595927 -230.300492)
			(xy 230.560236 -230.259423) (xy 230.530742 -230.2137) (xy 230.508044 -230.16425) (xy 230.492601 -230.112078)
			(xy 230.484727 -230.05824) (xy 230.484172 -230.031036) (xy 230.484172 -230.029766) (xy 230.484406 -230.01136)
			(xy 230.487968 -229.97472) (xy 230.491284 -229.956614) (xy 230.49357 -229.945438) (xy 230.487982 -229.923594)
			(xy 230.430832 -229.854252) (xy 230.430578 -229.853998) (xy 230.422973 -229.845747) (xy 230.40267 -229.836259)
			(xy 230.391462 -229.83571) (xy 226.326192 -229.83571) (xy 226.314999 -229.836302) (xy 226.294726 -229.845802)
			(xy 226.287076 -229.853998) (xy 226.237038 -229.914196) (xy 226.230344 -229.923153) (xy 226.224688 -229.94476)
			(xy 226.226116 -229.955852) (xy 226.226116 -229.95636) (xy 226.22918 -229.973725) (xy 226.23249 -230.008833)
			(xy 226.23272 -230.026464) (xy 226.23272 -230.027226) (xy 226.232234 -230.054477) (xy 226.224478 -230.108425)
			(xy 226.209123 -230.16072) (xy 226.186481 -230.210297) (xy 226.157015 -230.256147) (xy 226.121324 -230.297338)
			(xy 226.080133 -230.333029) (xy 226.034283 -230.362495) (xy 225.984706 -230.385137) (xy 225.932411 -230.400492)
			(xy 225.878463 -230.408248) (xy 225.823961 -230.408248) (xy 225.770013 -230.400492) (xy 225.717718 -230.385137)
			(xy 225.668141 -230.362495) (xy 225.622291 -230.333029) (xy 225.5811 -230.297338) (xy 225.545409 -230.256147)
			(xy 225.515943 -230.210297) (xy 225.493301 -230.16072) (xy 225.477946 -230.108425) (xy 225.47019 -230.054477)
			(xy 225.469704 -230.027226) (xy 225.469704 -230.026464) (xy 225.469924 -230.008832) (xy 225.473231 -229.973723)
			(xy 225.476308 -229.95636) (xy 225.476308 -229.955852) (xy 225.477756 -229.944761) (xy 225.472091 -229.923149)
			(xy 225.465386 -229.914196) (xy 225.415348 -229.853998) (xy 225.407747 -229.845735) (xy 225.387445 -229.83622)
			(xy 225.376232 -229.83571) (xy 222.340932 -229.83571) (xy 222.322136 -229.84333) (xy 222.315024 -229.850696)
			(xy 221.478094 -230.687626) (xy 221.471288 -230.694973) (xy 221.463566 -230.713435) (xy 221.463108 -230.72344)
			(xy 221.463108 -232.005886) (xy 221.463757 -232.017149) (xy 221.473515 -232.037459) (xy 221.481904 -232.045002)
			(xy 221.541086 -232.09377) (xy 221.56293 -232.099358) (xy 221.574106 -232.097072) (xy 221.592523 -232.093685)
			(xy 221.629803 -232.090122) (xy 221.648528 -232.08996) (xy 221.675732 -232.090516) (xy 221.72957 -232.098391)
			(xy 221.781744 -232.113834) (xy 221.831194 -232.136533) (xy 221.876918 -232.166027) (xy 221.917988 -232.201718)
			(xy 221.953571 -232.242881) (xy 221.982945 -232.288681) (xy 222.005515 -232.338191) (xy 222.020822 -232.390404)
			(xy 222.028557 -232.444263) (xy 222.02902 -232.471468) (xy 222.028559 -232.498723) (xy 222.020806 -232.552678)
			(xy 222.005453 -232.60498) (xy 221.982812 -232.654565) (xy 221.953345 -232.700423) (xy 221.917652 -232.741621)
			(xy 221.876459 -232.777319) (xy 221.830604 -232.806791) (xy 221.781021 -232.829438) (xy 221.728721 -232.844797)
			(xy 221.674767 -232.852556) (xy 221.647512 -232.852976) (xy 221.647258 -232.852976) (xy 221.628852 -232.852741)
			(xy 221.592213 -232.849178) (xy 221.574106 -232.845864) (xy 221.56293 -232.843578) (xy 221.541086 -232.849166)
			(xy 221.481904 -232.897934) (xy 221.473553 -232.905504) (xy 221.463811 -232.925799) (xy 221.463108 -232.93705)
			(xy 221.463108 -233.182668) (xy 222.281494 -233.182668) (xy 222.285565 -233.127046) (xy 222.297691 -233.072609)
			(xy 222.317614 -233.020518) (xy 222.34491 -232.971883) (xy 222.378996 -232.92774) (xy 222.419145 -232.889031)
			(xy 222.464503 -232.85658) (xy 222.514103 -232.831079) (xy 222.566887 -232.813072) (xy 222.62173 -232.802942)
			(xy 222.677464 -232.800905) (xy 222.732901 -232.807005) (xy 222.786858 -232.821111) (xy 222.838187 -232.842923)
			(xy 222.885793 -232.871977) (xy 222.928661 -232.907652) (xy 222.965878 -232.949189) (xy 222.996651 -232.995702)
			(xy 223.020323 -233.046199) (xy 223.036391 -233.099606) (xy 223.044511 -233.154782) (xy 223.04502 -233.182668)
			(xy 223.298004 -233.182668) (xy 223.298455 -233.156352) (xy 223.305675 -233.104218) (xy 223.319989 -233.053569)
			(xy 223.341123 -233.005367) (xy 223.368679 -232.960526) (xy 223.402133 -232.919894) (xy 223.421194 -232.901744)
			(xy 223.428577 -232.894207) (xy 223.437112 -232.874939) (xy 223.437704 -232.864406) (xy 223.437704 -232.78973)
			(xy 223.437171 -232.779181) (xy 223.428638 -232.759885) (xy 223.421194 -232.752392) (xy 223.40211 -232.734262)
			(xy 223.368632 -232.693641) (xy 223.341063 -232.648799) (xy 223.319925 -232.600591) (xy 223.305621 -232.549932)
			(xy 223.298424 -232.497788) (xy 223.298004 -232.471468) (xy 223.29849 -232.444217) (xy 223.306246 -232.390269)
			(xy 223.321601 -232.337974) (xy 223.344243 -232.288397) (xy 223.373709 -232.242547) (xy 223.4094 -232.201356)
			(xy 223.450591 -232.165665) (xy 223.496441 -232.136199) (xy 223.546018 -232.113557) (xy 223.598313 -232.098202)
			(xy 223.652261 -232.090446) (xy 223.706763 -232.090446) (xy 223.760711 -232.098202) (xy 223.813006 -232.113557)
			(xy 223.862583 -232.136199) (xy 223.908433 -232.165665) (xy 223.949624 -232.201356) (xy 223.985315 -232.242547)
			(xy 224.014781 -232.288397) (xy 224.037423 -232.337974) (xy 224.052778 -232.390269) (xy 224.060534 -232.444217)
			(xy 224.06102 -232.471468) (xy 224.060586 -232.497784) (xy 224.053361 -232.549919) (xy 224.039044 -232.600567)
			(xy 224.017906 -232.648769) (xy 223.990347 -232.693611) (xy 223.956891 -232.734242) (xy 223.93783 -232.752392)
			(xy 223.930434 -232.759919) (xy 223.921905 -232.779195) (xy 223.92132 -232.78973) (xy 223.92132 -232.864406)
			(xy 223.921827 -232.874958) (xy 223.930377 -232.894254) (xy 223.93783 -232.901744) (xy 223.956917 -232.919871)
			(xy 223.990397 -232.960492) (xy 224.017969 -233.005333) (xy 224.039106 -233.053542) (xy 224.053408 -233.104202)
			(xy 224.060602 -233.156348) (xy 224.06102 -233.182668) (xy 224.313494 -233.182668) (xy 224.317565 -233.127046)
			(xy 224.329691 -233.072609) (xy 224.349614 -233.020518) (xy 224.37691 -232.971883) (xy 224.410996 -232.92774)
			(xy 224.451145 -232.889031) (xy 224.496503 -232.85658) (xy 224.546103 -232.831079) (xy 224.598887 -232.813072)
			(xy 224.65373 -232.802942) (xy 224.709464 -232.800905) (xy 224.764901 -232.807005) (xy 224.818858 -232.821111)
			(xy 224.870187 -232.842923) (xy 224.917793 -232.871977) (xy 224.960661 -232.907652) (xy 224.997878 -232.949189)
			(xy 225.028651 -232.995702) (xy 225.052323 -233.046199) (xy 225.068391 -233.099606) (xy 225.076511 -233.154782)
			(xy 225.07702 -233.182668) (xy 225.330004 -233.182668) (xy 225.330455 -233.156352) (xy 225.337675 -233.104218)
			(xy 225.351989 -233.053569) (xy 225.373123 -233.005367) (xy 225.400679 -232.960526) (xy 225.434133 -232.919894)
			(xy 225.453194 -232.901744) (xy 225.460577 -232.894207) (xy 225.469112 -232.874939) (xy 225.469704 -232.864406)
			(xy 225.469704 -232.78973) (xy 225.469171 -232.779181) (xy 225.460638 -232.759885) (xy 225.453194 -232.752392)
			(xy 225.43411 -232.734262) (xy 225.400632 -232.693641) (xy 225.373063 -232.648799) (xy 225.351925 -232.600591)
			(xy 225.337621 -232.549932) (xy 225.330424 -232.497788) (xy 225.330004 -232.471468) (xy 225.33049 -232.444217)
			(xy 225.338246 -232.390269) (xy 225.353601 -232.337974) (xy 225.376243 -232.288397) (xy 225.405709 -232.242547)
			(xy 225.4414 -232.201356) (xy 225.482591 -232.165665) (xy 225.528441 -232.136199) (xy 225.578018 -232.113557)
			(xy 225.630313 -232.098202) (xy 225.684261 -232.090446) (xy 225.738763 -232.090446) (xy 225.792711 -232.098202)
			(xy 225.845006 -232.113557) (xy 225.894583 -232.136199) (xy 225.940433 -232.165665) (xy 225.981624 -232.201356)
			(xy 226.017315 -232.242547) (xy 226.046781 -232.288397) (xy 226.069423 -232.337974) (xy 226.084778 -232.390269)
			(xy 226.092534 -232.444217) (xy 226.09302 -232.471468) (xy 226.345494 -232.471468) (xy 226.349565 -232.415846)
			(xy 226.361691 -232.361409) (xy 226.381614 -232.309318) (xy 226.40891 -232.260683) (xy 226.442996 -232.21654)
			(xy 226.483145 -232.177831) (xy 226.528503 -232.14538) (xy 226.578103 -232.119879) (xy 226.630887 -232.101872)
			(xy 226.68573 -232.091742) (xy 226.741464 -232.089705) (xy 226.796901 -232.095805) (xy 226.850858 -232.109911)
			(xy 226.902187 -232.131723) (xy 226.949793 -232.160777) (xy 226.992661 -232.196452) (xy 227.029878 -232.237989)
			(xy 227.060651 -232.284502) (xy 227.084323 -232.334999) (xy 227.100391 -232.388406) (xy 227.108511 -232.443582)
			(xy 227.10902 -232.471468) (xy 228.377494 -232.471468) (xy 228.381565 -232.415846) (xy 228.393691 -232.361409)
			(xy 228.413614 -232.309318) (xy 228.44091 -232.260683) (xy 228.474996 -232.21654) (xy 228.515145 -232.177831)
			(xy 228.560503 -232.14538) (xy 228.610103 -232.119879) (xy 228.662887 -232.101872) (xy 228.71773 -232.091742)
			(xy 228.773464 -232.089705) (xy 228.828901 -232.095805) (xy 228.882858 -232.109911) (xy 228.934187 -232.131723)
			(xy 228.981793 -232.160777) (xy 229.024661 -232.196452) (xy 229.061878 -232.237989) (xy 229.092651 -232.284502)
			(xy 229.116323 -232.334999) (xy 229.132391 -232.388406) (xy 229.140511 -232.443582) (xy 229.14102 -232.471468)
			(xy 229.140566 -232.49636) (xy 229.446074 -232.49636) (xy 229.44656 -232.469109) (xy 229.454316 -232.415161)
			(xy 229.469671 -232.362866) (xy 229.492313 -232.313289) (xy 229.521779 -232.267439) (xy 229.55747 -232.226248)
			(xy 229.598661 -232.190557) (xy 229.644511 -232.161091) (xy 229.694088 -232.138449) (xy 229.746383 -232.123094)
			(xy 229.800331 -232.115338) (xy 229.854833 -232.115338) (xy 229.908781 -232.123094) (xy 229.961076 -232.138449)
			(xy 230.010653 -232.161091) (xy 230.056503 -232.190557) (xy 230.097694 -232.226248) (xy 230.133385 -232.267439)
			(xy 230.162851 -232.313289) (xy 230.185493 -232.362866) (xy 230.200848 -232.415161) (xy 230.208604 -232.469109)
			(xy 230.20909 -232.49636) (xy 230.208484 -232.526446) (xy 230.199033 -232.585871) (xy 230.180374 -232.643077)
			(xy 230.15297 -232.696646) (xy 230.117499 -232.745251) (xy 230.096568 -232.76687) (xy 230.089456 -232.773982)
			(xy 230.081582 -232.792778) (xy 230.081836 -232.885488) (xy 230.08971 -232.90403) (xy 230.096822 -232.911142)
			(xy 230.117954 -232.932771) (xy 230.153757 -232.981498) (xy 230.181422 -233.035265) (xy 230.200256 -233.092724)
			(xy 230.209788 -233.152435) (xy 230.21036 -233.182668) (xy 230.410004 -233.182668) (xy 230.410455 -233.156352)
			(xy 230.417675 -233.104218) (xy 230.431989 -233.053569) (xy 230.453123 -233.005367) (xy 230.480679 -232.960526)
			(xy 230.514133 -232.919894) (xy 230.533194 -232.901744) (xy 230.540577 -232.894207) (xy 230.549112 -232.874939)
			(xy 230.549704 -232.864406) (xy 230.549704 -232.78973) (xy 230.549171 -232.779181) (xy 230.540638 -232.759885)
			(xy 230.533194 -232.752392) (xy 230.51411 -232.734262) (xy 230.480632 -232.693641) (xy 230.453063 -232.648799)
			(xy 230.431925 -232.600591) (xy 230.417621 -232.549932) (xy 230.410424 -232.497788) (xy 230.410004 -232.471468)
			(xy 230.41049 -232.444217) (xy 230.418246 -232.390269) (xy 230.433601 -232.337974) (xy 230.456243 -232.288397)
			(xy 230.485709 -232.242547) (xy 230.5214 -232.201356) (xy 230.562591 -232.165665) (xy 230.608441 -232.136199)
			(xy 230.658018 -232.113557) (xy 230.710313 -232.098202) (xy 230.764261 -232.090446) (xy 230.818763 -232.090446)
			(xy 230.872711 -232.098202) (xy 230.925006 -232.113557) (xy 230.974583 -232.136199) (xy 231.020433 -232.165665)
			(xy 231.061624 -232.201356) (xy 231.097315 -232.242547) (xy 231.126781 -232.288397) (xy 231.149423 -232.337974)
			(xy 231.164778 -232.390269) (xy 231.172534 -232.444217) (xy 231.17302 -232.471468) (xy 231.172586 -232.497784)
			(xy 231.165361 -232.549919) (xy 231.151044 -232.600567) (xy 231.129906 -232.648769) (xy 231.102347 -232.693611)
			(xy 231.068891 -232.734242) (xy 231.04983 -232.752392) (xy 231.042434 -232.759919) (xy 231.033905 -232.779195)
			(xy 231.03332 -232.78973) (xy 231.03332 -232.864406) (xy 231.033827 -232.874958) (xy 231.042377 -232.894254)
			(xy 231.04983 -232.901744) (xy 231.068917 -232.919871) (xy 231.102397 -232.960492) (xy 231.129969 -233.005333)
			(xy 231.151106 -233.053542) (xy 231.165408 -233.104202) (xy 231.172602 -233.156348) (xy 231.17302 -233.182668)
			(xy 231.426004 -233.182668) (xy 231.426455 -233.156352) (xy 231.433675 -233.104218) (xy 231.447989 -233.053569)
			(xy 231.469123 -233.005367) (xy 231.496679 -232.960526) (xy 231.530133 -232.919894) (xy 231.549194 -232.901744)
			(xy 231.556577 -232.894207) (xy 231.565112 -232.874939) (xy 231.565704 -232.864406) (xy 231.565704 -232.78973)
			(xy 231.565171 -232.779181) (xy 231.556638 -232.759885) (xy 231.549194 -232.752392) (xy 231.53011 -232.734262)
			(xy 231.496632 -232.693641) (xy 231.469063 -232.648799) (xy 231.447925 -232.600591) (xy 231.433621 -232.549932)
			(xy 231.426424 -232.497788) (xy 231.426004 -232.471468) (xy 231.42649 -232.444217) (xy 231.434246 -232.390269)
			(xy 231.449601 -232.337974) (xy 231.472243 -232.288397) (xy 231.501709 -232.242547) (xy 231.5374 -232.201356)
			(xy 231.578591 -232.165665) (xy 231.624441 -232.136199) (xy 231.674018 -232.113557) (xy 231.726313 -232.098202)
			(xy 231.780261 -232.090446) (xy 231.834763 -232.090446) (xy 231.888711 -232.098202) (xy 231.941006 -232.113557)
			(xy 231.990583 -232.136199) (xy 232.036433 -232.165665) (xy 232.077624 -232.201356) (xy 232.113315 -232.242547)
			(xy 232.142781 -232.288397) (xy 232.165423 -232.337974) (xy 232.180778 -232.390269) (xy 232.188534 -232.444217)
			(xy 232.18902 -232.471468) (xy 232.188586 -232.497784) (xy 232.181361 -232.549919) (xy 232.167044 -232.600567)
			(xy 232.145906 -232.648769) (xy 232.118347 -232.693611) (xy 232.084891 -232.734242) (xy 232.06583 -232.752392)
			(xy 232.058434 -232.759919) (xy 232.049905 -232.779195) (xy 232.04932 -232.78973) (xy 232.04932 -232.864406)
			(xy 232.049827 -232.874958) (xy 232.058377 -232.894254) (xy 232.06583 -232.901744) (xy 232.084917 -232.919871)
			(xy 232.118397 -232.960492) (xy 232.145969 -233.005333) (xy 232.167106 -233.053542) (xy 232.181408 -233.104202)
			(xy 232.188602 -233.156348) (xy 232.18902 -233.182668) (xy 232.442004 -233.182668) (xy 232.442455 -233.156352)
			(xy 232.449675 -233.104218) (xy 232.463989 -233.053569) (xy 232.485123 -233.005367) (xy 232.512679 -232.960526)
			(xy 232.546133 -232.919894) (xy 232.565194 -232.901744) (xy 232.572577 -232.894207) (xy 232.581112 -232.874939)
			(xy 232.581704 -232.864406) (xy 232.581704 -232.78973) (xy 232.581171 -232.779181) (xy 232.572638 -232.759885)
			(xy 232.565194 -232.752392) (xy 232.54611 -232.734262) (xy 232.512632 -232.693641) (xy 232.485063 -232.648799)
			(xy 232.463925 -232.600591) (xy 232.449621 -232.549932) (xy 232.442424 -232.497788) (xy 232.442004 -232.471468)
			(xy 232.44249 -232.444217) (xy 232.450246 -232.390269) (xy 232.465601 -232.337974) (xy 232.488243 -232.288397)
			(xy 232.517709 -232.242547) (xy 232.5534 -232.201356) (xy 232.594591 -232.165665) (xy 232.640441 -232.136199)
			(xy 232.690018 -232.113557) (xy 232.742313 -232.098202) (xy 232.796261 -232.090446) (xy 232.850763 -232.090446)
			(xy 232.904711 -232.098202) (xy 232.957006 -232.113557) (xy 233.006583 -232.136199) (xy 233.052433 -232.165665)
			(xy 233.093624 -232.201356) (xy 233.129315 -232.242547) (xy 233.158781 -232.288397) (xy 233.181423 -232.337974)
			(xy 233.196778 -232.390269) (xy 233.204534 -232.444217) (xy 233.20502 -232.471468) (xy 233.204586 -232.497784)
			(xy 233.197361 -232.549919) (xy 233.183044 -232.600567) (xy 233.161906 -232.648769) (xy 233.134347 -232.693611)
			(xy 233.100891 -232.734242) (xy 233.08183 -232.752392) (xy 233.074434 -232.759919) (xy 233.065905 -232.779195)
			(xy 233.06532 -232.78973) (xy 233.06532 -232.864406) (xy 233.065827 -232.874958) (xy 233.074377 -232.894254)
			(xy 233.08183 -232.901744) (xy 233.100917 -232.919871) (xy 233.134397 -232.960492) (xy 233.161969 -233.005333)
			(xy 233.183106 -233.053542) (xy 233.197408 -233.104202) (xy 233.204602 -233.156348) (xy 233.20502 -233.182668)
			(xy 233.458004 -233.182668) (xy 233.458455 -233.156352) (xy 233.465675 -233.104218) (xy 233.479989 -233.053569)
			(xy 233.501123 -233.005367) (xy 233.528679 -232.960526) (xy 233.562133 -232.919894) (xy 233.581194 -232.901744)
			(xy 233.588577 -232.894207) (xy 233.597112 -232.874939) (xy 233.597704 -232.864406) (xy 233.597704 -232.78973)
			(xy 233.597171 -232.779181) (xy 233.588638 -232.759885) (xy 233.581194 -232.752392) (xy 233.56211 -232.734262)
			(xy 233.528632 -232.693641) (xy 233.501063 -232.648799) (xy 233.479925 -232.600591) (xy 233.465621 -232.549932)
			(xy 233.458424 -232.497788) (xy 233.458004 -232.471468) (xy 233.45849 -232.444217) (xy 233.466246 -232.390269)
			(xy 233.481601 -232.337974) (xy 233.504243 -232.288397) (xy 233.533709 -232.242547) (xy 233.5694 -232.201356)
			(xy 233.610591 -232.165665) (xy 233.656441 -232.136199) (xy 233.706018 -232.113557) (xy 233.758313 -232.098202)
			(xy 233.812261 -232.090446) (xy 233.866763 -232.090446) (xy 233.920711 -232.098202) (xy 233.973006 -232.113557)
			(xy 234.022583 -232.136199) (xy 234.068433 -232.165665) (xy 234.109624 -232.201356) (xy 234.145315 -232.242547)
			(xy 234.174781 -232.288397) (xy 234.197423 -232.337974) (xy 234.212778 -232.390269) (xy 234.220534 -232.444217)
			(xy 234.22102 -232.471468) (xy 234.220586 -232.497784) (xy 234.213361 -232.549919) (xy 234.199044 -232.600567)
			(xy 234.177906 -232.648769) (xy 234.150347 -232.693611) (xy 234.116891 -232.734242) (xy 234.09783 -232.752392)
			(xy 234.090434 -232.759919) (xy 234.081905 -232.779195) (xy 234.08132 -232.78973) (xy 234.08132 -232.864406)
			(xy 234.081827 -232.874958) (xy 234.090377 -232.894254) (xy 234.09783 -232.901744) (xy 234.116917 -232.919871)
			(xy 234.150397 -232.960492) (xy 234.177969 -233.005333) (xy 234.199106 -233.053542) (xy 234.213408 -233.104202)
			(xy 234.220602 -233.156348) (xy 234.22102 -233.182668) (xy 234.474004 -233.182668) (xy 234.474455 -233.156352)
			(xy 234.481675 -233.104218) (xy 234.495989 -233.053569) (xy 234.517123 -233.005367) (xy 234.544679 -232.960526)
			(xy 234.578133 -232.919894) (xy 234.597194 -232.901744) (xy 234.604577 -232.894207) (xy 234.613112 -232.874939)
			(xy 234.613704 -232.864406) (xy 234.613704 -232.78973) (xy 234.613171 -232.779181) (xy 234.604638 -232.759885)
			(xy 234.597194 -232.752392) (xy 234.57811 -232.734262) (xy 234.544632 -232.693641) (xy 234.517063 -232.648799)
			(xy 234.495925 -232.600591) (xy 234.481621 -232.549932) (xy 234.474424 -232.497788) (xy 234.474004 -232.471468)
			(xy 234.47449 -232.444217) (xy 234.482246 -232.390269) (xy 234.497601 -232.337974) (xy 234.520243 -232.288397)
			(xy 234.549709 -232.242547) (xy 234.5854 -232.201356) (xy 234.626591 -232.165665) (xy 234.672441 -232.136199)
			(xy 234.722018 -232.113557) (xy 234.774313 -232.098202) (xy 234.828261 -232.090446) (xy 234.882763 -232.090446)
			(xy 234.936711 -232.098202) (xy 234.989006 -232.113557) (xy 235.038583 -232.136199) (xy 235.084433 -232.165665)
			(xy 235.125624 -232.201356) (xy 235.161315 -232.242547) (xy 235.190781 -232.288397) (xy 235.213423 -232.337974)
			(xy 235.228778 -232.390269) (xy 235.236534 -232.444217) (xy 235.23702 -232.471468) (xy 235.236586 -232.497784)
			(xy 235.229361 -232.549919) (xy 235.215044 -232.600567) (xy 235.193906 -232.648769) (xy 235.166347 -232.693611)
			(xy 235.132891 -232.734242) (xy 235.11383 -232.752392) (xy 235.106434 -232.759919) (xy 235.097905 -232.779195)
			(xy 235.09732 -232.78973) (xy 235.09732 -232.864406) (xy 235.097827 -232.874958) (xy 235.106377 -232.894254)
			(xy 235.11383 -232.901744) (xy 235.132917 -232.919871) (xy 235.166397 -232.960492) (xy 235.193969 -233.005333)
			(xy 235.215106 -233.053542) (xy 235.229408 -233.104202) (xy 235.236602 -233.156348) (xy 235.23702 -233.182668)
			(xy 235.490004 -233.182668) (xy 235.490455 -233.156352) (xy 235.497675 -233.104218) (xy 235.511989 -233.053569)
			(xy 235.533123 -233.005367) (xy 235.560679 -232.960526) (xy 235.594133 -232.919894) (xy 235.613194 -232.901744)
			(xy 235.620577 -232.894207) (xy 235.629112 -232.874939) (xy 235.629704 -232.864406) (xy 235.629704 -232.78973)
			(xy 235.629171 -232.779181) (xy 235.620638 -232.759885) (xy 235.613194 -232.752392) (xy 235.59411 -232.734262)
			(xy 235.560632 -232.693641) (xy 235.533063 -232.648799) (xy 235.511925 -232.600591) (xy 235.497621 -232.549932)
			(xy 235.490424 -232.497788) (xy 235.490004 -232.471468) (xy 235.49049 -232.444217) (xy 235.498246 -232.390269)
			(xy 235.513601 -232.337974) (xy 235.536243 -232.288397) (xy 235.565709 -232.242547) (xy 235.6014 -232.201356)
			(xy 235.642591 -232.165665) (xy 235.688441 -232.136199) (xy 235.738018 -232.113557) (xy 235.790313 -232.098202)
			(xy 235.844261 -232.090446) (xy 235.898763 -232.090446) (xy 235.952711 -232.098202) (xy 236.005006 -232.113557)
			(xy 236.054583 -232.136199) (xy 236.100433 -232.165665) (xy 236.141624 -232.201356) (xy 236.177315 -232.242547)
			(xy 236.206781 -232.288397) (xy 236.229423 -232.337974) (xy 236.244778 -232.390269) (xy 236.252534 -232.444217)
			(xy 236.25302 -232.471468) (xy 236.252586 -232.497784) (xy 236.245361 -232.549919) (xy 236.231044 -232.600567)
			(xy 236.209906 -232.648769) (xy 236.182347 -232.693611) (xy 236.148891 -232.734242) (xy 236.12983 -232.752392)
			(xy 236.122434 -232.759919) (xy 236.113905 -232.779195) (xy 236.11332 -232.78973) (xy 236.11332 -232.864406)
			(xy 236.113827 -232.874958) (xy 236.122377 -232.894254) (xy 236.12983 -232.901744) (xy 236.148917 -232.919871)
			(xy 236.182397 -232.960492) (xy 236.209969 -233.005333) (xy 236.231106 -233.053542) (xy 236.245408 -233.104202)
			(xy 236.252602 -233.156348) (xy 236.25302 -233.182668) (xy 236.506004 -233.182668) (xy 236.506455 -233.156352)
			(xy 236.513675 -233.104218) (xy 236.527989 -233.053569) (xy 236.549123 -233.005367) (xy 236.576679 -232.960526)
			(xy 236.610133 -232.919894) (xy 236.629194 -232.901744) (xy 236.636577 -232.894207) (xy 236.645112 -232.874939)
			(xy 236.645704 -232.864406) (xy 236.645704 -232.78973) (xy 236.645171 -232.779181) (xy 236.636638 -232.759885)
			(xy 236.629194 -232.752392) (xy 236.61011 -232.734262) (xy 236.576632 -232.693641) (xy 236.549063 -232.648799)
			(xy 236.527925 -232.600591) (xy 236.513621 -232.549932) (xy 236.506424 -232.497788) (xy 236.506004 -232.471468)
			(xy 236.50649 -232.444217) (xy 236.514246 -232.390269) (xy 236.529601 -232.337974) (xy 236.552243 -232.288397)
			(xy 236.581709 -232.242547) (xy 236.6174 -232.201356) (xy 236.658591 -232.165665) (xy 236.704441 -232.136199)
			(xy 236.754018 -232.113557) (xy 236.806313 -232.098202) (xy 236.860261 -232.090446) (xy 236.914763 -232.090446)
			(xy 236.968711 -232.098202) (xy 237.021006 -232.113557) (xy 237.070583 -232.136199) (xy 237.116433 -232.165665)
			(xy 237.157624 -232.201356) (xy 237.193315 -232.242547) (xy 237.222781 -232.288397) (xy 237.245423 -232.337974)
			(xy 237.260778 -232.390269) (xy 237.268534 -232.444217) (xy 237.26902 -232.471468) (xy 237.268586 -232.497784)
			(xy 237.261361 -232.549919) (xy 237.247044 -232.600567) (xy 237.225906 -232.648769) (xy 237.198347 -232.693611)
			(xy 237.164891 -232.734242) (xy 237.14583 -232.752392) (xy 237.138434 -232.759919) (xy 237.129905 -232.779195)
			(xy 237.12932 -232.78973) (xy 237.12932 -232.864406) (xy 237.129827 -232.874958) (xy 237.138377 -232.894254)
			(xy 237.14583 -232.901744) (xy 237.164917 -232.919871) (xy 237.198397 -232.960492) (xy 237.225969 -233.005333)
			(xy 237.247106 -233.053542) (xy 237.261408 -233.104202) (xy 237.268602 -233.156348) (xy 237.26902 -233.182668)
			(xy 237.522004 -233.182668) (xy 237.522455 -233.156352) (xy 237.529675 -233.104218) (xy 237.543989 -233.053569)
			(xy 237.565123 -233.005367) (xy 237.592679 -232.960526) (xy 237.626133 -232.919894) (xy 237.645194 -232.901744)
			(xy 237.652577 -232.894207) (xy 237.661112 -232.874939) (xy 237.661704 -232.864406) (xy 237.661704 -232.78973)
			(xy 237.661171 -232.779181) (xy 237.652638 -232.759885) (xy 237.645194 -232.752392) (xy 237.62611 -232.734262)
			(xy 237.592632 -232.693641) (xy 237.565063 -232.648799) (xy 237.543925 -232.600591) (xy 237.529621 -232.549932)
			(xy 237.522424 -232.497788) (xy 237.522004 -232.471468) (xy 237.52249 -232.444217) (xy 237.530246 -232.390269)
			(xy 237.545601 -232.337974) (xy 237.568243 -232.288397) (xy 237.597709 -232.242547) (xy 237.6334 -232.201356)
			(xy 237.674591 -232.165665) (xy 237.720441 -232.136199) (xy 237.770018 -232.113557) (xy 237.822313 -232.098202)
			(xy 237.876261 -232.090446) (xy 237.930763 -232.090446) (xy 237.984711 -232.098202) (xy 238.037006 -232.113557)
			(xy 238.086583 -232.136199) (xy 238.132433 -232.165665) (xy 238.173624 -232.201356) (xy 238.209315 -232.242547)
			(xy 238.238781 -232.288397) (xy 238.261423 -232.337974) (xy 238.276778 -232.390269) (xy 238.284534 -232.444217)
			(xy 238.28502 -232.471468) (xy 238.537494 -232.471468) (xy 238.541565 -232.415846) (xy 238.553691 -232.361409)
			(xy 238.573614 -232.309318) (xy 238.60091 -232.260683) (xy 238.634996 -232.21654) (xy 238.675145 -232.177831)
			(xy 238.720503 -232.14538) (xy 238.770103 -232.119879) (xy 238.822887 -232.101872) (xy 238.87773 -232.091742)
			(xy 238.933464 -232.089705) (xy 238.988901 -232.095805) (xy 239.042858 -232.109911) (xy 239.094187 -232.131723)
			(xy 239.141793 -232.160777) (xy 239.184661 -232.196452) (xy 239.221878 -232.237989) (xy 239.252651 -232.284502)
			(xy 239.276323 -232.334999) (xy 239.292391 -232.388406) (xy 239.300511 -232.443582) (xy 239.30102 -232.471468)
			(xy 240.163348 -232.471468) (xy 240.167419 -232.415846) (xy 240.179545 -232.361409) (xy 240.199468 -232.309318)
			(xy 240.226764 -232.260683) (xy 240.26085 -232.21654) (xy 240.300999 -232.177831) (xy 240.346357 -232.14538)
			(xy 240.395957 -232.119879) (xy 240.448741 -232.101872) (xy 240.503584 -232.091742) (xy 240.559318 -232.089705)
			(xy 240.614755 -232.095805) (xy 240.668712 -232.109911) (xy 240.720041 -232.131723) (xy 240.767647 -232.160777)
			(xy 240.810515 -232.196452) (xy 240.847732 -232.237989) (xy 240.878505 -232.284502) (xy 240.902177 -232.334999)
			(xy 240.918245 -232.388406) (xy 240.926365 -232.443582) (xy 240.926874 -232.471468) (xy 240.926365 -232.499354)
			(xy 240.918245 -232.55453) (xy 240.902177 -232.607937) (xy 240.878505 -232.658434) (xy 240.847732 -232.704947)
			(xy 240.810515 -232.746484) (xy 240.767647 -232.782159) (xy 240.720041 -232.811213) (xy 240.668712 -232.833025)
			(xy 240.614755 -232.847131) (xy 240.559318 -232.853231) (xy 240.503584 -232.851194) (xy 240.448741 -232.841064)
			(xy 240.395957 -232.823057) (xy 240.346357 -232.797556) (xy 240.300999 -232.765105) (xy 240.26085 -232.726396)
			(xy 240.226764 -232.682253) (xy 240.199468 -232.633618) (xy 240.179545 -232.581527) (xy 240.167419 -232.52709)
			(xy 240.163348 -232.471468) (xy 239.30102 -232.471468) (xy 239.300511 -232.499354) (xy 239.292391 -232.55453)
			(xy 239.276323 -232.607937) (xy 239.252651 -232.658434) (xy 239.221878 -232.704947) (xy 239.184661 -232.746484)
			(xy 239.141793 -232.782159) (xy 239.094187 -232.811213) (xy 239.042858 -232.833025) (xy 238.988901 -232.847131)
			(xy 238.933464 -232.853231) (xy 238.87773 -232.851194) (xy 238.822887 -232.841064) (xy 238.770103 -232.823057)
			(xy 238.720503 -232.797556) (xy 238.675145 -232.765105) (xy 238.634996 -232.726396) (xy 238.60091 -232.682253)
			(xy 238.573614 -232.633618) (xy 238.553691 -232.581527) (xy 238.541565 -232.52709) (xy 238.537494 -232.471468)
			(xy 238.28502 -232.471468) (xy 238.284586 -232.497784) (xy 238.277361 -232.549919) (xy 238.263044 -232.600567)
			(xy 238.241906 -232.648769) (xy 238.214347 -232.693611) (xy 238.180891 -232.734242) (xy 238.16183 -232.752392)
			(xy 238.154434 -232.759919) (xy 238.145905 -232.779195) (xy 238.14532 -232.78973) (xy 238.14532 -232.864406)
			(xy 238.145827 -232.874958) (xy 238.154377 -232.894254) (xy 238.16183 -232.901744) (xy 238.180917 -232.919871)
			(xy 238.214397 -232.960492) (xy 238.241969 -233.005333) (xy 238.263106 -233.053542) (xy 238.277408 -233.104202)
			(xy 238.284602 -233.156348) (xy 238.28502 -233.182668) (xy 238.284534 -233.209919) (xy 238.278811 -233.249724)
			(xy 243.342412 -233.249724) (xy 243.346483 -233.194102) (xy 243.358609 -233.139665) (xy 243.378532 -233.087574)
			(xy 243.405828 -233.038939) (xy 243.439914 -232.994796) (xy 243.480063 -232.956087) (xy 243.525421 -232.923636)
			(xy 243.575021 -232.898135) (xy 243.627805 -232.880128) (xy 243.682648 -232.869998) (xy 243.738382 -232.867961)
			(xy 243.793819 -232.874061) (xy 243.847776 -232.888167) (xy 243.899105 -232.909979) (xy 243.946711 -232.939033)
			(xy 243.989579 -232.974708) (xy 244.026796 -233.016245) (xy 244.057569 -233.062758) (xy 244.081241 -233.113255)
			(xy 244.097309 -233.166662) (xy 244.105429 -233.221838) (xy 244.105938 -233.249724) (xy 244.105429 -233.27761)
			(xy 244.097309 -233.332786) (xy 244.081241 -233.386193) (xy 244.057569 -233.43669) (xy 244.026796 -233.483203)
			(xy 243.989579 -233.52474) (xy 243.946711 -233.560415) (xy 243.899105 -233.589469) (xy 243.847776 -233.611281)
			(xy 243.793819 -233.625387) (xy 243.738382 -233.631487) (xy 243.682648 -233.62945) (xy 243.627805 -233.61932)
			(xy 243.575021 -233.601313) (xy 243.525421 -233.575812) (xy 243.480063 -233.543361) (xy 243.439914 -233.504652)
			(xy 243.405828 -233.460509) (xy 243.378532 -233.411874) (xy 243.358609 -233.359783) (xy 243.346483 -233.305346)
			(xy 243.342412 -233.249724) (xy 238.278811 -233.249724) (xy 238.276778 -233.263867) (xy 238.261423 -233.316162)
			(xy 238.238781 -233.365739) (xy 238.209315 -233.411589) (xy 238.173624 -233.45278) (xy 238.132433 -233.488471)
			(xy 238.086583 -233.517937) (xy 238.037006 -233.540579) (xy 237.984711 -233.555934) (xy 237.930763 -233.56369)
			(xy 237.876261 -233.56369) (xy 237.822313 -233.555934) (xy 237.770018 -233.540579) (xy 237.720441 -233.517937)
			(xy 237.674591 -233.488471) (xy 237.6334 -233.45278) (xy 237.597709 -233.411589) (xy 237.568243 -233.365739)
			(xy 237.545601 -233.316162) (xy 237.530246 -233.263867) (xy 237.52249 -233.209919) (xy 237.522004 -233.182668)
			(xy 237.26902 -233.182668) (xy 237.268534 -233.209919) (xy 237.260778 -233.263867) (xy 237.245423 -233.316162)
			(xy 237.222781 -233.365739) (xy 237.193315 -233.411589) (xy 237.157624 -233.45278) (xy 237.116433 -233.488471)
			(xy 237.070583 -233.517937) (xy 237.021006 -233.540579) (xy 236.968711 -233.555934) (xy 236.914763 -233.56369)
			(xy 236.860261 -233.56369) (xy 236.806313 -233.555934) (xy 236.754018 -233.540579) (xy 236.704441 -233.517937)
			(xy 236.658591 -233.488471) (xy 236.6174 -233.45278) (xy 236.581709 -233.411589) (xy 236.552243 -233.365739)
			(xy 236.529601 -233.316162) (xy 236.514246 -233.263867) (xy 236.50649 -233.209919) (xy 236.506004 -233.182668)
			(xy 236.25302 -233.182668) (xy 236.252534 -233.209919) (xy 236.244778 -233.263867) (xy 236.229423 -233.316162)
			(xy 236.206781 -233.365739) (xy 236.177315 -233.411589) (xy 236.141624 -233.45278) (xy 236.100433 -233.488471)
			(xy 236.054583 -233.517937) (xy 236.005006 -233.540579) (xy 235.952711 -233.555934) (xy 235.898763 -233.56369)
			(xy 235.844261 -233.56369) (xy 235.790313 -233.555934) (xy 235.738018 -233.540579) (xy 235.688441 -233.517937)
			(xy 235.642591 -233.488471) (xy 235.6014 -233.45278) (xy 235.565709 -233.411589) (xy 235.536243 -233.365739)
			(xy 235.513601 -233.316162) (xy 235.498246 -233.263867) (xy 235.49049 -233.209919) (xy 235.490004 -233.182668)
			(xy 235.23702 -233.182668) (xy 235.236534 -233.209919) (xy 235.228778 -233.263867) (xy 235.213423 -233.316162)
			(xy 235.190781 -233.365739) (xy 235.161315 -233.411589) (xy 235.125624 -233.45278) (xy 235.084433 -233.488471)
			(xy 235.038583 -233.517937) (xy 234.989006 -233.540579) (xy 234.936711 -233.555934) (xy 234.882763 -233.56369)
			(xy 234.828261 -233.56369) (xy 234.774313 -233.555934) (xy 234.722018 -233.540579) (xy 234.672441 -233.517937)
			(xy 234.626591 -233.488471) (xy 234.5854 -233.45278) (xy 234.549709 -233.411589) (xy 234.520243 -233.365739)
			(xy 234.497601 -233.316162) (xy 234.482246 -233.263867) (xy 234.47449 -233.209919) (xy 234.474004 -233.182668)
			(xy 234.22102 -233.182668) (xy 234.220534 -233.209919) (xy 234.212778 -233.263867) (xy 234.197423 -233.316162)
			(xy 234.174781 -233.365739) (xy 234.145315 -233.411589) (xy 234.109624 -233.45278) (xy 234.068433 -233.488471)
			(xy 234.022583 -233.517937) (xy 233.973006 -233.540579) (xy 233.920711 -233.555934) (xy 233.866763 -233.56369)
			(xy 233.812261 -233.56369) (xy 233.758313 -233.555934) (xy 233.706018 -233.540579) (xy 233.656441 -233.517937)
			(xy 233.610591 -233.488471) (xy 233.5694 -233.45278) (xy 233.533709 -233.411589) (xy 233.504243 -233.365739)
			(xy 233.481601 -233.316162) (xy 233.466246 -233.263867) (xy 233.45849 -233.209919) (xy 233.458004 -233.182668)
			(xy 233.20502 -233.182668) (xy 233.204534 -233.209919) (xy 233.196778 -233.263867) (xy 233.181423 -233.316162)
			(xy 233.158781 -233.365739) (xy 233.129315 -233.411589) (xy 233.093624 -233.45278) (xy 233.052433 -233.488471)
			(xy 233.006583 -233.517937) (xy 232.957006 -233.540579) (xy 232.904711 -233.555934) (xy 232.850763 -233.56369)
			(xy 232.796261 -233.56369) (xy 232.742313 -233.555934) (xy 232.690018 -233.540579) (xy 232.640441 -233.517937)
			(xy 232.594591 -233.488471) (xy 232.5534 -233.45278) (xy 232.517709 -233.411589) (xy 232.488243 -233.365739)
			(xy 232.465601 -233.316162) (xy 232.450246 -233.263867) (xy 232.44249 -233.209919) (xy 232.442004 -233.182668)
			(xy 232.18902 -233.182668) (xy 232.188534 -233.209919) (xy 232.180778 -233.263867) (xy 232.165423 -233.316162)
			(xy 232.142781 -233.365739) (xy 232.113315 -233.411589) (xy 232.077624 -233.45278) (xy 232.036433 -233.488471)
			(xy 231.990583 -233.517937) (xy 231.941006 -233.540579) (xy 231.888711 -233.555934) (xy 231.834763 -233.56369)
			(xy 231.780261 -233.56369) (xy 231.726313 -233.555934) (xy 231.674018 -233.540579) (xy 231.624441 -233.517937)
			(xy 231.578591 -233.488471) (xy 231.5374 -233.45278) (xy 231.501709 -233.411589) (xy 231.472243 -233.365739)
			(xy 231.449601 -233.316162) (xy 231.434246 -233.263867) (xy 231.42649 -233.209919) (xy 231.426004 -233.182668)
			(xy 231.17302 -233.182668) (xy 231.172534 -233.209919) (xy 231.164778 -233.263867) (xy 231.149423 -233.316162)
			(xy 231.126781 -233.365739) (xy 231.097315 -233.411589) (xy 231.061624 -233.45278) (xy 231.020433 -233.488471)
			(xy 230.974583 -233.517937) (xy 230.925006 -233.540579) (xy 230.872711 -233.555934) (xy 230.818763 -233.56369)
			(xy 230.764261 -233.56369) (xy 230.710313 -233.555934) (xy 230.658018 -233.540579) (xy 230.608441 -233.517937)
			(xy 230.562591 -233.488471) (xy 230.5214 -233.45278) (xy 230.485709 -233.411589) (xy 230.456243 -233.365739)
			(xy 230.433601 -233.316162) (xy 230.418246 -233.263867) (xy 230.41049 -233.209919) (xy 230.410004 -233.182668)
			(xy 230.21036 -233.182668) (xy 230.209874 -233.209919) (xy 230.202118 -233.263867) (xy 230.186763 -233.316162)
			(xy 230.164121 -233.365739) (xy 230.134655 -233.411589) (xy 230.098964 -233.45278) (xy 230.057773 -233.488471)
			(xy 230.011923 -233.517937) (xy 229.962346 -233.540579) (xy 229.910051 -233.555934) (xy 229.856103 -233.56369)
			(xy 229.801601 -233.56369) (xy 229.747653 -233.555934) (xy 229.695358 -233.540579) (xy 229.645781 -233.517937)
			(xy 229.599931 -233.488471) (xy 229.55874 -233.45278) (xy 229.523049 -233.411589) (xy 229.493583 -233.365739)
			(xy 229.470941 -233.316162) (xy 229.455586 -233.263867) (xy 229.44783 -233.209919) (xy 229.447344 -233.182668)
			(xy 229.447895 -233.15258) (xy 229.457358 -233.093152) (xy 229.476029 -233.035945) (xy 229.503446 -232.982377)
			(xy 229.538929 -232.933775) (xy 229.559866 -232.912158) (xy 229.566978 -232.905046) (xy 229.574852 -232.88625)
			(xy 229.574598 -232.79354) (xy 229.566724 -232.774998) (xy 229.559612 -232.767886) (xy 229.538482 -232.746256)
			(xy 229.502681 -232.697527) (xy 229.475017 -232.643761) (xy 229.456182 -232.586303) (xy 229.446648 -232.526593)
			(xy 229.446074 -232.49636) (xy 229.140566 -232.49636) (xy 229.140511 -232.499354) (xy 229.132391 -232.55453)
			(xy 229.116323 -232.607937) (xy 229.092651 -232.658434) (xy 229.061878 -232.704947) (xy 229.024661 -232.746484)
			(xy 228.981793 -232.782159) (xy 228.934187 -232.811213) (xy 228.882858 -232.833025) (xy 228.828901 -232.847131)
			(xy 228.773464 -232.853231) (xy 228.71773 -232.851194) (xy 228.662887 -232.841064) (xy 228.610103 -232.823057)
			(xy 228.560503 -232.797556) (xy 228.515145 -232.765105) (xy 228.474996 -232.726396) (xy 228.44091 -232.682253)
			(xy 228.413614 -232.633618) (xy 228.393691 -232.581527) (xy 228.381565 -232.52709) (xy 228.377494 -232.471468)
			(xy 227.10902 -232.471468) (xy 227.108511 -232.499354) (xy 227.100391 -232.55453) (xy 227.084323 -232.607937)
			(xy 227.060651 -232.658434) (xy 227.029878 -232.704947) (xy 226.992661 -232.746484) (xy 226.949793 -232.782159)
			(xy 226.902187 -232.811213) (xy 226.850858 -232.833025) (xy 226.796901 -232.847131) (xy 226.741464 -232.853231)
			(xy 226.68573 -232.851194) (xy 226.630887 -232.841064) (xy 226.578103 -232.823057) (xy 226.528503 -232.797556)
			(xy 226.483145 -232.765105) (xy 226.442996 -232.726396) (xy 226.40891 -232.682253) (xy 226.381614 -232.633618)
			(xy 226.361691 -232.581527) (xy 226.349565 -232.52709) (xy 226.345494 -232.471468) (xy 226.09302 -232.471468)
			(xy 226.092586 -232.497784) (xy 226.085361 -232.549919) (xy 226.071044 -232.600567) (xy 226.049906 -232.648769)
			(xy 226.022347 -232.693611) (xy 225.988891 -232.734242) (xy 225.96983 -232.752392) (xy 225.962434 -232.759919)
			(xy 225.953905 -232.779195) (xy 225.95332 -232.78973) (xy 225.95332 -232.864406) (xy 225.953827 -232.874958)
			(xy 225.962377 -232.894254) (xy 225.96983 -232.901744) (xy 225.988917 -232.919871) (xy 226.022397 -232.960492)
			(xy 226.049969 -233.005333) (xy 226.071106 -233.053542) (xy 226.085408 -233.104202) (xy 226.092602 -233.156348)
			(xy 226.09302 -233.182668) (xy 227.342444 -233.182668) (xy 227.346515 -233.127046) (xy 227.358641 -233.072609)
			(xy 227.378564 -233.020518) (xy 227.40586 -232.971883) (xy 227.439946 -232.92774) (xy 227.480095 -232.889031)
			(xy 227.525453 -232.85658) (xy 227.575053 -232.831079) (xy 227.627837 -232.813072) (xy 227.68268 -232.802942)
			(xy 227.738414 -232.800905) (xy 227.793851 -232.807005) (xy 227.847808 -232.821111) (xy 227.899137 -232.842923)
			(xy 227.946743 -232.871977) (xy 227.989611 -232.907652) (xy 228.026828 -232.949189) (xy 228.057601 -232.995702)
			(xy 228.081273 -233.046199) (xy 228.097341 -233.099606) (xy 228.105461 -233.154782) (xy 228.10597 -233.182668)
			(xy 228.105461 -233.210554) (xy 228.097341 -233.26573) (xy 228.081273 -233.319137) (xy 228.057601 -233.369634)
			(xy 228.026828 -233.416147) (xy 227.989611 -233.457684) (xy 227.946743 -233.493359) (xy 227.899137 -233.522413)
			(xy 227.847808 -233.544225) (xy 227.793851 -233.558331) (xy 227.738414 -233.564431) (xy 227.68268 -233.562394)
			(xy 227.627837 -233.552264) (xy 227.575053 -233.534257) (xy 227.525453 -233.508756) (xy 227.480095 -233.476305)
			(xy 227.439946 -233.437596) (xy 227.40586 -233.393453) (xy 227.378564 -233.344818) (xy 227.358641 -233.292727)
			(xy 227.346515 -233.23829) (xy 227.342444 -233.182668) (xy 226.09302 -233.182668) (xy 226.092534 -233.209919)
			(xy 226.084778 -233.263867) (xy 226.069423 -233.316162) (xy 226.046781 -233.365739) (xy 226.017315 -233.411589)
			(xy 225.981624 -233.45278) (xy 225.940433 -233.488471) (xy 225.894583 -233.517937) (xy 225.845006 -233.540579)
			(xy 225.792711 -233.555934) (xy 225.738763 -233.56369) (xy 225.684261 -233.56369) (xy 225.630313 -233.555934)
			(xy 225.578018 -233.540579) (xy 225.528441 -233.517937) (xy 225.482591 -233.488471) (xy 225.4414 -233.45278)
			(xy 225.405709 -233.411589) (xy 225.376243 -233.365739) (xy 225.353601 -233.316162) (xy 225.338246 -233.263867)
			(xy 225.33049 -233.209919) (xy 225.330004 -233.182668) (xy 225.07702 -233.182668) (xy 225.076511 -233.210554)
			(xy 225.068391 -233.26573) (xy 225.052323 -233.319137) (xy 225.028651 -233.369634) (xy 224.997878 -233.416147)
			(xy 224.960661 -233.457684) (xy 224.917793 -233.493359) (xy 224.870187 -233.522413) (xy 224.818858 -233.544225)
			(xy 224.764901 -233.558331) (xy 224.709464 -233.564431) (xy 224.65373 -233.562394) (xy 224.598887 -233.552264)
			(xy 224.546103 -233.534257) (xy 224.496503 -233.508756) (xy 224.451145 -233.476305) (xy 224.410996 -233.437596)
			(xy 224.37691 -233.393453) (xy 224.349614 -233.344818) (xy 224.329691 -233.292727) (xy 224.317565 -233.23829)
			(xy 224.313494 -233.182668) (xy 224.06102 -233.182668) (xy 224.060534 -233.209919) (xy 224.052778 -233.263867)
			(xy 224.037423 -233.316162) (xy 224.014781 -233.365739) (xy 223.985315 -233.411589) (xy 223.949624 -233.45278)
			(xy 223.908433 -233.488471) (xy 223.862583 -233.517937) (xy 223.813006 -233.540579) (xy 223.760711 -233.555934)
			(xy 223.706763 -233.56369) (xy 223.652261 -233.56369) (xy 223.598313 -233.555934) (xy 223.546018 -233.540579)
			(xy 223.496441 -233.517937) (xy 223.450591 -233.488471) (xy 223.4094 -233.45278) (xy 223.373709 -233.411589)
			(xy 223.344243 -233.365739) (xy 223.321601 -233.316162) (xy 223.306246 -233.263867) (xy 223.29849 -233.209919)
			(xy 223.298004 -233.182668) (xy 223.04502 -233.182668) (xy 223.044511 -233.210554) (xy 223.036391 -233.26573)
			(xy 223.020323 -233.319137) (xy 222.996651 -233.369634) (xy 222.965878 -233.416147) (xy 222.928661 -233.457684)
			(xy 222.885793 -233.493359) (xy 222.838187 -233.522413) (xy 222.786858 -233.544225) (xy 222.732901 -233.558331)
			(xy 222.677464 -233.564431) (xy 222.62173 -233.562394) (xy 222.566887 -233.552264) (xy 222.514103 -233.534257)
			(xy 222.464503 -233.508756) (xy 222.419145 -233.476305) (xy 222.378996 -233.437596) (xy 222.34491 -233.393453)
			(xy 222.317614 -233.344818) (xy 222.297691 -233.292727) (xy 222.285565 -233.23829) (xy 222.281494 -233.182668)
			(xy 221.463108 -233.182668) (xy 221.463108 -235.737654) (xy 231.425494 -235.737654) (xy 231.429565 -235.682032)
			(xy 231.441691 -235.627595) (xy 231.461614 -235.575504) (xy 231.48891 -235.526869) (xy 231.522996 -235.482726)
			(xy 231.563145 -235.444017) (xy 231.608503 -235.411566) (xy 231.658103 -235.386065) (xy 231.710887 -235.368058)
			(xy 231.76573 -235.357928) (xy 231.821464 -235.355891) (xy 231.876901 -235.361991) (xy 231.930858 -235.376097)
			(xy 231.982187 -235.397909) (xy 232.029793 -235.426963) (xy 232.072661 -235.462638) (xy 232.109878 -235.504175)
			(xy 232.140651 -235.550688) (xy 232.164323 -235.601185) (xy 232.180391 -235.654592) (xy 232.188511 -235.709768)
			(xy 232.18902 -235.737654) (xy 232.441494 -235.737654) (xy 232.445565 -235.682032) (xy 232.457691 -235.627595)
			(xy 232.477614 -235.575504) (xy 232.50491 -235.526869) (xy 232.538996 -235.482726) (xy 232.579145 -235.444017)
			(xy 232.624503 -235.411566) (xy 232.674103 -235.386065) (xy 232.726887 -235.368058) (xy 232.78173 -235.357928)
			(xy 232.837464 -235.355891) (xy 232.892901 -235.361991) (xy 232.946858 -235.376097) (xy 232.998187 -235.397909)
			(xy 233.045793 -235.426963) (xy 233.088661 -235.462638) (xy 233.125878 -235.504175) (xy 233.156651 -235.550688)
			(xy 233.180323 -235.601185) (xy 233.196391 -235.654592) (xy 233.204511 -235.709768) (xy 233.20502 -235.737654)
			(xy 233.457494 -235.737654) (xy 233.461565 -235.682032) (xy 233.473691 -235.627595) (xy 233.493614 -235.575504)
			(xy 233.52091 -235.526869) (xy 233.554996 -235.482726) (xy 233.595145 -235.444017) (xy 233.640503 -235.411566)
			(xy 233.690103 -235.386065) (xy 233.742887 -235.368058) (xy 233.79773 -235.357928) (xy 233.853464 -235.355891)
			(xy 233.908901 -235.361991) (xy 233.962858 -235.376097) (xy 234.014187 -235.397909) (xy 234.061793 -235.426963)
			(xy 234.104661 -235.462638) (xy 234.141878 -235.504175) (xy 234.172651 -235.550688) (xy 234.196323 -235.601185)
			(xy 234.212391 -235.654592) (xy 234.220511 -235.709768) (xy 234.22102 -235.737654) (xy 234.473494 -235.737654)
			(xy 234.477565 -235.682032) (xy 234.489691 -235.627595) (xy 234.509614 -235.575504) (xy 234.53691 -235.526869)
			(xy 234.570996 -235.482726) (xy 234.611145 -235.444017) (xy 234.656503 -235.411566) (xy 234.706103 -235.386065)
			(xy 234.758887 -235.368058) (xy 234.81373 -235.357928) (xy 234.869464 -235.355891) (xy 234.924901 -235.361991)
			(xy 234.978858 -235.376097) (xy 235.030187 -235.397909) (xy 235.077793 -235.426963) (xy 235.120661 -235.462638)
			(xy 235.157878 -235.504175) (xy 235.188651 -235.550688) (xy 235.212323 -235.601185) (xy 235.228391 -235.654592)
			(xy 235.236511 -235.709768) (xy 235.23702 -235.737654) (xy 235.489494 -235.737654) (xy 235.493565 -235.682032)
			(xy 235.505691 -235.627595) (xy 235.525614 -235.575504) (xy 235.55291 -235.526869) (xy 235.586996 -235.482726)
			(xy 235.627145 -235.444017) (xy 235.672503 -235.411566) (xy 235.722103 -235.386065) (xy 235.774887 -235.368058)
			(xy 235.82973 -235.357928) (xy 235.885464 -235.355891) (xy 235.940901 -235.361991) (xy 235.994858 -235.376097)
			(xy 236.046187 -235.397909) (xy 236.093793 -235.426963) (xy 236.136661 -235.462638) (xy 236.173878 -235.504175)
			(xy 236.204651 -235.550688) (xy 236.228323 -235.601185) (xy 236.244391 -235.654592) (xy 236.252511 -235.709768)
			(xy 236.25302 -235.737654) (xy 236.505494 -235.737654) (xy 236.509565 -235.682032) (xy 236.521691 -235.627595)
			(xy 236.541614 -235.575504) (xy 236.56891 -235.526869) (xy 236.602996 -235.482726) (xy 236.643145 -235.444017)
			(xy 236.688503 -235.411566) (xy 236.738103 -235.386065) (xy 236.790887 -235.368058) (xy 236.84573 -235.357928)
			(xy 236.901464 -235.355891) (xy 236.956901 -235.361991) (xy 237.010858 -235.376097) (xy 237.062187 -235.397909)
			(xy 237.109793 -235.426963) (xy 237.152661 -235.462638) (xy 237.189878 -235.504175) (xy 237.220651 -235.550688)
			(xy 237.244323 -235.601185) (xy 237.260391 -235.654592) (xy 237.268511 -235.709768) (xy 237.26902 -235.737654)
			(xy 237.521494 -235.737654) (xy 237.525565 -235.682032) (xy 237.537691 -235.627595) (xy 237.557614 -235.575504)
			(xy 237.58491 -235.526869) (xy 237.618996 -235.482726) (xy 237.659145 -235.444017) (xy 237.704503 -235.411566)
			(xy 237.754103 -235.386065) (xy 237.806887 -235.368058) (xy 237.86173 -235.357928) (xy 237.917464 -235.355891)
			(xy 237.972901 -235.361991) (xy 238.026858 -235.376097) (xy 238.078187 -235.397909) (xy 238.125793 -235.426963)
			(xy 238.168661 -235.462638) (xy 238.205878 -235.504175) (xy 238.236651 -235.550688) (xy 238.260323 -235.601185)
			(xy 238.276391 -235.654592) (xy 238.284511 -235.709768) (xy 238.28502 -235.737654) (xy 238.50422 -235.737654)
			(xy 238.508291 -235.682032) (xy 238.520417 -235.627595) (xy 238.54034 -235.575504) (xy 238.567636 -235.526869)
			(xy 238.601722 -235.482726) (xy 238.641871 -235.444017) (xy 238.687229 -235.411566) (xy 238.736829 -235.386065)
			(xy 238.789613 -235.368058) (xy 238.844456 -235.357928) (xy 238.90019 -235.355891) (xy 238.955627 -235.361991)
			(xy 239.009584 -235.376097) (xy 239.060913 -235.397909) (xy 239.108519 -235.426963) (xy 239.151387 -235.462638)
			(xy 239.188604 -235.504175) (xy 239.219377 -235.550688) (xy 239.243049 -235.601185) (xy 239.259117 -235.654592)
			(xy 239.267237 -235.709768) (xy 239.267746 -235.737654) (xy 239.553494 -235.737654) (xy 239.557565 -235.682032)
			(xy 239.569691 -235.627595) (xy 239.589614 -235.575504) (xy 239.61691 -235.526869) (xy 239.650996 -235.482726)
			(xy 239.691145 -235.444017) (xy 239.736503 -235.411566) (xy 239.786103 -235.386065) (xy 239.838887 -235.368058)
			(xy 239.89373 -235.357928) (xy 239.949464 -235.355891) (xy 240.004901 -235.361991) (xy 240.058858 -235.376097)
			(xy 240.110187 -235.397909) (xy 240.157793 -235.426963) (xy 240.200661 -235.462638) (xy 240.237878 -235.504175)
			(xy 240.268651 -235.550688) (xy 240.292323 -235.601185) (xy 240.299222 -235.624116) (xy 241.062 -235.624116)
			(xy 241.066071 -235.568494) (xy 241.078197 -235.514057) (xy 241.09812 -235.461966) (xy 241.125416 -235.413331)
			(xy 241.159502 -235.369188) (xy 241.199651 -235.330479) (xy 241.245009 -235.298028) (xy 241.294609 -235.272527)
			(xy 241.347393 -235.25452) (xy 241.402236 -235.24439) (xy 241.45797 -235.242353) (xy 241.513407 -235.248453)
			(xy 241.567364 -235.262559) (xy 241.618693 -235.284371) (xy 241.666299 -235.313425) (xy 241.709167 -235.3491)
			(xy 241.746384 -235.390637) (xy 241.777157 -235.43715) (xy 241.800829 -235.487647) (xy 241.816897 -235.541054)
			(xy 241.825017 -235.59623) (xy 241.825526 -235.624116) (xy 241.825029 -235.651353) (xy 243.094971 -235.651353)
			(xy 243.094971 -235.596847) (xy 243.102728 -235.542897) (xy 243.118085 -235.4906) (xy 243.140728 -235.441021)
			(xy 243.170196 -235.395169) (xy 243.20589 -235.353977) (xy 243.247083 -235.318285) (xy 243.292937 -235.288819)
			(xy 243.342517 -235.266178) (xy 243.394815 -235.250825) (xy 243.448765 -235.24307) (xy 243.476018 -235.242608)
			(xy 243.503622 -235.243135) (xy 243.558254 -235.251082) (xy 243.61117 -235.266821) (xy 243.661265 -235.290025)
			(xy 243.707491 -235.320208) (xy 243.748883 -235.356739) (xy 243.767102 -235.377482) (xy 243.774468 -235.386372)
			(xy 243.794534 -235.395516) (xy 243.895372 -235.395262) (xy 243.915438 -235.385864) (xy 243.922804 -235.376974)
			(xy 243.941049 -235.355937) (xy 243.982537 -235.318797) (xy 244.028987 -235.288089) (xy 244.079411 -235.264465)
			(xy 244.132735 -235.24843) (xy 244.187825 -235.240323) (xy 244.215666 -235.239814) (xy 244.243541 -235.240341)
			(xy 244.298697 -235.248443) (xy 244.352086 -235.264493) (xy 244.402566 -235.28815) (xy 244.449062 -235.318908)
			(xy 244.490581 -235.356111) (xy 244.508782 -235.377228) (xy 244.515894 -235.38561) (xy 244.53469 -235.395008)
			(xy 244.63121 -235.39958) (xy 244.650768 -235.392214) (xy 244.658642 -235.38434) (xy 244.680218 -235.363778)
			(xy 244.728559 -235.328919) (xy 244.781733 -235.302005) (xy 244.838448 -235.283691) (xy 244.897321 -235.274423)
			(xy 244.92712 -235.27385) (xy 244.954367 -235.274422) (xy 245.008307 -235.282179) (xy 245.060593 -235.297535)
			(xy 245.110163 -235.320174) (xy 245.156005 -235.349638) (xy 245.197189 -235.385326) (xy 245.232874 -235.426511)
			(xy 245.262335 -235.472355) (xy 245.284972 -235.521925) (xy 245.300325 -235.574213) (xy 245.30808 -235.628153)
			(xy 245.30808 -235.682647) (xy 245.300325 -235.736587) (xy 245.284972 -235.788875) (xy 245.262335 -235.838445)
			(xy 245.232874 -235.884289) (xy 245.197189 -235.925474) (xy 245.156005 -235.961162) (xy 245.110163 -235.990626)
			(xy 245.060593 -236.013265) (xy 245.008307 -236.028621) (xy 244.954367 -236.036378) (xy 244.92712 -236.036866)
			(xy 244.899245 -236.036356) (xy 244.844087 -236.028252) (xy 244.790698 -236.012199) (xy 244.740217 -235.988539)
			(xy 244.693722 -235.957778) (xy 244.652204 -235.920571) (xy 244.634004 -235.899452) (xy 244.626892 -235.89107)
			(xy 244.608096 -235.881672) (xy 244.511576 -235.8771) (xy 244.492018 -235.884466) (xy 244.484144 -235.89234)
			(xy 244.462571 -235.912906) (xy 244.41423 -235.947764) (xy 244.361054 -235.974678) (xy 244.304339 -235.992991)
			(xy 244.245465 -236.002258) (xy 244.215666 -236.00283) (xy 244.188061 -236.002336) (xy 244.133426 -235.994385)
			(xy 244.080508 -235.978641) (xy 244.030414 -235.955431) (xy 243.984189 -235.925241) (xy 243.942799 -235.888702)
			(xy 243.924582 -235.867956) (xy 243.917216 -235.859066) (xy 243.89715 -235.849922) (xy 243.796312 -235.850176)
			(xy 243.776246 -235.859574) (xy 243.76888 -235.868464) (xy 243.750652 -235.889517) (xy 243.70916 -235.926654)
			(xy 243.662706 -235.957359) (xy 243.612279 -235.980979) (xy 243.558952 -235.997012) (xy 243.50386 -236.005116)
			(xy 243.476018 -236.005624) (xy 243.448765 -236.00513) (xy 243.394815 -235.997375) (xy 243.342517 -235.982022)
			(xy 243.292937 -235.959381) (xy 243.247083 -235.929915) (xy 243.20589 -235.894223) (xy 243.170196 -235.853031)
			(xy 243.140728 -235.807179) (xy 243.118085 -235.7576) (xy 243.102728 -235.705303) (xy 243.094971 -235.651353)
			(xy 241.825029 -235.651353) (xy 241.825017 -235.652002) (xy 241.816897 -235.707178) (xy 241.800829 -235.760585)
			(xy 241.777157 -235.811082) (xy 241.746384 -235.857595) (xy 241.709167 -235.899132) (xy 241.666299 -235.934807)
			(xy 241.618693 -235.963861) (xy 241.567364 -235.985673) (xy 241.513407 -235.999779) (xy 241.45797 -236.005879)
			(xy 241.402236 -236.003842) (xy 241.347393 -235.993712) (xy 241.294609 -235.975705) (xy 241.245009 -235.950204)
			(xy 241.199651 -235.917753) (xy 241.159502 -235.879044) (xy 241.125416 -235.834901) (xy 241.09812 -235.786266)
			(xy 241.078197 -235.734175) (xy 241.066071 -235.679738) (xy 241.062 -235.624116) (xy 240.299222 -235.624116)
			(xy 240.308391 -235.654592) (xy 240.316511 -235.709768) (xy 240.31702 -235.737654) (xy 240.316511 -235.76554)
			(xy 240.308391 -235.820716) (xy 240.292323 -235.874123) (xy 240.268651 -235.92462) (xy 240.237878 -235.971133)
			(xy 240.200661 -236.01267) (xy 240.157793 -236.048345) (xy 240.110187 -236.077399) (xy 240.058858 -236.099211)
			(xy 240.004901 -236.113317) (xy 239.949464 -236.119417) (xy 239.89373 -236.11738) (xy 239.838887 -236.10725)
			(xy 239.786103 -236.089243) (xy 239.736503 -236.063742) (xy 239.691145 -236.031291) (xy 239.650996 -235.992582)
			(xy 239.61691 -235.948439) (xy 239.589614 -235.899804) (xy 239.569691 -235.847713) (xy 239.557565 -235.793276)
			(xy 239.553494 -235.737654) (xy 239.267746 -235.737654) (xy 239.267237 -235.76554) (xy 239.259117 -235.820716)
			(xy 239.243049 -235.874123) (xy 239.219377 -235.92462) (xy 239.188604 -235.971133) (xy 239.151387 -236.01267)
			(xy 239.108519 -236.048345) (xy 239.060913 -236.077399) (xy 239.009584 -236.099211) (xy 238.955627 -236.113317)
			(xy 238.90019 -236.119417) (xy 238.844456 -236.11738) (xy 238.789613 -236.10725) (xy 238.736829 -236.089243)
			(xy 238.687229 -236.063742) (xy 238.641871 -236.031291) (xy 238.601722 -235.992582) (xy 238.567636 -235.948439)
			(xy 238.54034 -235.899804) (xy 238.520417 -235.847713) (xy 238.508291 -235.793276) (xy 238.50422 -235.737654)
			(xy 238.28502 -235.737654) (xy 238.284511 -235.76554) (xy 238.276391 -235.820716) (xy 238.260323 -235.874123)
			(xy 238.236651 -235.92462) (xy 238.205878 -235.971133) (xy 238.168661 -236.01267) (xy 238.125793 -236.048345)
			(xy 238.078187 -236.077399) (xy 238.026858 -236.099211) (xy 237.972901 -236.113317) (xy 237.917464 -236.119417)
			(xy 237.86173 -236.11738) (xy 237.806887 -236.10725) (xy 237.754103 -236.089243) (xy 237.704503 -236.063742)
			(xy 237.659145 -236.031291) (xy 237.618996 -235.992582) (xy 237.58491 -235.948439) (xy 237.557614 -235.899804)
			(xy 237.537691 -235.847713) (xy 237.525565 -235.793276) (xy 237.521494 -235.737654) (xy 237.26902 -235.737654)
			(xy 237.268511 -235.76554) (xy 237.260391 -235.820716) (xy 237.244323 -235.874123) (xy 237.220651 -235.92462)
			(xy 237.189878 -235.971133) (xy 237.152661 -236.01267) (xy 237.109793 -236.048345) (xy 237.062187 -236.077399)
			(xy 237.010858 -236.099211) (xy 236.956901 -236.113317) (xy 236.901464 -236.119417) (xy 236.84573 -236.11738)
			(xy 236.790887 -236.10725) (xy 236.738103 -236.089243) (xy 236.688503 -236.063742) (xy 236.643145 -236.031291)
			(xy 236.602996 -235.992582) (xy 236.56891 -235.948439) (xy 236.541614 -235.899804) (xy 236.521691 -235.847713)
			(xy 236.509565 -235.793276) (xy 236.505494 -235.737654) (xy 236.25302 -235.737654) (xy 236.252511 -235.76554)
			(xy 236.244391 -235.820716) (xy 236.228323 -235.874123) (xy 236.204651 -235.92462) (xy 236.173878 -235.971133)
			(xy 236.136661 -236.01267) (xy 236.093793 -236.048345) (xy 236.046187 -236.077399) (xy 235.994858 -236.099211)
			(xy 235.940901 -236.113317) (xy 235.885464 -236.119417) (xy 235.82973 -236.11738) (xy 235.774887 -236.10725)
			(xy 235.722103 -236.089243) (xy 235.672503 -236.063742) (xy 235.627145 -236.031291) (xy 235.586996 -235.992582)
			(xy 235.55291 -235.948439) (xy 235.525614 -235.899804) (xy 235.505691 -235.847713) (xy 235.493565 -235.793276)
			(xy 235.489494 -235.737654) (xy 235.23702 -235.737654) (xy 235.236511 -235.76554) (xy 235.228391 -235.820716)
			(xy 235.212323 -235.874123) (xy 235.188651 -235.92462) (xy 235.157878 -235.971133) (xy 235.120661 -236.01267)
			(xy 235.077793 -236.048345) (xy 235.030187 -236.077399) (xy 234.978858 -236.099211) (xy 234.924901 -236.113317)
			(xy 234.869464 -236.119417) (xy 234.81373 -236.11738) (xy 234.758887 -236.10725) (xy 234.706103 -236.089243)
			(xy 234.656503 -236.063742) (xy 234.611145 -236.031291) (xy 234.570996 -235.992582) (xy 234.53691 -235.948439)
			(xy 234.509614 -235.899804) (xy 234.489691 -235.847713) (xy 234.477565 -235.793276) (xy 234.473494 -235.737654)
			(xy 234.22102 -235.737654) (xy 234.220511 -235.76554) (xy 234.212391 -235.820716) (xy 234.196323 -235.874123)
			(xy 234.172651 -235.92462) (xy 234.141878 -235.971133) (xy 234.104661 -236.01267) (xy 234.061793 -236.048345)
			(xy 234.014187 -236.077399) (xy 233.962858 -236.099211) (xy 233.908901 -236.113317) (xy 233.853464 -236.119417)
			(xy 233.79773 -236.11738) (xy 233.742887 -236.10725) (xy 233.690103 -236.089243) (xy 233.640503 -236.063742)
			(xy 233.595145 -236.031291) (xy 233.554996 -235.992582) (xy 233.52091 -235.948439) (xy 233.493614 -235.899804)
			(xy 233.473691 -235.847713) (xy 233.461565 -235.793276) (xy 233.457494 -235.737654) (xy 233.20502 -235.737654)
			(xy 233.204511 -235.76554) (xy 233.196391 -235.820716) (xy 233.180323 -235.874123) (xy 233.156651 -235.92462)
			(xy 233.125878 -235.971133) (xy 233.088661 -236.01267) (xy 233.045793 -236.048345) (xy 232.998187 -236.077399)
			(xy 232.946858 -236.099211) (xy 232.892901 -236.113317) (xy 232.837464 -236.119417) (xy 232.78173 -236.11738)
			(xy 232.726887 -236.10725) (xy 232.674103 -236.089243) (xy 232.624503 -236.063742) (xy 232.579145 -236.031291)
			(xy 232.538996 -235.992582) (xy 232.50491 -235.948439) (xy 232.477614 -235.899804) (xy 232.457691 -235.847713)
			(xy 232.445565 -235.793276) (xy 232.441494 -235.737654) (xy 232.18902 -235.737654) (xy 232.188511 -235.76554)
			(xy 232.180391 -235.820716) (xy 232.164323 -235.874123) (xy 232.140651 -235.92462) (xy 232.109878 -235.971133)
			(xy 232.072661 -236.01267) (xy 232.029793 -236.048345) (xy 231.982187 -236.077399) (xy 231.930858 -236.099211)
			(xy 231.876901 -236.113317) (xy 231.821464 -236.119417) (xy 231.76573 -236.11738) (xy 231.710887 -236.10725)
			(xy 231.658103 -236.089243) (xy 231.608503 -236.063742) (xy 231.563145 -236.031291) (xy 231.522996 -235.992582)
			(xy 231.48891 -235.948439) (xy 231.461614 -235.899804) (xy 231.441691 -235.847713) (xy 231.429565 -235.793276)
			(xy 231.425494 -235.737654) (xy 221.463108 -235.737654) (xy 221.463108 -235.812584) (xy 221.463643 -235.822573)
			(xy 221.471353 -235.841008) (xy 221.478094 -235.848398) (xy 221.934278 -236.304582) (xy 221.957185 -236.328161)
			(xy 221.998153 -236.379577) (xy 222.033109 -236.435255) (xy 222.061611 -236.494497) (xy 222.083304 -236.556557)
			(xy 222.097912 -236.620655) (xy 222.105254 -236.685985) (xy 222.105728 -236.718856) (xy 222.105728 -237.101888)
			(xy 223.839784 -237.101888) (xy 223.843855 -237.046266) (xy 223.855981 -236.991829) (xy 223.875904 -236.939738)
			(xy 223.9032 -236.891103) (xy 223.937286 -236.84696) (xy 223.977435 -236.808251) (xy 224.022793 -236.7758)
			(xy 224.072393 -236.750299) (xy 224.125177 -236.732292) (xy 224.18002 -236.722162) (xy 224.235754 -236.720125)
			(xy 224.291191 -236.726225) (xy 224.345148 -236.740331) (xy 224.396477 -236.762143) (xy 224.444083 -236.791197)
			(xy 224.486951 -236.826872) (xy 224.524168 -236.868409) (xy 224.554941 -236.914922) (xy 224.578613 -236.965419)
			(xy 224.594681 -237.018826) (xy 224.602801 -237.074002) (xy 224.60331 -237.101888) (xy 224.602801 -237.129774)
			(xy 224.594681 -237.18495) (xy 224.578613 -237.238357) (xy 224.554941 -237.288854) (xy 224.524168 -237.335367)
			(xy 224.486951 -237.376904) (xy 224.444083 -237.412579) (xy 224.396477 -237.441633) (xy 224.345148 -237.463445)
			(xy 224.291191 -237.477551) (xy 224.235754 -237.483651) (xy 224.18002 -237.481614) (xy 224.125177 -237.471484)
			(xy 224.072393 -237.453477) (xy 224.022793 -237.427976) (xy 223.977435 -237.395525) (xy 223.937286 -237.356816)
			(xy 223.9032 -237.312673) (xy 223.875904 -237.264038) (xy 223.855981 -237.211947) (xy 223.843855 -237.15751)
			(xy 223.839784 -237.101888) (xy 222.105728 -237.101888) (xy 222.105728 -237.430564) (xy 222.10525 -237.464302)
			(xy 222.097494 -237.53133) (xy 222.082093 -237.597024) (xy 222.059249 -237.660515) (xy 222.029266 -237.720963)
			(xy 221.99254 -237.777567) (xy 221.985016 -237.786672) (xy 241.391184 -237.786672) (xy 241.395255 -237.73105)
			(xy 241.407381 -237.676613) (xy 241.427304 -237.624522) (xy 241.4546 -237.575887) (xy 241.488686 -237.531744)
			(xy 241.528835 -237.493035) (xy 241.574193 -237.460584) (xy 241.623793 -237.435083) (xy 241.676577 -237.417076)
			(xy 241.73142 -237.406946) (xy 241.787154 -237.404909) (xy 241.842591 -237.411009) (xy 241.896548 -237.425115)
			(xy 241.947877 -237.446927) (xy 241.995483 -237.475981) (xy 242.038351 -237.511656) (xy 242.075568 -237.553193)
			(xy 242.106341 -237.599706) (xy 242.130013 -237.650203) (xy 242.146081 -237.70361) (xy 242.154201 -237.758786)
			(xy 242.15471 -237.786672) (xy 242.154201 -237.814558) (xy 242.149707 -237.845092) (xy 242.755672 -237.845092)
			(xy 242.759743 -237.78947) (xy 242.771869 -237.735033) (xy 242.791792 -237.682942) (xy 242.819088 -237.634307)
			(xy 242.853174 -237.590164) (xy 242.893323 -237.551455) (xy 242.938681 -237.519004) (xy 242.988281 -237.493503)
			(xy 243.041065 -237.475496) (xy 243.095908 -237.465366) (xy 243.151642 -237.463329) (xy 243.207079 -237.469429)
			(xy 243.261036 -237.483535) (xy 243.312365 -237.505347) (xy 243.359971 -237.534401) (xy 243.402839 -237.570076)
			(xy 243.440056 -237.611613) (xy 243.470829 -237.658126) (xy 243.494501 -237.708623) (xy 243.510569 -237.76203)
			(xy 243.516476 -237.802166) (xy 244.049548 -237.802166) (xy 244.053619 -237.746544) (xy 244.065745 -237.692107)
			(xy 244.085668 -237.640016) (xy 244.112964 -237.591381) (xy 244.14705 -237.547238) (xy 244.187199 -237.508529)
			(xy 244.232557 -237.476078) (xy 244.282157 -237.450577) (xy 244.334941 -237.43257) (xy 244.389784 -237.42244)
			(xy 244.445518 -237.420403) (xy 244.500955 -237.426503) (xy 244.554912 -237.440609) (xy 244.606241 -237.462421)
			(xy 244.653847 -237.491475) (xy 244.696715 -237.52715) (xy 244.733932 -237.568687) (xy 244.764705 -237.6152)
			(xy 244.788377 -237.665697) (xy 244.804445 -237.719104) (xy 244.812565 -237.77428) (xy 244.813074 -237.802166)
			(xy 244.812565 -237.830052) (xy 244.804445 -237.885228) (xy 244.788377 -237.938635) (xy 244.764705 -237.989132)
			(xy 244.733932 -238.035645) (xy 244.696715 -238.077182) (xy 244.653847 -238.112857) (xy 244.606241 -238.141911)
			(xy 244.554912 -238.163723) (xy 244.500955 -238.177829) (xy 244.445518 -238.183929) (xy 244.389784 -238.181892)
			(xy 244.334941 -238.171762) (xy 244.282157 -238.153755) (xy 244.232557 -238.128254) (xy 244.187199 -238.095803)
			(xy 244.14705 -238.057094) (xy 244.112964 -238.012951) (xy 244.085668 -237.964316) (xy 244.065745 -237.912225)
			(xy 244.053619 -237.857788) (xy 244.049548 -237.802166) (xy 243.516476 -237.802166) (xy 243.518689 -237.817206)
			(xy 243.519198 -237.845092) (xy 243.518689 -237.872978) (xy 243.510569 -237.928154) (xy 243.494501 -237.981561)
			(xy 243.470829 -238.032058) (xy 243.440056 -238.078571) (xy 243.402839 -238.120108) (xy 243.359971 -238.155783)
			(xy 243.312365 -238.184837) (xy 243.261036 -238.206649) (xy 243.207079 -238.220755) (xy 243.151642 -238.226855)
			(xy 243.095908 -238.224818) (xy 243.041065 -238.214688) (xy 242.988281 -238.196681) (xy 242.938681 -238.17118)
			(xy 242.893323 -238.138729) (xy 242.853174 -238.10002) (xy 242.819088 -238.055877) (xy 242.791792 -238.007242)
			(xy 242.771869 -237.955151) (xy 242.759743 -237.900714) (xy 242.755672 -237.845092) (xy 242.149707 -237.845092)
			(xy 242.146081 -237.869734) (xy 242.130013 -237.923141) (xy 242.106341 -237.973638) (xy 242.075568 -238.020151)
			(xy 242.038351 -238.061688) (xy 241.995483 -238.097363) (xy 241.947877 -238.126417) (xy 241.896548 -238.148229)
			(xy 241.842591 -238.162335) (xy 241.787154 -238.168435) (xy 241.73142 -238.166398) (xy 241.676577 -238.156268)
			(xy 241.623793 -238.138261) (xy 241.574193 -238.11276) (xy 241.528835 -238.080309) (xy 241.488686 -238.0416)
			(xy 241.4546 -237.997457) (xy 241.427304 -237.948822) (xy 241.407381 -237.896731) (xy 241.395255 -237.842294)
			(xy 241.391184 -237.786672) (xy 221.985016 -237.786672) (xy 221.949557 -237.829581) (xy 221.900885 -237.876314)
			(xy 221.847169 -237.917149) (xy 221.789119 -237.951545) (xy 221.75851 -237.965742) (xy 221.746826 -237.970822)
			(xy 221.731332 -237.990634) (xy 221.716854 -238.073184) (xy 221.715408 -238.085354) (xy 221.722699 -238.108714)
			(xy 221.730824 -238.117888) (xy 222.34144 -238.728504) (xy 222.348014 -238.734481) (xy 222.364128 -238.741932)
			(xy 222.381816 -238.743452) (xy 222.398965 -238.738857) (xy 222.406464 -238.734092) (xy 222.43071 -238.717662)
			(xy 222.48318 -238.691645) (xy 222.539011 -238.673957) (xy 222.596891 -238.665013) (xy 222.626174 -238.664496)
			(xy 222.652989 -238.664956) (xy 222.706089 -238.672473) (xy 222.757614 -238.687348) (xy 222.806549 -238.70929)
			(xy 222.851932 -238.737865) (xy 222.892868 -238.772512) (xy 222.928551 -238.812547) (xy 222.958279 -238.857183)
			(xy 222.981466 -238.905541) (xy 222.997657 -238.956668) (xy 223.006531 -239.009558) (xy 223.007682 -239.036352)
			(xy 223.007682 -239.044734) (xy 223.007682 -239.046004) (xy 226.0252 -239.046004) (xy 226.029271 -238.990382)
			(xy 226.041397 -238.935945) (xy 226.06132 -238.883854) (xy 226.088616 -238.835219) (xy 226.122702 -238.791076)
			(xy 226.162851 -238.752367) (xy 226.208209 -238.719916) (xy 226.257809 -238.694415) (xy 226.310593 -238.676408)
			(xy 226.365436 -238.666278) (xy 226.42117 -238.664241) (xy 226.476607 -238.670341) (xy 226.530564 -238.684447)
			(xy 226.581893 -238.706259) (xy 226.629499 -238.735313) (xy 226.672367 -238.770988) (xy 226.709584 -238.812525)
			(xy 226.740357 -238.859038) (xy 226.764029 -238.909535) (xy 226.780097 -238.962942) (xy 226.783686 -238.98733)
			(xy 228.467664 -238.98733) (xy 228.471735 -238.931708) (xy 228.483861 -238.877271) (xy 228.503784 -238.82518)
			(xy 228.53108 -238.776545) (xy 228.565166 -238.732402) (xy 228.605315 -238.693693) (xy 228.650673 -238.661242)
			(xy 228.700273 -238.635741) (xy 228.753057 -238.617734) (xy 228.8079 -238.607604) (xy 228.863634 -238.605567)
			(xy 228.919071 -238.611667) (xy 228.973028 -238.625773) (xy 229.024357 -238.647585) (xy 229.071963 -238.676639)
			(xy 229.114831 -238.712314) (xy 229.152048 -238.753851) (xy 229.182821 -238.800364) (xy 229.206493 -238.850861)
			(xy 229.222561 -238.904268) (xy 229.230681 -238.959444) (xy 229.23119 -238.98733) (xy 229.230681 -239.015216)
			(xy 229.222561 -239.070392) (xy 229.206493 -239.123799) (xy 229.182821 -239.174296) (xy 229.152048 -239.220809)
			(xy 229.114831 -239.262346) (xy 229.071963 -239.298021) (xy 229.024357 -239.327075) (xy 228.973028 -239.348887)
			(xy 228.919071 -239.362993) (xy 228.863634 -239.369093) (xy 228.8079 -239.367056) (xy 228.753057 -239.356926)
			(xy 228.700273 -239.338919) (xy 228.650673 -239.313418) (xy 228.605315 -239.280967) (xy 228.565166 -239.242258)
			(xy 228.53108 -239.198115) (xy 228.503784 -239.14948) (xy 228.483861 -239.097389) (xy 228.471735 -239.042952)
			(xy 228.467664 -238.98733) (xy 226.783686 -238.98733) (xy 226.788217 -239.018118) (xy 226.788726 -239.046004)
			(xy 226.788217 -239.07389) (xy 226.780097 -239.129066) (xy 226.764029 -239.182473) (xy 226.740357 -239.23297)
			(xy 226.709584 -239.279483) (xy 226.672367 -239.32102) (xy 226.629499 -239.356695) (xy 226.581893 -239.385749)
			(xy 226.530564 -239.407561) (xy 226.476607 -239.421667) (xy 226.42117 -239.427767) (xy 226.365436 -239.42573)
			(xy 226.310593 -239.4156) (xy 226.257809 -239.397593) (xy 226.208209 -239.372092) (xy 226.162851 -239.339641)
			(xy 226.122702 -239.300932) (xy 226.088616 -239.256789) (xy 226.06132 -239.208154) (xy 226.041397 -239.156063)
			(xy 226.029271 -239.101626) (xy 226.0252 -239.046004) (xy 223.007682 -239.046004) (xy 223.007162 -239.074394)
			(xy 222.998751 -239.130549) (xy 222.982117 -239.184838) (xy 222.957626 -239.236065) (xy 222.94215 -239.259872)
			(xy 222.937832 -239.266222) (xy 222.933006 -239.281462) (xy 222.930013 -239.293458) (xy 222.934392 -239.317751)
			(xy 222.941388 -239.327944) (xy 222.94342 -239.330484) (xy 223.647087 -240.034151) (xy 231.103164 -240.034151)
			(xy 231.103164 -239.979649) (xy 231.11092 -239.925702) (xy 231.126274 -239.873408) (xy 231.148914 -239.823831)
			(xy 231.178378 -239.77798) (xy 231.214068 -239.736789) (xy 231.255256 -239.701096) (xy 231.301104 -239.671628)
			(xy 231.35068 -239.648984) (xy 231.402973 -239.633626) (xy 231.456919 -239.625866) (xy 231.48417 -239.625378)
			(xy 231.511347 -239.625861) (xy 231.565148 -239.633589) (xy 231.617307 -239.648878) (xy 231.666767 -239.671419)
			(xy 231.712525 -239.700754) (xy 231.753653 -239.736289) (xy 231.789319 -239.777305) (xy 231.804464 -239.799876)
			(xy 231.81056 -239.809274) (xy 231.828848 -239.820958) (xy 231.926892 -239.834928) (xy 231.94772 -239.828832)
			(xy 231.956102 -239.82172) (xy 231.976958 -239.804356) (xy 232.022677 -239.775119) (xy 232.07208 -239.75266)
			(xy 232.124167 -239.737431) (xy 232.177888 -239.729741) (xy 232.205022 -239.729264) (xy 232.23227 -239.729808)
			(xy 232.286212 -239.737566) (xy 232.3385 -239.752922) (xy 232.38807 -239.775563) (xy 232.433915 -239.805027)
			(xy 232.475099 -239.840716) (xy 232.510786 -239.881903) (xy 232.540248 -239.927749) (xy 232.562886 -239.977321)
			(xy 232.578238 -240.02961) (xy 232.585994 -240.083552) (xy 232.585994 -240.138048) (xy 232.578238 -240.19199)
			(xy 232.562886 -240.244279) (xy 232.540248 -240.293851) (xy 232.510786 -240.339697) (xy 232.475099 -240.380884)
			(xy 232.433915 -240.416573) (xy 232.38807 -240.446037) (xy 232.3385 -240.468678) (xy 232.286212 -240.484034)
			(xy 232.23227 -240.491792) (xy 232.205022 -240.49228) (xy 232.177844 -240.491822) (xy 232.124041 -240.484092)
			(xy 232.07188 -240.4688) (xy 232.02242 -240.446256) (xy 231.976662 -240.416916) (xy 231.935535 -240.381376)
			(xy 231.899871 -240.340355) (xy 231.884728 -240.317782) (xy 231.878632 -240.308384) (xy 231.860344 -240.2967)
			(xy 231.7623 -240.28273) (xy 231.741472 -240.288826) (xy 231.73309 -240.295938) (xy 231.712207 -240.313268)
			(xy 231.666494 -240.342508) (xy 231.617099 -240.364973) (xy 231.565017 -240.38021) (xy 231.511302 -240.387911)
			(xy 231.48417 -240.388394) (xy 231.456919 -240.387934) (xy 231.402973 -240.380174) (xy 231.35068 -240.364816)
			(xy 231.301104 -240.342172) (xy 231.255256 -240.312704) (xy 231.214068 -240.277011) (xy 231.178378 -240.23582)
			(xy 231.148914 -240.189969) (xy 231.126274 -240.140392) (xy 231.11092 -240.088098) (xy 231.103164 -240.034151)
			(xy 223.647087 -240.034151) (xy 225.292412 -241.679476) (xy 229.972868 -241.679476) (xy 229.976939 -241.623854)
			(xy 229.989065 -241.569417) (xy 230.008988 -241.517326) (xy 230.036284 -241.468691) (xy 230.07037 -241.424548)
			(xy 230.110519 -241.385839) (xy 230.155877 -241.353388) (xy 230.205477 -241.327887) (xy 230.258261 -241.30988)
			(xy 230.313104 -241.29975) (xy 230.368838 -241.297713) (xy 230.424275 -241.303813) (xy 230.478232 -241.317919)
			(xy 230.529561 -241.339731) (xy 230.577167 -241.368785) (xy 230.620035 -241.40446) (xy 230.657252 -241.445997)
			(xy 230.688025 -241.49251) (xy 230.711697 -241.543007) (xy 230.727765 -241.596414) (xy 230.734923 -241.645053)
			(xy 233.645432 -241.645053) (xy 233.645432 -241.590547) (xy 233.653188 -241.536597) (xy 233.668543 -241.4843)
			(xy 233.691183 -241.434719) (xy 233.720649 -241.388865) (xy 233.75634 -241.347671) (xy 233.79753 -241.311976)
			(xy 233.843381 -241.282505) (xy 233.892958 -241.259858) (xy 233.945254 -241.244497) (xy 233.999204 -241.236735)
			(xy 234.026456 -241.236246) (xy 234.052655 -241.236651) (xy 234.104559 -241.243822) (xy 234.154992 -241.258034)
			(xy 234.203003 -241.279021) (xy 234.247688 -241.306385) (xy 234.288202 -241.339612) (xy 234.323784 -241.378076)
			(xy 234.33913 -241.399314) (xy 234.347533 -241.410538) (xy 234.369231 -241.428276) (xy 234.394934 -241.439448)
			(xy 234.422707 -241.443211) (xy 234.450456 -241.439281) (xy 234.476092 -241.427956) (xy 234.497683 -241.410087)
			(xy 234.506008 -241.398806) (xy 234.52133 -241.377407) (xy 234.556962 -241.33867) (xy 234.597578 -241.305197)
			(xy 234.64241 -241.277623) (xy 234.690605 -241.256471) (xy 234.741249 -241.242142) (xy 234.793382 -241.234909)
			(xy 234.819698 -241.234468) (xy 234.846949 -241.234979) (xy 234.900897 -241.242735) (xy 234.953192 -241.25809)
			(xy 235.002769 -241.280731) (xy 235.04862 -241.310197) (xy 235.08981 -241.345889) (xy 235.125501 -241.387079)
			(xy 235.154968 -241.432929) (xy 235.177609 -241.482506) (xy 235.192964 -241.534801) (xy 235.20029 -241.58575)
			(xy 235.38764 -241.58575) (xy 235.391711 -241.530128) (xy 235.403837 -241.475691) (xy 235.42376 -241.4236)
			(xy 235.451056 -241.374965) (xy 235.485142 -241.330822) (xy 235.525291 -241.292113) (xy 235.570649 -241.259662)
			(xy 235.620249 -241.234161) (xy 235.673033 -241.216154) (xy 235.727876 -241.206024) (xy 235.78361 -241.203987)
			(xy 235.839047 -241.210087) (xy 235.893004 -241.224193) (xy 235.944333 -241.246005) (xy 235.991939 -241.275059)
			(xy 236.034807 -241.310734) (xy 236.072024 -241.352271) (xy 236.102797 -241.398784) (xy 236.126469 -241.449281)
			(xy 236.142537 -241.502688) (xy 236.150657 -241.557864) (xy 236.151166 -241.58575) (xy 236.150657 -241.613636)
			(xy 236.142537 -241.668812) (xy 236.140093 -241.676936) (xy 237.456216 -241.676936) (xy 237.460287 -241.621314)
			(xy 237.472413 -241.566877) (xy 237.492336 -241.514786) (xy 237.519632 -241.466151) (xy 237.553718 -241.422008)
			(xy 237.593867 -241.383299) (xy 237.639225 -241.350848) (xy 237.688825 -241.325347) (xy 237.741609 -241.30734)
			(xy 237.796452 -241.29721) (xy 237.852186 -241.295173) (xy 237.907623 -241.301273) (xy 237.96158 -241.315379)
			(xy 238.012909 -241.337191) (xy 238.060515 -241.366245) (xy 238.103383 -241.40192) (xy 238.1406 -241.443457)
			(xy 238.171373 -241.48997) (xy 238.195045 -241.540467) (xy 238.211113 -241.593874) (xy 238.219233 -241.64905)
			(xy 238.219742 -241.676936) (xy 238.219233 -241.704822) (xy 238.214029 -241.740182) (xy 238.559846 -241.740182)
			(xy 238.563917 -241.68456) (xy 238.576043 -241.630123) (xy 238.595966 -241.578032) (xy 238.623262 -241.529397)
			(xy 238.657348 -241.485254) (xy 238.697497 -241.446545) (xy 238.742855 -241.414094) (xy 238.792455 -241.388593)
			(xy 238.845239 -241.370586) (xy 238.900082 -241.360456) (xy 238.955816 -241.358419) (xy 239.011253 -241.364519)
			(xy 239.06521 -241.378625) (xy 239.116539 -241.400437) (xy 239.164145 -241.429491) (xy 239.207013 -241.465166)
			(xy 239.24423 -241.506703) (xy 239.275003 -241.553216) (xy 239.296684 -241.599466) (xy 239.994184 -241.599466)
			(xy 239.998255 -241.543844) (xy 240.010381 -241.489407) (xy 240.030304 -241.437316) (xy 240.0576 -241.388681)
			(xy 240.091686 -241.344538) (xy 240.131835 -241.305829) (xy 240.177193 -241.273378) (xy 240.226793 -241.247877)
			(xy 240.279577 -241.22987) (xy 240.33442 -241.21974) (xy 240.390154 -241.217703) (xy 240.445591 -241.223803)
			(xy 240.499548 -241.237909) (xy 240.550877 -241.259721) (xy 240.598483 -241.288775) (xy 240.641351 -241.32445)
			(xy 240.678568 -241.365987) (xy 240.709341 -241.4125) (xy 240.733013 -241.462997) (xy 240.749081 -241.516404)
			(xy 240.757201 -241.57158) (xy 240.75771 -241.599466) (xy 240.757201 -241.627352) (xy 240.749081 -241.682528)
			(xy 240.733013 -241.735935) (xy 240.709341 -241.786432) (xy 240.678568 -241.832945) (xy 240.641351 -241.874482)
			(xy 240.598483 -241.910157) (xy 240.550877 -241.939211) (xy 240.499548 -241.961023) (xy 240.445591 -241.975129)
			(xy 240.390154 -241.981229) (xy 240.33442 -241.979192) (xy 240.279577 -241.969062) (xy 240.226793 -241.951055)
			(xy 240.177193 -241.925554) (xy 240.131835 -241.893103) (xy 240.091686 -241.854394) (xy 240.0576 -241.810251)
			(xy 240.030304 -241.761616) (xy 240.010381 -241.709525) (xy 239.998255 -241.655088) (xy 239.994184 -241.599466)
			(xy 239.296684 -241.599466) (xy 239.298675 -241.603713) (xy 239.314743 -241.65712) (xy 239.322863 -241.712296)
			(xy 239.323372 -241.740182) (xy 239.322863 -241.768068) (xy 239.314743 -241.823244) (xy 239.298675 -241.876651)
			(xy 239.275003 -241.927148) (xy 239.24423 -241.973661) (xy 239.207013 -242.015198) (xy 239.164145 -242.050873)
			(xy 239.116539 -242.079927) (xy 239.06521 -242.101739) (xy 239.011253 -242.115845) (xy 238.955816 -242.121945)
			(xy 238.900082 -242.119908) (xy 238.845239 -242.109778) (xy 238.792455 -242.091771) (xy 238.742855 -242.06627)
			(xy 238.697497 -242.033819) (xy 238.657348 -241.99511) (xy 238.623262 -241.950967) (xy 238.595966 -241.902332)
			(xy 238.576043 -241.850241) (xy 238.563917 -241.795804) (xy 238.559846 -241.740182) (xy 238.214029 -241.740182)
			(xy 238.211113 -241.759998) (xy 238.195045 -241.813405) (xy 238.171373 -241.863902) (xy 238.1406 -241.910415)
			(xy 238.103383 -241.951952) (xy 238.060515 -241.987627) (xy 238.012909 -242.016681) (xy 237.96158 -242.038493)
			(xy 237.907623 -242.052599) (xy 237.852186 -242.058699) (xy 237.796452 -242.056662) (xy 237.741609 -242.046532)
			(xy 237.688825 -242.028525) (xy 237.639225 -242.003024) (xy 237.593867 -241.970573) (xy 237.553718 -241.931864)
			(xy 237.519632 -241.887721) (xy 237.492336 -241.839086) (xy 237.472413 -241.786995) (xy 237.460287 -241.732558)
			(xy 237.456216 -241.676936) (xy 236.140093 -241.676936) (xy 236.126469 -241.722219) (xy 236.102797 -241.772716)
			(xy 236.072024 -241.819229) (xy 236.034807 -241.860766) (xy 235.991939 -241.896441) (xy 235.944333 -241.925495)
			(xy 235.893004 -241.947307) (xy 235.839047 -241.961413) (xy 235.78361 -241.967513) (xy 235.727876 -241.965476)
			(xy 235.673033 -241.955346) (xy 235.620249 -241.937339) (xy 235.570649 -241.911838) (xy 235.525291 -241.879387)
			(xy 235.485142 -241.840678) (xy 235.451056 -241.796535) (xy 235.42376 -241.7479) (xy 235.403837 -241.695809)
			(xy 235.391711 -241.641372) (xy 235.38764 -241.58575) (xy 235.20029 -241.58575) (xy 235.200721 -241.588749)
			(xy 235.200721 -241.643251) (xy 235.192964 -241.697199) (xy 235.177609 -241.749494) (xy 235.154968 -241.799071)
			(xy 235.125501 -241.844921) (xy 235.08981 -241.886111) (xy 235.04862 -241.921803) (xy 235.002769 -241.951269)
			(xy 234.953192 -241.97391) (xy 234.900897 -241.989265) (xy 234.846949 -241.997021) (xy 234.819698 -241.997484)
			(xy 234.793501 -241.997026) (xy 234.7416 -241.989863) (xy 234.691168 -241.975659) (xy 234.643158 -241.954681)
			(xy 234.598473 -241.927325) (xy 234.557956 -241.894106) (xy 234.522372 -241.855651) (xy 234.507024 -241.834416)
			(xy 234.498673 -241.823154) (xy 234.476959 -241.805426) (xy 234.451246 -241.794266) (xy 234.423467 -241.790512)
			(xy 234.395713 -241.794447) (xy 234.370073 -241.805775) (xy 234.348476 -241.823643) (xy 234.340146 -241.834924)
			(xy 234.324769 -241.856282) (xy 234.289149 -241.895024) (xy 234.248543 -241.928502) (xy 234.203721 -241.956082)
			(xy 234.155534 -241.977241) (xy 234.104897 -241.991577) (xy 234.05277 -241.998817) (xy 234.026456 -241.999262)
			(xy 233.999204 -241.998865) (xy 233.945254 -241.991103) (xy 233.892958 -241.975742) (xy 233.843381 -241.953095)
			(xy 233.79753 -241.923624) (xy 233.75634 -241.887929) (xy 233.720649 -241.846735) (xy 233.691183 -241.800881)
			(xy 233.668543 -241.7513) (xy 233.653188 -241.699003) (xy 233.645432 -241.645053) (xy 230.734923 -241.645053)
			(xy 230.735885 -241.65159) (xy 230.736394 -241.679476) (xy 230.735885 -241.707362) (xy 230.727765 -241.762538)
			(xy 230.711697 -241.815945) (xy 230.688025 -241.866442) (xy 230.657252 -241.912955) (xy 230.620035 -241.954492)
			(xy 230.577167 -241.990167) (xy 230.529561 -242.019221) (xy 230.478232 -242.041033) (xy 230.424275 -242.055139)
			(xy 230.368838 -242.061239) (xy 230.313104 -242.059202) (xy 230.258261 -242.049072) (xy 230.205477 -242.031065)
			(xy 230.155877 -242.005564) (xy 230.110519 -241.973113) (xy 230.07037 -241.934404) (xy 230.036284 -241.890261)
			(xy 230.008988 -241.841626) (xy 229.989065 -241.789535) (xy 229.976939 -241.735098) (xy 229.972868 -241.679476)
			(xy 225.292412 -241.679476) (xy 225.627946 -242.01501) (xy 225.634797 -242.022406) (xy 225.642536 -242.041005)
			(xy 225.642932 -242.051078) (xy 225.642932 -243.19738) (xy 225.643167 -243.205087) (xy 225.6477 -243.219818)
			(xy 225.651822 -243.226336) (xy 225.671498 -243.255772) (xy 225.704418 -243.318459) (xy 225.729553 -243.384653)
			(xy 225.746538 -243.453391) (xy 225.755124 -243.523674) (xy 225.755708 -243.559076) (xy 225.755708 -244.485256)
			(xy 229.923237 -244.485256) (xy 229.923237 -244.430744) (xy 229.930995 -244.376787) (xy 229.946354 -244.324483)
			(xy 229.969001 -244.274898) (xy 229.998474 -244.229041) (xy 230.034174 -244.187845) (xy 230.075373 -244.15215)
			(xy 230.121233 -244.122682) (xy 230.170821 -244.10004) (xy 230.223126 -244.084687) (xy 230.277084 -244.076934)
			(xy 230.30434 -244.076474) (xy 230.33003 -244.076878) (xy 230.380945 -244.083779) (xy 230.430473 -244.09745)
			(xy 230.477718 -244.117644) (xy 230.521826 -244.143997) (xy 230.561999 -244.17603) (xy 230.597509 -244.213164)
			(xy 230.61295 -244.2337) (xy 230.621458 -244.244635) (xy 230.643186 -244.26181) (xy 230.668729 -244.272519)
			(xy 230.696209 -244.275975) (xy 230.723608 -244.271923) (xy 230.748912 -244.260663) (xy 230.770262 -244.24302)
			(xy 230.778558 -244.231922) (xy 230.793933 -244.210608) (xy 230.829565 -244.171979) (xy 230.870159 -244.138603)
			(xy 230.914949 -244.111112) (xy 230.963086 -244.090025) (xy 231.013661 -244.075741) (xy 231.065717 -244.068531)
			(xy 231.091994 -244.068092) (xy 231.119247 -244.068555) (xy 231.173199 -244.076311) (xy 231.225497 -244.091667)
			(xy 231.275078 -244.114309) (xy 231.320932 -244.143777) (xy 231.362125 -244.17947) (xy 231.39782 -244.220663)
			(xy 231.427288 -244.266517) (xy 231.449931 -244.316097) (xy 231.465288 -244.368395) (xy 231.473045 -244.422347)
			(xy 231.473045 -244.476853) (xy 231.465288 -244.530805) (xy 231.464893 -244.53215) (xy 237.172752 -244.53215)
			(xy 237.176823 -244.476528) (xy 237.188949 -244.422091) (xy 237.208872 -244.37) (xy 237.236168 -244.321365)
			(xy 237.270254 -244.277222) (xy 237.310403 -244.238513) (xy 237.355761 -244.206062) (xy 237.405361 -244.180561)
			(xy 237.458145 -244.162554) (xy 237.512988 -244.152424) (xy 237.568722 -244.150387) (xy 237.624159 -244.156487)
			(xy 237.678116 -244.170593) (xy 237.729445 -244.192405) (xy 237.777051 -244.221459) (xy 237.819919 -244.257134)
			(xy 237.857136 -244.298671) (xy 237.887909 -244.345184) (xy 237.911581 -244.395681) (xy 237.927649 -244.449088)
			(xy 237.935769 -244.504264) (xy 237.936278 -244.53215) (xy 237.935769 -244.560036) (xy 237.927649 -244.615212)
			(xy 237.911581 -244.668619) (xy 237.887909 -244.719116) (xy 237.857136 -244.765629) (xy 237.819919 -244.807166)
			(xy 237.777051 -244.842841) (xy 237.729445 -244.871895) (xy 237.678116 -244.893707) (xy 237.624159 -244.907813)
			(xy 237.568722 -244.913913) (xy 237.512988 -244.911876) (xy 237.458145 -244.901746) (xy 237.405361 -244.883739)
			(xy 237.355761 -244.858238) (xy 237.310403 -244.825787) (xy 237.270254 -244.787078) (xy 237.236168 -244.742935)
			(xy 237.208872 -244.6943) (xy 237.188949 -244.642209) (xy 237.176823 -244.587772) (xy 237.172752 -244.53215)
			(xy 231.464893 -244.53215) (xy 231.449931 -244.583103) (xy 231.427288 -244.632683) (xy 231.39782 -244.678537)
			(xy 231.362125 -244.71973) (xy 231.320932 -244.755423) (xy 231.275078 -244.784891) (xy 231.225497 -244.807533)
			(xy 231.173199 -244.822889) (xy 231.119247 -244.830645) (xy 231.091994 -244.831108) (xy 231.066304 -244.830685)
			(xy 231.01539 -244.823789) (xy 230.965862 -244.810121) (xy 230.918617 -244.78993) (xy 230.874509 -244.763581)
			(xy 230.834336 -244.73155) (xy 230.798826 -244.694417) (xy 230.783384 -244.673882) (xy 230.774835 -244.662982)
			(xy 230.753115 -244.645811) (xy 230.727582 -244.635102) (xy 230.700111 -244.631643) (xy 230.67272 -244.635687)
			(xy 230.647421 -244.646937) (xy 230.626072 -244.664568) (xy 230.617776 -244.67566) (xy 230.602375 -244.696954)
			(xy 230.566748 -244.735585) (xy 230.526158 -244.768963) (xy 230.481373 -244.796457) (xy 230.43324 -244.817547)
			(xy 230.382669 -244.831834) (xy 230.330615 -244.839049) (xy 230.30434 -244.83949) (xy 230.277084 -244.839066)
			(xy 230.223126 -244.831313) (xy 230.170821 -244.81596) (xy 230.121233 -244.793318) (xy 230.075373 -244.76385)
			(xy 230.034174 -244.728155) (xy 229.998474 -244.686959) (xy 229.969001 -244.641102) (xy 229.946354 -244.591517)
			(xy 229.930995 -244.539213) (xy 229.923237 -244.485256) (xy 225.755708 -244.485256) (xy 225.755708 -245.038118)
			(xy 232.954574 -245.038118) (xy 232.958645 -244.982496) (xy 232.970771 -244.928059) (xy 232.990694 -244.875968)
			(xy 233.01799 -244.827333) (xy 233.052076 -244.78319) (xy 233.092225 -244.744481) (xy 233.137583 -244.71203)
			(xy 233.187183 -244.686529) (xy 233.239967 -244.668522) (xy 233.29481 -244.658392) (xy 233.350544 -244.656355)
			(xy 233.405981 -244.662455) (xy 233.459938 -244.676561) (xy 233.511267 -244.698373) (xy 233.558873 -244.727427)
			(xy 233.601741 -244.763102) (xy 233.638958 -244.804639) (xy 233.669731 -244.851152) (xy 233.693403 -244.901649)
			(xy 233.709471 -244.955056) (xy 233.717591 -245.010232) (xy 233.7181 -245.038118) (xy 233.717591 -245.066004)
			(xy 233.709471 -245.12118) (xy 233.693403 -245.174587) (xy 233.669731 -245.225084) (xy 233.638958 -245.271597)
			(xy 233.606234 -245.30812) (xy 234.133388 -245.30812) (xy 234.137459 -245.252498) (xy 234.149585 -245.198061)
			(xy 234.169508 -245.14597) (xy 234.196804 -245.097335) (xy 234.23089 -245.053192) (xy 234.271039 -245.014483)
			(xy 234.316397 -244.982032) (xy 234.365997 -244.956531) (xy 234.418781 -244.938524) (xy 234.473624 -244.928394)
			(xy 234.529358 -244.926357) (xy 234.584795 -244.932457) (xy 234.638752 -244.946563) (xy 234.690081 -244.968375)
			(xy 234.737687 -244.997429) (xy 234.780555 -245.033104) (xy 234.817772 -245.074641) (xy 234.848545 -245.121154)
			(xy 234.872217 -245.171651) (xy 234.888285 -245.225058) (xy 234.896405 -245.280234) (xy 234.896914 -245.30812)
			(xy 234.896405 -245.336006) (xy 234.888285 -245.391182) (xy 234.872217 -245.444589) (xy 234.861876 -245.466648)
			(xy 235.025216 -245.466648) (xy 235.025216 -245.412152) (xy 235.032971 -245.358211) (xy 235.048324 -245.305923)
			(xy 235.070962 -245.256352) (xy 235.100424 -245.210507) (xy 235.13611 -245.169321) (xy 235.177294 -245.133633)
			(xy 235.223138 -245.10417) (xy 235.272708 -245.08153) (xy 235.324996 -245.066175) (xy 235.378936 -245.058417)
			(xy 235.406184 -245.05793) (xy 235.433792 -245.05844) (xy 235.488431 -245.066403) (xy 235.54135 -245.082165)
			(xy 235.591442 -245.105396) (xy 235.637658 -245.135611) (xy 235.679032 -245.172176) (xy 235.714699 -245.214327)
			(xy 235.743912 -245.261183) (xy 235.755434 -245.286276) (xy 235.761218 -245.29837) (xy 235.778028 -245.319242)
			(xy 235.799682 -245.335032) (xy 235.824695 -245.344654) (xy 235.851348 -245.34745) (xy 235.877813 -245.343227)
			(xy 235.902272 -245.332274) (xy 235.912914 -245.324122) (xy 235.933425 -245.307911) (xy 235.978037 -245.280653)
			(xy 236.025957 -245.259748) (xy 236.076284 -245.245591) (xy 236.128074 -245.238446) (xy 236.154214 -245.238016)
			(xy 236.181466 -245.238455) (xy 236.235416 -245.246213) (xy 236.287712 -245.261571) (xy 236.337291 -245.284214)
			(xy 236.383142 -245.313683) (xy 236.424334 -245.349376) (xy 236.460026 -245.390569) (xy 236.489493 -245.436421)
			(xy 236.512134 -245.486001) (xy 236.52749 -245.538298) (xy 236.535246 -245.592248) (xy 236.535246 -245.646752)
			(xy 236.52749 -245.700702) (xy 236.512134 -245.752999) (xy 236.489493 -245.802579) (xy 236.460026 -245.848431)
			(xy 236.424334 -245.889624) (xy 236.383142 -245.925317) (xy 236.337291 -245.954786) (xy 236.287712 -245.977429)
			(xy 236.235416 -245.992787) (xy 236.181466 -246.000545) (xy 236.154214 -246.001032) (xy 236.126605 -246.000546)
			(xy 236.071964 -245.992582) (xy 236.019043 -245.976818) (xy 235.96895 -245.953584) (xy 235.922734 -245.923366)
			(xy 235.88136 -245.886797) (xy 235.845695 -245.844641) (xy 235.816485 -245.797782) (xy 235.804964 -245.772686)
			(xy 235.799192 -245.760587) (xy 235.782376 -245.73972) (xy 235.760719 -245.723934) (xy 235.735706 -245.714314)
			(xy 235.709053 -245.711519) (xy 235.682588 -245.715741) (xy 235.658128 -245.72669) (xy 235.647484 -245.73484)
			(xy 235.626969 -245.751046) (xy 235.582358 -245.778306) (xy 235.53444 -245.799212) (xy 235.484114 -245.81337)
			(xy 235.432324 -245.820516) (xy 235.406184 -245.820946) (xy 235.378936 -245.820383) (xy 235.324996 -245.812625)
			(xy 235.272708 -245.79727) (xy 235.223138 -245.77463) (xy 235.177294 -245.745167) (xy 235.13611 -245.709479)
			(xy 235.100424 -245.668293) (xy 235.070962 -245.622448) (xy 235.048324 -245.572877) (xy 235.032971 -245.520589)
			(xy 235.025216 -245.466648) (xy 234.861876 -245.466648) (xy 234.848545 -245.495086) (xy 234.817772 -245.541599)
			(xy 234.780555 -245.583136) (xy 234.737687 -245.618811) (xy 234.690081 -245.647865) (xy 234.638752 -245.669677)
			(xy 234.584795 -245.683783) (xy 234.529358 -245.689883) (xy 234.473624 -245.687846) (xy 234.418781 -245.677716)
			(xy 234.365997 -245.659709) (xy 234.316397 -245.634208) (xy 234.271039 -245.601757) (xy 234.23089 -245.563048)
			(xy 234.196804 -245.518905) (xy 234.169508 -245.47027) (xy 234.149585 -245.418179) (xy 234.137459 -245.363742)
			(xy 234.133388 -245.30812) (xy 233.606234 -245.30812) (xy 233.601741 -245.313134) (xy 233.558873 -245.348809)
			(xy 233.511267 -245.377863) (xy 233.459938 -245.399675) (xy 233.405981 -245.413781) (xy 233.350544 -245.419881)
			(xy 233.29481 -245.417844) (xy 233.239967 -245.407714) (xy 233.187183 -245.389707) (xy 233.137583 -245.364206)
			(xy 233.092225 -245.331755) (xy 233.052076 -245.293046) (xy 233.01799 -245.248903) (xy 232.990694 -245.200268)
			(xy 232.970771 -245.148177) (xy 232.958645 -245.09374) (xy 232.954574 -245.038118) (xy 225.755708 -245.038118)
			(xy 225.755708 -246.306952) (xy 231.522248 -246.306952) (xy 231.522248 -246.252448) (xy 231.530004 -246.198499)
			(xy 231.545359 -246.146202) (xy 231.568 -246.096623) (xy 231.597465 -246.05077) (xy 231.633157 -246.009578)
			(xy 231.674346 -245.973883) (xy 231.720197 -245.944414) (xy 231.769774 -245.921769) (xy 231.822069 -245.90641)
			(xy 231.876018 -245.89865) (xy 231.90327 -245.898162) (xy 231.929659 -245.898584) (xy 231.981931 -245.905867)
			(xy 232.032701 -245.920285) (xy 232.080999 -245.941562) (xy 232.125904 -245.969292) (xy 232.166558 -246.002947)
			(xy 232.184702 -246.022114) (xy 232.191052 -246.029226) (xy 232.207308 -246.037354) (xy 232.292398 -246.047006)
			(xy 232.309924 -246.042434) (xy 232.317544 -246.0371) (xy 232.341579 -246.021128) (xy 232.393456 -245.995852)
			(xy 232.448552 -245.978693) (xy 232.505606 -245.970041) (xy 232.53446 -245.969536) (xy 232.563794 -245.970093)
			(xy 232.621774 -245.979057) (xy 232.677696 -245.996795) (xy 232.730241 -246.022889) (xy 232.778171 -246.056724)
			(xy 232.799636 -246.076724) (xy 232.807256 -246.08409) (xy 232.826814 -246.091456) (xy 232.922064 -246.08663)
			(xy 232.94086 -246.077232) (xy 232.947718 -246.069104) (xy 232.96595 -246.04829) (xy 233.007385 -246.011618)
			(xy 233.05368 -245.981314) (xy 233.103867 -245.958012) (xy 233.156892 -245.942202) (xy 233.211644 -245.934213)
			(xy 233.23931 -245.933722) (xy 233.266563 -245.934149) (xy 233.320514 -245.941907) (xy 233.372811 -245.957264)
			(xy 233.422391 -245.979908) (xy 233.468244 -246.009376) (xy 233.509436 -246.045071) (xy 233.54513 -246.086264)
			(xy 233.574597 -246.132117) (xy 233.597239 -246.181698) (xy 233.612595 -246.233996) (xy 233.620352 -246.287947)
			(xy 233.620352 -246.342453) (xy 233.612595 -246.396404) (xy 233.597239 -246.448702) (xy 233.574597 -246.498283)
			(xy 233.54513 -246.544136) (xy 233.509436 -246.585329) (xy 233.468244 -246.621024) (xy 233.422391 -246.650492)
			(xy 233.372811 -246.673136) (xy 233.320514 -246.688493) (xy 233.266563 -246.696251) (xy 233.23931 -246.696738)
			(xy 233.209975 -246.696207) (xy 233.151994 -246.687238) (xy 233.096071 -246.669494) (xy 233.043526 -246.643394)
			(xy 232.995598 -246.609553) (xy 232.974134 -246.58955) (xy 232.966514 -246.582184) (xy 232.946956 -246.574818)
			(xy 232.851706 -246.579644) (xy 232.83291 -246.589042) (xy 232.826052 -246.59717) (xy 232.80783 -246.617994)
			(xy 232.766394 -246.654666) (xy 232.720096 -246.684969) (xy 232.669908 -246.708269) (xy 232.616881 -246.724078)
			(xy 232.562127 -246.732063) (xy 232.53446 -246.732552) (xy 232.508072 -246.732106) (xy 232.455801 -246.724827)
			(xy 232.405032 -246.710414) (xy 232.356734 -246.689141) (xy 232.311828 -246.661415) (xy 232.271173 -246.627765)
			(xy 232.253028 -246.6086) (xy 232.246678 -246.601488) (xy 232.230422 -246.59336) (xy 232.145332 -246.583708)
			(xy 232.127806 -246.58828) (xy 232.120186 -246.593614) (xy 232.096144 -246.609575) (xy 232.04427 -246.634853)
			(xy 231.989176 -246.652015) (xy 231.932123 -246.660671) (xy 231.90327 -246.661178) (xy 231.876018 -246.66075)
			(xy 231.822069 -246.65299) (xy 231.769774 -246.637631) (xy 231.720197 -246.614986) (xy 231.674346 -246.585517)
			(xy 231.633157 -246.549822) (xy 231.597465 -246.50863) (xy 231.568 -246.462777) (xy 231.545359 -246.413198)
			(xy 231.530004 -246.360901) (xy 231.522248 -246.306952) (xy 225.755708 -246.306952) (xy 225.755708 -246.997982)
			(xy 236.805722 -246.997982) (xy 236.809793 -246.94236) (xy 236.821919 -246.887923) (xy 236.841842 -246.835832)
			(xy 236.869138 -246.787197) (xy 236.903224 -246.743054) (xy 236.943373 -246.704345) (xy 236.988731 -246.671894)
			(xy 237.038331 -246.646393) (xy 237.091115 -246.628386) (xy 237.145958 -246.618256) (xy 237.201692 -246.616219)
			(xy 237.257129 -246.622319) (xy 237.311086 -246.636425) (xy 237.362415 -246.658237) (xy 237.410021 -246.687291)
			(xy 237.452889 -246.722966) (xy 237.490106 -246.764503) (xy 237.520879 -246.811016) (xy 237.544551 -246.861513)
			(xy 237.560619 -246.91492) (xy 237.568739 -246.970096) (xy 237.569248 -246.997982) (xy 237.568739 -247.025868)
			(xy 237.560619 -247.081044) (xy 237.544551 -247.134451) (xy 237.520879 -247.184948) (xy 237.490106 -247.231461)
			(xy 237.452889 -247.272998) (xy 237.410021 -247.308673) (xy 237.362415 -247.337727) (xy 237.311086 -247.359539)
			(xy 237.257129 -247.373645) (xy 237.201692 -247.379745) (xy 237.145958 -247.377708) (xy 237.091115 -247.367578)
			(xy 237.038331 -247.349571) (xy 236.988731 -247.32407) (xy 236.943373 -247.291619) (xy 236.903224 -247.25291)
			(xy 236.869138 -247.208767) (xy 236.841842 -247.160132) (xy 236.821919 -247.108041) (xy 236.809793 -247.053604)
			(xy 236.805722 -246.997982) (xy 225.755708 -246.997982) (xy 225.755708 -248.391934) (xy 240.834416 -248.391934)
			(xy 240.838487 -248.336312) (xy 240.850613 -248.281875) (xy 240.870536 -248.229784) (xy 240.897832 -248.181149)
			(xy 240.931918 -248.137006) (xy 240.972067 -248.098297) (xy 241.017425 -248.065846) (xy 241.067025 -248.040345)
			(xy 241.119809 -248.022338) (xy 241.174652 -248.012208) (xy 241.230386 -248.010171) (xy 241.285823 -248.016271)
			(xy 241.33978 -248.030377) (xy 241.391109 -248.052189) (xy 241.438715 -248.081243) (xy 241.481583 -248.116918)
			(xy 241.5188 -248.158455) (xy 241.549573 -248.204968) (xy 241.573245 -248.255465) (xy 241.589313 -248.308872)
			(xy 241.597433 -248.364048) (xy 241.597942 -248.391934) (xy 242.866416 -248.391934) (xy 242.870487 -248.336312)
			(xy 242.882613 -248.281875) (xy 242.902536 -248.229784) (xy 242.929832 -248.181149) (xy 242.963918 -248.137006)
			(xy 243.004067 -248.098297) (xy 243.049425 -248.065846) (xy 243.099025 -248.040345) (xy 243.151809 -248.022338)
			(xy 243.206652 -248.012208) (xy 243.262386 -248.010171) (xy 243.317823 -248.016271) (xy 243.37178 -248.030377)
			(xy 243.423109 -248.052189) (xy 243.470715 -248.081243) (xy 243.513583 -248.116918) (xy 243.5508 -248.158455)
			(xy 243.581573 -248.204968) (xy 243.605245 -248.255465) (xy 243.621313 -248.308872) (xy 243.629433 -248.364048)
			(xy 243.629942 -248.391934) (xy 243.629433 -248.41982) (xy 243.621313 -248.474996) (xy 243.605245 -248.528403)
			(xy 243.581573 -248.5789) (xy 243.5508 -248.625413) (xy 243.513583 -248.66695) (xy 243.470715 -248.702625)
			(xy 243.423109 -248.731679) (xy 243.37178 -248.753491) (xy 243.317823 -248.767597) (xy 243.262386 -248.773697)
			(xy 243.206652 -248.77166) (xy 243.151809 -248.76153) (xy 243.099025 -248.743523) (xy 243.049425 -248.718022)
			(xy 243.004067 -248.685571) (xy 242.963918 -248.646862) (xy 242.929832 -248.602719) (xy 242.902536 -248.554084)
			(xy 242.882613 -248.501993) (xy 242.870487 -248.447556) (xy 242.866416 -248.391934) (xy 241.597942 -248.391934)
			(xy 241.597433 -248.41982) (xy 241.589313 -248.474996) (xy 241.573245 -248.528403) (xy 241.549573 -248.5789)
			(xy 241.5188 -248.625413) (xy 241.481583 -248.66695) (xy 241.438715 -248.702625) (xy 241.391109 -248.731679)
			(xy 241.33978 -248.753491) (xy 241.285823 -248.767597) (xy 241.230386 -248.773697) (xy 241.174652 -248.77166)
			(xy 241.119809 -248.76153) (xy 241.067025 -248.743523) (xy 241.017425 -248.718022) (xy 240.972067 -248.685571)
			(xy 240.931918 -248.646862) (xy 240.897832 -248.602719) (xy 240.870536 -248.554084) (xy 240.850613 -248.501993)
			(xy 240.838487 -248.447556) (xy 240.834416 -248.391934) (xy 225.755708 -248.391934) (xy 225.755708 -249.476514)
			(xy 239.818416 -249.476514) (xy 239.822487 -249.420892) (xy 239.834613 -249.366455) (xy 239.854536 -249.314364)
			(xy 239.881832 -249.265729) (xy 239.915918 -249.221586) (xy 239.956067 -249.182877) (xy 240.001425 -249.150426)
			(xy 240.051025 -249.124925) (xy 240.103809 -249.106918) (xy 240.158652 -249.096788) (xy 240.214386 -249.094751)
			(xy 240.269823 -249.100851) (xy 240.32378 -249.114957) (xy 240.375109 -249.136769) (xy 240.422715 -249.165823)
			(xy 240.465583 -249.201498) (xy 240.5028 -249.243035) (xy 240.533573 -249.289548) (xy 240.557245 -249.340045)
			(xy 240.573313 -249.393452) (xy 240.581433 -249.448628) (xy 240.581942 -249.476514) (xy 241.850416 -249.476514)
			(xy 241.854487 -249.420892) (xy 241.866613 -249.366455) (xy 241.886536 -249.314364) (xy 241.913832 -249.265729)
			(xy 241.947918 -249.221586) (xy 241.988067 -249.182877) (xy 242.033425 -249.150426) (xy 242.083025 -249.124925)
			(xy 242.135809 -249.106918) (xy 242.190652 -249.096788) (xy 242.246386 -249.094751) (xy 242.301823 -249.100851)
			(xy 242.35578 -249.114957) (xy 242.407109 -249.136769) (xy 242.454715 -249.165823) (xy 242.497583 -249.201498)
			(xy 242.5348 -249.243035) (xy 242.565573 -249.289548) (xy 242.589245 -249.340045) (xy 242.605313 -249.393452)
			(xy 242.613433 -249.448628) (xy 242.613942 -249.476514) (xy 244.898416 -249.476514) (xy 244.902487 -249.420892)
			(xy 244.914613 -249.366455) (xy 244.934536 -249.314364) (xy 244.961832 -249.265729) (xy 244.995918 -249.221586)
			(xy 245.036067 -249.182877) (xy 245.081425 -249.150426) (xy 245.131025 -249.124925) (xy 245.183809 -249.106918)
			(xy 245.238652 -249.096788) (xy 245.294386 -249.094751) (xy 245.349823 -249.100851) (xy 245.40378 -249.114957)
			(xy 245.455109 -249.136769) (xy 245.502715 -249.165823) (xy 245.545583 -249.201498) (xy 245.5828 -249.243035)
			(xy 245.613573 -249.289548) (xy 245.637245 -249.340045) (xy 245.653313 -249.393452) (xy 245.661433 -249.448628)
			(xy 245.661942 -249.476514) (xy 245.661433 -249.5044) (xy 245.653313 -249.559576) (xy 245.637245 -249.612983)
			(xy 245.613573 -249.66348) (xy 245.5828 -249.709993) (xy 245.545583 -249.75153) (xy 245.502715 -249.787205)
			(xy 245.455109 -249.816259) (xy 245.40378 -249.838071) (xy 245.349823 -249.852177) (xy 245.294386 -249.858277)
			(xy 245.238652 -249.85624) (xy 245.183809 -249.84611) (xy 245.131025 -249.828103) (xy 245.081425 -249.802602)
			(xy 245.036067 -249.770151) (xy 244.995918 -249.731442) (xy 244.961832 -249.687299) (xy 244.934536 -249.638664)
			(xy 244.914613 -249.586573) (xy 244.902487 -249.532136) (xy 244.898416 -249.476514) (xy 242.613942 -249.476514)
			(xy 242.613433 -249.5044) (xy 242.605313 -249.559576) (xy 242.589245 -249.612983) (xy 242.565573 -249.66348)
			(xy 242.5348 -249.709993) (xy 242.497583 -249.75153) (xy 242.454715 -249.787205) (xy 242.407109 -249.816259)
			(xy 242.35578 -249.838071) (xy 242.301823 -249.852177) (xy 242.246386 -249.858277) (xy 242.190652 -249.85624)
			(xy 242.135809 -249.84611) (xy 242.083025 -249.828103) (xy 242.033425 -249.802602) (xy 241.988067 -249.770151)
			(xy 241.947918 -249.731442) (xy 241.913832 -249.687299) (xy 241.886536 -249.638664) (xy 241.866613 -249.586573)
			(xy 241.854487 -249.532136) (xy 241.850416 -249.476514) (xy 240.581942 -249.476514) (xy 240.581433 -249.5044)
			(xy 240.573313 -249.559576) (xy 240.557245 -249.612983) (xy 240.533573 -249.66348) (xy 240.5028 -249.709993)
			(xy 240.465583 -249.75153) (xy 240.422715 -249.787205) (xy 240.375109 -249.816259) (xy 240.32378 -249.838071)
			(xy 240.269823 -249.852177) (xy 240.214386 -249.858277) (xy 240.158652 -249.85624) (xy 240.103809 -249.84611)
			(xy 240.051025 -249.828103) (xy 240.001425 -249.802602) (xy 239.956067 -249.770151) (xy 239.915918 -249.731442)
			(xy 239.881832 -249.687299) (xy 239.854536 -249.638664) (xy 239.834613 -249.586573) (xy 239.822487 -249.532136)
			(xy 239.818416 -249.476514) (xy 225.755708 -249.476514) (xy 225.755708 -251.83295) (xy 240.066072 -251.83295)
			(xy 240.066072 -251.77845) (xy 240.073828 -251.724504) (xy 240.089181 -251.672211) (xy 240.11182 -251.622635)
			(xy 240.141284 -251.576786) (xy 240.176973 -251.535595) (xy 240.21816 -251.499903) (xy 240.264007 -251.470436)
			(xy 240.313581 -251.447792) (xy 240.365873 -251.432434) (xy 240.419818 -251.424674) (xy 240.447068 -251.424186)
			(xy 240.474091 -251.424656) (xy 240.527597 -251.432275) (xy 240.579494 -251.447366) (xy 240.628743 -251.469625)
			(xy 240.67436 -251.498609) (xy 240.715433 -251.533737) (xy 240.75114 -251.574308) (xy 240.766346 -251.596652)
			(xy 240.77408 -251.607639) (xy 240.794151 -251.625488) (xy 240.818181 -251.637486) (xy 240.844507 -251.642807)
			(xy 240.87131 -251.64108) (xy 240.896737 -251.632426) (xy 240.919028 -251.617444) (xy 240.928144 -251.607574)
			(xy 240.946328 -251.587263) (xy 240.987496 -251.551526) (xy 241.033337 -251.522021) (xy 241.082914 -251.49935)
			(xy 241.135217 -251.483975) (xy 241.189176 -251.476211) (xy 241.216434 -251.475748) (xy 241.24368 -251.476324)
			(xy 241.297618 -251.484084) (xy 241.349903 -251.49944) (xy 241.39947 -251.522081) (xy 241.445311 -251.551545)
			(xy 241.486492 -251.587232) (xy 241.522176 -251.628416) (xy 241.551636 -251.67426) (xy 241.574272 -251.723829)
			(xy 241.589623 -251.776115) (xy 241.597378 -251.830053) (xy 241.597378 -251.857256) (xy 242.866416 -251.857256)
			(xy 242.870487 -251.801634) (xy 242.882613 -251.747197) (xy 242.902536 -251.695106) (xy 242.929832 -251.646471)
			(xy 242.963918 -251.602328) (xy 243.004067 -251.563619) (xy 243.049425 -251.531168) (xy 243.099025 -251.505667)
			(xy 243.151809 -251.48766) (xy 243.206652 -251.47753) (xy 243.262386 -251.475493) (xy 243.317823 -251.481593)
			(xy 243.37178 -251.495699) (xy 243.423109 -251.517511) (xy 243.470715 -251.546565) (xy 243.513583 -251.58224)
			(xy 243.5508 -251.623777) (xy 243.581573 -251.67029) (xy 243.605245 -251.720787) (xy 243.621313 -251.774194)
			(xy 243.629433 -251.82937) (xy 243.629942 -251.857256) (xy 243.629433 -251.885142) (xy 243.621313 -251.940318)
			(xy 243.605245 -251.993725) (xy 243.581573 -252.044222) (xy 243.5508 -252.090735) (xy 243.513583 -252.132272)
			(xy 243.470715 -252.167947) (xy 243.423109 -252.197001) (xy 243.37178 -252.218813) (xy 243.327527 -252.230382)
			(xy 245.948706 -252.230382) (xy 245.952777 -252.17476) (xy 245.964903 -252.120323) (xy 245.984826 -252.068232)
			(xy 246.012122 -252.019597) (xy 246.046208 -251.975454) (xy 246.086357 -251.936745) (xy 246.131715 -251.904294)
			(xy 246.181315 -251.878793) (xy 246.234099 -251.860786) (xy 246.288942 -251.850656) (xy 246.344676 -251.848619)
			(xy 246.400113 -251.854719) (xy 246.45407 -251.868825) (xy 246.505399 -251.890637) (xy 246.553005 -251.919691)
			(xy 246.595873 -251.955366) (xy 246.63309 -251.996903) (xy 246.663863 -252.043416) (xy 246.687535 -252.093913)
			(xy 246.703603 -252.14732) (xy 246.711723 -252.202496) (xy 246.712232 -252.230382) (xy 246.711723 -252.258268)
			(xy 246.703603 -252.313444) (xy 246.687535 -252.366851) (xy 246.663863 -252.417348) (xy 246.63309 -252.463861)
			(xy 246.595873 -252.505398) (xy 246.553005 -252.541073) (xy 246.505399 -252.570127) (xy 246.45407 -252.591939)
			(xy 246.400113 -252.606045) (xy 246.344676 -252.612145) (xy 246.288942 -252.610108) (xy 246.234099 -252.599978)
			(xy 246.181315 -252.581971) (xy 246.131715 -252.55647) (xy 246.086357 -252.524019) (xy 246.046208 -252.48531)
			(xy 246.012122 -252.441167) (xy 245.984826 -252.392532) (xy 245.964903 -252.340441) (xy 245.952777 -252.286004)
			(xy 245.948706 -252.230382) (xy 243.327527 -252.230382) (xy 243.317823 -252.232919) (xy 243.262386 -252.239019)
			(xy 243.206652 -252.236982) (xy 243.151809 -252.226852) (xy 243.099025 -252.208845) (xy 243.049425 -252.183344)
			(xy 243.004067 -252.150893) (xy 242.963918 -252.112184) (xy 242.929832 -252.068041) (xy 242.902536 -252.019406)
			(xy 242.882613 -251.967315) (xy 242.870487 -251.912878) (xy 242.866416 -251.857256) (xy 241.597378 -251.857256)
			(xy 241.597378 -251.884547) (xy 241.589623 -251.938485) (xy 241.574272 -251.990771) (xy 241.551636 -252.04034)
			(xy 241.522176 -252.086184) (xy 241.486492 -252.127368) (xy 241.445311 -252.163055) (xy 241.39947 -252.192519)
			(xy 241.349903 -252.21516) (xy 241.297618 -252.230516) (xy 241.24368 -252.238276) (xy 241.216434 -252.238764)
			(xy 241.189412 -252.23827) (xy 241.135908 -252.230652) (xy 241.084013 -252.215564) (xy 241.034764 -252.193308)
			(xy 240.989147 -252.164329) (xy 240.948073 -252.129205) (xy 240.912364 -252.088639) (xy 240.897156 -252.066298)
			(xy 240.88942 -252.055313) (xy 240.869347 -252.037473) (xy 240.845318 -252.02548) (xy 240.818994 -252.020162)
			(xy 240.792194 -252.021887) (xy 240.766769 -252.030536) (xy 240.744476 -252.045511) (xy 240.735358 -252.055376)
			(xy 240.717162 -252.075676) (xy 240.675998 -252.111416) (xy 240.63016 -252.140924) (xy 240.580585 -252.163597)
			(xy 240.528284 -252.178974) (xy 240.474325 -252.186739) (xy 240.447068 -252.187202) (xy 240.419818 -252.186726)
			(xy 240.365873 -252.178966) (xy 240.313581 -252.163608) (xy 240.264007 -252.140964) (xy 240.21816 -252.111497)
			(xy 240.176973 -252.075805) (xy 240.141284 -252.034614) (xy 240.11182 -251.988765) (xy 240.089181 -251.939189)
			(xy 240.073828 -251.886896) (xy 240.066072 -251.83295) (xy 225.755708 -251.83295) (xy 225.755708 -251.951998)
			(xy 225.756182 -251.961966) (xy 225.763753 -251.980407) (xy 225.77044 -251.987812) (xy 225.958654 -252.176026)
			(xy 225.959162 -252.176534) (xy 225.966543 -252.183117) (xy 225.984842 -252.190567) (xy 225.994722 -252.191012)
			(xy 226.38258 -252.191012) (xy 226.401122 -252.190504) (xy 226.42068 -252.191012) (xy 226.422458 -252.191012)
			(xy 226.449342 -252.192983) (xy 226.502202 -252.203542) (xy 226.553051 -252.221433) (xy 226.600877 -252.2463)
			(xy 226.644728 -252.277648) (xy 226.683733 -252.314854) (xy 226.717115 -252.357178) (xy 226.731068 -252.380242)
			(xy 226.731068 -252.380496) (xy 226.731322 -252.38075) (xy 226.736173 -252.388245) (xy 226.749994 -252.39953)
			(xy 226.766846 -252.405392) (xy 226.775772 -252.405642) (xy 226.878388 -252.404372) (xy 226.901502 -252.390402)
			(xy 226.90836 -252.377956) (xy 226.92277 -252.352464) (xy 226.958198 -252.30584) (xy 227.00034 -252.265183)
			(xy 227.048205 -252.231452) (xy 227.100667 -252.205438) (xy 227.15649 -252.187756) (xy 227.214361 -252.17882)
			(xy 227.24364 -252.178312) (xy 227.271174 -252.178798) (xy 227.325669 -252.186719) (xy 227.37846 -252.202392)
			(xy 227.428449 -252.22549) (xy 227.474599 -252.255534) (xy 227.515951 -252.2919) (xy 227.551646 -252.333832)
			(xy 227.566728 -252.356874) (xy 227.573586 -252.367796) (xy 227.59543 -252.380242) (xy 227.705666 -252.383036)
			(xy 227.728272 -252.37186) (xy 227.735638 -252.361192) (xy 227.751012 -252.340102) (xy 227.786599 -252.301925)
			(xy 227.827059 -252.268956) (xy 227.871636 -252.241812) (xy 227.919497 -252.221) (xy 227.96975 -252.206907)
			(xy 228.021454 -252.199798) (xy 228.04755 -252.199394) (xy 228.074805 -252.199854) (xy 228.128761 -252.207605)
			(xy 228.181065 -252.222957) (xy 228.230651 -252.245596) (xy 228.27651 -252.275063) (xy 228.317708 -252.310756)
			(xy 228.353407 -252.35195) (xy 228.38288 -252.397805) (xy 228.405526 -252.447388) (xy 228.420884 -252.49969)
			(xy 228.424344 -252.523752) (xy 230.546146 -252.523752) (xy 230.550217 -252.46813) (xy 230.562343 -252.413693)
			(xy 230.582266 -252.361602) (xy 230.609562 -252.312967) (xy 230.643648 -252.268824) (xy 230.683797 -252.230115)
			(xy 230.729155 -252.197664) (xy 230.778755 -252.172163) (xy 230.831539 -252.154156) (xy 230.886382 -252.144026)
			(xy 230.942116 -252.141989) (xy 230.997553 -252.148089) (xy 231.05151 -252.162195) (xy 231.102839 -252.184007)
			(xy 231.150445 -252.213061) (xy 231.193313 -252.248736) (xy 231.23053 -252.290273) (xy 231.261303 -252.336786)
			(xy 231.284975 -252.387283) (xy 231.301043 -252.44069) (xy 231.309163 -252.495866) (xy 231.309672 -252.523752)
			(xy 231.309163 -252.551638) (xy 231.307211 -252.5649) (xy 231.441242 -252.5649) (xy 231.445313 -252.509278)
			(xy 231.457439 -252.454841) (xy 231.477362 -252.40275) (xy 231.504658 -252.354115) (xy 231.538744 -252.309972)
			(xy 231.578893 -252.271263) (xy 231.624251 -252.238812) (xy 231.673851 -252.213311) (xy 231.726635 -252.195304)
			(xy 231.781478 -252.185174) (xy 231.837212 -252.183137) (xy 231.892649 -252.189237) (xy 231.946606 -252.203343)
			(xy 231.997935 -252.225155) (xy 232.045541 -252.254209) (xy 232.088409 -252.289884) (xy 232.125626 -252.331421)
			(xy 232.156399 -252.377934) (xy 232.180071 -252.428431) (xy 232.196139 -252.481838) (xy 232.204259 -252.537014)
			(xy 232.204768 -252.5649) (xy 232.204513 -252.57887) (xy 232.51871 -252.57887) (xy 232.522781 -252.523248)
			(xy 232.534907 -252.468811) (xy 232.55483 -252.41672) (xy 232.582126 -252.368085) (xy 232.616212 -252.323942)
			(xy 232.656361 -252.285233) (xy 232.701719 -252.252782) (xy 232.751319 -252.227281) (xy 232.804103 -252.209274)
			(xy 232.858946 -252.199144) (xy 232.91468 -252.197107) (xy 232.970117 -252.203207) (xy 233.024074 -252.217313)
			(xy 233.075403 -252.239125) (xy 233.123009 -252.268179) (xy 233.165877 -252.303854) (xy 233.203094 -252.345391)
			(xy 233.233867 -252.391904) (xy 233.257539 -252.442401) (xy 233.273607 -252.495808) (xy 233.281727 -252.550984)
			(xy 233.281847 -252.557534) (xy 234.556806 -252.557534) (xy 234.560877 -252.501912) (xy 234.573003 -252.447475)
			(xy 234.592926 -252.395384) (xy 234.620222 -252.346749) (xy 234.654308 -252.302606) (xy 234.694457 -252.263897)
			(xy 234.739815 -252.231446) (xy 234.789415 -252.205945) (xy 234.842199 -252.187938) (xy 234.897042 -252.177808)
			(xy 234.952776 -252.175771) (xy 235.008213 -252.181871) (xy 235.06217 -252.195977) (xy 235.113499 -252.217789)
			(xy 235.161105 -252.246843) (xy 235.203973 -252.282518) (xy 235.24119 -252.324055) (xy 235.271963 -252.370568)
			(xy 235.295635 -252.421065) (xy 235.311703 -252.474472) (xy 235.319823 -252.529648) (xy 235.320332 -252.557534)
			(xy 235.319823 -252.58542) (xy 235.311703 -252.640596) (xy 235.295635 -252.694003) (xy 235.271963 -252.7445)
			(xy 235.24119 -252.791013) (xy 235.203973 -252.83255) (xy 235.161105 -252.868225) (xy 235.113499 -252.897279)
			(xy 235.06217 -252.919091) (xy 235.008213 -252.933197) (xy 234.952776 -252.939297) (xy 234.897042 -252.93726)
			(xy 234.842199 -252.92713) (xy 234.789415 -252.909123) (xy 234.739815 -252.883622) (xy 234.694457 -252.851171)
			(xy 234.654308 -252.812462) (xy 234.620222 -252.768319) (xy 234.592926 -252.719684) (xy 234.573003 -252.667593)
			(xy 234.560877 -252.613156) (xy 234.556806 -252.557534) (xy 233.281847 -252.557534) (xy 233.282236 -252.57887)
			(xy 233.281727 -252.606756) (xy 233.273607 -252.661932) (xy 233.257539 -252.715339) (xy 233.233867 -252.765836)
			(xy 233.203094 -252.812349) (xy 233.165877 -252.853886) (xy 233.123009 -252.889561) (xy 233.075403 -252.918615)
			(xy 233.024074 -252.940427) (xy 232.970117 -252.954533) (xy 232.91468 -252.960633) (xy 232.858946 -252.958596)
			(xy 232.804103 -252.948466) (xy 232.751319 -252.930459) (xy 232.701719 -252.904958) (xy 232.656361 -252.872507)
			(xy 232.616212 -252.833798) (xy 232.582126 -252.789655) (xy 232.55483 -252.74102) (xy 232.534907 -252.688929)
			(xy 232.522781 -252.634492) (xy 232.51871 -252.57887) (xy 232.204513 -252.57887) (xy 232.204259 -252.592786)
			(xy 232.196139 -252.647962) (xy 232.180071 -252.701369) (xy 232.156399 -252.751866) (xy 232.125626 -252.798379)
			(xy 232.088409 -252.839916) (xy 232.045541 -252.875591) (xy 231.997935 -252.904645) (xy 231.946606 -252.926457)
			(xy 231.892649 -252.940563) (xy 231.837212 -252.946663) (xy 231.781478 -252.944626) (xy 231.726635 -252.934496)
			(xy 231.673851 -252.916489) (xy 231.624251 -252.890988) (xy 231.578893 -252.858537) (xy 231.538744 -252.819828)
			(xy 231.504658 -252.775685) (xy 231.477362 -252.72705) (xy 231.457439 -252.674959) (xy 231.445313 -252.620522)
			(xy 231.441242 -252.5649) (xy 231.307211 -252.5649) (xy 231.301043 -252.606814) (xy 231.284975 -252.660221)
			(xy 231.261303 -252.710718) (xy 231.23053 -252.757231) (xy 231.193313 -252.798768) (xy 231.150445 -252.834443)
			(xy 231.102839 -252.863497) (xy 231.05151 -252.885309) (xy 230.997553 -252.899415) (xy 230.942116 -252.905515)
			(xy 230.886382 -252.903478) (xy 230.831539 -252.893348) (xy 230.778755 -252.875341) (xy 230.729155 -252.84984)
			(xy 230.683797 -252.817389) (xy 230.643648 -252.77868) (xy 230.609562 -252.734537) (xy 230.582266 -252.685902)
			(xy 230.562343 -252.633811) (xy 230.550217 -252.579374) (xy 230.546146 -252.523752) (xy 228.424344 -252.523752)
			(xy 228.428643 -252.553645) (xy 228.428643 -252.608155) (xy 228.420884 -252.66211) (xy 228.405526 -252.714412)
			(xy 228.38288 -252.763995) (xy 228.353407 -252.80985) (xy 228.317708 -252.851044) (xy 228.27651 -252.886737)
			(xy 228.230651 -252.916204) (xy 228.181065 -252.938843) (xy 228.128761 -252.954195) (xy 228.074805 -252.961946)
			(xy 228.04755 -252.96241) (xy 228.020016 -252.961924) (xy 227.965521 -252.954001) (xy 227.912731 -252.938328)
			(xy 227.862742 -252.91523) (xy 227.816592 -252.885187) (xy 227.775239 -252.848822) (xy 227.739543 -252.80689)
			(xy 227.724462 -252.783848) (xy 227.717604 -252.772926) (xy 227.69576 -252.76048) (xy 227.585524 -252.757686)
			(xy 227.563172 -252.768862) (xy 227.555552 -252.77953) (xy 227.539732 -252.801223) (xy 227.50299 -252.84037)
			(xy 227.461122 -252.873979) (xy 227.414955 -252.901387) (xy 227.365403 -252.922052) (xy 227.313442 -252.935567)
			(xy 227.28682 -252.939042) (xy 227.286058 -252.939042) (xy 227.276679 -252.940561) (xy 227.259948 -252.949534)
			(xy 227.247635 -252.963985) (xy 227.244148 -252.972824) (xy 227.239322 -252.986794) (xy 227.245926 -253.014988)
			(xy 227.31857 -253.087632) (xy 227.325969 -253.094475) (xy 227.344568 -253.102194) (xy 227.354638 -253.102618)
			(xy 227.476812 -253.102618) (xy 227.486881 -253.103044) (xy 227.50548 -253.110763) (xy 227.51288 -253.117604)
			(xy 227.995734 -253.600458) (xy 227.996242 -253.600966) (xy 228.003623 -253.607549) (xy 228.021922 -253.615001)
			(xy 228.031802 -253.615444)
		)
		(stroke
			(width 0)
			(type solid)
		)
		(fill yes)
		(layer "In9.Cu")
		(net "P3V3_AUX")
	)
	(gr_poly
		(pts
			(xy 193.28384 -414.117282) (xy 193.297456 -414.116843) (xy 193.323718 -414.109639) (xy 193.347143 -414.095752)
			(xy 193.366067 -414.07617) (xy 193.379146 -414.052285) (xy 193.38545 -414.025792) (xy 193.384532 -413.998576)
			(xy 193.380868 -413.985456) (xy 193.372706 -413.957652) (xy 193.363902 -413.900381) (xy 193.363342 -413.87141)
			(xy 193.363828 -413.844141) (xy 193.37159 -413.790157) (xy 193.386955 -413.737827) (xy 193.409612 -413.688217)
			(xy 193.439098 -413.642336) (xy 193.474813 -413.601119) (xy 193.51603 -413.565404) (xy 193.561911 -413.535918)
			(xy 193.611521 -413.513261) (xy 193.663851 -413.497896) (xy 193.717835 -413.490134) (xy 193.772373 -413.490134)
			(xy 193.826357 -413.497896) (xy 193.878687 -413.513261) (xy 193.928297 -413.535918) (xy 193.974178 -413.565404)
			(xy 194.015395 -413.601119) (xy 194.05111 -413.642336) (xy 194.080596 -413.688217) (xy 194.103253 -413.737827)
			(xy 194.118618 -413.790157) (xy 194.12638 -413.844141) (xy 194.126866 -413.87141) (xy 194.12631 -413.900382)
			(xy 194.117508 -413.957654) (xy 194.10934 -413.985456) (xy 194.105701 -413.998585) (xy 194.104757 -414.025804)
			(xy 194.111045 -414.052303) (xy 194.12412 -414.076194) (xy 194.143047 -414.095777) (xy 194.166481 -414.109655)
			(xy 194.19275 -414.116841) (xy 194.206368 -414.117282) (xy 203.122784 -414.117282) (xy 203.132847 -414.116843)
			(xy 203.151428 -414.109105) (xy 203.158852 -414.102296) (xy 203.78801 -413.473138) (xy 203.788518 -413.47263)
			(xy 203.795101 -413.46525) (xy 203.802551 -413.44695) (xy 203.802996 -413.43707) (xy 203.802996 -396.298166)
			(xy 203.802447 -396.287536) (xy 203.79384 -396.268094) (xy 203.778109 -396.253791) (xy 203.768198 -396.249906)
			(xy 203.660756 -396.214346) (xy 203.629768 -396.224252) (xy 203.619862 -396.237714) (xy 203.558584 -396.319306)
			(xy 203.43055 -396.478227) (xy 203.296446 -396.63206) (xy 203.156474 -396.780574) (xy 203.010844 -396.923544)
			(xy 202.859777 -397.060756) (xy 202.703499 -397.192003) (xy 202.542246 -397.317087) (xy 202.376261 -397.43582)
			(xy 202.205793 -397.548023) (xy 202.031101 -397.653526) (xy 201.852446 -397.752172) (xy 201.670098 -397.843811)
			(xy 201.484331 -397.928305) (xy 201.295426 -398.005527) (xy 201.103667 -398.075361) (xy 200.909342 -398.137702)
			(xy 200.712744 -398.192456) (xy 200.51417 -398.23954) (xy 200.313919 -398.278883) (xy 200.112292 -398.310426)
			(xy 199.909592 -398.334122) (xy 199.706126 -398.349934) (xy 199.5022 -398.35784) (xy 199.40016 -398.35836)
			(xy 199.399906 -398.35836) (xy 199.297931 -398.357866) (xy 199.094134 -398.349957) (xy 198.890797 -398.334152)
			(xy 198.688226 -398.310475) (xy 198.486725 -398.278961) (xy 198.286597 -398.239657) (xy 198.088145 -398.192623)
			(xy 197.891665 -398.137929) (xy 197.697453 -398.075657) (xy 197.505803 -398.005902) (xy 197.317001 -397.928768)
			(xy 197.131332 -397.844371) (xy 196.949076 -397.752838) (xy 196.770505 -397.654307) (xy 196.59589 -397.548926)
			(xy 196.425492 -397.436853) (xy 196.259568 -397.318258) (xy 196.098367 -397.193317) (xy 195.942132 -397.062221)
			(xy 195.791098 -396.925164) (xy 195.645492 -396.782355) (xy 195.505533 -396.634007) (xy 195.371431 -396.480343)
			(xy 195.243388 -396.321595) (xy 195.121598 -396.158002) (xy 195.006242 -395.989809) (xy 194.897495 -395.81727)
			(xy 194.79552 -395.640644) (xy 194.70047 -395.460196) (xy 194.612489 -395.276199) (xy 194.531708 -395.088928)
			(xy 194.45825 -394.898666) (xy 194.392224 -394.705699) (xy 194.333731 -394.510317) (xy 194.282857 -394.312813)
			(xy 194.23968 -394.113486) (xy 194.204264 -393.912634) (xy 194.176664 -393.71056) (xy 194.156919 -393.507567)
			(xy 194.14506 -393.303962) (xy 194.141105 -393.10005) (xy 194.14506 -392.896138) (xy 194.156919 -392.692533)
			(xy 194.176664 -392.48954) (xy 194.204264 -392.287466) (xy 194.23968 -392.086614) (xy 194.282857 -391.887287)
			(xy 194.333731 -391.689783) (xy 194.392224 -391.494401) (xy 194.45825 -391.301434) (xy 194.531708 -391.111172)
			(xy 194.612489 -390.923901) (xy 194.70047 -390.739904) (xy 194.79552 -390.559456) (xy 194.897495 -390.38283)
			(xy 195.006242 -390.210291) (xy 195.121598 -390.042098) (xy 195.243388 -389.878505) (xy 195.371431 -389.719757)
			(xy 195.505533 -389.566093) (xy 195.645492 -389.417745) (xy 195.791098 -389.274936) (xy 195.942132 -389.137879)
			(xy 196.098367 -389.006783) (xy 196.259568 -388.881842) (xy 196.425492 -388.763247) (xy 196.59589 -388.651174)
			(xy 196.770505 -388.545793) (xy 196.949076 -388.447262) (xy 197.131332 -388.355729) (xy 197.317001 -388.271332)
			(xy 197.505803 -388.194198) (xy 197.697453 -388.124443) (xy 197.891665 -388.062171) (xy 198.088145 -388.007477)
			(xy 198.286597 -387.960443) (xy 198.486725 -387.921139) (xy 198.688226 -387.889625) (xy 198.890797 -387.865948)
			(xy 199.094134 -387.850143) (xy 199.297931 -387.842234) (xy 199.399906 -387.841744) (xy 199.40016 -387.841744)
			(xy 199.502199 -387.842235) (xy 199.706124 -387.850154) (xy 199.909588 -387.86598) (xy 200.112285 -387.889687)
			(xy 200.31391 -387.92124) (xy 200.514159 -387.960592) (xy 200.71273 -388.007683) (xy 200.909325 -388.062443)
			(xy 201.103647 -388.124788) (xy 201.295404 -388.194626) (xy 201.484307 -388.27185) (xy 201.670072 -388.356345)
			(xy 201.85242 -388.447984) (xy 202.031074 -388.546628) (xy 202.205767 -388.652128) (xy 202.376236 -388.764327)
			(xy 202.542223 -388.883055) (xy 202.703479 -389.008133) (xy 202.859761 -389.139374) (xy 203.010834 -389.276578)
			(xy 203.15647 -389.419541) (xy 203.29645 -389.568046) (xy 203.430563 -389.721869) (xy 203.558608 -389.88078)
			(xy 203.619862 -389.96239) (xy 203.629768 -389.975852) (xy 203.660756 -389.985758) (xy 203.768198 -389.950198)
			(xy 203.778133 -389.946343) (xy 203.793904 -389.932047) (xy 203.802517 -389.912581) (xy 203.802996 -389.901938)
			(xy 203.802996 -376.041666) (xy 203.802298 -376.029507) (xy 203.791156 -376.00789) (xy 203.78166 -376.000264)
			(xy 203.70419 -375.945146) (xy 203.68006 -375.94159) (xy 203.668376 -375.945654) (xy 203.638253 -375.95539)
			(xy 203.575821 -375.965857) (xy 203.54417 -375.966482) (xy 203.543916 -375.966482) (xy 203.516664 -375.96602)
			(xy 203.462715 -375.958265) (xy 203.410419 -375.942912) (xy 203.36084 -375.920272) (xy 203.314988 -375.890806)
			(xy 203.273797 -375.855115) (xy 203.238104 -375.813925) (xy 203.208636 -375.768074) (xy 203.185994 -375.718496)
			(xy 203.170638 -375.6662) (xy 203.162881 -375.612252) (xy 203.162881 -375.557748) (xy 203.170638 -375.5038)
			(xy 203.185994 -375.451504) (xy 203.208636 -375.401926) (xy 203.238104 -375.356075) (xy 203.273797 -375.314885)
			(xy 203.314988 -375.279194) (xy 203.36084 -375.249728) (xy 203.410419 -375.227088) (xy 203.462715 -375.211735)
			(xy 203.516664 -375.20398) (xy 203.543916 -375.203466) (xy 203.54417 -375.203466) (xy 203.575816 -375.204147)
			(xy 203.638239 -375.214613) (xy 203.668376 -375.224294) (xy 203.68006 -375.228358) (xy 203.70419 -375.224802)
			(xy 203.78166 -375.169684) (xy 203.79118 -375.162073) (xy 203.802347 -375.14045) (xy 203.802996 -375.128282)
			(xy 203.802996 -372.661688) (xy 203.802365 -372.651014) (xy 203.793571 -372.631552) (xy 203.777657 -372.617309)
			(xy 203.76769 -372.613428) (xy 203.767436 -372.613428) (xy 203.740458 -372.60441) (xy 203.689318 -372.579506)
			(xy 203.642441 -372.547287) (xy 203.600868 -372.508465) (xy 203.565519 -372.463901) (xy 203.537177 -372.414583)
			(xy 203.516472 -372.361603) (xy 203.503861 -372.306137) (xy 203.499625 -372.249414) (xy 203.503857 -372.19269)
			(xy 203.516464 -372.137223) (xy 203.537165 -372.084242) (xy 203.565503 -372.034922) (xy 203.600849 -371.990356)
			(xy 203.64242 -371.951531) (xy 203.689294 -371.919308) (xy 203.740432 -371.894401) (xy 203.767436 -371.885464)
			(xy 203.76769 -371.885464) (xy 203.777766 -371.881766) (xy 203.793773 -371.867495) (xy 203.802545 -371.847926)
			(xy 203.802996 -371.837204) (xy 203.802996 -371.702838) (xy 203.802561 -371.692773) (xy 203.794831 -371.674185)
			(xy 203.78801 -371.66677) (xy 203.644246 -371.523006) (xy 203.637134 -371.51564) (xy 203.618338 -371.50802)
			(xy 202.062842 -371.50802) (xy 202.048729 -371.508472) (xy 202.021579 -371.516188) (xy 201.997579 -371.531043)
			(xy 201.978564 -371.551901) (xy 201.965985 -371.577168) (xy 201.960805 -371.604914) (xy 201.963419 -371.633018)
			(xy 201.973628 -371.659332) (xy 201.981816 -371.670834) (xy 201.999967 -371.695844) (xy 202.028798 -371.750499)
			(xy 202.048461 -371.80908) (xy 202.058441 -371.870062) (xy 202.059032 -371.900958) (xy 202.059032 -371.901212)
			(xy 202.058546 -371.928481) (xy 202.050784 -371.982465) (xy 202.035419 -372.034795) (xy 202.012762 -372.084405)
			(xy 201.983276 -372.130286) (xy 201.947561 -372.171503) (xy 201.906344 -372.207218) (xy 201.860463 -372.236704)
			(xy 201.810853 -372.259361) (xy 201.758523 -372.274726) (xy 201.704539 -372.282488) (xy 201.650001 -372.282488)
			(xy 201.596017 -372.274726) (xy 201.543687 -372.259361) (xy 201.494077 -372.236704) (xy 201.448196 -372.207218)
			(xy 201.406979 -372.171503) (xy 201.371264 -372.130286) (xy 201.341778 -372.084405) (xy 201.319121 -372.034795)
			(xy 201.303756 -371.982465) (xy 201.295994 -371.928481) (xy 201.295508 -371.901212) (xy 201.295508 -371.900958)
			(xy 201.295965 -371.874362) (xy 201.303344 -371.821685) (xy 201.317968 -371.770544) (xy 201.339553 -371.721929)
			(xy 201.367681 -371.676784) (xy 201.384408 -371.656102) (xy 201.393027 -371.645061) (xy 201.404433 -371.61949)
			(xy 201.408478 -371.591784) (xy 201.404859 -371.564019) (xy 201.393845 -371.538276) (xy 201.376264 -371.516485)
			(xy 201.365104 -371.50802) (xy 201.281538 -371.50802) (xy 201.178922 -371.405404) (xy 201.169778 -371.396514)
			(xy 199.995536 -370.222018) (xy 199.988135 -370.21518) (xy 199.969536 -370.207466) (xy 199.959468 -370.207032)
			(xy 199.526652 -370.207032) (xy 199.512682 -370.206778) (xy 199.368664 -370.206778) (xy 199.266302 -370.104416)
			(xy 199.256904 -370.095272) (xy 197.907148 -368.745262) (xy 197.90537 -368.74323) (xy 197.899782 -368.737642)
			(xy 197.88124 -368.730276) (xy 197.54215 -368.730276) (xy 197.514918 -368.729787) (xy 197.461008 -368.722029)
			(xy 197.408751 -368.706679) (xy 197.359211 -368.684049) (xy 197.313394 -368.654599) (xy 197.272235 -368.61893)
			(xy 197.236571 -368.577766) (xy 197.207127 -368.531946) (xy 197.184503 -368.482402) (xy 197.16916 -368.430143)
			(xy 197.16141 -368.376232) (xy 197.16141 -368.321768) (xy 197.16916 -368.267857) (xy 197.184503 -368.215598)
			(xy 197.207127 -368.166054) (xy 197.236571 -368.120234) (xy 197.272235 -368.07907) (xy 197.313394 -368.043401)
			(xy 197.359211 -368.013951) (xy 197.408751 -367.991321) (xy 197.461008 -367.975971) (xy 197.514918 -367.968213)
			(xy 197.54215 -367.967768) (xy 198.208138 -367.967768) (xy 198.3105 -368.070384) (xy 198.319898 -368.079274)
			(xy 198.773796 -368.533172) (xy 201.113134 -368.533172) (xy 201.117205 -368.47755) (xy 201.129331 -368.423113)
			(xy 201.149254 -368.371022) (xy 201.17655 -368.322387) (xy 201.210636 -368.278244) (xy 201.250785 -368.239535)
			(xy 201.296143 -368.207084) (xy 201.345743 -368.181583) (xy 201.398527 -368.163576) (xy 201.45337 -368.153446)
			(xy 201.509104 -368.151409) (xy 201.564541 -368.157509) (xy 201.618498 -368.171615) (xy 201.669827 -368.193427)
			(xy 201.717433 -368.222481) (xy 201.760301 -368.258156) (xy 201.797518 -368.299693) (xy 201.828291 -368.346206)
			(xy 201.851963 -368.396703) (xy 201.868031 -368.45011) (xy 201.876151 -368.505286) (xy 201.87666 -368.533172)
			(xy 201.876151 -368.561058) (xy 201.868031 -368.616234) (xy 201.851963 -368.669641) (xy 201.828291 -368.720138)
			(xy 201.797518 -368.766651) (xy 201.760301 -368.808188) (xy 201.717433 -368.843863) (xy 201.669827 -368.872917)
			(xy 201.618498 -368.894729) (xy 201.564541 -368.908835) (xy 201.509104 -368.914935) (xy 201.45337 -368.912898)
			(xy 201.398527 -368.902768) (xy 201.345743 -368.884761) (xy 201.296143 -368.85926) (xy 201.250785 -368.826809)
			(xy 201.210636 -368.7881) (xy 201.17655 -368.743957) (xy 201.149254 -368.695322) (xy 201.129331 -368.643231)
			(xy 201.117205 -368.588794) (xy 201.113134 -368.533172) (xy 198.773796 -368.533172) (xy 199.245728 -369.005104)
			(xy 199.252602 -369.011339) (xy 199.269549 -369.018871) (xy 199.288064 -369.019928) (xy 199.297036 -369.01755)
			(xy 199.396858 -368.985546) (xy 199.4154 -368.96421) (xy 199.417686 -368.949986) (xy 199.422505 -368.923558)
			(xy 199.438587 -368.872301) (xy 199.461702 -368.823807) (xy 199.491391 -368.779036) (xy 199.527067 -368.738873)
			(xy 199.568025 -368.704112) (xy 199.613455 -368.67544) (xy 199.662458 -368.653426) (xy 199.714064 -368.638504)
			(xy 199.767254 -368.630969) (xy 199.794114 -368.630454) (xy 199.821366 -368.630941) (xy 199.875314 -368.638699)
			(xy 199.927609 -368.654055) (xy 199.977187 -368.676696) (xy 200.023038 -368.706162) (xy 200.06423 -368.741853)
			(xy 200.099924 -368.783042) (xy 200.129392 -368.828892) (xy 200.152037 -368.878468) (xy 200.167396 -368.930763)
			(xy 200.175158 -368.98471) (xy 200.175622 -369.011962) (xy 200.175074 -369.041399) (xy 200.166032 -369.099576)
			(xy 200.148171 -369.155676) (xy 200.121915 -369.208372) (xy 200.087886 -369.256416) (xy 200.046888 -369.298671)
			(xy 199.999893 -369.334135) (xy 199.9742 -369.348512) (xy 199.961754 -369.355116) (xy 199.94753 -369.378992)
			(xy 199.94753 -369.393216) (xy 199.947953 -369.403233) (xy 199.955627 -369.421739) (xy 199.969799 -369.435899)
			(xy 199.988313 -369.443556) (xy 199.99833 -369.444016) (xy 200.138284 -369.444016) (xy 200.152254 -369.44427)
			(xy 200.296272 -369.44427) (xy 200.398634 -369.546632) (xy 200.408032 -369.555776) (xy 200.424034 -369.571778)
			(xy 200.432645 -369.579591) (xy 200.454607 -369.587151) (xy 200.466198 -369.586256) (xy 200.543414 -369.576604)
			(xy 200.546716 -369.576096) (xy 200.55967 -369.573556) (xy 200.57745 -369.56111) (xy 200.583038 -369.551712)
			(xy 200.597896 -369.527712) (xy 200.63357 -369.483968) (xy 200.675296 -369.445954) (xy 200.722165 -369.414498)
			(xy 200.773154 -369.390286) (xy 200.827152 -369.373846) (xy 200.882983 -369.365536) (xy 200.911206 -369.365022)
			(xy 200.938458 -369.365486) (xy 200.992406 -369.373244) (xy 201.044702 -369.3886) (xy 201.094279 -369.411244)
			(xy 201.14013 -369.440712) (xy 201.181319 -369.476406) (xy 201.217009 -369.517599) (xy 201.246474 -369.563452)
			(xy 201.269112 -369.613032) (xy 201.284464 -369.665329) (xy 201.292217 -369.719278) (xy 201.292714 -369.74653)
			(xy 201.292202 -369.774764) (xy 201.283874 -369.830615) (xy 201.267405 -369.884629) (xy 201.243154 -369.935625)
			(xy 201.21165 -369.982489) (xy 201.173584 -370.024198) (xy 201.129785 -370.05984) (xy 201.10577 -370.074698)
			(xy 201.09561 -370.080794) (xy 201.08291 -370.100352) (xy 201.07148 -370.191538) (xy 201.070589 -370.203132)
			(xy 201.078132 -370.225102) (xy 201.085958 -370.233702) (xy 201.582528 -370.730526) (xy 201.583036 -370.731034)
			(xy 201.590415 -370.737621) (xy 201.608715 -370.74508) (xy 201.618596 -370.745512) (xy 203.093828 -370.745512)
			(xy 203.095352 -370.745512) (xy 203.110592 -370.745512) (xy 203.135484 -370.730272) (xy 203.179426 -370.6368)
			(xy 203.183292 -370.627608) (xy 203.184196 -370.607705) (xy 203.181204 -370.598192) (xy 203.174346 -370.579396)
			(xy 203.169266 -370.572792) (xy 203.153736 -370.552503) (xy 203.127669 -370.508559) (xy 203.107703 -370.461527)
			(xy 203.094197 -370.41225) (xy 203.087391 -370.361611) (xy 203.08697 -370.336064) (xy 203.087478 -370.315744)
			(xy 203.087465 -370.305116) (xy 203.079842 -370.285304) (xy 203.072746 -370.27739) (xy 203.019152 -370.223796)
			(xy 203.011242 -370.216694) (xy 202.991426 -370.209068) (xy 202.980798 -370.209064) (xy 202.960478 -370.209572)
			(xy 202.93323 -370.209084) (xy 202.87929 -370.201326) (xy 202.827003 -370.18597) (xy 202.777433 -370.16333)
			(xy 202.73159 -370.133866) (xy 202.690406 -370.098178) (xy 202.654721 -370.056992) (xy 202.625259 -370.011147)
			(xy 202.602622 -369.961576) (xy 202.587269 -369.909288) (xy 202.579514 -369.855348) (xy 202.579514 -369.800852)
			(xy 202.587269 -369.746912) (xy 202.602622 -369.694624) (xy 202.625259 -369.645053) (xy 202.654721 -369.599208)
			(xy 202.690406 -369.558022) (xy 202.73159 -369.522334) (xy 202.777433 -369.49287) (xy 202.827003 -369.47023)
			(xy 202.87929 -369.454874) (xy 202.93323 -369.447116) (xy 202.960478 -369.446556) (xy 202.989075 -369.447064)
			(xy 203.045628 -369.455598) (xy 203.100273 -369.472477) (xy 203.151788 -369.497323) (xy 203.199017 -369.52958)
			(xy 203.22032 -369.548664) (xy 203.231496 -369.559078) (xy 203.261214 -369.564158) (xy 203.360528 -369.520724)
			(xy 203.369355 -369.516364) (xy 203.383086 -369.502283) (xy 203.390524 -369.484075) (xy 203.391008 -369.474242)
			(xy 203.391008 -368.439954) (xy 203.390557 -368.430112) (xy 203.383137 -368.41188) (xy 203.369376 -368.397806)
			(xy 203.360528 -368.393472) (xy 203.261214 -368.350038) (xy 203.231496 -368.355118) (xy 203.22032 -368.365532)
			(xy 203.199022 -368.38462) (xy 203.151784 -368.416859) (xy 203.100267 -368.441693) (xy 203.045623 -368.458569)
			(xy 202.989073 -368.467108) (xy 202.960478 -368.46764) (xy 202.933225 -368.467153) (xy 202.879276 -368.459393)
			(xy 202.826979 -368.444035) (xy 202.777401 -368.42139) (xy 202.731549 -368.391921) (xy 202.690358 -368.356226)
			(xy 202.654666 -368.315033) (xy 202.625199 -368.26918) (xy 202.602558 -368.2196) (xy 202.587202 -368.167303)
			(xy 202.579446 -368.113353) (xy 202.579446 -368.058847) (xy 202.587202 -368.004897) (xy 202.602558 -367.9526)
			(xy 202.625199 -367.90302) (xy 202.654666 -367.857167) (xy 202.690358 -367.815974) (xy 202.731549 -367.780279)
			(xy 202.777401 -367.75081) (xy 202.826979 -367.728165) (xy 202.879276 -367.712807) (xy 202.933225 -367.705047)
			(xy 202.960478 -367.704624) (xy 202.980798 -367.705132) (xy 202.991432 -367.705132) (xy 203.011265 -367.697531)
			(xy 203.019152 -367.6904) (xy 203.072746 -367.636806) (xy 203.079835 -367.628892) (xy 203.087437 -367.609078)
			(xy 203.087478 -367.598452) (xy 203.08697 -367.578132) (xy 203.08743 -367.55122) (xy 203.094994 -367.49793)
			(xy 203.109977 -367.446233) (xy 203.13208 -367.397157) (xy 203.160865 -367.351676) (xy 203.195758 -367.310695)
			(xy 203.236068 -367.275028) (xy 203.280993 -367.245384) (xy 203.32964 -367.222351) (xy 203.355194 -367.213896)
			(xy 203.355448 -367.213896) (xy 203.365597 -367.210202) (xy 203.381725 -367.195867) (xy 203.390542 -367.176172)
			(xy 203.391008 -367.165382) (xy 203.391008 -366.79378) (xy 203.391435 -366.783712) (xy 203.399155 -366.765113)
			(xy 203.405994 -366.757712) (xy 203.713334 -366.450372) (xy 203.720731 -366.443523) (xy 203.73933 -366.43579)
			(xy 203.749402 -366.435386) (xy 204.169772 -366.435386) (xy 204.17409 -366.435132) (xy 204.184332 -366.433773)
			(xy 204.202555 -366.424077) (xy 204.209396 -366.416336) (xy 204.211936 -366.41278) (xy 204.254608 -366.348772)
			(xy 204.258525 -366.342326) (xy 204.262783 -366.327864) (xy 204.26299 -366.320324) (xy 204.26299 -366.29467)
			(xy 204.259434 -366.285526) (xy 204.251073 -366.263239) (xy 204.239314 -366.217112) (xy 204.233377 -366.169881)
			(xy 204.233018 -366.14608) (xy 204.233018 -366.145826) (xy 204.233504 -366.118575) (xy 204.24126 -366.064627)
			(xy 204.256615 -366.012332) (xy 204.279257 -365.962755) (xy 204.308723 -365.916905) (xy 204.344414 -365.875714)
			(xy 204.385605 -365.840023) (xy 204.431455 -365.810557) (xy 204.481032 -365.787915) (xy 204.533327 -365.77256)
			(xy 204.587275 -365.764804) (xy 204.641777 -365.764804) (xy 204.695725 -365.77256) (xy 204.74802 -365.787915)
			(xy 204.797597 -365.810557) (xy 204.843447 -365.840023) (xy 204.884638 -365.875714) (xy 204.920329 -365.916905)
			(xy 204.949795 -365.962755) (xy 204.972437 -366.012332) (xy 204.987792 -366.064627) (xy 204.995548 -366.118575)
			(xy 204.996034 -366.145826) (xy 204.996034 -366.14608) (xy 204.995624 -366.171522) (xy 204.988896 -366.221958)
			(xy 204.975543 -366.271057) (xy 204.966062 -366.29467) (xy 204.960982 -366.306354) (xy 204.963522 -366.331754)
			(xy 205.017116 -366.412526) (xy 205.020672 -366.417606) (xy 205.027422 -366.424899) (xy 205.045097 -366.433947)
			(xy 205.054962 -366.435132) (xy 205.05928 -366.435386) (xy 209.766154 -366.435386) (xy 209.776137 -366.434892)
			(xy 209.794582 -366.427247) (xy 209.80871 -366.413138) (xy 209.816379 -366.394703) (xy 209.816426 -366.374736)
			(xy 209.808845 -366.356265) (xy 209.802222 -366.348772) (xy 209.766154 -366.312704) (xy 209.761866 -366.308687)
			(xy 209.751858 -366.302537) (xy 209.746342 -366.300512) (xy 209.741008 -366.298734) (xy 209.715556 -366.290245)
			(xy 209.667142 -366.267123) (xy 209.62245 -366.237438) (xy 209.582363 -366.201779) (xy 209.547673 -366.16085)
			(xy 209.519067 -366.11546) (xy 209.49711 -366.066507) (xy 209.482235 -366.014958) (xy 209.474737 -365.961832)
			(xy 209.474308 -365.935006) (xy 209.474771 -365.907753) (xy 209.482527 -365.853803) (xy 209.497883 -365.801505)
			(xy 209.520525 -365.751925) (xy 209.549993 -365.706072) (xy 209.585687 -365.66488) (xy 209.62688 -365.629187)
			(xy 209.672734 -365.599721) (xy 209.722314 -365.577079) (xy 209.774612 -365.561725) (xy 209.828563 -365.55397)
			(xy 209.855816 -365.553498) (xy 209.882604 -365.553953) (xy 209.935651 -365.561457) (xy 209.987125 -365.576314)
			(xy 210.036012 -365.598233) (xy 210.081348 -365.62678) (xy 210.12224 -365.661394) (xy 210.157883 -365.701393)
			(xy 210.187575 -365.745989) (xy 210.210729 -365.794302) (xy 210.21929 -365.81969) (xy 210.219544 -365.820452)
			(xy 210.2231 -365.831374) (xy 210.22945 -365.84128) (xy 210.233768 -365.845598) (xy 210.529678 -366.141254)
			(xy 210.537078 -366.148093) (xy 210.555677 -366.155807) (xy 210.565746 -366.15624) (xy 212.046312 -366.15624)
			(xy 212.057422 -366.155682) (xy 212.077579 -366.146333) (xy 212.085174 -366.138206) (xy 212.13445 -366.08004)
			(xy 212.139946 -366.07299) (xy 212.146061 -366.056206) (xy 212.146388 -366.047274) (xy 212.146388 -366.037876)
			(xy 212.14588 -366.034066) (xy 212.143776 -366.019743) (xy 212.141487 -365.990883) (xy 212.141308 -365.976408)
			(xy 212.141308 -365.975646) (xy 212.141768 -365.948391) (xy 212.14952 -365.894436) (xy 212.164872 -365.842134)
			(xy 212.187512 -365.792549) (xy 212.216979 -365.746691) (xy 212.252673 -365.705494) (xy 212.293867 -365.669797)
			(xy 212.339723 -365.640327) (xy 212.389306 -365.617683) (xy 212.441607 -365.602326) (xy 212.495561 -365.59457)
			(xy 212.522816 -365.594138) (xy 212.551998 -365.594697) (xy 212.609678 -365.603606) (xy 212.665323 -365.621214)
			(xy 212.717629 -365.647106) (xy 212.765371 -365.680678) (xy 212.80743 -365.721143) (xy 212.825584 -365.743998)
			(xy 212.827616 -365.746538) (xy 212.833712 -365.752634) (xy 212.836612 -365.755419) (xy 212.843118 -365.760141)
			(xy 212.846666 -365.762032) (xy 212.84692 -365.762286) (xy 212.852245 -365.76475) (xy 212.863661 -365.767448)
			(xy 212.869526 -365.76762) (xy 212.961982 -365.768128) (xy 212.983318 -365.757714) (xy 212.990684 -365.748062)
			(xy 212.991192 -365.747554) (xy 212.993224 -365.745014) (xy 213.011381 -365.722348) (xy 213.053403 -365.682264)
			(xy 213.101022 -365.649023) (xy 213.153136 -365.623398) (xy 213.208537 -365.60598) (xy 213.265939 -365.597176)
			(xy 213.294976 -365.596678) (xy 213.32223 -365.597139) (xy 213.376185 -365.604893) (xy 213.428486 -365.620247)
			(xy 213.47807 -365.642888) (xy 213.523928 -365.672355) (xy 213.565124 -365.708049) (xy 213.600822 -365.749242)
			(xy 213.630294 -365.795096) (xy 213.65294 -365.844678) (xy 213.668299 -365.896978) (xy 213.676058 -365.950932)
			(xy 213.676484 -365.978186) (xy 213.676327 -365.993302) (xy 213.673914 -366.023437) (xy 213.671658 -366.038384)
			(xy 213.66988 -366.04956) (xy 213.675976 -366.070642) (xy 213.733634 -366.13846) (xy 213.741212 -366.146471)
			(xy 213.761228 -366.155666) (xy 213.772242 -366.15624) (xy 217.438224 -366.15624) (xy 217.464204 -366.156742)
			(xy 217.515517 -366.16491) (xy 217.56492 -366.181011) (xy 217.611193 -366.204647) (xy 217.653195 -366.235235)
			(xy 217.671904 -366.253268) (xy 217.839544 -366.420654) (xy 217.846953 -366.427341) (xy 217.865389 -366.434935)
			(xy 217.875358 -366.435386) (xy 223.509078 -366.435386) (xy 223.519253 -366.434936) (xy 223.538003 -366.427025)
			(xy 223.552196 -366.41244) (xy 223.556322 -366.403128) (xy 223.596454 -366.300258) (xy 223.589342 -366.269778)
			(xy 223.577658 -366.25911) (xy 223.558611 -366.240976) (xy 223.525176 -366.200381) (xy 223.497629 -366.155581)
			(xy 223.47649 -366.107425) (xy 223.46216 -366.056824) (xy 223.45491 -366.004735) (xy 223.454468 -365.97844)
			(xy 223.454468 -365.978186) (xy 223.454954 -365.950935) (xy 223.46271 -365.896987) (xy 223.478065 -365.844692)
			(xy 223.500707 -365.795115) (xy 223.530173 -365.749265) (xy 223.565864 -365.708074) (xy 223.607055 -365.672383)
			(xy 223.652905 -365.642917) (xy 223.702482 -365.620275) (xy 223.754777 -365.60492) (xy 223.808725 -365.597164)
			(xy 223.863227 -365.597164) (xy 223.917175 -365.60492) (xy 223.96947 -365.620275) (xy 224.019047 -365.642917)
			(xy 224.064897 -365.672383) (xy 224.106088 -365.708074) (xy 224.141779 -365.749265) (xy 224.171245 -365.795115)
			(xy 224.193887 -365.844692) (xy 224.209242 -365.896987) (xy 224.216998 -365.950935) (xy 224.217484 -365.978186)
			(xy 224.217484 -365.97844) (xy 224.217047 -366.004738) (xy 224.209824 -366.056835) (xy 224.195507 -366.107444)
			(xy 224.174368 -366.155605) (xy 224.146809 -366.200402) (xy 224.113353 -366.240985) (xy 224.094294 -366.25911)
			(xy 224.08261 -366.269778) (xy 224.075498 -366.300258) (xy 224.11563 -366.403128) (xy 224.119768 -366.412431)
			(xy 224.133968 -366.427) (xy 224.152703 -366.434929) (xy 224.162874 -366.435386) (xy 226.303078 -366.435386)
			(xy 226.313253 -366.434936) (xy 226.332003 -366.427025) (xy 226.346196 -366.41244) (xy 226.350322 -366.403128)
			(xy 226.390454 -366.300258) (xy 226.383342 -366.269778) (xy 226.371658 -366.25911) (xy 226.352611 -366.240976)
			(xy 226.319176 -366.200381) (xy 226.291629 -366.155581) (xy 226.27049 -366.107425) (xy 226.25616 -366.056824)
			(xy 226.24891 -366.004735) (xy 226.248468 -365.97844) (xy 226.248468 -365.978186) (xy 226.248954 -365.950935)
			(xy 226.25671 -365.896987) (xy 226.272065 -365.844692) (xy 226.294707 -365.795115) (xy 226.324173 -365.749265)
			(xy 226.359864 -365.708074) (xy 226.401055 -365.672383) (xy 226.446905 -365.642917) (xy 226.496482 -365.620275)
			(xy 226.548777 -365.60492) (xy 226.602725 -365.597164) (xy 226.657227 -365.597164) (xy 226.711175 -365.60492)
			(xy 226.76347 -365.620275) (xy 226.813047 -365.642917) (xy 226.858897 -365.672383) (xy 226.900088 -365.708074)
			(xy 226.935779 -365.749265) (xy 226.965245 -365.795115) (xy 226.987887 -365.844692) (xy 227.003242 -365.896987)
			(xy 227.010998 -365.950935) (xy 227.011484 -365.978186) (xy 227.011484 -365.97844) (xy 227.011047 -366.004738)
			(xy 227.003824 -366.056835) (xy 226.989507 -366.107444) (xy 226.968368 -366.155605) (xy 226.940809 -366.200402)
			(xy 226.907353 -366.240985) (xy 226.888294 -366.25911) (xy 226.87661 -366.269778) (xy 226.869498 -366.300258)
			(xy 226.90963 -366.403128) (xy 226.913768 -366.412431) (xy 226.927968 -366.427) (xy 226.946703 -366.434929)
			(xy 226.956874 -366.435386) (xy 233.171492 -366.435386) (xy 233.179874 -366.434624) (xy 233.187481 -366.433114)
			(xy 233.201322 -366.426134) (xy 233.207052 -366.420908) (xy 233.463338 -366.164622) (xy 233.470179 -366.157222)
			(xy 233.477894 -366.138623) (xy 233.478324 -366.128554) (xy 233.478324 -362.086398) (xy 233.470704 -362.067602)
			(xy 233.463338 -362.06049) (xy 233.340148 -361.9373) (xy 233.332747 -361.930462) (xy 233.314149 -361.922746)
			(xy 233.30408 -361.922314) (xy 206.651098 -361.922314) (xy 206.641529 -361.922663) (xy 206.623692 -361.929585)
			(xy 206.609642 -361.942573) (xy 206.605124 -361.951016) (xy 206.566262 -362.03255) (xy 206.561868 -362.043028)
			(xy 206.56172 -362.065718) (xy 206.566008 -362.076238) (xy 206.571088 -362.08716) (xy 206.574644 -362.091478)
			(xy 206.589969 -362.111687) (xy 206.615709 -362.155391) (xy 206.635426 -362.202121) (xy 206.648773 -362.251053)
			(xy 206.655514 -362.301322) (xy 206.655924 -362.326682) (xy 206.655438 -362.353933) (xy 206.647682 -362.407881)
			(xy 206.632327 -362.460176) (xy 206.609685 -362.509753) (xy 206.580219 -362.555603) (xy 206.544528 -362.596794)
			(xy 206.503337 -362.632485) (xy 206.457487 -362.661951) (xy 206.40791 -362.684593) (xy 206.355615 -362.699948)
			(xy 206.301667 -362.707704) (xy 206.247165 -362.707704) (xy 206.193217 -362.699948) (xy 206.140922 -362.684593)
			(xy 206.091345 -362.661951) (xy 206.045495 -362.632485) (xy 206.004304 -362.596794) (xy 205.968613 -362.555603)
			(xy 205.939147 -362.509753) (xy 205.916505 -362.460176) (xy 205.90115 -362.407881) (xy 205.893394 -362.353933)
			(xy 205.892908 -362.326682) (xy 205.89337 -362.300861) (xy 205.900403 -362.2497) (xy 205.914269 -362.199954)
			(xy 205.934717 -362.152531) (xy 205.961371 -362.108299) (xy 205.977236 -362.087922) (xy 205.98638 -362.076238)
			(xy 205.989682 -362.047282) (xy 205.943708 -361.95127) (xy 205.939255 -361.942809) (xy 205.925309 -361.929753)
			(xy 205.90754 -361.922736) (xy 205.897988 -361.922314) (xy 203.679552 -361.922314) (xy 203.669056 -361.922837)
			(xy 203.649819 -361.93124) (xy 203.635538 -361.946627) (xy 203.631546 -361.95635) (xy 203.594462 -362.062268)
			(xy 203.603352 -362.093256) (xy 203.616052 -362.103416) (xy 203.638111 -362.121601) (xy 203.677051 -362.163455)
			(xy 203.709306 -362.210654) (xy 203.734154 -362.262139) (xy 203.751036 -362.316756) (xy 203.759576 -362.373282)
			(xy 203.76007 -362.401866) (xy 203.759584 -362.429117) (xy 203.751828 -362.483065) (xy 203.736473 -362.53536)
			(xy 203.713831 -362.584937) (xy 203.684365 -362.630787) (xy 203.648674 -362.671978) (xy 203.607483 -362.707669)
			(xy 203.561633 -362.737135) (xy 203.512056 -362.759777) (xy 203.459761 -362.775132) (xy 203.405813 -362.782888)
			(xy 203.351311 -362.782888) (xy 203.297363 -362.775132) (xy 203.245068 -362.759777) (xy 203.195491 -362.737135)
			(xy 203.149641 -362.707669) (xy 203.10845 -362.671978) (xy 203.072759 -362.630787) (xy 203.043293 -362.584937)
			(xy 203.020651 -362.53536) (xy 203.005296 -362.483065) (xy 202.99754 -362.429117) (xy 202.997054 -362.401866)
			(xy 202.997567 -362.373284) (xy 203.006106 -362.316761) (xy 203.022989 -362.262147) (xy 203.047837 -362.210666)
			(xy 203.080092 -362.163471) (xy 203.119031 -362.121621) (xy 203.141072 -362.103416) (xy 203.153772 -362.093256)
			(xy 203.162662 -362.062268) (xy 203.125578 -361.95635) (xy 203.121634 -361.946598) (xy 203.107348 -361.931188)
			(xy 203.08808 -361.922805) (xy 203.077572 -361.922314) (xy 200.052432 -361.922314) (xy 200.042272 -361.92333)
			(xy 200.032366 -361.925362) (xy 200.02246 -361.92841) (xy 200.01357 -361.93222) (xy 199.957944 -362.014008)
			(xy 199.954611 -362.019261) (xy 199.950369 -362.030953) (xy 199.949562 -362.037122) (xy 199.948292 -362.050076)
			(xy 199.953118 -362.062522) (xy 199.961531 -362.084843) (xy 199.973379 -362.131049) (xy 199.979379 -362.178372)
			(xy 199.979788 -362.202222) (xy 199.9793 -362.229472) (xy 199.971541 -362.283416) (xy 199.956184 -362.335707)
			(xy 199.933541 -362.38528) (xy 199.904074 -362.431126) (xy 199.868382 -362.472312) (xy 199.827192 -362.507999)
			(xy 199.781343 -362.537461) (xy 199.731767 -362.560099) (xy 199.679475 -362.57545) (xy 199.62553 -362.583203)
			(xy 199.59828 -362.58373) (xy 199.57055 -362.583232) (xy 199.515674 -362.575203) (xy 199.462537 -362.559318)
			(xy 199.412259 -362.535911) (xy 199.365897 -362.505474) (xy 199.324427 -362.468649) (xy 199.288723 -362.42621)
			(xy 199.259537 -362.379051) (xy 199.237481 -362.328165) (xy 199.229726 -362.301536) (xy 199.229726 -362.301282)
			(xy 199.226932 -362.291376) (xy 199.22109 -362.283502) (xy 199.217888 -362.279556) (xy 199.210212 -362.2729)
			(xy 199.20585 -362.270294) (xy 199.134222 -362.2294) (xy 199.114156 -362.22686) (xy 199.10425 -362.229654)
			(xy 199.078984 -362.23628) (xy 199.027242 -362.243415) (xy 199.001126 -362.243878) (xy 198.973316 -362.24337)
			(xy 198.918286 -362.235284) (xy 198.865014 -362.219294) (xy 198.814627 -362.19574) (xy 198.768194 -362.165119)
			(xy 198.726698 -362.128082) (xy 198.691019 -362.085413) (xy 198.661913 -362.038016) (xy 198.639997 -361.986895)
			(xy 198.632318 -361.96016) (xy 198.632318 -361.959906) (xy 198.628874 -361.94932) (xy 198.614562 -361.932301)
			(xy 198.594413 -361.922895) (xy 198.583296 -361.922314) (xy 187.009024 -361.922314) (xy 186.99896 -361.922751)
			(xy 186.980377 -361.930487) (xy 186.972956 -361.9373) (xy 186.320684 -362.589572) (xy 200.18832 -362.589572)
			(xy 200.192391 -362.53395) (xy 200.204517 -362.479513) (xy 200.22444 -362.427422) (xy 200.251736 -362.378787)
			(xy 200.285822 -362.334644) (xy 200.325971 -362.295935) (xy 200.371329 -362.263484) (xy 200.420929 -362.237983)
			(xy 200.473713 -362.219976) (xy 200.528556 -362.209846) (xy 200.58429 -362.207809) (xy 200.639727 -362.213909)
			(xy 200.693684 -362.228015) (xy 200.745013 -362.249827) (xy 200.792619 -362.278881) (xy 200.835487 -362.314556)
			(xy 200.872704 -362.356093) (xy 200.903477 -362.402606) (xy 200.927149 -362.453103) (xy 200.943217 -362.50651)
			(xy 200.951337 -362.561686) (xy 200.951846 -362.589572) (xy 200.951337 -362.617458) (xy 200.943217 -362.672634)
			(xy 200.927149 -362.726041) (xy 200.903477 -362.776538) (xy 200.872704 -362.823051) (xy 200.835487 -362.864588)
			(xy 200.792619 -362.900263) (xy 200.745013 -362.929317) (xy 200.693684 -362.951129) (xy 200.639727 -362.965235)
			(xy 200.58429 -362.971335) (xy 200.528556 -362.969298) (xy 200.473713 -362.959168) (xy 200.420929 -362.941161)
			(xy 200.371329 -362.91566) (xy 200.325971 -362.883209) (xy 200.285822 -362.8445) (xy 200.251736 -362.800357)
			(xy 200.22444 -362.751722) (xy 200.204517 -362.699631) (xy 200.192391 -362.645194) (xy 200.18832 -362.589572)
			(xy 186.320684 -362.589572) (xy 185.902346 -363.00791) (xy 201.156568 -363.00791) (xy 201.160639 -362.952288)
			(xy 201.172765 -362.897851) (xy 201.192688 -362.84576) (xy 201.219984 -362.797125) (xy 201.25407 -362.752982)
			(xy 201.294219 -362.714273) (xy 201.339577 -362.681822) (xy 201.389177 -362.656321) (xy 201.441961 -362.638314)
			(xy 201.496804 -362.628184) (xy 201.552538 -362.626147) (xy 201.607975 -362.632247) (xy 201.661932 -362.646353)
			(xy 201.713261 -362.668165) (xy 201.760867 -362.697219) (xy 201.803735 -362.732894) (xy 201.840952 -362.774431)
			(xy 201.871725 -362.820944) (xy 201.895397 -362.871441) (xy 201.911465 -362.924848) (xy 201.919585 -362.980024)
			(xy 201.920094 -363.00791) (xy 201.919585 -363.035796) (xy 201.911465 -363.090972) (xy 201.895397 -363.144379)
			(xy 201.871725 -363.194876) (xy 201.840952 -363.241389) (xy 201.803735 -363.282926) (xy 201.760867 -363.318601)
			(xy 201.713261 -363.347655) (xy 201.661932 -363.369467) (xy 201.607975 -363.383573) (xy 201.552538 -363.389673)
			(xy 201.496804 -363.387636) (xy 201.441961 -363.377506) (xy 201.389177 -363.359499) (xy 201.339577 -363.333998)
			(xy 201.294219 -363.301547) (xy 201.25407 -363.262838) (xy 201.219984 -363.218695) (xy 201.192688 -363.17006)
			(xy 201.172765 -363.117969) (xy 201.160639 -363.063532) (xy 201.156568 -363.00791) (xy 185.902346 -363.00791)
			(xy 185.326528 -363.583728) (xy 197.166228 -363.583728) (xy 197.170299 -363.528106) (xy 197.182425 -363.473669)
			(xy 197.202348 -363.421578) (xy 197.229644 -363.372943) (xy 197.26373 -363.3288) (xy 197.303879 -363.290091)
			(xy 197.349237 -363.25764) (xy 197.398837 -363.232139) (xy 197.451621 -363.214132) (xy 197.506464 -363.204002)
			(xy 197.562198 -363.201965) (xy 197.617635 -363.208065) (xy 197.671592 -363.222171) (xy 197.722921 -363.243983)
			(xy 197.770527 -363.273037) (xy 197.813395 -363.308712) (xy 197.850612 -363.350249) (xy 197.881385 -363.396762)
			(xy 197.905057 -363.447259) (xy 197.921125 -363.500666) (xy 197.929245 -363.555842) (xy 197.929754 -363.583728)
			(xy 197.929245 -363.611614) (xy 197.92434 -363.644942) (xy 202.462636 -363.644942) (xy 202.466707 -363.58932)
			(xy 202.478833 -363.534883) (xy 202.498756 -363.482792) (xy 202.526052 -363.434157) (xy 202.560138 -363.390014)
			(xy 202.600287 -363.351305) (xy 202.645645 -363.318854) (xy 202.695245 -363.293353) (xy 202.748029 -363.275346)
			(xy 202.802872 -363.265216) (xy 202.858606 -363.263179) (xy 202.914043 -363.269279) (xy 202.968 -363.283385)
			(xy 203.019329 -363.305197) (xy 203.066935 -363.334251) (xy 203.109803 -363.369926) (xy 203.14702 -363.411463)
			(xy 203.177793 -363.457976) (xy 203.201465 -363.508473) (xy 203.217533 -363.56188) (xy 203.225653 -363.617056)
			(xy 203.226162 -363.644942) (xy 203.225653 -363.672828) (xy 203.217533 -363.728004) (xy 203.201465 -363.781411)
			(xy 203.177793 -363.831908) (xy 203.14702 -363.878421) (xy 203.109803 -363.919958) (xy 203.066935 -363.955633)
			(xy 203.019329 -363.984687) (xy 202.968 -364.006499) (xy 202.914043 -364.020605) (xy 202.858606 -364.026705)
			(xy 202.802872 -364.024668) (xy 202.748029 -364.014538) (xy 202.695245 -363.996531) (xy 202.645645 -363.97103)
			(xy 202.600287 -363.938579) (xy 202.560138 -363.89987) (xy 202.526052 -363.855727) (xy 202.498756 -363.807092)
			(xy 202.478833 -363.755001) (xy 202.466707 -363.700564) (xy 202.462636 -363.644942) (xy 197.92434 -363.644942)
			(xy 197.921125 -363.66679) (xy 197.905057 -363.720197) (xy 197.881385 -363.770694) (xy 197.850612 -363.817207)
			(xy 197.813395 -363.858744) (xy 197.770527 -363.894419) (xy 197.722921 -363.923473) (xy 197.671592 -363.945285)
			(xy 197.617635 -363.959391) (xy 197.562198 -363.965491) (xy 197.506464 -363.963454) (xy 197.451621 -363.953324)
			(xy 197.398837 -363.935317) (xy 197.349237 -363.909816) (xy 197.303879 -363.877365) (xy 197.26373 -363.838656)
			(xy 197.229644 -363.794513) (xy 197.202348 -363.745878) (xy 197.182425 -363.693787) (xy 197.170299 -363.63935)
			(xy 197.166228 -363.583728) (xy 185.326528 -363.583728) (xy 185.038238 -363.872018) (xy 185.030872 -363.87913)
			(xy 185.023252 -363.897926) (xy 185.023252 -364.1852) (xy 199.46188 -364.1852) (xy 199.465951 -364.129578)
			(xy 199.478077 -364.075141) (xy 199.498 -364.02305) (xy 199.525296 -363.974415) (xy 199.559382 -363.930272)
			(xy 199.599531 -363.891563) (xy 199.644889 -363.859112) (xy 199.694489 -363.833611) (xy 199.747273 -363.815604)
			(xy 199.802116 -363.805474) (xy 199.85785 -363.803437) (xy 199.913287 -363.809537) (xy 199.967244 -363.823643)
			(xy 200.018573 -363.845455) (xy 200.066179 -363.874509) (xy 200.109047 -363.910184) (xy 200.146264 -363.951721)
			(xy 200.177037 -363.998234) (xy 200.200709 -364.048731) (xy 200.216777 -364.102138) (xy 200.224897 -364.157314)
			(xy 200.225406 -364.1852) (xy 200.224897 -364.213086) (xy 200.216777 -364.268262) (xy 200.200709 -364.321669)
			(xy 200.177037 -364.372166) (xy 200.146264 -364.418679) (xy 200.109047 -364.460216) (xy 200.066179 -364.495891)
			(xy 200.018573 -364.524945) (xy 199.967244 -364.546757) (xy 199.913287 -364.560863) (xy 199.85785 -364.566963)
			(xy 199.802116 -364.564926) (xy 199.747273 -364.554796) (xy 199.694489 -364.536789) (xy 199.644889 -364.511288)
			(xy 199.599531 -364.478837) (xy 199.559382 -364.440128) (xy 199.525296 -364.395985) (xy 199.498 -364.34735)
			(xy 199.478077 -364.295259) (xy 199.465951 -364.240822) (xy 199.46188 -364.1852) (xy 185.023252 -364.1852)
			(xy 185.023252 -364.599728) (xy 197.166228 -364.599728) (xy 197.170299 -364.544106) (xy 197.182425 -364.489669)
			(xy 197.202348 -364.437578) (xy 197.229644 -364.388943) (xy 197.26373 -364.3448) (xy 197.303879 -364.306091)
			(xy 197.349237 -364.27364) (xy 197.398837 -364.248139) (xy 197.451621 -364.230132) (xy 197.506464 -364.220002)
			(xy 197.562198 -364.217965) (xy 197.617635 -364.224065) (xy 197.671592 -364.238171) (xy 197.722921 -364.259983)
			(xy 197.770527 -364.289037) (xy 197.813395 -364.324712) (xy 197.850612 -364.366249) (xy 197.881385 -364.412762)
			(xy 197.905057 -364.463259) (xy 197.921125 -364.516666) (xy 197.929245 -364.571842) (xy 197.929754 -364.599728)
			(xy 197.929245 -364.627614) (xy 197.921125 -364.68279) (xy 197.905057 -364.736197) (xy 197.881385 -364.786694)
			(xy 197.850612 -364.833207) (xy 197.813395 -364.874744) (xy 197.770527 -364.910419) (xy 197.722921 -364.939473)
			(xy 197.671592 -364.961285) (xy 197.617635 -364.975391) (xy 197.562198 -364.981491) (xy 197.506464 -364.979454)
			(xy 197.451621 -364.969324) (xy 197.398837 -364.951317) (xy 197.349237 -364.925816) (xy 197.303879 -364.893365)
			(xy 197.26373 -364.854656) (xy 197.229644 -364.810513) (xy 197.202348 -364.761878) (xy 197.182425 -364.709787)
			(xy 197.170299 -364.65535) (xy 197.166228 -364.599728) (xy 185.023252 -364.599728) (xy 185.023252 -365.117952)
			(xy 194.110065 -365.117952) (xy 194.110065 -365.063448) (xy 194.117822 -365.009498) (xy 194.133178 -364.957201)
			(xy 194.15582 -364.907622) (xy 194.185287 -364.86177) (xy 194.22098 -364.820579) (xy 194.262172 -364.784886)
			(xy 194.308024 -364.755419) (xy 194.357603 -364.732777) (xy 194.4099 -364.717422) (xy 194.46385 -364.709665)
			(xy 194.491102 -364.709202) (xy 194.517968 -364.709649) (xy 194.571169 -364.717189) (xy 194.622786 -364.732119)
			(xy 194.671797 -364.754143) (xy 194.717233 -364.782827) (xy 194.758194 -364.817602) (xy 194.793871 -364.857781)
			(xy 194.823558 -364.902568) (xy 194.835526 -364.926626) (xy 194.842292 -364.939646) (xy 194.861922 -364.961438)
			(xy 194.886936 -364.976752) (xy 194.915271 -364.984326) (xy 194.94459 -364.983533) (xy 194.972474 -364.974441)
			(xy 194.996625 -364.957798) (xy 195.006214 -364.946692) (xy 195.024426 -364.92493) (xy 195.066198 -364.886523)
			(xy 195.113199 -364.854729) (xy 195.164393 -364.830249) (xy 195.218648 -364.813626) (xy 195.274767 -364.805224)
			(xy 195.30314 -364.804706) (xy 195.33039 -364.805167) (xy 195.384336 -364.812928) (xy 195.436628 -364.828287)
			(xy 195.486202 -364.850931) (xy 195.532049 -364.8804) (xy 195.573236 -364.916093) (xy 195.608924 -364.957283)
			(xy 195.638388 -365.003134) (xy 195.654486 -365.038386) (xy 201.228958 -365.038386) (xy 201.233029 -364.982764)
			(xy 201.245155 -364.928327) (xy 201.265078 -364.876236) (xy 201.292374 -364.827601) (xy 201.32646 -364.783458)
			(xy 201.366609 -364.744749) (xy 201.411967 -364.712298) (xy 201.461567 -364.686797) (xy 201.514351 -364.66879)
			(xy 201.569194 -364.65866) (xy 201.624928 -364.656623) (xy 201.680365 -364.662723) (xy 201.734322 -364.676829)
			(xy 201.785651 -364.698641) (xy 201.833257 -364.727695) (xy 201.876125 -364.76337) (xy 201.913342 -364.804907)
			(xy 201.944115 -364.85142) (xy 201.967787 -364.901917) (xy 201.983855 -364.955324) (xy 201.991975 -365.0105)
			(xy 201.992484 -365.038386) (xy 201.991975 -365.066272) (xy 201.983855 -365.121448) (xy 201.967787 -365.174855)
			(xy 201.944115 -365.225352) (xy 201.913342 -365.271865) (xy 201.876125 -365.313402) (xy 201.867805 -365.320326)
			(xy 214.325706 -365.320326) (xy 214.329777 -365.264704) (xy 214.341903 -365.210267) (xy 214.361826 -365.158176)
			(xy 214.389122 -365.109541) (xy 214.423208 -365.065398) (xy 214.463357 -365.026689) (xy 214.508715 -364.994238)
			(xy 214.558315 -364.968737) (xy 214.611099 -364.95073) (xy 214.665942 -364.9406) (xy 214.721676 -364.938563)
			(xy 214.777113 -364.944663) (xy 214.83107 -364.958769) (xy 214.882399 -364.980581) (xy 214.930005 -365.009635)
			(xy 214.972873 -365.04531) (xy 215.01009 -365.086847) (xy 215.040863 -365.13336) (xy 215.064535 -365.183857)
			(xy 215.080603 -365.237264) (xy 215.088723 -365.29244) (xy 215.089232 -365.320326) (xy 215.088723 -365.348212)
			(xy 215.080603 -365.403388) (xy 215.064535 -365.456795) (xy 215.040863 -365.507292) (xy 215.01009 -365.553805)
			(xy 214.972873 -365.595342) (xy 214.930005 -365.631017) (xy 214.882399 -365.660071) (xy 214.83107 -365.681883)
			(xy 214.777113 -365.695989) (xy 214.721676 -365.702089) (xy 214.665942 -365.700052) (xy 214.611099 -365.689922)
			(xy 214.558315 -365.671915) (xy 214.508715 -365.646414) (xy 214.463357 -365.613963) (xy 214.423208 -365.575254)
			(xy 214.389122 -365.531111) (xy 214.361826 -365.482476) (xy 214.341903 -365.430385) (xy 214.329777 -365.375948)
			(xy 214.325706 -365.320326) (xy 201.867805 -365.320326) (xy 201.833257 -365.349077) (xy 201.785651 -365.378131)
			(xy 201.734322 -365.399943) (xy 201.680365 -365.414049) (xy 201.624928 -365.420149) (xy 201.569194 -365.418112)
			(xy 201.514351 -365.407982) (xy 201.461567 -365.389975) (xy 201.411967 -365.364474) (xy 201.366609 -365.332023)
			(xy 201.32646 -365.293314) (xy 201.292374 -365.249171) (xy 201.265078 -365.200536) (xy 201.245155 -365.148445)
			(xy 201.233029 -365.094008) (xy 201.228958 -365.038386) (xy 195.654486 -365.038386) (xy 195.661027 -365.05271)
			(xy 195.676381 -365.105003) (xy 195.684136 -365.15895) (xy 195.684136 -365.21345) (xy 195.676381 -365.267397)
			(xy 195.661027 -365.31969) (xy 195.638388 -365.369266) (xy 195.608924 -365.415117) (xy 195.573236 -365.456307)
			(xy 195.532049 -365.492) (xy 195.486202 -365.521469) (xy 195.436628 -365.544113) (xy 195.384336 -365.559472)
			(xy 195.33039 -365.567233) (xy 195.30314 -365.567722) (xy 195.276276 -365.567226) (xy 195.223077 -365.559693)
			(xy 195.171463 -365.544769) (xy 195.122453 -365.522751) (xy 195.077017 -365.494074) (xy 195.036054 -365.459306)
			(xy 195.000375 -365.419134) (xy 194.970686 -365.374353) (xy 194.958716 -365.350298) (xy 194.951897 -365.337311)
			(xy 194.932271 -365.315537) (xy 194.907268 -365.300233) (xy 194.878948 -365.292662) (xy 194.849644 -365.293446)
			(xy 194.82177 -365.302521) (xy 194.797621 -365.319139) (xy 194.788028 -365.330232) (xy 194.769799 -365.351979)
			(xy 194.72803 -365.390387) (xy 194.681032 -365.422182) (xy 194.629842 -365.446663) (xy 194.57559 -365.463291)
			(xy 194.519473 -365.471698) (xy 194.491102 -365.472218) (xy 194.46385 -365.471735) (xy 194.4099 -365.463978)
			(xy 194.357603 -365.448623) (xy 194.308024 -365.425981) (xy 194.262172 -365.396514) (xy 194.22098 -365.360821)
			(xy 194.185287 -365.31963) (xy 194.15582 -365.273778) (xy 194.133178 -365.224199) (xy 194.117822 -365.171902)
			(xy 194.110065 -365.117952) (xy 185.023252 -365.117952) (xy 185.023252 -365.830104) (xy 192.759074 -365.830104)
			(xy 192.763145 -365.774482) (xy 192.775271 -365.720045) (xy 192.795194 -365.667954) (xy 192.82249 -365.619319)
			(xy 192.856576 -365.575176) (xy 192.896725 -365.536467) (xy 192.942083 -365.504016) (xy 192.991683 -365.478515)
			(xy 193.044467 -365.460508) (xy 193.09931 -365.450378) (xy 193.155044 -365.448341) (xy 193.210481 -365.454441)
			(xy 193.264438 -365.468547) (xy 193.315767 -365.490359) (xy 193.363373 -365.519413) (xy 193.406241 -365.555088)
			(xy 193.443458 -365.596625) (xy 193.474231 -365.643138) (xy 193.497903 -365.693635) (xy 193.513971 -365.747042)
			(xy 193.522091 -365.802218) (xy 193.5226 -365.830104) (xy 193.522091 -365.85799) (xy 193.513971 -365.913166)
			(xy 193.497903 -365.966573) (xy 193.474231 -366.01707) (xy 193.443458 -366.063583) (xy 193.406241 -366.10512)
			(xy 193.363373 -366.140795) (xy 193.315767 -366.169849) (xy 193.264438 -366.191661) (xy 193.210481 -366.205767)
			(xy 193.155044 -366.211867) (xy 193.09931 -366.20983) (xy 193.044467 -366.1997) (xy 192.991683 -366.181693)
			(xy 192.942083 -366.156192) (xy 192.896725 -366.123741) (xy 192.856576 -366.085032) (xy 192.82249 -366.040889)
			(xy 192.795194 -365.992254) (xy 192.775271 -365.940163) (xy 192.763145 -365.885726) (xy 192.759074 -365.830104)
			(xy 185.023252 -365.830104) (xy 185.023252 -366.655096) (xy 191.396872 -366.655096) (xy 191.400943 -366.599474)
			(xy 191.413069 -366.545037) (xy 191.432992 -366.492946) (xy 191.460288 -366.444311) (xy 191.494374 -366.400168)
			(xy 191.534523 -366.361459) (xy 191.579881 -366.329008) (xy 191.629481 -366.303507) (xy 191.682265 -366.2855)
			(xy 191.737108 -366.27537) (xy 191.792842 -366.273333) (xy 191.848279 -366.279433) (xy 191.902236 -366.293539)
			(xy 191.953565 -366.315351) (xy 191.988349 -366.33658) (xy 197.005448 -366.33658) (xy 197.005908 -366.31057)
			(xy 197.012979 -366.259032) (xy 197.026987 -366.208932) (xy 197.047672 -366.161201) (xy 197.07465 -366.116722)
			(xy 197.107422 -366.076322) (xy 197.145379 -366.040749) (xy 197.187817 -366.010663) (xy 197.21068 -365.998252)
			(xy 197.220288 -365.992609) (xy 197.233842 -365.974949) (xy 197.236842 -365.964216) (xy 197.256146 -365.877348)
			(xy 197.25132 -365.855758) (xy 197.244462 -365.846614) (xy 197.226193 -365.821546) (xy 197.197163 -365.766734)
			(xy 197.177374 -365.70795) (xy 197.167345 -365.646741) (xy 197.166738 -365.615728) (xy 197.167224 -365.588477)
			(xy 197.17498 -365.534529) (xy 197.190335 -365.482234) (xy 197.212977 -365.432657) (xy 197.242443 -365.386807)
			(xy 197.278134 -365.345616) (xy 197.319325 -365.309925) (xy 197.365175 -365.280459) (xy 197.414752 -365.257817)
			(xy 197.467047 -365.242462) (xy 197.520995 -365.234706) (xy 197.575497 -365.234706) (xy 197.629445 -365.242462)
			(xy 197.68174 -365.257817) (xy 197.731317 -365.280459) (xy 197.777167 -365.309925) (xy 197.818358 -365.345616)
			(xy 197.854049 -365.386807) (xy 197.883515 -365.432657) (xy 197.906157 -365.482234) (xy 197.921512 -365.534529)
			(xy 197.929268 -365.588477) (xy 197.929754 -365.615728) (xy 197.929299 -365.641739) (xy 197.922228 -365.693277)
			(xy 197.908219 -365.743376) (xy 197.887533 -365.791108) (xy 197.860554 -365.835586) (xy 197.827781 -365.875986)
			(xy 197.789824 -365.911559) (xy 197.747385 -365.941645) (xy 197.724522 -365.954056) (xy 197.714943 -365.959739)
			(xy 197.701375 -365.977371) (xy 197.69836 -365.988092) (xy 197.679056 -366.07496) (xy 197.683882 -366.09655)
			(xy 197.69074 -366.105694) (xy 197.709013 -366.130759) (xy 197.738042 -366.185573) (xy 197.75783 -366.244357)
			(xy 197.767858 -366.305567) (xy 197.768464 -366.33658) (xy 197.767978 -366.363831) (xy 197.760222 -366.417779)
			(xy 197.744867 -366.470074) (xy 197.737846 -366.485447) (xy 199.693324 -366.485447) (xy 199.693324 -366.430953)
			(xy 199.701079 -366.377014) (xy 199.716431 -366.324728) (xy 199.739068 -366.275158) (xy 199.768528 -366.229314)
			(xy 199.804213 -366.18813) (xy 199.845395 -366.152443) (xy 199.891237 -366.122979) (xy 199.940805 -366.100339)
			(xy 199.993091 -366.084984) (xy 200.047029 -366.077226) (xy 200.074276 -366.076738) (xy 200.099405 -366.077117)
			(xy 200.149228 -366.083724) (xy 200.197752 -366.096816) (xy 200.244138 -366.116164) (xy 200.287582 -366.141433)
			(xy 200.307702 -366.156494) (xy 200.315104 -366.161755) (xy 200.33243 -366.16715) (xy 200.350549 -366.166143)
			(xy 200.35901 -366.162844) (xy 200.44029 -366.127538) (xy 200.444018 -366.125815) (xy 200.450907 -366.121343)
			(xy 200.454006 -366.118648) (xy 200.458832 -366.114076) (xy 200.470008 -366.098074) (xy 200.471278 -366.084358)
			(xy 200.471278 -366.084104) (xy 200.474076 -366.055823) (xy 200.487088 -366.000502) (xy 200.50816 -365.947722)
			(xy 200.536828 -365.898652) (xy 200.572457 -365.854376) (xy 200.614259 -365.815875) (xy 200.66131 -365.784)
			(xy 200.712567 -365.759457) (xy 200.766898 -365.742787) (xy 200.823101 -365.73436) (xy 200.851516 -365.733838)
			(xy 200.880176 -365.734359) (xy 200.93685 -365.742944) (xy 200.991605 -365.759903) (xy 201.04321 -365.784856)
			(xy 201.090505 -365.817241) (xy 201.132428 -365.856332) (xy 201.168038 -365.901249) (xy 201.182732 -365.925862)
			(xy 201.189336 -365.937546) (xy 201.211942 -365.951008) (xy 201.31151 -365.954056) (xy 201.320204 -365.953965)
			(xy 201.336764 -365.948719) (xy 201.350627 -365.938251) (xy 201.355706 -365.931196) (xy 201.370883 -365.908897)
			(xy 201.406561 -365.86844) (xy 201.447584 -365.833414) (xy 201.493133 -365.804518) (xy 201.542299 -365.782329)
			(xy 201.594101 -365.76729) (xy 201.647505 -365.759699) (xy 201.674476 -365.759238) (xy 201.701733 -365.759607)
			(xy 201.755693 -365.767362) (xy 201.808 -365.782718) (xy 201.85759 -365.805362) (xy 201.903451 -365.834833)
			(xy 201.944652 -365.870531) (xy 201.980352 -365.911729) (xy 202.006902 -365.95304) (xy 202.97216 -365.95304)
			(xy 202.976231 -365.897418) (xy 202.988357 -365.842981) (xy 203.00828 -365.79089) (xy 203.035576 -365.742255)
			(xy 203.069662 -365.698112) (xy 203.109811 -365.659403) (xy 203.155169 -365.626952) (xy 203.204769 -365.601451)
			(xy 203.257553 -365.583444) (xy 203.312396 -365.573314) (xy 203.36813 -365.571277) (xy 203.423567 -365.577377)
			(xy 203.477524 -365.591483) (xy 203.528853 -365.613295) (xy 203.576459 -365.642349) (xy 203.619327 -365.678024)
			(xy 203.656544 -365.719561) (xy 203.687317 -365.766074) (xy 203.710989 -365.816571) (xy 203.727057 -365.869978)
			(xy 203.735177 -365.925154) (xy 203.735686 -365.95304) (xy 203.735177 -365.980926) (xy 203.727057 -366.036102)
			(xy 203.710989 -366.089509) (xy 203.687317 -366.140006) (xy 203.656544 -366.186519) (xy 203.619327 -366.228056)
			(xy 203.576459 -366.263731) (xy 203.528853 -366.292785) (xy 203.477524 -366.314597) (xy 203.423567 -366.328703)
			(xy 203.36813 -366.334803) (xy 203.312396 -366.332766) (xy 203.257553 -366.322636) (xy 203.204769 -366.304629)
			(xy 203.155169 -366.279128) (xy 203.109811 -366.246677) (xy 203.069662 -366.207968) (xy 203.035576 -366.163825)
			(xy 203.00828 -366.11519) (xy 202.988357 -366.063099) (xy 202.976231 -366.008662) (xy 202.97216 -365.95304)
			(xy 202.006902 -365.95304) (xy 202.009826 -365.957589) (xy 202.032473 -366.007177) (xy 202.047832 -366.059483)
			(xy 202.055591 -366.113443) (xy 202.055591 -366.167957) (xy 202.047832 -366.221917) (xy 202.032473 -366.274223)
			(xy 202.009826 -366.323811) (xy 201.980352 -366.369671) (xy 201.944652 -366.410869) (xy 201.903451 -366.446567)
			(xy 201.85759 -366.476038) (xy 201.808 -366.498682) (xy 201.755693 -366.514038) (xy 201.701733 -366.521793)
			(xy 201.674476 -366.522254) (xy 201.645815 -366.521743) (xy 201.58914 -366.513157) (xy 201.534386 -366.496196)
			(xy 201.482781 -366.471242) (xy 201.435486 -366.438855) (xy 201.393562 -366.399763) (xy 201.357953 -366.354843)
			(xy 201.34326 -366.33023) (xy 201.336656 -366.318546) (xy 201.31405 -366.305084) (xy 201.214482 -366.302036)
			(xy 201.205788 -366.302124) (xy 201.189228 -366.307373) (xy 201.175365 -366.317841) (xy 201.170286 -366.324896)
			(xy 201.155046 -366.347151) (xy 201.119379 -366.387609) (xy 201.078368 -366.422638) (xy 201.032829 -366.451539)
			(xy 200.983673 -366.473736) (xy 200.93188 -366.488785) (xy 200.878484 -366.496386) (xy 200.851516 -366.496854)
			(xy 200.826386 -366.496481) (xy 200.776563 -366.489872) (xy 200.728039 -366.47678) (xy 200.681654 -366.457431)
			(xy 200.63821 -366.432159) (xy 200.61809 -366.417098) (xy 200.610692 -366.411831) (xy 200.593363 -366.406438)
			(xy 200.575243 -366.407448) (xy 200.566782 -366.410748) (xy 200.477882 -366.449356) (xy 200.471278 -366.455452)
			(xy 200.463404 -366.464342) (xy 200.455784 -366.475518) (xy 200.454514 -366.489234) (xy 200.454514 -366.489488)
			(xy 200.451717 -366.517769) (xy 200.438706 -366.573091) (xy 200.417634 -366.625871) (xy 200.388966 -366.674942)
			(xy 200.353337 -366.719218) (xy 200.311535 -366.757719) (xy 200.264484 -366.789594) (xy 200.213226 -366.814138)
			(xy 200.158895 -366.830807) (xy 200.102692 -366.839233) (xy 200.074276 -366.839754) (xy 200.047029 -366.839174)
			(xy 199.993091 -366.831416) (xy 199.940805 -366.816061) (xy 199.891237 -366.793421) (xy 199.845395 -366.763957)
			(xy 199.804213 -366.72827) (xy 199.768528 -366.687086) (xy 199.739068 -366.641242) (xy 199.716431 -366.591672)
			(xy 199.701079 -366.539386) (xy 199.693324 -366.485447) (xy 197.737846 -366.485447) (xy 197.722225 -366.519651)
			(xy 197.692759 -366.565501) (xy 197.657068 -366.606692) (xy 197.615877 -366.642383) (xy 197.570027 -366.671849)
			(xy 197.52045 -366.694491) (xy 197.468155 -366.709846) (xy 197.414207 -366.717602) (xy 197.359705 -366.717602)
			(xy 197.305757 -366.709846) (xy 197.253462 -366.694491) (xy 197.203885 -366.671849) (xy 197.158035 -366.642383)
			(xy 197.116844 -366.606692) (xy 197.081153 -366.565501) (xy 197.051687 -366.519651) (xy 197.029045 -366.470074)
			(xy 197.01369 -366.417779) (xy 197.005934 -366.363831) (xy 197.005448 -366.33658) (xy 191.988349 -366.33658)
			(xy 192.001171 -366.344405) (xy 192.044039 -366.38008) (xy 192.081256 -366.421617) (xy 192.112029 -366.46813)
			(xy 192.135701 -366.518627) (xy 192.151769 -366.572034) (xy 192.159889 -366.62721) (xy 192.160398 -366.655096)
			(xy 192.159889 -366.682982) (xy 192.151769 -366.738158) (xy 192.135701 -366.791565) (xy 192.112029 -366.842062)
			(xy 192.081256 -366.888575) (xy 192.044039 -366.930112) (xy 192.001171 -366.965787) (xy 191.953565 -366.994841)
			(xy 191.902236 -367.016653) (xy 191.848279 -367.030759) (xy 191.792842 -367.036859) (xy 191.737108 -367.034822)
			(xy 191.682265 -367.024692) (xy 191.629481 -367.006685) (xy 191.579881 -366.981184) (xy 191.534523 -366.948733)
			(xy 191.494374 -366.910024) (xy 191.460288 -366.865881) (xy 191.432992 -366.817246) (xy 191.413069 -366.765155)
			(xy 191.400943 -366.710718) (xy 191.396872 -366.655096) (xy 185.023252 -366.655096) (xy 185.023252 -367.216182)
			(xy 188.252352 -367.216182) (xy 188.256423 -367.16056) (xy 188.268549 -367.106123) (xy 188.288472 -367.054032)
			(xy 188.315768 -367.005397) (xy 188.349854 -366.961254) (xy 188.390003 -366.922545) (xy 188.435361 -366.890094)
			(xy 188.484961 -366.864593) (xy 188.537745 -366.846586) (xy 188.592588 -366.836456) (xy 188.648322 -366.834419)
			(xy 188.703759 -366.840519) (xy 188.757716 -366.854625) (xy 188.809045 -366.876437) (xy 188.856651 -366.905491)
			(xy 188.899519 -366.941166) (xy 188.936736 -366.982703) (xy 188.967509 -367.029216) (xy 188.991181 -367.079713)
			(xy 189.007249 -367.13312) (xy 189.015369 -367.188296) (xy 189.015878 -367.216182) (xy 189.015369 -367.244068)
			(xy 189.007249 -367.299244) (xy 188.993724 -367.344198) (xy 197.042022 -367.344198) (xy 197.046093 -367.288576)
			(xy 197.058219 -367.234139) (xy 197.078142 -367.182048) (xy 197.105438 -367.133413) (xy 197.139524 -367.08927)
			(xy 197.179673 -367.050561) (xy 197.225031 -367.01811) (xy 197.274631 -366.992609) (xy 197.327415 -366.974602)
			(xy 197.382258 -366.964472) (xy 197.437992 -366.962435) (xy 197.493429 -366.968535) (xy 197.547386 -366.982641)
			(xy 197.598715 -367.004453) (xy 197.646321 -367.033507) (xy 197.689189 -367.069182) (xy 197.726406 -367.110719)
			(xy 197.757179 -367.157232) (xy 197.780851 -367.207729) (xy 197.796919 -367.261136) (xy 197.805039 -367.316312)
			(xy 197.805548 -367.344198) (xy 197.805039 -367.372084) (xy 197.796919 -367.42726) (xy 197.780851 -367.480667)
			(xy 197.757179 -367.531164) (xy 197.726406 -367.577677) (xy 197.689189 -367.619214) (xy 197.646321 -367.654889)
			(xy 197.598715 -367.683943) (xy 197.547386 -367.705755) (xy 197.493429 -367.719861) (xy 197.437992 -367.725961)
			(xy 197.382258 -367.723924) (xy 197.327415 -367.713794) (xy 197.274631 -367.695787) (xy 197.225031 -367.670286)
			(xy 197.179673 -367.637835) (xy 197.139524 -367.599126) (xy 197.105438 -367.554983) (xy 197.078142 -367.506348)
			(xy 197.058219 -367.454257) (xy 197.046093 -367.39982) (xy 197.042022 -367.344198) (xy 188.993724 -367.344198)
			(xy 188.991181 -367.352651) (xy 188.967509 -367.403148) (xy 188.936736 -367.449661) (xy 188.899519 -367.491198)
			(xy 188.856651 -367.526873) (xy 188.809045 -367.555927) (xy 188.757716 -367.577739) (xy 188.703759 -367.591845)
			(xy 188.648322 -367.597945) (xy 188.592588 -367.595908) (xy 188.537745 -367.585778) (xy 188.484961 -367.567771)
			(xy 188.435361 -367.54227) (xy 188.390003 -367.509819) (xy 188.349854 -367.47111) (xy 188.315768 -367.426967)
			(xy 188.288472 -367.378332) (xy 188.268549 -367.326241) (xy 188.256423 -367.271804) (xy 188.252352 -367.216182)
			(xy 185.023252 -367.216182) (xy 185.023252 -367.76533) (xy 200.369676 -367.76533) (xy 200.373747 -367.709708)
			(xy 200.385873 -367.655271) (xy 200.405796 -367.60318) (xy 200.433092 -367.554545) (xy 200.467178 -367.510402)
			(xy 200.507327 -367.471693) (xy 200.552685 -367.439242) (xy 200.602285 -367.413741) (xy 200.655069 -367.395734)
			(xy 200.709912 -367.385604) (xy 200.765646 -367.383567) (xy 200.821083 -367.389667) (xy 200.87504 -367.403773)
			(xy 200.926369 -367.425585) (xy 200.973975 -367.454639) (xy 201.016843 -367.490314) (xy 201.05406 -367.531851)
			(xy 201.084833 -367.578364) (xy 201.108505 -367.628861) (xy 201.124573 -367.682268) (xy 201.132693 -367.737444)
			(xy 201.133202 -367.76533) (xy 201.132693 -367.793216) (xy 201.124573 -367.848392) (xy 201.108505 -367.901799)
			(xy 201.084833 -367.952296) (xy 201.05406 -367.998809) (xy 201.016843 -368.040346) (xy 200.973975 -368.076021)
			(xy 200.926369 -368.105075) (xy 200.87504 -368.126887) (xy 200.821083 -368.140993) (xy 200.765646 -368.147093)
			(xy 200.709912 -368.145056) (xy 200.655069 -368.134926) (xy 200.602285 -368.116919) (xy 200.552685 -368.091418)
			(xy 200.507327 -368.058967) (xy 200.467178 -368.020258) (xy 200.433092 -367.976115) (xy 200.405796 -367.92748)
			(xy 200.385873 -367.875389) (xy 200.373747 -367.820952) (xy 200.369676 -367.76533) (xy 185.023252 -367.76533)
			(xy 185.023252 -369.139724) (xy 194.89623 -369.139724) (xy 194.900301 -369.084102) (xy 194.912427 -369.029665)
			(xy 194.93235 -368.977574) (xy 194.959646 -368.928939) (xy 194.993732 -368.884796) (xy 195.033881 -368.846087)
			(xy 195.079239 -368.813636) (xy 195.128839 -368.788135) (xy 195.181623 -368.770128) (xy 195.236466 -368.759998)
			(xy 195.2922 -368.757961) (xy 195.347637 -368.764061) (xy 195.401594 -368.778167) (xy 195.452923 -368.799979)
			(xy 195.500529 -368.829033) (xy 195.543397 -368.864708) (xy 195.580614 -368.906245) (xy 195.611387 -368.952758)
			(xy 195.635059 -369.003255) (xy 195.651127 -369.056662) (xy 195.659247 -369.111838) (xy 195.659756 -369.139724)
			(xy 195.659247 -369.16761) (xy 195.651127 -369.222786) (xy 195.635059 -369.276193) (xy 195.611387 -369.32669)
			(xy 195.580614 -369.373203) (xy 195.543397 -369.41474) (xy 195.500529 -369.450415) (xy 195.452923 -369.479469)
			(xy 195.401594 -369.501281) (xy 195.347637 -369.515387) (xy 195.2922 -369.521487) (xy 195.236466 -369.51945)
			(xy 195.181623 -369.50932) (xy 195.128839 -369.491313) (xy 195.079239 -369.465812) (xy 195.033881 -369.433361)
			(xy 194.993732 -369.394652) (xy 194.959646 -369.350509) (xy 194.93235 -369.301874) (xy 194.912427 -369.249783)
			(xy 194.900301 -369.195346) (xy 194.89623 -369.139724) (xy 185.023252 -369.139724) (xy 185.023252 -369.609624)
			(xy 197.338694 -369.609624) (xy 197.342765 -369.554002) (xy 197.354891 -369.499565) (xy 197.374814 -369.447474)
			(xy 197.40211 -369.398839) (xy 197.436196 -369.354696) (xy 197.476345 -369.315987) (xy 197.521703 -369.283536)
			(xy 197.571303 -369.258035) (xy 197.624087 -369.240028) (xy 197.67893 -369.229898) (xy 197.734664 -369.227861)
			(xy 197.790101 -369.233961) (xy 197.844058 -369.248067) (xy 197.895387 -369.269879) (xy 197.942993 -369.298933)
			(xy 197.985861 -369.334608) (xy 198.023078 -369.376145) (xy 198.053851 -369.422658) (xy 198.077523 -369.473155)
			(xy 198.093591 -369.526562) (xy 198.101711 -369.581738) (xy 198.10222 -369.609624) (xy 198.101711 -369.63751)
			(xy 198.093591 -369.692686) (xy 198.077523 -369.746093) (xy 198.053851 -369.79659) (xy 198.023078 -369.843103)
			(xy 197.985861 -369.88464) (xy 197.942993 -369.920315) (xy 197.895387 -369.949369) (xy 197.844058 -369.971181)
			(xy 197.790101 -369.985287) (xy 197.734664 -369.991387) (xy 197.67893 -369.98935) (xy 197.624087 -369.97922)
			(xy 197.571303 -369.961213) (xy 197.521703 -369.935712) (xy 197.476345 -369.903261) (xy 197.436196 -369.864552)
			(xy 197.40211 -369.820409) (xy 197.374814 -369.771774) (xy 197.354891 -369.719683) (xy 197.342765 -369.665246)
			(xy 197.338694 -369.609624) (xy 185.023252 -369.609624) (xy 185.023252 -370.529358) (xy 189.975488 -370.529358)
			(xy 189.979559 -370.473736) (xy 189.991685 -370.419299) (xy 190.011608 -370.367208) (xy 190.038904 -370.318573)
			(xy 190.07299 -370.27443) (xy 190.113139 -370.235721) (xy 190.158497 -370.20327) (xy 190.208097 -370.177769)
			(xy 190.260881 -370.159762) (xy 190.315724 -370.149632) (xy 190.371458 -370.147595) (xy 190.426895 -370.153695)
			(xy 190.480852 -370.167801) (xy 190.532181 -370.189613) (xy 190.579787 -370.218667) (xy 190.622655 -370.254342)
			(xy 190.659872 -370.295879) (xy 190.690645 -370.342392) (xy 190.714317 -370.392889) (xy 190.730385 -370.446296)
			(xy 190.738505 -370.501472) (xy 190.739014 -370.529358) (xy 190.738505 -370.557244) (xy 190.730385 -370.61242)
			(xy 190.714317 -370.665827) (xy 190.690645 -370.716324) (xy 190.659872 -370.762837) (xy 190.622655 -370.804374)
			(xy 190.579787 -370.840049) (xy 190.534919 -370.867432) (xy 198.657208 -370.867432) (xy 198.661281 -370.811773)
			(xy 198.673416 -370.7573) (xy 198.693352 -370.705174) (xy 198.720666 -370.656506) (xy 198.754774 -370.612334)
			(xy 198.794951 -370.573599) (xy 198.840339 -370.541127) (xy 198.889971 -370.515609) (xy 198.942791 -370.49759)
			(xy 198.99767 -370.487453) (xy 199.053441 -370.485415) (xy 199.108915 -370.491518) (xy 199.162908 -370.505634)
			(xy 199.214271 -370.527461) (xy 199.261909 -370.556534) (xy 199.304805 -370.592233) (xy 199.342047 -370.633797)
			(xy 199.372841 -370.680341) (xy 199.396529 -370.730872) (xy 199.412607 -370.784314) (xy 199.420733 -370.839528)
			(xy 199.421242 -370.867432) (xy 199.420733 -370.895336) (xy 199.412607 -370.95055) (xy 199.405136 -370.975382)
			(xy 199.52538 -370.975382) (xy 199.529453 -370.919723) (xy 199.541588 -370.86525) (xy 199.561524 -370.813124)
			(xy 199.588838 -370.764456) (xy 199.622946 -370.720284) (xy 199.663123 -370.681549) (xy 199.708511 -370.649077)
			(xy 199.758143 -370.623559) (xy 199.810963 -370.60554) (xy 199.865842 -370.595403) (xy 199.921613 -370.593365)
			(xy 199.977087 -370.599468) (xy 200.03108 -370.613584) (xy 200.082443 -370.635411) (xy 200.130081 -370.664484)
			(xy 200.172977 -370.700183) (xy 200.210219 -370.741747) (xy 200.241013 -370.788291) (xy 200.264701 -370.838822)
			(xy 200.280779 -370.892264) (xy 200.288905 -370.947478) (xy 200.289414 -370.975382) (xy 200.288905 -371.003286)
			(xy 200.280779 -371.0585) (xy 200.264701 -371.111942) (xy 200.241013 -371.162473) (xy 200.210219 -371.209017)
			(xy 200.172977 -371.250581) (xy 200.130081 -371.28628) (xy 200.082443 -371.315353) (xy 200.03108 -371.33718)
			(xy 199.977087 -371.351296) (xy 199.921613 -371.357399) (xy 199.865842 -371.355361) (xy 199.810963 -371.345224)
			(xy 199.758143 -371.327205) (xy 199.708511 -371.301687) (xy 199.663123 -371.269215) (xy 199.622946 -371.23048)
			(xy 199.588838 -371.186308) (xy 199.561524 -371.13764) (xy 199.541588 -371.085514) (xy 199.529453 -371.031041)
			(xy 199.52538 -370.975382) (xy 199.405136 -370.975382) (xy 199.396529 -371.003992) (xy 199.372841 -371.054523)
			(xy 199.342047 -371.101067) (xy 199.304805 -371.142631) (xy 199.261909 -371.17833) (xy 199.214271 -371.207403)
			(xy 199.162908 -371.22923) (xy 199.108915 -371.243346) (xy 199.053441 -371.249449) (xy 198.99767 -371.247411)
			(xy 198.942791 -371.237274) (xy 198.889971 -371.219255) (xy 198.840339 -371.193737) (xy 198.794951 -371.161265)
			(xy 198.754774 -371.12253) (xy 198.720666 -371.078358) (xy 198.693352 -371.02969) (xy 198.673416 -370.977564)
			(xy 198.661281 -370.923091) (xy 198.657208 -370.867432) (xy 190.534919 -370.867432) (xy 190.532181 -370.869103)
			(xy 190.480852 -370.890915) (xy 190.426895 -370.905021) (xy 190.371458 -370.911121) (xy 190.315724 -370.909084)
			(xy 190.260881 -370.898954) (xy 190.208097 -370.880947) (xy 190.158497 -370.855446) (xy 190.113139 -370.822995)
			(xy 190.07299 -370.784286) (xy 190.038904 -370.740143) (xy 190.011608 -370.691508) (xy 189.991685 -370.639417)
			(xy 189.979559 -370.58498) (xy 189.975488 -370.529358) (xy 185.023252 -370.529358) (xy 185.023252 -371.718586)
			(xy 200.352912 -371.718586) (xy 200.356985 -371.662927) (xy 200.36912 -371.608454) (xy 200.389056 -371.556328)
			(xy 200.41637 -371.50766) (xy 200.450478 -371.463488) (xy 200.490655 -371.424753) (xy 200.536043 -371.392281)
			(xy 200.585675 -371.366763) (xy 200.638495 -371.348744) (xy 200.693374 -371.338607) (xy 200.749145 -371.336569)
			(xy 200.804619 -371.342672) (xy 200.858612 -371.356788) (xy 200.909975 -371.378615) (xy 200.957613 -371.407688)
			(xy 201.000509 -371.443387) (xy 201.037751 -371.484951) (xy 201.068545 -371.531495) (xy 201.092233 -371.582026)
			(xy 201.108311 -371.635468) (xy 201.116437 -371.690682) (xy 201.116946 -371.718586) (xy 201.116437 -371.74649)
			(xy 201.108311 -371.801704) (xy 201.092233 -371.855146) (xy 201.068545 -371.905677) (xy 201.037751 -371.952221)
			(xy 201.000509 -371.993785) (xy 200.957613 -372.029484) (xy 200.909975 -372.058557) (xy 200.858612 -372.080384)
			(xy 200.804619 -372.0945) (xy 200.749145 -372.100603) (xy 200.693374 -372.098565) (xy 200.638495 -372.088428)
			(xy 200.585675 -372.070409) (xy 200.536043 -372.044891) (xy 200.490655 -372.012419) (xy 200.450478 -371.973684)
			(xy 200.41637 -371.929512) (xy 200.389056 -371.880844) (xy 200.36912 -371.828718) (xy 200.356985 -371.774245)
			(xy 200.352912 -371.718586) (xy 185.023252 -371.718586) (xy 185.023252 -372.890034) (xy 201.22337 -372.890034)
			(xy 201.227443 -372.834375) (xy 201.239578 -372.779902) (xy 201.259514 -372.727776) (xy 201.286828 -372.679108)
			(xy 201.320936 -372.634936) (xy 201.361113 -372.596201) (xy 201.406501 -372.563729) (xy 201.456133 -372.538211)
			(xy 201.508953 -372.520192) (xy 201.563832 -372.510055) (xy 201.619603 -372.508017) (xy 201.675077 -372.51412)
			(xy 201.72907 -372.528236) (xy 201.780433 -372.550063) (xy 201.828071 -372.579136) (xy 201.870967 -372.614835)
			(xy 201.908209 -372.656399) (xy 201.939003 -372.702943) (xy 201.962691 -372.753474) (xy 201.978769 -372.806916)
			(xy 201.983974 -372.842282) (xy 202.07732 -372.842282) (xy 202.077806 -372.815013) (xy 202.085568 -372.761029)
			(xy 202.100933 -372.708699) (xy 202.12359 -372.659089) (xy 202.153076 -372.613208) (xy 202.188791 -372.571991)
			(xy 202.230008 -372.536276) (xy 202.275889 -372.50679) (xy 202.325499 -372.484133) (xy 202.377829 -372.468768)
			(xy 202.431813 -372.461006) (xy 202.486351 -372.461006) (xy 202.540335 -372.468768) (xy 202.592665 -372.484133)
			(xy 202.642275 -372.50679) (xy 202.688156 -372.536276) (xy 202.729373 -372.571991) (xy 202.765088 -372.613208)
			(xy 202.794574 -372.659089) (xy 202.817231 -372.708699) (xy 202.832596 -372.761029) (xy 202.840358 -372.815013)
			(xy 202.840844 -372.842282) (xy 202.840338 -372.870015) (xy 202.832313 -372.924897) (xy 202.816431 -372.97804)
			(xy 202.793024 -373.028325) (xy 202.762586 -373.074693) (xy 202.725759 -373.116168) (xy 202.683316 -373.151876)
			(xy 202.659996 -373.166894) (xy 202.64849 -373.174561) (xy 202.629729 -373.194852) (xy 202.617105 -373.219436)
			(xy 202.611545 -373.246506) (xy 202.613457 -373.274075) (xy 202.622701 -373.300119) (xy 202.638597 -373.322724)
			(xy 202.65998 -373.340232) (xy 202.672442 -373.346218) (xy 202.697498 -373.357765) (xy 202.74426 -373.387041)
			(xy 202.78632 -373.422744) (xy 202.822801 -373.464132) (xy 202.852943 -373.51034) (xy 202.876118 -373.560406)
			(xy 202.891844 -373.613288) (xy 202.899791 -373.667883) (xy 202.90028 -373.695468) (xy 202.899794 -373.722719)
			(xy 202.892038 -373.776667) (xy 202.876683 -373.828962) (xy 202.854041 -373.878539) (xy 202.824575 -373.924389)
			(xy 202.788884 -373.96558) (xy 202.747693 -374.001271) (xy 202.701843 -374.030737) (xy 202.652266 -374.053379)
			(xy 202.599971 -374.068734) (xy 202.546023 -374.07649) (xy 202.491521 -374.07649) (xy 202.437573 -374.068734)
			(xy 202.385278 -374.053379) (xy 202.335701 -374.030737) (xy 202.289851 -374.001271) (xy 202.24866 -373.96558)
			(xy 202.212969 -373.924389) (xy 202.183503 -373.878539) (xy 202.160861 -373.828962) (xy 202.145506 -373.776667)
			(xy 202.13775 -373.722719) (xy 202.137264 -373.695468) (xy 202.137745 -373.66776) (xy 202.145753 -373.612927)
			(xy 202.161612 -373.55983) (xy 202.184987 -373.509587) (xy 202.215386 -373.463254) (xy 202.25217 -373.421808)
			(xy 202.294564 -373.386121) (xy 202.317858 -373.37111) (xy 202.329368 -373.363445) (xy 202.348138 -373.343156)
			(xy 202.360768 -373.318572) (xy 202.366332 -373.291498) (xy 202.36442 -373.263925) (xy 202.355173 -373.237878)
			(xy 202.339269 -373.215272) (xy 202.317878 -373.197769) (xy 202.305412 -373.191786) (xy 202.280314 -373.180268)
			(xy 202.2335 -373.150978) (xy 202.191393 -373.115251) (xy 202.154871 -373.073831) (xy 202.124696 -373.027583)
			(xy 202.101497 -372.977471) (xy 202.085758 -372.924539) (xy 202.077806 -372.869893) (xy 202.07732 -372.842282)
			(xy 201.983974 -372.842282) (xy 201.986895 -372.86213) (xy 201.987404 -372.890034) (xy 201.986895 -372.917938)
			(xy 201.978769 -372.973152) (xy 201.962691 -373.026594) (xy 201.939003 -373.077125) (xy 201.908209 -373.123669)
			(xy 201.870967 -373.165233) (xy 201.828071 -373.200932) (xy 201.780433 -373.230005) (xy 201.72907 -373.251832)
			(xy 201.675077 -373.265948) (xy 201.619603 -373.272051) (xy 201.563832 -373.270013) (xy 201.508953 -373.259876)
			(xy 201.456133 -373.241857) (xy 201.406501 -373.216339) (xy 201.361113 -373.183867) (xy 201.320936 -373.145132)
			(xy 201.286828 -373.10096) (xy 201.259514 -373.052292) (xy 201.239578 -373.000166) (xy 201.227443 -372.945693)
			(xy 201.22337 -372.890034) (xy 185.023252 -372.890034) (xy 185.023252 -378.70003) (xy 190.444636 -378.70003)
			(xy 190.448637 -378.494991) (xy 190.460635 -378.290263) (xy 190.480612 -378.08616) (xy 190.508537 -377.882992)
			(xy 190.544367 -377.681068) (xy 190.588049 -377.480695) (xy 190.639515 -377.28218) (xy 190.698687 -377.085823)
			(xy 190.765475 -376.891925) (xy 190.839777 -376.70078) (xy 190.92148 -376.51268) (xy 191.010461 -376.327911)
			(xy 191.106582 -376.146754) (xy 191.209698 -375.969485) (xy 191.319652 -375.796375) (xy 191.436277 -375.627686)
			(xy 191.559394 -375.463676) (xy 191.688817 -375.304594) (xy 191.824347 -375.150683) (xy 191.96578 -375.002177)
			(xy 192.112899 -374.859302) (xy 192.26548 -374.722277) (xy 192.423292 -374.591308) (xy 192.586093 -374.466597)
			(xy 192.753636 -374.348332) (xy 192.925665 -374.236694) (xy 193.10192 -374.131853) (xy 193.28213 -374.033969)
			(xy 193.466022 -373.94319) (xy 193.653317 -373.859656) (xy 193.843727 -373.783492) (xy 194.036965 -373.714815)
			(xy 194.232735 -373.65373) (xy 194.430739 -373.60033) (xy 194.630675 -373.554696) (xy 194.83224 -373.516897)
			(xy 195.035126 -373.486991) (xy 195.239025 -373.465024) (xy 195.443625 -373.451029) (xy 195.648616 -373.445028)
			(xy 195.853685 -373.447028) (xy 196.058519 -373.457029) (xy 196.262807 -373.475013) (xy 196.466239 -373.500955)
			(xy 196.668503 -373.534813) (xy 196.869292 -373.576538) (xy 197.0683 -373.626064) (xy 197.265224 -373.683318)
			(xy 197.459765 -373.748211) (xy 197.651626 -373.820645) (xy 197.840514 -373.900509) (xy 198.026143 -373.987683)
			(xy 198.208229 -374.082032) (xy 198.386495 -374.183414) (xy 198.56067 -374.291674) (xy 198.730489 -374.406647)
			(xy 198.895692 -374.528158) (xy 199.056029 -374.656022) (xy 199.211255 -374.790045) (xy 199.249777 -374.826022)
			(xy 202.643738 -374.826022) (xy 202.647809 -374.7704) (xy 202.659935 -374.715963) (xy 202.679858 -374.663872)
			(xy 202.707154 -374.615237) (xy 202.74124 -374.571094) (xy 202.781389 -374.532385) (xy 202.826747 -374.499934)
			(xy 202.876347 -374.474433) (xy 202.929131 -374.456426) (xy 202.983974 -374.446296) (xy 203.039708 -374.444259)
			(xy 203.095145 -374.450359) (xy 203.149102 -374.464465) (xy 203.200431 -374.486277) (xy 203.248037 -374.515331)
			(xy 203.290905 -374.551006) (xy 203.328122 -374.592543) (xy 203.358895 -374.639056) (xy 203.382567 -374.689553)
			(xy 203.398635 -374.74296) (xy 203.406755 -374.798136) (xy 203.407264 -374.826022) (xy 203.406755 -374.853908)
			(xy 203.398635 -374.909084) (xy 203.382567 -374.962491) (xy 203.358895 -375.012988) (xy 203.328122 -375.059501)
			(xy 203.290905 -375.101038) (xy 203.248037 -375.136713) (xy 203.200431 -375.165767) (xy 203.149102 -375.187579)
			(xy 203.095145 -375.201685) (xy 203.039708 -375.207785) (xy 202.983974 -375.205748) (xy 202.929131 -375.195618)
			(xy 202.876347 -375.177611) (xy 202.826747 -375.15211) (xy 202.781389 -375.119659) (xy 202.74124 -375.08095)
			(xy 202.707154 -375.036807) (xy 202.679858 -374.988172) (xy 202.659935 -374.936081) (xy 202.647809 -374.881644)
			(xy 202.643738 -374.826022) (xy 199.249777 -374.826022) (xy 199.361134 -374.930022) (xy 199.505437 -375.07574)
			(xy 199.643945 -375.226977) (xy 199.776447 -375.383504) (xy 199.902741 -375.54508) (xy 200.022634 -375.711461)
			(xy 200.135945 -375.882393) (xy 200.242501 -376.057616) (xy 200.342138 -376.236863) (xy 200.434707 -376.419861)
			(xy 200.520065 -376.606332) (xy 200.598083 -376.79599) (xy 200.668641 -376.988548) (xy 200.731633 -377.183713)
			(xy 200.786963 -377.381187) (xy 200.834546 -377.580669) (xy 200.874309 -377.781855) (xy 200.906193 -377.98444)
			(xy 200.930148 -378.188114) (xy 200.946139 -378.392568) (xy 200.95414 -378.597491) (xy 200.95464 -378.70003)
			(xy 200.95414 -378.802569) (xy 200.946139 -379.007492) (xy 200.930148 -379.211946) (xy 200.906193 -379.41562)
			(xy 200.874309 -379.618205) (xy 200.834546 -379.819391) (xy 200.786963 -380.018873) (xy 200.731633 -380.216347)
			(xy 200.668641 -380.411512) (xy 200.598083 -380.60407) (xy 200.520065 -380.793728) (xy 200.434707 -380.980199)
			(xy 200.342138 -381.163197) (xy 200.242501 -381.342444) (xy 200.135945 -381.517667) (xy 200.022634 -381.688599)
			(xy 199.902741 -381.85498) (xy 199.776447 -382.016556) (xy 199.643945 -382.173083) (xy 199.505437 -382.32432)
			(xy 199.361134 -382.470038) (xy 199.211255 -382.610015) (xy 199.056029 -382.744038) (xy 198.895692 -382.871902)
			(xy 198.730489 -382.993413) (xy 198.56067 -383.108386) (xy 198.386495 -383.216646) (xy 198.208229 -383.318028)
			(xy 198.026143 -383.412377) (xy 197.840514 -383.499551) (xy 197.651626 -383.579415) (xy 197.459765 -383.651849)
			(xy 197.265224 -383.716742) (xy 197.0683 -383.773996) (xy 196.869292 -383.823522) (xy 196.668503 -383.865247)
			(xy 196.466239 -383.899105) (xy 196.262807 -383.925047) (xy 196.058519 -383.943031) (xy 195.853685 -383.953032)
			(xy 195.648616 -383.955032) (xy 195.443625 -383.949031) (xy 195.239025 -383.935036) (xy 195.035126 -383.913069)
			(xy 194.83224 -383.883163) (xy 194.630675 -383.845364) (xy 194.430739 -383.79973) (xy 194.232735 -383.74633)
			(xy 194.036965 -383.685245) (xy 193.843727 -383.616568) (xy 193.653317 -383.540404) (xy 193.466022 -383.45687)
			(xy 193.28213 -383.366091) (xy 193.10192 -383.268207) (xy 192.925665 -383.163366) (xy 192.753636 -383.051728)
			(xy 192.586093 -382.933463) (xy 192.423292 -382.808752) (xy 192.26548 -382.677783) (xy 192.112899 -382.540758)
			(xy 191.96578 -382.397883) (xy 191.824347 -382.249377) (xy 191.688817 -382.095466) (xy 191.559394 -381.936384)
			(xy 191.436277 -381.772374) (xy 191.319652 -381.603685) (xy 191.209698 -381.430575) (xy 191.106582 -381.253306)
			(xy 191.010461 -381.072149) (xy 190.92148 -380.88738) (xy 190.839777 -380.69928) (xy 190.765475 -380.508135)
			(xy 190.698687 -380.314237) (xy 190.639515 -380.11788) (xy 190.588049 -379.919365) (xy 190.544367 -379.718992)
			(xy 190.508537 -379.517068) (xy 190.480612 -379.3139) (xy 190.460635 -379.109797) (xy 190.448637 -378.905069)
			(xy 190.444636 -378.70003) (xy 185.023252 -378.70003) (xy 185.023252 -387.124702) (xy 187.712602 -387.124702)
			(xy 187.716673 -387.06908) (xy 187.728799 -387.014643) (xy 187.748722 -386.962552) (xy 187.776018 -386.913917)
			(xy 187.810104 -386.869774) (xy 187.850253 -386.831065) (xy 187.895611 -386.798614) (xy 187.945211 -386.773113)
			(xy 187.997995 -386.755106) (xy 188.052838 -386.744976) (xy 188.108572 -386.742939) (xy 188.164009 -386.749039)
			(xy 188.217966 -386.763145) (xy 188.269295 -386.784957) (xy 188.316901 -386.814011) (xy 188.359769 -386.849686)
			(xy 188.396986 -386.891223) (xy 188.427759 -386.937736) (xy 188.451431 -386.988233) (xy 188.467499 -387.04164)
			(xy 188.475619 -387.096816) (xy 188.476128 -387.124702) (xy 188.475619 -387.152588) (xy 188.467499 -387.207764)
			(xy 188.451431 -387.261171) (xy 188.427759 -387.311668) (xy 188.396986 -387.358181) (xy 188.359769 -387.399718)
			(xy 188.316901 -387.435393) (xy 188.269295 -387.464447) (xy 188.217966 -387.486259) (xy 188.164009 -387.500365)
			(xy 188.108572 -387.506465) (xy 188.052838 -387.504428) (xy 187.997995 -387.494298) (xy 187.945211 -387.476291)
			(xy 187.895611 -387.45079) (xy 187.850253 -387.418339) (xy 187.810104 -387.37963) (xy 187.776018 -387.335487)
			(xy 187.748722 -387.286852) (xy 187.728799 -387.234761) (xy 187.716673 -387.180324) (xy 187.712602 -387.124702)
			(xy 185.023252 -387.124702) (xy 185.023252 -401.65909) (xy 190.407542 -401.65909) (xy 190.411613 -401.603468)
			(xy 190.423739 -401.549031) (xy 190.443662 -401.49694) (xy 190.470958 -401.448305) (xy 190.505044 -401.404162)
			(xy 190.545193 -401.365453) (xy 190.590551 -401.333002) (xy 190.640151 -401.307501) (xy 190.692935 -401.289494)
			(xy 190.747778 -401.279364) (xy 190.803512 -401.277327) (xy 190.858949 -401.283427) (xy 190.912906 -401.297533)
			(xy 190.964235 -401.319345) (xy 191.011841 -401.348399) (xy 191.054709 -401.384074) (xy 191.091926 -401.425611)
			(xy 191.122699 -401.472124) (xy 191.146371 -401.522621) (xy 191.162439 -401.576028) (xy 191.170559 -401.631204)
			(xy 191.171068 -401.65909) (xy 191.170559 -401.686976) (xy 191.162439 -401.742152) (xy 191.146371 -401.795559)
			(xy 191.122699 -401.846056) (xy 191.091926 -401.892569) (xy 191.054709 -401.934106) (xy 191.011841 -401.969781)
			(xy 190.964235 -401.998835) (xy 190.912906 -402.020647) (xy 190.858949 -402.034753) (xy 190.803512 -402.040853)
			(xy 190.747778 -402.038816) (xy 190.692935 -402.028686) (xy 190.640151 -402.010679) (xy 190.590551 -401.985178)
			(xy 190.545193 -401.952727) (xy 190.505044 -401.914018) (xy 190.470958 -401.869875) (xy 190.443662 -401.82124)
			(xy 190.423739 -401.769149) (xy 190.411613 -401.714712) (xy 190.407542 -401.65909) (xy 185.023252 -401.65909)
			(xy 185.023252 -402.263102) (xy 194.29171 -402.263102) (xy 194.295783 -402.207443) (xy 194.307918 -402.15297)
			(xy 194.327854 -402.100844) (xy 194.355168 -402.052176) (xy 194.389276 -402.008004) (xy 194.429453 -401.969269)
			(xy 194.474841 -401.936797) (xy 194.524473 -401.911279) (xy 194.577293 -401.89326) (xy 194.632172 -401.883123)
			(xy 194.687943 -401.881085) (xy 194.743417 -401.887188) (xy 194.79741 -401.901304) (xy 194.848773 -401.923131)
			(xy 194.896411 -401.952204) (xy 194.939307 -401.987903) (xy 194.976549 -402.029467) (xy 195.007343 -402.076011)
			(xy 195.031031 -402.126542) (xy 195.047109 -402.179984) (xy 195.053361 -402.222462) (xy 198.023478 -402.222462)
			(xy 198.027549 -402.16684) (xy 198.039675 -402.112403) (xy 198.059598 -402.060312) (xy 198.086894 -402.011677)
			(xy 198.12098 -401.967534) (xy 198.161129 -401.928825) (xy 198.206487 -401.896374) (xy 198.256087 -401.870873)
			(xy 198.308871 -401.852866) (xy 198.363714 -401.842736) (xy 198.419448 -401.840699) (xy 198.474885 -401.846799)
			(xy 198.528842 -401.860905) (xy 198.580171 -401.882717) (xy 198.627777 -401.911771) (xy 198.670645 -401.947446)
			(xy 198.707862 -401.988983) (xy 198.738635 -402.035496) (xy 198.762307 -402.085993) (xy 198.778375 -402.1394)
			(xy 198.786495 -402.194576) (xy 198.787004 -402.222462) (xy 198.786495 -402.250348) (xy 198.778375 -402.305524)
			(xy 198.762307 -402.358931) (xy 198.738635 -402.409428) (xy 198.707862 -402.455941) (xy 198.670645 -402.497478)
			(xy 198.627777 -402.533153) (xy 198.580171 -402.562207) (xy 198.528842 -402.584019) (xy 198.474885 -402.598125)
			(xy 198.419448 -402.604225) (xy 198.363714 -402.602188) (xy 198.308871 -402.592058) (xy 198.256087 -402.574051)
			(xy 198.206487 -402.54855) (xy 198.161129 -402.516099) (xy 198.12098 -402.47739) (xy 198.086894 -402.433247)
			(xy 198.059598 -402.384612) (xy 198.039675 -402.332521) (xy 198.027549 -402.278084) (xy 198.023478 -402.222462)
			(xy 195.053361 -402.222462) (xy 195.055235 -402.235198) (xy 195.055744 -402.263102) (xy 195.055235 -402.291006)
			(xy 195.047109 -402.34622) (xy 195.031031 -402.399662) (xy 195.007343 -402.450193) (xy 194.976549 -402.496737)
			(xy 194.939307 -402.538301) (xy 194.896411 -402.574) (xy 194.848773 -402.603073) (xy 194.79741 -402.6249)
			(xy 194.743417 -402.639016) (xy 194.687943 -402.645119) (xy 194.632172 -402.643081) (xy 194.577293 -402.632944)
			(xy 194.524473 -402.614925) (xy 194.474841 -402.589407) (xy 194.429453 -402.556935) (xy 194.389276 -402.5182)
			(xy 194.355168 -402.474028) (xy 194.327854 -402.42536) (xy 194.307918 -402.373234) (xy 194.295783 -402.318761)
			(xy 194.29171 -402.263102) (xy 185.023252 -402.263102) (xy 185.023252 -403.06879) (xy 187.740542 -403.06879)
			(xy 187.744613 -403.013168) (xy 187.756739 -402.958731) (xy 187.776662 -402.90664) (xy 187.803958 -402.858005)
			(xy 187.838044 -402.813862) (xy 187.878193 -402.775153) (xy 187.923551 -402.742702) (xy 187.973151 -402.717201)
			(xy 188.025935 -402.699194) (xy 188.080778 -402.689064) (xy 188.136512 -402.687027) (xy 188.191949 -402.693127)
			(xy 188.245906 -402.707233) (xy 188.297235 -402.729045) (xy 188.344841 -402.758099) (xy 188.387709 -402.793774)
			(xy 188.424926 -402.835311) (xy 188.455699 -402.881824) (xy 188.479371 -402.932321) (xy 188.495439 -402.985728)
			(xy 188.503559 -403.040904) (xy 188.504068 -403.06879) (xy 188.503559 -403.096676) (xy 188.495439 -403.151852)
			(xy 188.479371 -403.205259) (xy 188.455699 -403.255756) (xy 188.424926 -403.302269) (xy 188.387709 -403.343806)
			(xy 188.344841 -403.379481) (xy 188.297235 -403.408535) (xy 188.245906 -403.430347) (xy 188.191949 -403.444453)
			(xy 188.136512 -403.450553) (xy 188.080778 -403.448516) (xy 188.025935 -403.438386) (xy 187.973151 -403.420379)
			(xy 187.923551 -403.394878) (xy 187.878193 -403.362427) (xy 187.838044 -403.323718) (xy 187.803958 -403.279575)
			(xy 187.776662 -403.23094) (xy 187.756739 -403.178849) (xy 187.744613 -403.124412) (xy 187.740542 -403.06879)
			(xy 185.023252 -403.06879) (xy 185.023252 -403.991318) (xy 190.063626 -403.991318) (xy 190.067697 -403.935696)
			(xy 190.079823 -403.881259) (xy 190.099746 -403.829168) (xy 190.127042 -403.780533) (xy 190.161128 -403.73639)
			(xy 190.201277 -403.697681) (xy 190.246635 -403.66523) (xy 190.296235 -403.639729) (xy 190.349019 -403.621722)
			(xy 190.403862 -403.611592) (xy 190.459596 -403.609555) (xy 190.515033 -403.615655) (xy 190.56899 -403.629761)
			(xy 190.620319 -403.651573) (xy 190.667925 -403.680627) (xy 190.710793 -403.716302) (xy 190.74801 -403.757839)
			(xy 190.778783 -403.804352) (xy 190.802455 -403.854849) (xy 190.818523 -403.908256) (xy 190.826643 -403.963432)
			(xy 190.827152 -403.991318) (xy 190.826643 -404.019204) (xy 190.818523 -404.07438) (xy 190.816996 -404.079456)
			(xy 192.60769 -404.079456) (xy 192.611761 -404.023834) (xy 192.623887 -403.969397) (xy 192.64381 -403.917306)
			(xy 192.671106 -403.868671) (xy 192.705192 -403.824528) (xy 192.745341 -403.785819) (xy 192.790699 -403.753368)
			(xy 192.840299 -403.727867) (xy 192.893083 -403.70986) (xy 192.947926 -403.69973) (xy 193.00366 -403.697693)
			(xy 193.059097 -403.703793) (xy 193.113054 -403.717899) (xy 193.164383 -403.739711) (xy 193.211989 -403.768765)
			(xy 193.254857 -403.80444) (xy 193.292074 -403.845977) (xy 193.322847 -403.89249) (xy 193.329763 -403.907244)
			(xy 193.55765 -403.907244) (xy 193.561721 -403.851622) (xy 193.573847 -403.797185) (xy 193.59377 -403.745094)
			(xy 193.621066 -403.696459) (xy 193.655152 -403.652316) (xy 193.695301 -403.613607) (xy 193.740659 -403.581156)
			(xy 193.790259 -403.555655) (xy 193.843043 -403.537648) (xy 193.897886 -403.527518) (xy 193.95362 -403.525481)
			(xy 194.009057 -403.531581) (xy 194.063014 -403.545687) (xy 194.114343 -403.567499) (xy 194.161949 -403.596553)
			(xy 194.204817 -403.632228) (xy 194.242034 -403.673765) (xy 194.272807 -403.720278) (xy 194.296479 -403.770775)
			(xy 194.312547 -403.824182) (xy 194.320667 -403.879358) (xy 194.321176 -403.907244) (xy 194.320667 -403.93513)
			(xy 194.312547 -403.990306) (xy 194.296479 -404.043713) (xy 194.272807 -404.09421) (xy 194.242034 -404.140723)
			(xy 194.204817 -404.18226) (xy 194.161949 -404.217935) (xy 194.114343 -404.246989) (xy 194.063014 -404.268801)
			(xy 194.009057 -404.282907) (xy 193.95362 -404.289007) (xy 193.897886 -404.28697) (xy 193.843043 -404.27684)
			(xy 193.790259 -404.258833) (xy 193.740659 -404.233332) (xy 193.695301 -404.200881) (xy 193.655152 -404.162172)
			(xy 193.621066 -404.118029) (xy 193.59377 -404.069394) (xy 193.573847 -404.017303) (xy 193.561721 -403.962866)
			(xy 193.55765 -403.907244) (xy 193.329763 -403.907244) (xy 193.346519 -403.942987) (xy 193.362587 -403.996394)
			(xy 193.370707 -404.05157) (xy 193.371216 -404.079456) (xy 193.370707 -404.107342) (xy 193.362587 -404.162518)
			(xy 193.346519 -404.215925) (xy 193.322847 -404.266422) (xy 193.292074 -404.312935) (xy 193.254857 -404.354472)
			(xy 193.211989 -404.390147) (xy 193.164383 -404.419201) (xy 193.113054 -404.441013) (xy 193.059097 -404.455119)
			(xy 193.00366 -404.461219) (xy 192.947926 -404.459182) (xy 192.893083 -404.449052) (xy 192.840299 -404.431045)
			(xy 192.790699 -404.405544) (xy 192.745341 -404.373093) (xy 192.705192 -404.334384) (xy 192.671106 -404.290241)
			(xy 192.64381 -404.241606) (xy 192.623887 -404.189515) (xy 192.611761 -404.135078) (xy 192.60769 -404.079456)
			(xy 190.816996 -404.079456) (xy 190.802455 -404.127787) (xy 190.778783 -404.178284) (xy 190.74801 -404.224797)
			(xy 190.710793 -404.266334) (xy 190.667925 -404.302009) (xy 190.620319 -404.331063) (xy 190.56899 -404.352875)
			(xy 190.515033 -404.366981) (xy 190.459596 -404.373081) (xy 190.403862 -404.371044) (xy 190.349019 -404.360914)
			(xy 190.296235 -404.342907) (xy 190.246635 -404.317406) (xy 190.201277 -404.284955) (xy 190.161128 -404.246246)
			(xy 190.127042 -404.202103) (xy 190.099746 -404.153468) (xy 190.079823 -404.101377) (xy 190.067697 -404.04694)
			(xy 190.063626 -403.991318) (xy 185.023252 -403.991318) (xy 185.023252 -404.770844) (xy 199.62952 -404.770844)
			(xy 199.633591 -404.715222) (xy 199.645717 -404.660785) (xy 199.66564 -404.608694) (xy 199.692936 -404.560059)
			(xy 199.727022 -404.515916) (xy 199.767171 -404.477207) (xy 199.812529 -404.444756) (xy 199.862129 -404.419255)
			(xy 199.914913 -404.401248) (xy 199.969756 -404.391118) (xy 200.02549 -404.389081) (xy 200.080927 -404.395181)
			(xy 200.134884 -404.409287) (xy 200.186213 -404.431099) (xy 200.233819 -404.460153) (xy 200.276687 -404.495828)
			(xy 200.313904 -404.537365) (xy 200.344677 -404.583878) (xy 200.368349 -404.634375) (xy 200.384417 -404.687782)
			(xy 200.392537 -404.742958) (xy 200.393046 -404.770844) (xy 200.392537 -404.79873) (xy 200.39208 -404.801832)
			(xy 200.686922 -404.801832) (xy 200.690993 -404.74621) (xy 200.703119 -404.691773) (xy 200.723042 -404.639682)
			(xy 200.750338 -404.591047) (xy 200.784424 -404.546904) (xy 200.824573 -404.508195) (xy 200.869931 -404.475744)
			(xy 200.919531 -404.450243) (xy 200.972315 -404.432236) (xy 201.027158 -404.422106) (xy 201.082892 -404.420069)
			(xy 201.138329 -404.426169) (xy 201.192286 -404.440275) (xy 201.243615 -404.462087) (xy 201.291221 -404.491141)
			(xy 201.334089 -404.526816) (xy 201.371306 -404.568353) (xy 201.402079 -404.614866) (xy 201.425751 -404.665363)
			(xy 201.441819 -404.71877) (xy 201.449939 -404.773946) (xy 201.450448 -404.801832) (xy 201.449939 -404.829718)
			(xy 201.441819 -404.884894) (xy 201.425751 -404.938301) (xy 201.402079 -404.988798) (xy 201.371306 -405.035311)
			(xy 201.334089 -405.076848) (xy 201.291221 -405.112523) (xy 201.243615 -405.141577) (xy 201.192286 -405.163389)
			(xy 201.138329 -405.177495) (xy 201.082892 -405.183595) (xy 201.027158 -405.181558) (xy 200.972315 -405.171428)
			(xy 200.919531 -405.153421) (xy 200.869931 -405.12792) (xy 200.824573 -405.095469) (xy 200.784424 -405.05676)
			(xy 200.750338 -405.012617) (xy 200.723042 -404.963982) (xy 200.703119 -404.911891) (xy 200.690993 -404.857454)
			(xy 200.686922 -404.801832) (xy 200.39208 -404.801832) (xy 200.384417 -404.853906) (xy 200.368349 -404.907313)
			(xy 200.344677 -404.95781) (xy 200.313904 -405.004323) (xy 200.276687 -405.04586) (xy 200.233819 -405.081535)
			(xy 200.186213 -405.110589) (xy 200.134884 -405.132401) (xy 200.080927 -405.146507) (xy 200.02549 -405.152607)
			(xy 199.969756 -405.15057) (xy 199.914913 -405.14044) (xy 199.862129 -405.122433) (xy 199.812529 -405.096932)
			(xy 199.767171 -405.064481) (xy 199.727022 -405.025772) (xy 199.692936 -404.981629) (xy 199.66564 -404.932994)
			(xy 199.645717 -404.880903) (xy 199.633591 -404.826466) (xy 199.62952 -404.770844) (xy 185.023252 -404.770844)
			(xy 185.023252 -405.18461) (xy 196.984364 -405.18461) (xy 196.988435 -405.128988) (xy 197.000561 -405.074551)
			(xy 197.020484 -405.02246) (xy 197.04778 -404.973825) (xy 197.081866 -404.929682) (xy 197.122015 -404.890973)
			(xy 197.167373 -404.858522) (xy 197.216973 -404.833021) (xy 197.269757 -404.815014) (xy 197.3246 -404.804884)
			(xy 197.380334 -404.802847) (xy 197.435771 -404.808947) (xy 197.489728 -404.823053) (xy 197.541057 -404.844865)
			(xy 197.588663 -404.873919) (xy 197.631531 -404.909594) (xy 197.668748 -404.951131) (xy 197.699521 -404.997644)
			(xy 197.723193 -405.048141) (xy 197.739261 -405.101548) (xy 197.747381 -405.156724) (xy 197.74789 -405.18461)
			(xy 197.747709 -405.194516) (xy 198.019922 -405.194516) (xy 198.023993 -405.138894) (xy 198.036119 -405.084457)
			(xy 198.056042 -405.032366) (xy 198.083338 -404.983731) (xy 198.117424 -404.939588) (xy 198.157573 -404.900879)
			(xy 198.202931 -404.868428) (xy 198.252531 -404.842927) (xy 198.305315 -404.82492) (xy 198.360158 -404.81479)
			(xy 198.415892 -404.812753) (xy 198.471329 -404.818853) (xy 198.525286 -404.832959) (xy 198.576615 -404.854771)
			(xy 198.624221 -404.883825) (xy 198.667089 -404.9195) (xy 198.704306 -404.961037) (xy 198.735079 -405.00755)
			(xy 198.758751 -405.058047) (xy 198.774819 -405.111454) (xy 198.782939 -405.16663) (xy 198.783448 -405.194516)
			(xy 198.782939 -405.222402) (xy 198.774819 -405.277578) (xy 198.758751 -405.330985) (xy 198.735079 -405.381482)
			(xy 198.704306 -405.427995) (xy 198.667089 -405.469532) (xy 198.624221 -405.505207) (xy 198.576615 -405.534261)
			(xy 198.525286 -405.556073) (xy 198.471329 -405.570179) (xy 198.415892 -405.576279) (xy 198.360158 -405.574242)
			(xy 198.305315 -405.564112) (xy 198.252531 -405.546105) (xy 198.202931 -405.520604) (xy 198.157573 -405.488153)
			(xy 198.117424 -405.449444) (xy 198.083338 -405.405301) (xy 198.056042 -405.356666) (xy 198.036119 -405.304575)
			(xy 198.023993 -405.250138) (xy 198.019922 -405.194516) (xy 197.747709 -405.194516) (xy 197.747381 -405.212496)
			(xy 197.739261 -405.267672) (xy 197.723193 -405.321079) (xy 197.699521 -405.371576) (xy 197.668748 -405.418089)
			(xy 197.631531 -405.459626) (xy 197.588663 -405.495301) (xy 197.541057 -405.524355) (xy 197.489728 -405.546167)
			(xy 197.435771 -405.560273) (xy 197.380334 -405.566373) (xy 197.3246 -405.564336) (xy 197.269757 -405.554206)
			(xy 197.216973 -405.536199) (xy 197.167373 -405.510698) (xy 197.122015 -405.478247) (xy 197.081866 -405.439538)
			(xy 197.04778 -405.395395) (xy 197.020484 -405.34676) (xy 197.000561 -405.294669) (xy 196.988435 -405.240232)
			(xy 196.984364 -405.18461) (xy 185.023252 -405.18461) (xy 185.023252 -405.857964) (xy 187.266832 -405.857964)
			(xy 187.270903 -405.802342) (xy 187.283029 -405.747905) (xy 187.302952 -405.695814) (xy 187.330248 -405.647179)
			(xy 187.364334 -405.603036) (xy 187.404483 -405.564327) (xy 187.449841 -405.531876) (xy 187.499441 -405.506375)
			(xy 187.552225 -405.488368) (xy 187.607068 -405.478238) (xy 187.662802 -405.476201) (xy 187.718239 -405.482301)
			(xy 187.772196 -405.496407) (xy 187.823525 -405.518219) (xy 187.871131 -405.547273) (xy 187.913999 -405.582948)
			(xy 187.951216 -405.624485) (xy 187.981989 -405.670998) (xy 188.005661 -405.721495) (xy 188.021729 -405.774902)
			(xy 188.029849 -405.830078) (xy 188.030358 -405.857964) (xy 188.029849 -405.88585) (xy 188.021729 -405.941026)
			(xy 188.005661 -405.994433) (xy 187.981989 -406.04493) (xy 187.951216 -406.091443) (xy 187.913999 -406.13298)
			(xy 187.871131 -406.168655) (xy 187.839997 -406.187656) (xy 194.514722 -406.187656) (xy 194.518793 -406.132034)
			(xy 194.530919 -406.077597) (xy 194.550842 -406.025506) (xy 194.578138 -405.976871) (xy 194.612224 -405.932728)
			(xy 194.652373 -405.894019) (xy 194.697731 -405.861568) (xy 194.747331 -405.836067) (xy 194.800115 -405.81806)
			(xy 194.854958 -405.80793) (xy 194.910692 -405.805893) (xy 194.966129 -405.811993) (xy 195.020086 -405.826099)
			(xy 195.071415 -405.847911) (xy 195.119021 -405.876965) (xy 195.161889 -405.91264) (xy 195.199106 -405.954177)
			(xy 195.229879 -406.00069) (xy 195.253551 -406.051187) (xy 195.269619 -406.104594) (xy 195.277739 -406.15977)
			(xy 195.278248 -406.187656) (xy 195.277739 -406.215542) (xy 195.269619 -406.270718) (xy 195.253551 -406.324125)
			(xy 195.229879 -406.374622) (xy 195.199106 -406.421135) (xy 195.161889 -406.462672) (xy 195.119021 -406.498347)
			(xy 195.071415 -406.527401) (xy 195.020086 -406.549213) (xy 194.966129 -406.563319) (xy 194.910692 -406.569419)
			(xy 194.854958 -406.567382) (xy 194.800115 -406.557252) (xy 194.747331 -406.539245) (xy 194.697731 -406.513744)
			(xy 194.652373 -406.481293) (xy 194.612224 -406.442584) (xy 194.578138 -406.398441) (xy 194.550842 -406.349806)
			(xy 194.530919 -406.297715) (xy 194.518793 -406.243278) (xy 194.514722 -406.187656) (xy 187.839997 -406.187656)
			(xy 187.823525 -406.197709) (xy 187.772196 -406.219521) (xy 187.718239 -406.233627) (xy 187.662802 -406.239727)
			(xy 187.607068 -406.23769) (xy 187.552225 -406.22756) (xy 187.499441 -406.209553) (xy 187.449841 -406.184052)
			(xy 187.404483 -406.151601) (xy 187.364334 -406.112892) (xy 187.330248 -406.068749) (xy 187.302952 -406.020114)
			(xy 187.283029 -405.968023) (xy 187.270903 -405.913586) (xy 187.266832 -405.857964) (xy 185.023252 -405.857964)
			(xy 185.023252 -406.99436) (xy 187.04255 -406.99436) (xy 187.046621 -406.938738) (xy 187.058747 -406.884301)
			(xy 187.07867 -406.83221) (xy 187.105966 -406.783575) (xy 187.140052 -406.739432) (xy 187.180201 -406.700723)
			(xy 187.225559 -406.668272) (xy 187.275159 -406.642771) (xy 187.327943 -406.624764) (xy 187.382786 -406.614634)
			(xy 187.43852 -406.612597) (xy 187.493957 -406.618697) (xy 187.547914 -406.632803) (xy 187.599243 -406.654615)
			(xy 187.60323 -406.657048) (xy 196.381114 -406.657048) (xy 196.385185 -406.601426) (xy 196.397311 -406.546989)
			(xy 196.417234 -406.494898) (xy 196.44453 -406.446263) (xy 196.478616 -406.40212) (xy 196.518765 -406.363411)
			(xy 196.564123 -406.33096) (xy 196.613723 -406.305459) (xy 196.666507 -406.287452) (xy 196.72135 -406.277322)
			(xy 196.777084 -406.275285) (xy 196.832521 -406.281385) (xy 196.886478 -406.295491) (xy 196.937807 -406.317303)
			(xy 196.985413 -406.346357) (xy 197.028281 -406.382032) (xy 197.065498 -406.423569) (xy 197.096271 -406.470082)
			(xy 197.115571 -406.511252) (xy 198.765666 -406.511252) (xy 198.769737 -406.45563) (xy 198.781863 -406.401193)
			(xy 198.801786 -406.349102) (xy 198.829082 -406.300467) (xy 198.863168 -406.256324) (xy 198.903317 -406.217615)
			(xy 198.948675 -406.185164) (xy 198.998275 -406.159663) (xy 199.051059 -406.141656) (xy 199.105902 -406.131526)
			(xy 199.161636 -406.129489) (xy 199.217073 -406.135589) (xy 199.27103 -406.149695) (xy 199.322359 -406.171507)
			(xy 199.369965 -406.200561) (xy 199.412833 -406.236236) (xy 199.45005 -406.277773) (xy 199.480823 -406.324286)
			(xy 199.504495 -406.374783) (xy 199.520563 -406.42819) (xy 199.528683 -406.483366) (xy 199.529192 -406.511252)
			(xy 199.528683 -406.539138) (xy 199.520563 -406.594314) (xy 199.504495 -406.647721) (xy 199.480823 -406.698218)
			(xy 199.45005 -406.744731) (xy 199.412833 -406.786268) (xy 199.369965 -406.821943) (xy 199.322359 -406.850997)
			(xy 199.27103 -406.872809) (xy 199.217073 -406.886915) (xy 199.161636 -406.893015) (xy 199.105902 -406.890978)
			(xy 199.051059 -406.880848) (xy 198.998275 -406.862841) (xy 198.948675 -406.83734) (xy 198.903317 -406.804889)
			(xy 198.863168 -406.76618) (xy 198.829082 -406.722037) (xy 198.801786 -406.673402) (xy 198.781863 -406.621311)
			(xy 198.769737 -406.566874) (xy 198.765666 -406.511252) (xy 197.115571 -406.511252) (xy 197.119943 -406.520579)
			(xy 197.136011 -406.573986) (xy 197.144131 -406.629162) (xy 197.14464 -406.657048) (xy 197.144131 -406.684934)
			(xy 197.136011 -406.74011) (xy 197.119943 -406.793517) (xy 197.096271 -406.844014) (xy 197.065498 -406.890527)
			(xy 197.028281 -406.932064) (xy 196.985413 -406.967739) (xy 196.937807 -406.996793) (xy 196.886478 -407.018605)
			(xy 196.832521 -407.032711) (xy 196.777084 -407.038811) (xy 196.72135 -407.036774) (xy 196.666507 -407.026644)
			(xy 196.613723 -407.008637) (xy 196.564123 -406.983136) (xy 196.518765 -406.950685) (xy 196.478616 -406.911976)
			(xy 196.44453 -406.867833) (xy 196.417234 -406.819198) (xy 196.397311 -406.767107) (xy 196.385185 -406.71267)
			(xy 196.381114 -406.657048) (xy 187.60323 -406.657048) (xy 187.646849 -406.683669) (xy 187.689717 -406.719344)
			(xy 187.726934 -406.760881) (xy 187.757707 -406.807394) (xy 187.781379 -406.857891) (xy 187.797447 -406.911298)
			(xy 187.805567 -406.966474) (xy 187.806076 -406.99436) (xy 187.805567 -407.022246) (xy 187.797447 -407.077422)
			(xy 187.78461 -407.12009) (xy 198.130412 -407.12009) (xy 198.134483 -407.064468) (xy 198.146609 -407.010031)
			(xy 198.166532 -406.95794) (xy 198.193828 -406.909305) (xy 198.227914 -406.865162) (xy 198.268063 -406.826453)
			(xy 198.313421 -406.794002) (xy 198.363021 -406.768501) (xy 198.415805 -406.750494) (xy 198.470648 -406.740364)
			(xy 198.526382 -406.738327) (xy 198.581819 -406.744427) (xy 198.635776 -406.758533) (xy 198.687105 -406.780345)
			(xy 198.734711 -406.809399) (xy 198.777579 -406.845074) (xy 198.814796 -406.886611) (xy 198.845569 -406.933124)
			(xy 198.869241 -406.983621) (xy 198.885309 -407.037028) (xy 198.893429 -407.092204) (xy 198.893938 -407.12009)
			(xy 198.893429 -407.147976) (xy 198.885309 -407.203152) (xy 198.869241 -407.256559) (xy 198.845569 -407.307056)
			(xy 198.814796 -407.353569) (xy 198.777579 -407.395106) (xy 198.734711 -407.430781) (xy 198.687105 -407.459835)
			(xy 198.635776 -407.481647) (xy 198.581819 -407.495753) (xy 198.526382 -407.501853) (xy 198.470648 -407.499816)
			(xy 198.415805 -407.489686) (xy 198.363021 -407.471679) (xy 198.313421 -407.446178) (xy 198.268063 -407.413727)
			(xy 198.227914 -407.375018) (xy 198.193828 -407.330875) (xy 198.166532 -407.28224) (xy 198.146609 -407.230149)
			(xy 198.134483 -407.175712) (xy 198.130412 -407.12009) (xy 187.78461 -407.12009) (xy 187.781379 -407.130829)
			(xy 187.757707 -407.181326) (xy 187.726934 -407.227839) (xy 187.689717 -407.269376) (xy 187.646849 -407.305051)
			(xy 187.599243 -407.334105) (xy 187.547914 -407.355917) (xy 187.493957 -407.370023) (xy 187.43852 -407.376123)
			(xy 187.382786 -407.374086) (xy 187.327943 -407.363956) (xy 187.275159 -407.345949) (xy 187.225559 -407.320448)
			(xy 187.180201 -407.287997) (xy 187.140052 -407.249288) (xy 187.105966 -407.205145) (xy 187.07867 -407.15651)
			(xy 187.058747 -407.104419) (xy 187.046621 -407.049982) (xy 187.04255 -406.99436) (xy 185.023252 -406.99436)
			(xy 185.023252 -407.4414) (xy 185.755532 -407.4414) (xy 185.759603 -407.385778) (xy 185.771729 -407.331341)
			(xy 185.791652 -407.27925) (xy 185.818948 -407.230615) (xy 185.853034 -407.186472) (xy 185.893183 -407.147763)
			(xy 185.938541 -407.115312) (xy 185.988141 -407.089811) (xy 186.040925 -407.071804) (xy 186.095768 -407.061674)
			(xy 186.151502 -407.059637) (xy 186.206939 -407.065737) (xy 186.260896 -407.079843) (xy 186.312225 -407.101655)
			(xy 186.359831 -407.130709) (xy 186.402699 -407.166384) (xy 186.439916 -407.207921) (xy 186.470689 -407.254434)
			(xy 186.494361 -407.304931) (xy 186.510429 -407.358338) (xy 186.518549 -407.413514) (xy 186.519058 -407.4414)
			(xy 186.518549 -407.469286) (xy 186.510429 -407.524462) (xy 186.494361 -407.577869) (xy 186.470689 -407.628366)
			(xy 186.439916 -407.674879) (xy 186.402699 -407.716416) (xy 186.359831 -407.752091) (xy 186.312225 -407.781145)
			(xy 186.260896 -407.802957) (xy 186.206939 -407.817063) (xy 186.151502 -407.823163) (xy 186.095768 -407.821126)
			(xy 186.040925 -407.810996) (xy 185.988141 -407.792989) (xy 185.938541 -407.767488) (xy 185.893183 -407.735037)
			(xy 185.853034 -407.696328) (xy 185.818948 -407.652185) (xy 185.791652 -407.60355) (xy 185.771729 -407.551459)
			(xy 185.759603 -407.497022) (xy 185.755532 -407.4414) (xy 185.023252 -407.4414) (xy 185.023252 -408.592274)
			(xy 190.042798 -408.592274) (xy 190.046869 -408.536652) (xy 190.058995 -408.482215) (xy 190.078918 -408.430124)
			(xy 190.106214 -408.381489) (xy 190.1403 -408.337346) (xy 190.180449 -408.298637) (xy 190.225807 -408.266186)
			(xy 190.275407 -408.240685) (xy 190.328191 -408.222678) (xy 190.383034 -408.212548) (xy 190.438768 -408.210511)
			(xy 190.494205 -408.216611) (xy 190.548162 -408.230717) (xy 190.599491 -408.252529) (xy 190.647097 -408.281583)
			(xy 190.689965 -408.317258) (xy 190.727182 -408.358795) (xy 190.757955 -408.405308) (xy 190.781627 -408.455805)
			(xy 190.797695 -408.509212) (xy 190.805815 -408.564388) (xy 190.806324 -408.592274) (xy 190.805815 -408.62016)
			(xy 190.797695 -408.675336) (xy 190.781627 -408.728743) (xy 190.757955 -408.77924) (xy 190.727182 -408.825753)
			(xy 190.689965 -408.86729) (xy 190.647097 -408.902965) (xy 190.599491 -408.932019) (xy 190.548162 -408.953831)
			(xy 190.520426 -408.961082) (xy 194.781676 -408.961082) (xy 194.785747 -408.90546) (xy 194.797873 -408.851023)
			(xy 194.817796 -408.798932) (xy 194.845092 -408.750297) (xy 194.879178 -408.706154) (xy 194.919327 -408.667445)
			(xy 194.964685 -408.634994) (xy 195.014285 -408.609493) (xy 195.067069 -408.591486) (xy 195.121912 -408.581356)
			(xy 195.177646 -408.579319) (xy 195.233083 -408.585419) (xy 195.28704 -408.599525) (xy 195.338369 -408.621337)
			(xy 195.385975 -408.650391) (xy 195.42327 -408.681428) (xy 196.990968 -408.681428) (xy 196.995039 -408.625806)
			(xy 197.007165 -408.571369) (xy 197.027088 -408.519278) (xy 197.054384 -408.470643) (xy 197.08847 -408.4265)
			(xy 197.128619 -408.387791) (xy 197.173977 -408.35534) (xy 197.223577 -408.329839) (xy 197.276361 -408.311832)
			(xy 197.331204 -408.301702) (xy 197.386938 -408.299665) (xy 197.442375 -408.305765) (xy 197.496332 -408.319871)
			(xy 197.547661 -408.341683) (xy 197.595267 -408.370737) (xy 197.638135 -408.406412) (xy 197.675352 -408.447949)
			(xy 197.706125 -408.494462) (xy 197.729797 -408.544959) (xy 197.745865 -408.598366) (xy 197.753985 -408.653542)
			(xy 197.754494 -408.681428) (xy 197.753985 -408.709314) (xy 197.745865 -408.76449) (xy 197.729797 -408.817897)
			(xy 197.706125 -408.868394) (xy 197.675352 -408.914907) (xy 197.638135 -408.956444) (xy 197.595267 -408.992119)
			(xy 197.547661 -409.021173) (xy 197.496332 -409.042985) (xy 197.442375 -409.057091) (xy 197.386938 -409.063191)
			(xy 197.331204 -409.061154) (xy 197.276361 -409.051024) (xy 197.223577 -409.033017) (xy 197.173977 -409.007516)
			(xy 197.128619 -408.975065) (xy 197.08847 -408.936356) (xy 197.054384 -408.892213) (xy 197.027088 -408.843578)
			(xy 197.007165 -408.791487) (xy 196.995039 -408.73705) (xy 196.990968 -408.681428) (xy 195.42327 -408.681428)
			(xy 195.428843 -408.686066) (xy 195.46606 -408.727603) (xy 195.496833 -408.774116) (xy 195.520505 -408.824613)
			(xy 195.536573 -408.87802) (xy 195.544693 -408.933196) (xy 195.545202 -408.961082) (xy 195.544693 -408.988968)
			(xy 195.536573 -409.044144) (xy 195.520505 -409.097551) (xy 195.496833 -409.148048) (xy 195.46606 -409.194561)
			(xy 195.428843 -409.236098) (xy 195.385975 -409.271773) (xy 195.338369 -409.300827) (xy 195.28704 -409.322639)
			(xy 195.233083 -409.336745) (xy 195.177646 -409.342845) (xy 195.121912 -409.340808) (xy 195.067069 -409.330678)
			(xy 195.014285 -409.312671) (xy 194.964685 -409.28717) (xy 194.919327 -409.254719) (xy 194.879178 -409.21601)
			(xy 194.845092 -409.171867) (xy 194.817796 -409.123232) (xy 194.797873 -409.071141) (xy 194.785747 -409.016704)
			(xy 194.781676 -408.961082) (xy 190.520426 -408.961082) (xy 190.494205 -408.967937) (xy 190.438768 -408.974037)
			(xy 190.383034 -408.972) (xy 190.328191 -408.96187) (xy 190.275407 -408.943863) (xy 190.225807 -408.918362)
			(xy 190.180449 -408.885911) (xy 190.1403 -408.847202) (xy 190.106214 -408.803059) (xy 190.078918 -408.754424)
			(xy 190.058995 -408.702333) (xy 190.046869 -408.647896) (xy 190.042798 -408.592274) (xy 185.023252 -408.592274)
			(xy 185.023252 -409.420568) (xy 186.579 -409.420568) (xy 186.583071 -409.364946) (xy 186.595197 -409.310509)
			(xy 186.61512 -409.258418) (xy 186.642416 -409.209783) (xy 186.676502 -409.16564) (xy 186.716651 -409.126931)
			(xy 186.762009 -409.09448) (xy 186.811609 -409.068979) (xy 186.864393 -409.050972) (xy 186.919236 -409.040842)
			(xy 186.97497 -409.038805) (xy 187.030407 -409.044905) (xy 187.084364 -409.059011) (xy 187.135693 -409.080823)
			(xy 187.183299 -409.109877) (xy 187.226167 -409.145552) (xy 187.263384 -409.187089) (xy 187.294157 -409.233602)
			(xy 187.317829 -409.284099) (xy 187.333897 -409.337506) (xy 187.342017 -409.392682) (xy 187.342526 -409.420568)
			(xy 187.342017 -409.448454) (xy 187.333897 -409.50363) (xy 187.317829 -409.557037) (xy 187.294157 -409.607534)
			(xy 187.263384 -409.654047) (xy 187.226167 -409.695584) (xy 187.183299 -409.731259) (xy 187.135693 -409.760313)
			(xy 187.084364 -409.782125) (xy 187.030407 -409.796231) (xy 186.97497 -409.802331) (xy 186.919236 -409.800294)
			(xy 186.864393 -409.790164) (xy 186.811609 -409.772157) (xy 186.762009 -409.746656) (xy 186.716651 -409.714205)
			(xy 186.676502 -409.675496) (xy 186.642416 -409.631353) (xy 186.61512 -409.582718) (xy 186.595197 -409.530627)
			(xy 186.583071 -409.47619) (xy 186.579 -409.420568) (xy 185.023252 -409.420568) (xy 185.023252 -411.03804)
			(xy 185.614054 -411.03804) (xy 185.618125 -410.982418) (xy 185.630251 -410.927981) (xy 185.650174 -410.87589)
			(xy 185.67747 -410.827255) (xy 185.711556 -410.783112) (xy 185.751705 -410.744403) (xy 185.797063 -410.711952)
			(xy 185.846663 -410.686451) (xy 185.899447 -410.668444) (xy 185.95429 -410.658314) (xy 186.010024 -410.656277)
			(xy 186.065461 -410.662377) (xy 186.119418 -410.676483) (xy 186.170747 -410.698295) (xy 186.207196 -410.72054)
			(xy 186.530994 -410.72054) (xy 186.535065 -410.664918) (xy 186.547191 -410.610481) (xy 186.567114 -410.55839)
			(xy 186.59441 -410.509755) (xy 186.628496 -410.465612) (xy 186.668645 -410.426903) (xy 186.714003 -410.394452)
			(xy 186.763603 -410.368951) (xy 186.816387 -410.350944) (xy 186.87123 -410.340814) (xy 186.926964 -410.338777)
			(xy 186.982401 -410.344877) (xy 187.036358 -410.358983) (xy 187.087687 -410.380795) (xy 187.135293 -410.409849)
			(xy 187.178161 -410.445524) (xy 187.215378 -410.487061) (xy 187.246151 -410.533574) (xy 187.269823 -410.584071)
			(xy 187.285891 -410.637478) (xy 187.294011 -410.692654) (xy 187.29452 -410.72054) (xy 187.294011 -410.748426)
			(xy 187.285891 -410.803602) (xy 187.269823 -410.857009) (xy 187.250567 -410.898086) (xy 189.844424 -410.898086)
			(xy 189.848497 -410.842427) (xy 189.860632 -410.787954) (xy 189.880568 -410.735828) (xy 189.907882 -410.68716)
			(xy 189.94199 -410.642988) (xy 189.982167 -410.604253) (xy 190.027555 -410.571781) (xy 190.077187 -410.546263)
			(xy 190.130007 -410.528244) (xy 190.184886 -410.518107) (xy 190.240657 -410.516069) (xy 190.296131 -410.522172)
			(xy 190.350124 -410.536288) (xy 190.401487 -410.558115) (xy 190.449125 -410.587188) (xy 190.492021 -410.622887)
			(xy 190.529263 -410.664451) (xy 190.550744 -410.696918) (xy 191.73317 -410.696918) (xy 191.733682 -410.670028)
			(xy 191.741227 -410.616781) (xy 191.75617 -410.565119) (xy 191.778214 -410.516066) (xy 191.806925 -410.470592)
			(xy 191.841734 -410.429597) (xy 191.881951 -410.393892) (xy 191.904112 -410.378656) (xy 191.908176 -410.375608)
			(xy 191.918375 -410.366697) (xy 191.934158 -410.344706) (xy 191.943596 -410.319336) (xy 191.946023 -410.292376)
			(xy 191.941267 -410.265729) (xy 191.929665 -410.241272) (xy 191.912033 -410.220733) (xy 191.901064 -410.212794)
			(xy 191.879287 -410.197507) (xy 191.839807 -410.161841) (xy 191.805664 -410.121036) (xy 191.777519 -410.075885)
			(xy 191.755917 -410.027262) (xy 191.741279 -409.97611) (xy 191.733886 -409.923421) (xy 191.733424 -409.896818)
			(xy 191.73391 -409.869567) (xy 191.741666 -409.815619) (xy 191.757021 -409.763324) (xy 191.779663 -409.713747)
			(xy 191.809129 -409.667897) (xy 191.84482 -409.626706) (xy 191.886011 -409.591015) (xy 191.931861 -409.561549)
			(xy 191.981438 -409.538907) (xy 192.033733 -409.523552) (xy 192.087681 -409.515796) (xy 192.142183 -409.515796)
			(xy 192.196131 -409.523552) (xy 192.248426 -409.538907) (xy 192.298003 -409.561549) (xy 192.343853 -409.591015)
			(xy 192.385044 -409.626706) (xy 192.420735 -409.667897) (xy 192.450201 -409.713747) (xy 192.472843 -409.763324)
			(xy 192.488198 -409.815619) (xy 192.495954 -409.869567) (xy 192.49644 -409.896818) (xy 192.496031 -409.923424)
			(xy 192.488646 -409.97612) (xy 192.474006 -410.027277) (xy 192.452398 -410.075903) (xy 192.42424 -410.121053)
			(xy 192.390078 -410.161851) (xy 192.350578 -410.197503) (xy 192.3288 -410.212794) (xy 192.317789 -410.220685)
			(xy 192.300152 -410.241239) (xy 192.288546 -410.265711) (xy 192.283789 -410.292373) (xy 192.286216 -410.319348)
			(xy 192.295657 -410.344734) (xy 192.311445 -410.36674) (xy 192.321688 -410.375608) (xy 192.325752 -410.378656)
			(xy 192.347915 -410.393893) (xy 192.388145 -410.42959) (xy 192.422965 -410.470581) (xy 192.451686 -410.516055)
			(xy 192.473739 -410.565109) (xy 192.488688 -410.616774) (xy 192.496235 -410.670026) (xy 192.496694 -410.696918)
			(xy 195.54901 -410.696918) (xy 195.553083 -410.641259) (xy 195.565218 -410.586786) (xy 195.585154 -410.53466)
			(xy 195.612468 -410.485992) (xy 195.646576 -410.44182) (xy 195.686753 -410.403085) (xy 195.732141 -410.370613)
			(xy 195.781773 -410.345095) (xy 195.834593 -410.327076) (xy 195.889472 -410.316939) (xy 195.945243 -410.314901)
			(xy 196.000717 -410.321004) (xy 196.05471 -410.33512) (xy 196.106073 -410.356947) (xy 196.153711 -410.38602)
			(xy 196.196607 -410.421719) (xy 196.233849 -410.463283) (xy 196.264643 -410.509827) (xy 196.288331 -410.560358)
			(xy 196.304409 -410.6138) (xy 196.312535 -410.669014) (xy 196.313044 -410.696918) (xy 196.312535 -410.724822)
			(xy 196.304409 -410.780036) (xy 196.288331 -410.833478) (xy 196.264643 -410.884009) (xy 196.233849 -410.930553)
			(xy 196.196607 -410.972117) (xy 196.153711 -411.007816) (xy 196.106073 -411.036889) (xy 196.05471 -411.058716)
			(xy 196.000717 -411.072832) (xy 195.945243 -411.078935) (xy 195.889472 -411.076897) (xy 195.834593 -411.06676)
			(xy 195.781773 -411.048741) (xy 195.732141 -411.023223) (xy 195.686753 -410.990751) (xy 195.646576 -410.952016)
			(xy 195.612468 -410.907844) (xy 195.585154 -410.859176) (xy 195.565218 -410.80705) (xy 195.553083 -410.752577)
			(xy 195.54901 -410.696918) (xy 192.496694 -410.696918) (xy 192.496208 -410.724187) (xy 192.488446 -410.778171)
			(xy 192.473081 -410.830501) (xy 192.450424 -410.880111) (xy 192.420938 -410.925992) (xy 192.385223 -410.967209)
			(xy 192.344006 -411.002924) (xy 192.298125 -411.03241) (xy 192.248515 -411.055067) (xy 192.196185 -411.070432)
			(xy 192.142201 -411.078194) (xy 192.087663 -411.078194) (xy 192.033679 -411.070432) (xy 191.981349 -411.055067)
			(xy 191.931739 -411.03241) (xy 191.885858 -411.002924) (xy 191.844641 -410.967209) (xy 191.808926 -410.925992)
			(xy 191.77944 -410.880111) (xy 191.756783 -410.830501) (xy 191.741418 -410.778171) (xy 191.733656 -410.724187)
			(xy 191.73317 -410.696918) (xy 190.550744 -410.696918) (xy 190.560057 -410.710995) (xy 190.583745 -410.761526)
			(xy 190.599823 -410.814968) (xy 190.607949 -410.870182) (xy 190.608458 -410.898086) (xy 190.607949 -410.92599)
			(xy 190.599823 -410.981204) (xy 190.583745 -411.034646) (xy 190.560057 -411.085177) (xy 190.529263 -411.131721)
			(xy 190.492021 -411.173285) (xy 190.449125 -411.208984) (xy 190.401487 -411.238057) (xy 190.350124 -411.259884)
			(xy 190.296131 -411.274) (xy 190.240657 -411.280103) (xy 190.184886 -411.278065) (xy 190.130007 -411.267928)
			(xy 190.077187 -411.249909) (xy 190.027555 -411.224391) (xy 189.982167 -411.191919) (xy 189.94199 -411.153184)
			(xy 189.907882 -411.109012) (xy 189.880568 -411.060344) (xy 189.860632 -411.008218) (xy 189.848497 -410.953745)
			(xy 189.844424 -410.898086) (xy 187.250567 -410.898086) (xy 187.246151 -410.907506) (xy 187.215378 -410.954019)
			(xy 187.178161 -410.995556) (xy 187.135293 -411.031231) (xy 187.087687 -411.060285) (xy 187.036358 -411.082097)
			(xy 186.982401 -411.096203) (xy 186.926964 -411.102303) (xy 186.87123 -411.100266) (xy 186.816387 -411.090136)
			(xy 186.763603 -411.072129) (xy 186.714003 -411.046628) (xy 186.668645 -411.014177) (xy 186.628496 -410.975468)
			(xy 186.59441 -410.931325) (xy 186.567114 -410.88269) (xy 186.547191 -410.830599) (xy 186.535065 -410.776162)
			(xy 186.530994 -410.72054) (xy 186.207196 -410.72054) (xy 186.218353 -410.727349) (xy 186.261221 -410.763024)
			(xy 186.298438 -410.804561) (xy 186.329211 -410.851074) (xy 186.352883 -410.901571) (xy 186.368951 -410.954978)
			(xy 186.377071 -411.010154) (xy 186.37758 -411.03804) (xy 186.377071 -411.065926) (xy 186.368951 -411.121102)
			(xy 186.352883 -411.174509) (xy 186.329211 -411.225006) (xy 186.298438 -411.271519) (xy 186.261221 -411.313056)
			(xy 186.253817 -411.319218) (xy 193.336162 -411.319218) (xy 193.340235 -411.263559) (xy 193.35237 -411.209086)
			(xy 193.372306 -411.15696) (xy 193.39962 -411.108292) (xy 193.433728 -411.06412) (xy 193.473905 -411.025385)
			(xy 193.519293 -410.992913) (xy 193.568925 -410.967395) (xy 193.621745 -410.949376) (xy 193.676624 -410.939239)
			(xy 193.732395 -410.937201) (xy 193.787869 -410.943304) (xy 193.841862 -410.95742) (xy 193.893225 -410.979247)
			(xy 193.940863 -411.00832) (xy 193.983759 -411.044019) (xy 194.021001 -411.085583) (xy 194.051795 -411.132127)
			(xy 194.075483 -411.182658) (xy 194.091561 -411.2361) (xy 194.099687 -411.291314) (xy 194.100196 -411.319218)
			(xy 194.099687 -411.347122) (xy 194.091561 -411.402336) (xy 194.075483 -411.455778) (xy 194.051795 -411.506309)
			(xy 194.050884 -411.507686) (xy 198.319134 -411.507686) (xy 198.323207 -411.452027) (xy 198.335342 -411.397554)
			(xy 198.355278 -411.345428) (xy 198.382592 -411.29676) (xy 198.4167 -411.252588) (xy 198.456877 -411.213853)
			(xy 198.502265 -411.181381) (xy 198.551897 -411.155863) (xy 198.604717 -411.137844) (xy 198.659596 -411.127707)
			(xy 198.715367 -411.125669) (xy 198.770841 -411.131772) (xy 198.824834 -411.145888) (xy 198.876197 -411.167715)
			(xy 198.923835 -411.196788) (xy 198.966731 -411.232487) (xy 199.003973 -411.274051) (xy 199.034767 -411.320595)
			(xy 199.058455 -411.371126) (xy 199.074533 -411.424568) (xy 199.082659 -411.479782) (xy 199.083168 -411.507686)
			(xy 199.082659 -411.53559) (xy 199.074533 -411.590804) (xy 199.058455 -411.644246) (xy 199.034767 -411.694777)
			(xy 199.003973 -411.741321) (xy 198.966731 -411.782885) (xy 198.923835 -411.818584) (xy 198.876197 -411.847657)
			(xy 198.824834 -411.869484) (xy 198.770841 -411.8836) (xy 198.715367 -411.889703) (xy 198.659596 -411.887665)
			(xy 198.604717 -411.877528) (xy 198.551897 -411.859509) (xy 198.502265 -411.833991) (xy 198.456877 -411.801519)
			(xy 198.4167 -411.762784) (xy 198.382592 -411.718612) (xy 198.355278 -411.669944) (xy 198.335342 -411.617818)
			(xy 198.323207 -411.563345) (xy 198.319134 -411.507686) (xy 194.050884 -411.507686) (xy 194.021001 -411.552853)
			(xy 193.983759 -411.594417) (xy 193.940863 -411.630116) (xy 193.893225 -411.659189) (xy 193.841862 -411.681016)
			(xy 193.787869 -411.695132) (xy 193.732395 -411.701235) (xy 193.676624 -411.699197) (xy 193.621745 -411.68906)
			(xy 193.568925 -411.671041) (xy 193.519293 -411.645523) (xy 193.473905 -411.613051) (xy 193.433728 -411.574316)
			(xy 193.39962 -411.530144) (xy 193.372306 -411.481476) (xy 193.35237 -411.42935) (xy 193.340235 -411.374877)
			(xy 193.336162 -411.319218) (xy 186.253817 -411.319218) (xy 186.218353 -411.348731) (xy 186.170747 -411.377785)
			(xy 186.119418 -411.399597) (xy 186.065461 -411.413703) (xy 186.010024 -411.419803) (xy 185.95429 -411.417766)
			(xy 185.899447 -411.407636) (xy 185.846663 -411.389629) (xy 185.797063 -411.364128) (xy 185.751705 -411.331677)
			(xy 185.711556 -411.292968) (xy 185.67747 -411.248825) (xy 185.650174 -411.20019) (xy 185.630251 -411.148099)
			(xy 185.618125 -411.093662) (xy 185.614054 -411.03804) (xy 185.023252 -411.03804) (xy 185.023252 -411.99181)
			(xy 188.010798 -411.99181) (xy 188.014871 -411.936151) (xy 188.027006 -411.881678) (xy 188.046942 -411.829552)
			(xy 188.074256 -411.780884) (xy 188.108364 -411.736712) (xy 188.148541 -411.697977) (xy 188.193929 -411.665505)
			(xy 188.243561 -411.639987) (xy 188.296381 -411.621968) (xy 188.35126 -411.611831) (xy 188.407031 -411.609793)
			(xy 188.462505 -411.615896) (xy 188.516498 -411.630012) (xy 188.567861 -411.651839) (xy 188.615499 -411.680912)
			(xy 188.658395 -411.716611) (xy 188.695637 -411.758175) (xy 188.726431 -411.804719) (xy 188.750119 -411.85525)
			(xy 188.766197 -411.908692) (xy 188.774323 -411.963906) (xy 188.774832 -411.99181) (xy 188.774323 -412.019714)
			(xy 188.766197 -412.074928) (xy 188.750703 -412.12643) (xy 197.241158 -412.12643) (xy 197.245231 -412.070771)
			(xy 197.257366 -412.016298) (xy 197.277302 -411.964172) (xy 197.304616 -411.915504) (xy 197.338724 -411.871332)
			(xy 197.378901 -411.832597) (xy 197.424289 -411.800125) (xy 197.473921 -411.774607) (xy 197.526741 -411.756588)
			(xy 197.58162 -411.746451) (xy 197.637391 -411.744413) (xy 197.692865 -411.750516) (xy 197.746858 -411.764632)
			(xy 197.798221 -411.786459) (xy 197.845859 -411.815532) (xy 197.888755 -411.851231) (xy 197.925997 -411.892795)
			(xy 197.956791 -411.939339) (xy 197.980479 -411.98987) (xy 197.996557 -412.043312) (xy 198.004683 -412.098526)
			(xy 198.005192 -412.12643) (xy 198.004683 -412.154334) (xy 197.996557 -412.209548) (xy 197.980479 -412.26299)
			(xy 197.956791 -412.313521) (xy 197.925997 -412.360065) (xy 197.888755 -412.401629) (xy 197.845859 -412.437328)
			(xy 197.798221 -412.466401) (xy 197.746858 -412.488228) (xy 197.692865 -412.502344) (xy 197.637391 -412.508447)
			(xy 197.58162 -412.506409) (xy 197.526741 -412.496272) (xy 197.473921 -412.478253) (xy 197.424289 -412.452735)
			(xy 197.378901 -412.420263) (xy 197.338724 -412.381528) (xy 197.304616 -412.337356) (xy 197.277302 -412.288688)
			(xy 197.257366 -412.236562) (xy 197.245231 -412.182089) (xy 197.241158 -412.12643) (xy 188.750703 -412.12643)
			(xy 188.750119 -412.12837) (xy 188.726431 -412.178901) (xy 188.695637 -412.225445) (xy 188.658395 -412.267009)
			(xy 188.615499 -412.302708) (xy 188.567861 -412.331781) (xy 188.516498 -412.353608) (xy 188.462505 -412.367724)
			(xy 188.407031 -412.373827) (xy 188.35126 -412.371789) (xy 188.296381 -412.361652) (xy 188.243561 -412.343633)
			(xy 188.193929 -412.318115) (xy 188.148541 -412.285643) (xy 188.108364 -412.246908) (xy 188.074256 -412.202736)
			(xy 188.046942 -412.154068) (xy 188.027006 -412.101942) (xy 188.014871 -412.047469) (xy 188.010798 -411.99181)
			(xy 185.023252 -411.99181) (xy 185.023252 -412.362396) (xy 185.035444 -412.384748) (xy 185.046366 -412.39186)
			(xy 185.117232 -412.438342) (xy 185.12917 -412.444184) (xy 185.129424 -412.444184) (xy 185.133258 -412.445348)
			(xy 185.141167 -412.446621) (xy 185.145172 -412.446724) (xy 185.165746 -412.442406) (xy 185.189913 -412.432301)
			(xy 185.240324 -412.418065) (xy 185.292209 -412.410865) (xy 185.3184 -412.410402) (xy 185.34565 -412.410888)
			(xy 185.399597 -412.418645) (xy 185.45189 -412.433999) (xy 185.501466 -412.45664) (xy 185.547315 -412.486105)
			(xy 185.588504 -412.521796) (xy 185.624195 -412.562985) (xy 185.65366 -412.608834) (xy 185.676301 -412.65841)
			(xy 185.691655 -412.710703) (xy 185.699412 -412.76465) (xy 185.699412 -412.81915) (xy 185.691655 -412.873097)
			(xy 185.676301 -412.92539) (xy 185.65366 -412.974966) (xy 185.624195 -413.020815) (xy 185.588504 -413.062004)
			(xy 185.547315 -413.097695) (xy 185.501466 -413.12716) (xy 185.45189 -413.149801) (xy 185.399597 -413.165155)
			(xy 185.34565 -413.172912) (xy 185.3184 -413.173418) (xy 185.317892 -413.173418) (xy 185.2917 -413.17297)
			(xy 185.239812 -413.165771) (xy 185.189399 -413.151537) (xy 185.165238 -413.141414) (xy 185.1533 -413.13608)
			(xy 185.1279 -413.138112) (xy 185.046366 -413.19196) (xy 185.035444 -413.199072) (xy 185.023252 -413.221424)
			(xy 185.023252 -413.249872) (xy 185.023721 -413.259746) (xy 185.031172 -413.278035) (xy 185.03773 -413.285432)
			(xy 185.231532 -413.479234) (xy 189.505588 -413.479234) (xy 189.509661 -413.423575) (xy 189.521796 -413.369102)
			(xy 189.541732 -413.316976) (xy 189.569046 -413.268308) (xy 189.603154 -413.224136) (xy 189.643331 -413.185401)
			(xy 189.688719 -413.152929) (xy 189.738351 -413.127411) (xy 189.791171 -413.109392) (xy 189.84605 -413.099255)
			(xy 189.901821 -413.097217) (xy 189.957295 -413.10332) (xy 190.011288 -413.117436) (xy 190.062651 -413.139263)
			(xy 190.110289 -413.168336) (xy 190.153185 -413.204035) (xy 190.190427 -413.245599) (xy 190.221221 -413.292143)
			(xy 190.244909 -413.342674) (xy 190.260987 -413.396116) (xy 190.269113 -413.45133) (xy 190.269622 -413.479234)
			(xy 190.663828 -413.479234) (xy 190.667901 -413.423575) (xy 190.680036 -413.369102) (xy 190.699972 -413.316976)
			(xy 190.727286 -413.268308) (xy 190.761394 -413.224136) (xy 190.801571 -413.185401) (xy 190.846959 -413.152929)
			(xy 190.896591 -413.127411) (xy 190.949411 -413.109392) (xy 191.00429 -413.099255) (xy 191.060061 -413.097217)
			(xy 191.115535 -413.10332) (xy 191.169528 -413.117436) (xy 191.220891 -413.139263) (xy 191.268529 -413.168336)
			(xy 191.311425 -413.204035) (xy 191.348667 -413.245599) (xy 191.379461 -413.292143) (xy 191.403149 -413.342674)
			(xy 191.409617 -413.364172) (xy 196.168516 -413.364172) (xy 196.172589 -413.308513) (xy 196.184724 -413.25404)
			(xy 196.20466 -413.201914) (xy 196.231974 -413.153246) (xy 196.266082 -413.109074) (xy 196.306259 -413.070339)
			(xy 196.351647 -413.037867) (xy 196.401279 -413.012349) (xy 196.454099 -412.99433) (xy 196.508978 -412.984193)
			(xy 196.564749 -412.982155) (xy 196.620223 -412.988258) (xy 196.674216 -413.002374) (xy 196.725579 -413.024201)
			(xy 196.773217 -413.053274) (xy 196.816113 -413.088973) (xy 196.853355 -413.130537) (xy 196.884149 -413.177081)
			(xy 196.907837 -413.227612) (xy 196.923915 -413.281054) (xy 196.932041 -413.336268) (xy 196.93255 -413.364172)
			(xy 197.32066 -413.364172) (xy 197.324733 -413.308513) (xy 197.336868 -413.25404) (xy 197.356804 -413.201914)
			(xy 197.384118 -413.153246) (xy 197.418226 -413.109074) (xy 197.458403 -413.070339) (xy 197.503791 -413.037867)
			(xy 197.553423 -413.012349) (xy 197.606243 -412.99433) (xy 197.661122 -412.984193) (xy 197.716893 -412.982155)
			(xy 197.772367 -412.988258) (xy 197.82636 -413.002374) (xy 197.877723 -413.024201) (xy 197.925361 -413.053274)
			(xy 197.968257 -413.088973) (xy 198.005499 -413.130537) (xy 198.036293 -413.177081) (xy 198.059981 -413.227612)
			(xy 198.076059 -413.281054) (xy 198.084185 -413.336268) (xy 198.084694 -413.364172) (xy 198.084185 -413.392076)
			(xy 198.076059 -413.44729) (xy 198.059981 -413.500732) (xy 198.036293 -413.551263) (xy 198.005499 -413.597807)
			(xy 197.968257 -413.639371) (xy 197.925361 -413.67507) (xy 197.877723 -413.704143) (xy 197.82636 -413.72597)
			(xy 197.772367 -413.740086) (xy 197.716893 -413.746189) (xy 197.661122 -413.744151) (xy 197.606243 -413.734014)
			(xy 197.553423 -413.715995) (xy 197.503791 -413.690477) (xy 197.458403 -413.658005) (xy 197.418226 -413.61927)
			(xy 197.384118 -413.575098) (xy 197.356804 -413.52643) (xy 197.336868 -413.474304) (xy 197.324733 -413.419831)
			(xy 197.32066 -413.364172) (xy 196.93255 -413.364172) (xy 196.932041 -413.392076) (xy 196.923915 -413.44729)
			(xy 196.907837 -413.500732) (xy 196.884149 -413.551263) (xy 196.853355 -413.597807) (xy 196.816113 -413.639371)
			(xy 196.773217 -413.67507) (xy 196.725579 -413.704143) (xy 196.674216 -413.72597) (xy 196.620223 -413.740086)
			(xy 196.564749 -413.746189) (xy 196.508978 -413.744151) (xy 196.454099 -413.734014) (xy 196.401279 -413.715995)
			(xy 196.351647 -413.690477) (xy 196.306259 -413.658005) (xy 196.266082 -413.61927) (xy 196.231974 -413.575098)
			(xy 196.20466 -413.52643) (xy 196.184724 -413.474304) (xy 196.172589 -413.419831) (xy 196.168516 -413.364172)
			(xy 191.409617 -413.364172) (xy 191.419227 -413.396116) (xy 191.427353 -413.45133) (xy 191.427862 -413.479234)
			(xy 191.427353 -413.507138) (xy 191.419227 -413.562352) (xy 191.403149 -413.615794) (xy 191.379461 -413.666325)
			(xy 191.348667 -413.712869) (xy 191.311425 -413.754433) (xy 191.268529 -413.790132) (xy 191.220891 -413.819205)
			(xy 191.169528 -413.841032) (xy 191.115535 -413.855148) (xy 191.060061 -413.861251) (xy 191.00429 -413.859213)
			(xy 190.949411 -413.849076) (xy 190.896591 -413.831057) (xy 190.846959 -413.805539) (xy 190.801571 -413.773067)
			(xy 190.761394 -413.734332) (xy 190.727286 -413.69016) (xy 190.699972 -413.641492) (xy 190.680036 -413.589366)
			(xy 190.667901 -413.534893) (xy 190.663828 -413.479234) (xy 190.269622 -413.479234) (xy 190.269113 -413.507138)
			(xy 190.260987 -413.562352) (xy 190.244909 -413.615794) (xy 190.221221 -413.666325) (xy 190.190427 -413.712869)
			(xy 190.153185 -413.754433) (xy 190.110289 -413.790132) (xy 190.062651 -413.819205) (xy 190.011288 -413.841032)
			(xy 189.957295 -413.855148) (xy 189.901821 -413.861251) (xy 189.84605 -413.859213) (xy 189.791171 -413.849076)
			(xy 189.738351 -413.831057) (xy 189.688719 -413.805539) (xy 189.643331 -413.773067) (xy 189.603154 -413.734332)
			(xy 189.569046 -413.69016) (xy 189.541732 -413.641492) (xy 189.521796 -413.589366) (xy 189.509661 -413.534893)
			(xy 189.505588 -413.479234) (xy 185.231532 -413.479234) (xy 185.854594 -414.102296) (xy 185.855102 -414.102804)
			(xy 185.862483 -414.109384) (xy 185.880783 -414.116824) (xy 185.890662 -414.117282)
		)
		(stroke
			(width 0)
			(type solid)
		)
		(fill yes)
		(layer "In9.Cu")
		(net "P12V_AUX")
	)
	(gr_poly
		(pts
			(xy 374.519952 -301.460662) (xy 374.524971 -301.460569) (xy 374.534822 -301.458648) (xy 374.53951 -301.456852)
			(xy 375.581418 -301.024798) (xy 375.597928 -301.0027) (xy 375.599452 -300.98873) (xy 375.603106 -300.961141)
			(xy 375.617373 -300.907351) (xy 375.639297 -300.856201) (xy 375.668416 -300.808776) (xy 375.70411 -300.766081)
			(xy 375.745625 -300.72902) (xy 375.79208 -300.698379) (xy 375.842491 -300.674806) (xy 375.895791 -300.658802)
			(xy 375.950849 -300.650705) (xy 375.978674 -300.650148) (xy 375.978674 -300.649894) (xy 376.007543 -300.650421)
			(xy 376.064625 -300.659106) (xy 376.11975 -300.676283) (xy 376.171662 -300.701561) (xy 376.219178 -300.734363)
			(xy 376.240548 -300.75378) (xy 376.249946 -300.76267) (xy 376.274076 -300.769274) (xy 376.550936 -300.706028)
			(xy 376.557854 -300.704182) (xy 376.57036 -300.69722) (xy 376.575574 -300.692312) (xy 380.022862 -297.245024)
			(xy 380.029152 -297.238078) (xy 380.036684 -297.220938) (xy 380.037569 -297.202236) (xy 380.035054 -297.193208)
			(xy 380.002034 -297.093132) (xy 379.979936 -297.074844) (xy 379.965458 -297.072812) (xy 379.938005 -297.06837)
			(xy 379.884683 -297.052576) (xy 379.834218 -297.029211) (xy 379.787678 -296.998769) (xy 379.746049 -296.961895)
			(xy 379.710212 -296.91937) (xy 379.680925 -296.872095) (xy 379.65881 -296.82107) (xy 379.644333 -296.767375)
			(xy 379.640592 -296.739818) (xy 379.639576 -296.729912) (xy 379.637798 -296.695368) (xy 379.637798 -296.69486)
			(xy 379.638359 -296.665448) (xy 379.647417 -296.607326) (xy 379.665283 -296.551281) (xy 379.691534 -296.498639)
			(xy 379.725548 -296.450647) (xy 379.76652 -296.408439) (xy 379.78969 -296.390314) (xy 379.789944 -296.39006)
			(xy 379.798847 -296.382565) (xy 379.809298 -296.361798) (xy 379.81001 -296.350182) (xy 379.810518 -296.311066)
			(xy 379.810518 -296.310558) (xy 379.810772 -296.270426) (xy 379.81024 -296.259157) (xy 379.800768 -296.238711)
			(xy 379.792484 -296.231056) (xy 379.791976 -296.230548) (xy 379.791722 -296.230294) (xy 379.769926 -296.212075)
			(xy 379.73145 -296.170284) (xy 379.699598 -296.123247) (xy 379.675075 -296.072007) (xy 379.658423 -296.017697)
			(xy 379.65001 -295.961517) (xy 379.649482 -295.933114) (xy 379.649944 -295.90586) (xy 379.657699 -295.851907)
			(xy 379.673054 -295.799607) (xy 379.695696 -295.750024) (xy 379.725163 -295.704169) (xy 379.760857 -295.662974)
			(xy 379.80205 -295.627277) (xy 379.847903 -295.597807) (xy 379.897484 -295.575162) (xy 379.949784 -295.559804)
			(xy 380.003736 -295.552046) (xy 380.03099 -295.551606) (xy 380.058727 -295.55211) (xy 380.113614 -295.560153)
			(xy 380.166759 -295.576057) (xy 380.217042 -295.599486) (xy 380.263403 -295.629948) (xy 380.304867 -295.6668)
			(xy 380.340559 -295.709266) (xy 380.369728 -295.756451) (xy 380.39176 -295.807362) (xy 380.40619 -295.860926)
			(xy 380.409958 -295.88841) (xy 380.411482 -295.902126) (xy 380.413234 -295.929516) (xy 380.409808 -295.984294)
			(xy 380.398575 -296.038016) (xy 380.379766 -296.089577) (xy 380.353768 -296.137913) (xy 380.321118 -296.182029)
			(xy 380.282488 -296.221016) (xy 380.26086 -296.237914) (xy 380.260606 -296.238168) (xy 380.251701 -296.245661)
			(xy 380.24125 -296.266429) (xy 380.24054 -296.278046) (xy 380.240032 -296.317162) (xy 380.240032 -296.31767)
			(xy 380.239778 -296.357802) (xy 380.240317 -296.369067) (xy 380.249802 -296.389498) (xy 380.258066 -296.397172)
			(xy 380.258574 -296.39768) (xy 380.258828 -296.397934) (xy 380.280357 -296.415898) (xy 380.318414 -296.457075)
			(xy 380.350026 -296.503383) (xy 380.374512 -296.553824) (xy 380.391342 -296.607308) (xy 380.396242 -296.634916)
			(xy 380.397512 -296.64152) (xy 380.403608 -296.655236) (xy 380.408364 -296.664552) (xy 380.423846 -296.678584)
			(xy 380.43358 -296.682414) (xy 380.517654 -296.710608) (xy 380.526731 -296.71323) (xy 380.54559 -296.712309)
			(xy 380.562838 -296.704629) (xy 380.569724 -296.698162) (xy 382.697228 -294.570658) (xy 382.703271 -294.564193)
			(xy 382.710802 -294.548191) (xy 382.71196 -294.539416) (xy 382.712214 -294.536876) (xy 382.712214 -293.867332)
			(xy 382.71196 -293.863014) (xy 382.710182 -293.841932) (xy 382.678178 -293.814754) (xy 382.670304 -293.815262)
			(xy 382.64211 -293.8018) (xy 382.641602 -293.8018) (xy 382.614424 -293.788846) (xy 382.584452 -293.79291)
			(xy 382.573022 -293.80307) (xy 382.550509 -293.822135) (xy 382.501037 -293.854271) (xy 382.447464 -293.87897)
			(xy 382.3909 -293.895723) (xy 382.332517 -293.904181) (xy 382.30302 -293.90467) (xy 382.274448 -293.904176)
			(xy 382.217857 -293.896243) (xy 382.162917 -293.880527) (xy 382.110692 -293.857334) (xy 382.062193 -293.827113)
			(xy 382.018362 -293.790449) (xy 381.980047 -293.748053) (xy 381.947992 -293.700747) (xy 381.934974 -293.675308)
			(xy 381.928624 -293.662608) (xy 381.904494 -293.647114) (xy 381.785368 -293.645336) (xy 381.76073 -293.660068)
			(xy 381.753872 -293.672768) (xy 381.739585 -293.698681) (xy 381.704242 -293.746137) (xy 381.66199 -293.78756)
			(xy 381.613843 -293.821956) (xy 381.560959 -293.848497) (xy 381.504609 -293.866546) (xy 381.446146 -293.875669)
			(xy 381.41656 -293.876222) (xy 381.38931 -293.875733) (xy 381.335364 -293.867972) (xy 381.283072 -293.852613)
			(xy 381.233498 -293.829969) (xy 381.187651 -293.8005) (xy 381.146464 -293.764807) (xy 381.110776 -293.723617)
			(xy 381.081312 -293.677766) (xy 381.058673 -293.62819) (xy 381.043319 -293.575897) (xy 381.035564 -293.52195)
			(xy 381.035564 -293.46745) (xy 381.043319 -293.413503) (xy 381.058673 -293.36121) (xy 381.081312 -293.311634)
			(xy 381.110776 -293.265783) (xy 381.146464 -293.224593) (xy 381.187651 -293.1889) (xy 381.233498 -293.159431)
			(xy 381.283072 -293.136787) (xy 381.335364 -293.121428) (xy 381.38931 -293.113667) (xy 381.41656 -293.113206)
			(xy 381.446142 -293.113768) (xy 381.504595 -293.122914) (xy 381.560934 -293.140976) (xy 381.613809 -293.167521)
			(xy 381.66195 -293.201913) (xy 381.704203 -293.243326) (xy 381.739554 -293.290767) (xy 381.753872 -293.31666)
			(xy 381.76073 -293.32936) (xy 381.785368 -293.344092) (xy 381.904494 -293.342314) (xy 381.928624 -293.32682)
			(xy 381.934974 -293.31412) (xy 381.948004 -293.288688) (xy 381.980057 -293.241381) (xy 382.018369 -293.198984)
			(xy 382.062198 -293.162319) (xy 382.110695 -293.132096) (xy 382.162919 -293.108902) (xy 382.217859 -293.093186)
			(xy 382.274448 -293.085252) (xy 382.30302 -293.084758) (xy 382.332515 -293.085273) (xy 382.390894 -293.093737)
			(xy 382.447455 -293.110488) (xy 382.501029 -293.135178) (xy 382.550507 -293.167298) (xy 382.573022 -293.186358)
			(xy 382.584452 -293.196518) (xy 382.614424 -293.200582) (xy 382.641602 -293.187628) (xy 382.64211 -293.187628)
			(xy 382.683512 -293.167562) (xy 382.691916 -293.163065) (xy 382.704862 -293.149094) (xy 382.711823 -293.131365)
			(xy 382.712214 -293.121842) (xy 382.712214 -290.666932) (xy 382.71196 -290.662614) (xy 382.710182 -290.641532)
			(xy 382.678178 -290.614354) (xy 382.670304 -290.614862) (xy 382.64211 -290.6014) (xy 382.641602 -290.6014)
			(xy 382.614424 -290.588446) (xy 382.584452 -290.59251) (xy 382.573022 -290.60267) (xy 382.550509 -290.621735)
			(xy 382.501037 -290.653871) (xy 382.447464 -290.67857) (xy 382.3909 -290.695323) (xy 382.332517 -290.703781)
			(xy 382.30302 -290.70427) (xy 382.274448 -290.703776) (xy 382.217857 -290.695843) (xy 382.162917 -290.680127)
			(xy 382.110692 -290.656934) (xy 382.062193 -290.626713) (xy 382.018362 -290.590049) (xy 381.980047 -290.547653)
			(xy 381.947992 -290.500347) (xy 381.934974 -290.474908) (xy 381.928624 -290.462208) (xy 381.904494 -290.446714)
			(xy 381.785368 -290.444936) (xy 381.76073 -290.459668) (xy 381.753872 -290.472368) (xy 381.739585 -290.498281)
			(xy 381.704242 -290.545737) (xy 381.66199 -290.58716) (xy 381.613843 -290.621556) (xy 381.560959 -290.648097)
			(xy 381.504609 -290.666146) (xy 381.446146 -290.675269) (xy 381.41656 -290.675822) (xy 381.38931 -290.675333)
			(xy 381.335364 -290.667572) (xy 381.283072 -290.652213) (xy 381.233498 -290.629569) (xy 381.187651 -290.6001)
			(xy 381.146464 -290.564407) (xy 381.110776 -290.523217) (xy 381.081312 -290.477366) (xy 381.058673 -290.42779)
			(xy 381.043319 -290.375497) (xy 381.035564 -290.32155) (xy 381.035564 -290.26705) (xy 381.043319 -290.213103)
			(xy 381.058673 -290.16081) (xy 381.081312 -290.111234) (xy 381.110776 -290.065383) (xy 381.146464 -290.024193)
			(xy 381.187651 -289.9885) (xy 381.233498 -289.959031) (xy 381.283072 -289.936387) (xy 381.335364 -289.921028)
			(xy 381.38931 -289.913267) (xy 381.41656 -289.912806) (xy 381.446142 -289.913368) (xy 381.504595 -289.922514)
			(xy 381.560934 -289.940576) (xy 381.613809 -289.967121) (xy 381.66195 -290.001513) (xy 381.704203 -290.042926)
			(xy 381.739554 -290.090367) (xy 381.753872 -290.11626) (xy 381.76073 -290.12896) (xy 381.785368 -290.143692)
			(xy 381.904494 -290.141914) (xy 381.928624 -290.12642) (xy 381.934974 -290.11372) (xy 381.948004 -290.088288)
			(xy 381.980057 -290.040981) (xy 382.018369 -289.998584) (xy 382.062198 -289.961919) (xy 382.110695 -289.931696)
			(xy 382.162919 -289.908502) (xy 382.217859 -289.892786) (xy 382.274448 -289.884852) (xy 382.30302 -289.884358)
			(xy 382.332515 -289.884873) (xy 382.390894 -289.893337) (xy 382.447455 -289.910088) (xy 382.501029 -289.934778)
			(xy 382.550507 -289.966898) (xy 382.573022 -289.985958) (xy 382.584452 -289.996118) (xy 382.614424 -290.000182)
			(xy 382.641602 -289.987228) (xy 382.64211 -289.987228) (xy 382.683512 -289.967162) (xy 382.691916 -289.962665)
			(xy 382.704862 -289.948694) (xy 382.711823 -289.930965) (xy 382.712214 -289.921442) (xy 382.712214 -287.466532)
			(xy 382.71196 -287.462214) (xy 382.710182 -287.441132) (xy 382.678178 -287.413954) (xy 382.670304 -287.414462)
			(xy 382.64211 -287.401) (xy 382.641602 -287.401) (xy 382.614424 -287.388046) (xy 382.584452 -287.39211)
			(xy 382.573022 -287.40227) (xy 382.550509 -287.421335) (xy 382.501037 -287.453471) (xy 382.447464 -287.47817)
			(xy 382.3909 -287.494923) (xy 382.332517 -287.503381) (xy 382.30302 -287.50387) (xy 382.274448 -287.503376)
			(xy 382.217857 -287.495443) (xy 382.162917 -287.479727) (xy 382.110692 -287.456534) (xy 382.062193 -287.426313)
			(xy 382.018362 -287.389649) (xy 381.980047 -287.347253) (xy 381.947992 -287.299947) (xy 381.934974 -287.274508)
			(xy 381.928624 -287.261808) (xy 381.904494 -287.246314) (xy 381.785368 -287.244536) (xy 381.76073 -287.259268)
			(xy 381.753872 -287.271968) (xy 381.739585 -287.297881) (xy 381.704242 -287.345337) (xy 381.66199 -287.38676)
			(xy 381.613843 -287.421156) (xy 381.560959 -287.447697) (xy 381.504609 -287.465746) (xy 381.446146 -287.474869)
			(xy 381.41656 -287.475422) (xy 381.38931 -287.474933) (xy 381.335364 -287.467172) (xy 381.283072 -287.451813)
			(xy 381.233498 -287.429169) (xy 381.187651 -287.3997) (xy 381.146464 -287.364007) (xy 381.110776 -287.322817)
			(xy 381.081312 -287.276966) (xy 381.058673 -287.22739) (xy 381.043319 -287.175097) (xy 381.035564 -287.12115)
			(xy 381.035564 -287.06665) (xy 381.043319 -287.012703) (xy 381.058673 -286.96041) (xy 381.081312 -286.910834)
			(xy 381.110776 -286.864983) (xy 381.146464 -286.823793) (xy 381.187651 -286.7881) (xy 381.233498 -286.758631)
			(xy 381.283072 -286.735987) (xy 381.335364 -286.720628) (xy 381.38931 -286.712867) (xy 381.41656 -286.712406)
			(xy 381.446142 -286.712968) (xy 381.504595 -286.722114) (xy 381.560934 -286.740176) (xy 381.613809 -286.766721)
			(xy 381.66195 -286.801113) (xy 381.704203 -286.842526) (xy 381.739554 -286.889967) (xy 381.753872 -286.91586)
			(xy 381.76073 -286.92856) (xy 381.785368 -286.943292) (xy 381.904494 -286.941514) (xy 381.928624 -286.92602)
			(xy 381.934974 -286.91332) (xy 381.948004 -286.887888) (xy 381.980057 -286.840581) (xy 382.018369 -286.798184)
			(xy 382.062198 -286.761519) (xy 382.110695 -286.731296) (xy 382.162919 -286.708102) (xy 382.217859 -286.692386)
			(xy 382.274448 -286.684452) (xy 382.30302 -286.683958) (xy 382.332515 -286.684473) (xy 382.390894 -286.692937)
			(xy 382.447455 -286.709688) (xy 382.501029 -286.734378) (xy 382.550507 -286.766498) (xy 382.573022 -286.785558)
			(xy 382.584452 -286.795718) (xy 382.614424 -286.799782) (xy 382.641602 -286.786828) (xy 382.64211 -286.786828)
			(xy 382.683512 -286.766762) (xy 382.691916 -286.762265) (xy 382.704862 -286.748294) (xy 382.711823 -286.730565)
			(xy 382.712214 -286.721042) (xy 382.712214 -284.266132) (xy 382.71196 -284.261814) (xy 382.710182 -284.240732)
			(xy 382.678178 -284.213554) (xy 382.670304 -284.214062) (xy 382.64211 -284.2006) (xy 382.641602 -284.2006)
			(xy 382.614424 -284.187646) (xy 382.584452 -284.19171) (xy 382.573022 -284.20187) (xy 382.550509 -284.220935)
			(xy 382.501037 -284.253071) (xy 382.447464 -284.27777) (xy 382.3909 -284.294523) (xy 382.332517 -284.302981)
			(xy 382.30302 -284.30347) (xy 382.274448 -284.302976) (xy 382.217857 -284.295043) (xy 382.162917 -284.279327)
			(xy 382.110692 -284.256134) (xy 382.062193 -284.225913) (xy 382.018362 -284.189249) (xy 381.980047 -284.146853)
			(xy 381.947992 -284.099547) (xy 381.934974 -284.074108) (xy 381.928624 -284.061408) (xy 381.904494 -284.045914)
			(xy 381.785368 -284.044136) (xy 381.76073 -284.058868) (xy 381.753872 -284.071568) (xy 381.739585 -284.097481)
			(xy 381.704242 -284.144937) (xy 381.66199 -284.18636) (xy 381.613843 -284.220756) (xy 381.560959 -284.247297)
			(xy 381.504609 -284.265346) (xy 381.446146 -284.274469) (xy 381.41656 -284.275022) (xy 381.38931 -284.274533)
			(xy 381.335364 -284.266772) (xy 381.283072 -284.251413) (xy 381.233498 -284.228769) (xy 381.187651 -284.1993)
			(xy 381.146464 -284.163607) (xy 381.110776 -284.122417) (xy 381.081312 -284.076566) (xy 381.058673 -284.02699)
			(xy 381.043319 -283.974697) (xy 381.035564 -283.92075) (xy 381.035564 -283.86625) (xy 381.043319 -283.812303)
			(xy 381.058673 -283.76001) (xy 381.081312 -283.710434) (xy 381.110776 -283.664583) (xy 381.146464 -283.623393)
			(xy 381.187651 -283.5877) (xy 381.233498 -283.558231) (xy 381.283072 -283.535587) (xy 381.335364 -283.520228)
			(xy 381.38931 -283.512467) (xy 381.41656 -283.512006) (xy 381.446142 -283.512568) (xy 381.504595 -283.521714)
			(xy 381.560934 -283.539776) (xy 381.613809 -283.566321) (xy 381.66195 -283.600713) (xy 381.704203 -283.642126)
			(xy 381.739554 -283.689567) (xy 381.753872 -283.71546) (xy 381.76073 -283.72816) (xy 381.785368 -283.742892)
			(xy 381.904494 -283.741114) (xy 381.928624 -283.72562) (xy 381.934974 -283.71292) (xy 381.948004 -283.687488)
			(xy 381.980057 -283.640181) (xy 382.018369 -283.597784) (xy 382.062198 -283.561119) (xy 382.110695 -283.530896)
			(xy 382.162919 -283.507702) (xy 382.217859 -283.491986) (xy 382.274448 -283.484052) (xy 382.30302 -283.483558)
			(xy 382.331617 -283.484057) (xy 382.388256 -283.492012) (xy 382.443239 -283.507765) (xy 382.495497 -283.531011)
			(xy 382.544015 -283.561296) (xy 382.587851 -283.598034) (xy 382.626153 -283.64051) (xy 382.642618 -283.663898)
			(xy 382.649222 -283.673804) (xy 382.669288 -283.685488) (xy 382.72085 -283.689044) (xy 382.731756 -283.689306)
			(xy 382.752168 -283.681672) (xy 382.76022 -283.674312) (xy 384.36677 -282.067762) (xy 384.374898 -282.057094)
			(xy 384.378454 -282.050998) (xy 384.380232 -282.044394) (xy 384.386328 -282.023562) (xy 384.403603 -281.983745)
			(xy 384.426352 -281.946781) (xy 384.439922 -281.92984) (xy 384.440176 -281.92984) (xy 384.455195 -281.912405)
			(xy 384.489569 -281.881813) (xy 384.528143 -281.856723) (xy 384.570043 -281.837701) (xy 384.592068 -281.831034)
			(xy 384.595624 -281.830018) (xy 384.601733 -281.828021) (xy 384.612785 -281.821467) (xy 384.617468 -281.817064)
			(xy 385.31673 -281.117802) (xy 385.324858 -281.107134) (xy 385.328414 -281.101038) (xy 385.330192 -281.094434)
			(xy 385.336284 -281.0736) (xy 385.353553 -281.033778) (xy 385.376297 -280.996809) (xy 385.389882 -280.97988)
			(xy 385.390136 -280.97988) (xy 385.405156 -280.962446) (xy 385.439531 -280.931856) (xy 385.478104 -280.906765)
			(xy 385.520004 -280.887742) (xy 385.542028 -280.881074) (xy 385.545584 -280.880058) (xy 385.551694 -280.878062)
			(xy 385.562747 -280.871509) (xy 385.567428 -280.867104) (xy 386.266944 -280.167588) (xy 386.275072 -280.15692)
			(xy 386.278628 -280.150824) (xy 386.280406 -280.14422) (xy 386.286499 -280.123387) (xy 386.30377 -280.083566)
			(xy 386.326516 -280.046599) (xy 386.340096 -280.029666) (xy 386.34035 -280.029666) (xy 386.355371 -280.012234)
			(xy 386.389747 -279.981646) (xy 386.428321 -279.956558) (xy 386.470221 -279.937538) (xy 386.492242 -279.93086)
			(xy 386.495798 -279.929844) (xy 386.50191 -279.92785) (xy 386.512968 -279.921303) (xy 386.517642 -279.91689)
			(xy 387.216904 -279.217628) (xy 387.225032 -279.20696) (xy 387.228588 -279.200864) (xy 387.230366 -279.19426)
			(xy 387.236456 -279.173425) (xy 387.253721 -279.1336) (xy 387.276461 -279.096627) (xy 387.290056 -279.079706)
			(xy 387.29031 -279.079706) (xy 387.305329 -279.06227) (xy 387.339701 -279.031674) (xy 387.378273 -279.006578)
			(xy 387.420172 -278.98755) (xy 387.442202 -278.9809) (xy 387.445758 -278.979884) (xy 387.451864 -278.977882)
			(xy 387.462908 -278.97132) (xy 387.467602 -278.96693) (xy 387.726174 -278.708358) (xy 387.733017 -278.700959)
			(xy 387.74074 -278.68236) (xy 387.74116 -278.67229) (xy 387.74116 -278.640286) (xy 387.740737 -278.630269)
			(xy 387.733064 -278.611764) (xy 387.71889 -278.597606) (xy 387.700377 -278.589952) (xy 387.69036 -278.589486)
			(xy 387.677914 -278.589486) (xy 387.666738 -278.595328) (xy 387.644733 -278.606279) (xy 387.598097 -278.621793)
			(xy 387.54958 -278.629651) (xy 387.525006 -278.630126) (xy 387.499746 -278.629634) (xy 387.449916 -278.621319)
			(xy 387.402134 -278.604917) (xy 387.357704 -278.580873) (xy 387.317837 -278.549844) (xy 387.283621 -278.512676)
			(xy 387.255989 -278.470384) (xy 387.235696 -278.42412) (xy 387.223294 -278.375146) (xy 387.219122 -278.3248)
			(xy 387.223294 -278.274454) (xy 387.235696 -278.22548) (xy 387.255989 -278.179216) (xy 387.283621 -278.136924)
			(xy 387.317837 -278.099756) (xy 387.357704 -278.068727) (xy 387.402134 -278.044683) (xy 387.449916 -278.028281)
			(xy 387.499746 -278.019966) (xy 387.525006 -278.01951) (xy 387.546775 -278.019935) (xy 387.589864 -278.026184)
			(xy 387.610858 -278.031956) (xy 387.622796 -278.035258) (xy 387.64591 -278.031194) (xy 387.72084 -277.97506)
			(xy 387.729954 -277.967461) (xy 387.740567 -277.94627) (xy 387.74116 -277.93442) (xy 387.74116 -277.765256)
			(xy 387.74053 -277.753416) (xy 387.729919 -277.732246) (xy 387.72084 -277.724616) (xy 387.64591 -277.668482)
			(xy 387.622796 -277.664418) (xy 387.610858 -277.66772) (xy 387.589871 -277.673528) (xy 387.546778 -277.679779)
			(xy 387.525006 -277.680166) (xy 387.499751 -277.679674) (xy 387.449931 -277.671361) (xy 387.402158 -277.654962)
			(xy 387.357737 -277.630923) (xy 387.317877 -277.5999) (xy 387.283668 -277.562739) (xy 387.256042 -277.520455)
			(xy 387.235752 -277.4742) (xy 387.223353 -277.425237) (xy 387.219182 -277.3749) (xy 387.223353 -277.324563)
			(xy 387.235752 -277.2756) (xy 387.256042 -277.229345) (xy 387.283668 -277.187061) (xy 387.317877 -277.1499)
			(xy 387.357737 -277.118877) (xy 387.402158 -277.094838) (xy 387.449931 -277.078439) (xy 387.499751 -277.070126)
			(xy 387.525006 -277.06955) (xy 387.546775 -277.069975) (xy 387.589864 -277.076225) (xy 387.610858 -277.081996)
			(xy 387.622796 -277.085298) (xy 387.64591 -277.081234) (xy 387.72084 -277.0251) (xy 387.729945 -277.017498)
			(xy 387.740532 -276.996305) (xy 387.74116 -276.98446) (xy 387.74116 -276.815296) (xy 387.740539 -276.803452)
			(xy 387.729937 -276.782268) (xy 387.72084 -276.774656) (xy 387.64591 -276.718522) (xy 387.622796 -276.714458)
			(xy 387.610858 -276.71776) (xy 387.589871 -276.723568) (xy 387.546778 -276.729818) (xy 387.525006 -276.730206)
			(xy 387.499748 -276.729714) (xy 387.449921 -276.7214) (xy 387.402142 -276.704998) (xy 387.357715 -276.680956)
			(xy 387.31785 -276.649929) (xy 387.283637 -276.612764) (xy 387.256007 -276.570474) (xy 387.235715 -276.524213)
			(xy 387.223314 -276.475243) (xy 387.219142 -276.4249) (xy 387.223314 -276.374557) (xy 387.235715 -276.325587)
			(xy 387.256007 -276.279326) (xy 387.283637 -276.237036) (xy 387.31785 -276.199871) (xy 387.357715 -276.168844)
			(xy 387.402142 -276.144802) (xy 387.449921 -276.1284) (xy 387.499748 -276.120086) (xy 387.525006 -276.11959)
			(xy 387.546775 -276.120015) (xy 387.589864 -276.126263) (xy 387.610858 -276.132036) (xy 387.622796 -276.135338)
			(xy 387.64591 -276.131274) (xy 387.72084 -276.07514) (xy 387.729951 -276.06754) (xy 387.740556 -276.046348)
			(xy 387.74116 -276.0345) (xy 387.74116 -275.865336) (xy 387.740547 -275.853487) (xy 387.729955 -275.83229)
			(xy 387.72084 -275.824696) (xy 387.64591 -275.768562) (xy 387.622796 -275.764498) (xy 387.610858 -275.7678)
			(xy 387.589871 -275.773607) (xy 387.546778 -275.779856) (xy 387.525006 -275.780246) (xy 387.499745 -275.779754)
			(xy 387.449911 -275.771439) (xy 387.402126 -275.755035) (xy 387.357693 -275.73099) (xy 387.317823 -275.699959)
			(xy 387.283605 -275.662788) (xy 387.255972 -275.620493) (xy 387.235677 -275.574226) (xy 387.223274 -275.52525)
			(xy 387.219102 -275.4749) (xy 387.223274 -275.42455) (xy 387.235677 -275.375574) (xy 387.255972 -275.329307)
			(xy 387.283605 -275.287012) (xy 387.317823 -275.249841) (xy 387.357693 -275.21881) (xy 387.402126 -275.194765)
			(xy 387.449911 -275.178361) (xy 387.499745 -275.170046) (xy 387.525006 -275.16963) (xy 387.546775 -275.170055)
			(xy 387.589864 -275.176304) (xy 387.610858 -275.182076) (xy 387.622796 -275.185378) (xy 387.64591 -275.181314)
			(xy 387.72084 -275.12518) (xy 387.729958 -275.117583) (xy 387.740579 -275.096392) (xy 387.74116 -275.08454)
			(xy 387.74116 -274.915376) (xy 387.740534 -274.903534) (xy 387.729928 -274.882357) (xy 387.72084 -274.874736)
			(xy 387.64591 -274.818602) (xy 387.622796 -274.814538) (xy 387.610858 -274.81784) (xy 387.589871 -274.823648)
			(xy 387.546778 -274.829898) (xy 387.525006 -274.830286) (xy 387.49975 -274.829794) (xy 387.449926 -274.821481)
			(xy 387.40215 -274.80508) (xy 387.357726 -274.781039) (xy 387.317864 -274.750014) (xy 387.283652 -274.712852)
			(xy 387.256024 -274.670564) (xy 387.235734 -274.624307) (xy 387.223333 -274.57534) (xy 387.219162 -274.525)
			(xy 387.223333 -274.47466) (xy 387.235734 -274.425693) (xy 387.256024 -274.379436) (xy 387.283652 -274.337148)
			(xy 387.317864 -274.299986) (xy 387.357726 -274.268961) (xy 387.40215 -274.24492) (xy 387.449926 -274.228519)
			(xy 387.49975 -274.220206) (xy 387.525006 -274.21967) (xy 387.546775 -274.220095) (xy 387.589864 -274.226343)
			(xy 387.610858 -274.232116) (xy 387.622796 -274.235418) (xy 387.64591 -274.231354) (xy 387.72084 -274.17522)
			(xy 387.729948 -274.167619) (xy 387.740544 -274.146427) (xy 387.74116 -274.13458) (xy 387.74116 -273.965162)
			(xy 387.740531 -273.953322) (xy 387.729921 -273.93215) (xy 387.72084 -273.924522) (xy 387.64591 -273.868388)
			(xy 387.622796 -273.864324) (xy 387.610858 -273.867626) (xy 387.589871 -273.873434) (xy 387.546778 -273.879685)
			(xy 387.525006 -273.880072) (xy 387.499751 -273.87958) (xy 387.44993 -273.871267) (xy 387.402156 -273.854867)
			(xy 387.357733 -273.830828) (xy 387.317873 -273.799804) (xy 387.283663 -273.762643) (xy 387.256037 -273.720358)
			(xy 387.235747 -273.674102) (xy 387.223347 -273.625138) (xy 387.219176 -273.5748) (xy 387.223347 -273.524462)
			(xy 387.235747 -273.475498) (xy 387.256037 -273.429242) (xy 387.283663 -273.386957) (xy 387.317873 -273.349796)
			(xy 387.357733 -273.318772) (xy 387.402156 -273.294733) (xy 387.44993 -273.278333) (xy 387.499751 -273.27002)
			(xy 387.525006 -273.269456) (xy 387.546775 -273.269881) (xy 387.589864 -273.276131) (xy 387.610858 -273.281902)
			(xy 387.622796 -273.285204) (xy 387.64591 -273.28114) (xy 387.72084 -273.225006) (xy 387.729945 -273.217404)
			(xy 387.740536 -273.196212) (xy 387.74116 -273.184366) (xy 387.74116 -273.015202) (xy 387.74054 -273.003357)
			(xy 387.729939 -272.982171) (xy 387.72084 -272.974562) (xy 387.64591 -272.918428) (xy 387.622796 -272.914364)
			(xy 387.610858 -272.917666) (xy 387.589871 -272.923474) (xy 387.546778 -272.929723) (xy 387.525006 -272.930112)
			(xy 387.499748 -272.92962) (xy 387.44992 -272.921306) (xy 387.40214 -272.904904) (xy 387.357711 -272.880861)
			(xy 387.317846 -272.849834) (xy 387.283632 -272.812668) (xy 387.256002 -272.770377) (xy 387.235709 -272.724115)
			(xy 387.223308 -272.675144) (xy 387.219136 -272.6248) (xy 387.223308 -272.574456) (xy 387.235709 -272.525485)
			(xy 387.256002 -272.479223) (xy 387.283632 -272.436932) (xy 387.317846 -272.399766) (xy 387.357711 -272.368739)
			(xy 387.40214 -272.344696) (xy 387.44992 -272.328294) (xy 387.499748 -272.31998) (xy 387.525006 -272.319496)
			(xy 387.546775 -272.319921) (xy 387.589864 -272.32617) (xy 387.610858 -272.331942) (xy 387.622796 -272.335244)
			(xy 387.64591 -272.33118) (xy 387.72084 -272.275046) (xy 387.729952 -272.267447) (xy 387.740559 -272.246255)
			(xy 387.74116 -272.234406) (xy 387.74116 -267.340842) (xy 387.740772 -267.331314) (xy 387.733827 -267.313571)
			(xy 387.72088 -267.29959) (xy 387.712458 -267.295122) (xy 387.6167 -267.249148) (xy 387.587744 -267.25245)
			(xy 387.57606 -267.261594) (xy 387.555704 -267.277303) (xy 387.511571 -267.303688) (xy 387.464293 -267.323903)
			(xy 387.414726 -267.337581) (xy 387.363772 -267.344472) (xy 387.338062 -267.344906) (xy 387.310813 -267.344418)
			(xy 387.256869 -267.336657) (xy 387.204579 -267.321298) (xy 387.155007 -267.298655) (xy 387.109162 -267.269188)
			(xy 387.067976 -267.233497) (xy 387.032289 -267.192308) (xy 387.002827 -267.146459) (xy 386.980188 -267.096885)
			(xy 386.964835 -267.044593) (xy 386.95708 -266.990649) (xy 386.95708 -266.936151) (xy 386.964835 -266.882207)
			(xy 386.980188 -266.829915) (xy 387.002827 -266.780341) (xy 387.032289 -266.734492) (xy 387.067976 -266.693303)
			(xy 387.109162 -266.657612) (xy 387.155007 -266.628145) (xy 387.204579 -266.605502) (xy 387.256869 -266.590143)
			(xy 387.310813 -266.582382) (xy 387.338062 -266.58189) (xy 387.36377 -266.582314) (xy 387.414721 -266.589224)
			(xy 387.464283 -266.602912) (xy 387.511558 -266.623129) (xy 387.555692 -266.649509) (xy 387.57606 -266.665202)
			(xy 387.587744 -266.674346) (xy 387.6167 -266.677648) (xy 387.712458 -266.631674) (xy 387.720857 -266.627172)
			(xy 387.733795 -266.6132) (xy 387.740753 -266.595475) (xy 387.74116 -266.585954) (xy 387.74116 -260.771132)
			(xy 387.72084 -260.744208) (xy 387.70433 -260.739636) (xy 387.678159 -260.731605) (xy 387.628262 -260.709088)
			(xy 387.582094 -260.679674) (xy 387.540601 -260.643964) (xy 387.504637 -260.602693) (xy 387.474938 -260.556707)
			(xy 387.452114 -260.506949) (xy 387.436634 -260.454441) (xy 387.428814 -260.40026) (xy 387.428816 -260.345518)
			(xy 387.436638 -260.291337) (xy 387.452122 -260.23883) (xy 387.474949 -260.189074) (xy 387.50465 -260.143089)
			(xy 387.540617 -260.10182) (xy 387.582111 -260.066113) (xy 387.628281 -260.036701) (xy 387.67818 -260.014187)
			(xy 387.70433 -260.006084) (xy 387.72084 -260.001512) (xy 387.74116 -259.974588) (xy 387.74116 -258.75742)
			(xy 387.740721 -258.747357) (xy 387.732982 -258.728778) (xy 387.726174 -258.721352) (xy 384.917188 -255.912366)
			(xy 384.909792 -255.905514) (xy 384.891193 -255.897774) (xy 384.88112 -255.89738) (xy 383.291334 -255.89738)
			(xy 383.280839 -255.897906) (xy 383.261602 -255.90631) (xy 383.247318 -255.921693) (xy 383.243328 -255.931416)
			(xy 383.206244 -256.03708) (xy 383.215134 -256.068068) (xy 383.22758 -256.078228) (xy 383.249486 -256.096433)
			(xy 383.288169 -256.138238) (xy 383.320199 -256.185335) (xy 383.344863 -256.236674) (xy 383.361611 -256.291113)
			(xy 383.370071 -256.347438) (xy 383.370582 -256.375916) (xy 383.370018 -256.405295) (xy 383.360967 -256.463353)
			(xy 383.343127 -256.519339) (xy 383.316921 -256.57193) (xy 383.282966 -256.619886) (xy 383.242064 -256.662072)
			(xy 383.218944 -256.680208) (xy 383.209546 -256.687574) (xy 383.199132 -256.708148) (xy 383.197608 -256.812034)
			(xy 383.207514 -256.833116) (xy 383.216658 -256.840482) (xy 383.238483 -256.858712) (xy 383.277013 -256.900533)
			(xy 383.308915 -256.947606) (xy 383.333484 -256.99889) (xy 383.350175 -257.05325) (xy 383.35862 -257.109484)
			(xy 383.359152 -257.137916) (xy 383.992626 -257.137916) (xy 383.996697 -257.082294) (xy 384.008823 -257.027857)
			(xy 384.028746 -256.975766) (xy 384.056042 -256.927131) (xy 384.090128 -256.882988) (xy 384.130277 -256.844279)
			(xy 384.175635 -256.811828) (xy 384.225235 -256.786327) (xy 384.278019 -256.76832) (xy 384.332862 -256.75819)
			(xy 384.388596 -256.756153) (xy 384.444033 -256.762253) (xy 384.49799 -256.776359) (xy 384.549319 -256.798171)
			(xy 384.596925 -256.827225) (xy 384.639793 -256.8629) (xy 384.67701 -256.904437) (xy 384.707783 -256.95095)
			(xy 384.731455 -257.001447) (xy 384.747523 -257.054854) (xy 384.755643 -257.11003) (xy 384.756152 -257.137916)
			(xy 384.879086 -257.137916) (xy 384.883157 -257.082294) (xy 384.895283 -257.027857) (xy 384.915206 -256.975766)
			(xy 384.942502 -256.927131) (xy 384.976588 -256.882988) (xy 385.016737 -256.844279) (xy 385.062095 -256.811828)
			(xy 385.111695 -256.786327) (xy 385.164479 -256.76832) (xy 385.219322 -256.75819) (xy 385.275056 -256.756153)
			(xy 385.330493 -256.762253) (xy 385.38445 -256.776359) (xy 385.435779 -256.798171) (xy 385.483385 -256.827225)
			(xy 385.526253 -256.8629) (xy 385.56347 -256.904437) (xy 385.594243 -256.95095) (xy 385.617915 -257.001447)
			(xy 385.633983 -257.054854) (xy 385.642103 -257.11003) (xy 385.642612 -257.137916) (xy 385.642103 -257.165802)
			(xy 385.633983 -257.220978) (xy 385.617915 -257.274385) (xy 385.594243 -257.324882) (xy 385.56347 -257.371395)
			(xy 385.526253 -257.412932) (xy 385.483385 -257.448607) (xy 385.435779 -257.477661) (xy 385.38445 -257.499473)
			(xy 385.330493 -257.513579) (xy 385.275056 -257.519679) (xy 385.219322 -257.517642) (xy 385.164479 -257.507512)
			(xy 385.111695 -257.489505) (xy 385.062095 -257.464004) (xy 385.016737 -257.431553) (xy 384.976588 -257.392844)
			(xy 384.942502 -257.348701) (xy 384.915206 -257.300066) (xy 384.895283 -257.247975) (xy 384.883157 -257.193538)
			(xy 384.879086 -257.137916) (xy 384.756152 -257.137916) (xy 384.755643 -257.165802) (xy 384.747523 -257.220978)
			(xy 384.731455 -257.274385) (xy 384.707783 -257.324882) (xy 384.67701 -257.371395) (xy 384.639793 -257.412932)
			(xy 384.596925 -257.448607) (xy 384.549319 -257.477661) (xy 384.49799 -257.499473) (xy 384.444033 -257.513579)
			(xy 384.388596 -257.519679) (xy 384.332862 -257.517642) (xy 384.278019 -257.507512) (xy 384.225235 -257.489505)
			(xy 384.175635 -257.464004) (xy 384.130277 -257.431553) (xy 384.090128 -257.392844) (xy 384.056042 -257.348701)
			(xy 384.028746 -257.300066) (xy 384.008823 -257.247975) (xy 383.996697 -257.193538) (xy 383.992626 -257.137916)
			(xy 383.359152 -257.137916) (xy 383.358666 -257.165167) (xy 383.35091 -257.219115) (xy 383.335555 -257.27141)
			(xy 383.312913 -257.320987) (xy 383.283447 -257.366837) (xy 383.247756 -257.408028) (xy 383.206565 -257.443719)
			(xy 383.160715 -257.473185) (xy 383.111138 -257.495827) (xy 383.058843 -257.511182) (xy 383.004895 -257.518938)
			(xy 382.950393 -257.518938) (xy 382.896445 -257.511182) (xy 382.84415 -257.495827) (xy 382.794573 -257.473185)
			(xy 382.748723 -257.443719) (xy 382.707532 -257.408028) (xy 382.671841 -257.366837) (xy 382.642375 -257.320987)
			(xy 382.619733 -257.27141) (xy 382.604378 -257.219115) (xy 382.596622 -257.165167) (xy 382.596136 -257.137916)
			(xy 382.596698 -257.108536) (xy 382.605745 -257.050476) (xy 382.623582 -256.994487) (xy 382.649787 -256.941893)
			(xy 382.683741 -256.893935) (xy 382.724643 -256.851747) (xy 382.747774 -256.833624) (xy 382.757172 -256.826258)
			(xy 382.767586 -256.805684) (xy 382.76911 -256.701798) (xy 382.759204 -256.680716) (xy 382.75006 -256.67335)
			(xy 382.728237 -256.655118) (xy 382.689711 -256.613294) (xy 382.657812 -256.566221) (xy 382.633245 -256.514938)
			(xy 382.616553 -256.46058) (xy 382.608105 -256.404348) (xy 382.607566 -256.375916) (xy 382.6081 -256.347441)
			(xy 382.61658 -256.291127) (xy 382.633338 -256.236699) (xy 382.658002 -256.185368) (xy 382.690024 -256.138274)
			(xy 382.728692 -256.096464) (xy 382.750568 -256.078228) (xy 382.763014 -256.068068) (xy 382.771904 -256.03708)
			(xy 382.73482 -255.931416) (xy 382.730874 -255.921664) (xy 382.716588 -255.906253) (xy 382.697322 -255.897861)
			(xy 382.686814 -255.89738) (xy 380.118366 -255.89738) (xy 380.107867 -255.8979) (xy 380.08862 -255.906297)
			(xy 380.074326 -255.921681) (xy 380.07036 -255.931416) (xy 380.033276 -256.03708) (xy 380.042166 -256.068068)
			(xy 380.054612 -256.078228) (xy 380.076517 -256.096434) (xy 380.115196 -256.13824) (xy 380.147224 -256.185338)
			(xy 380.171885 -256.236677) (xy 380.188632 -256.291114) (xy 380.197091 -256.347438) (xy 380.197614 -256.375916)
			(xy 380.197128 -256.403167) (xy 380.189372 -256.457115) (xy 380.174017 -256.50941) (xy 380.151375 -256.558987)
			(xy 380.121909 -256.604837) (xy 380.086218 -256.646028) (xy 380.045027 -256.681719) (xy 379.999177 -256.711185)
			(xy 379.9496 -256.733827) (xy 379.897305 -256.749182) (xy 379.843357 -256.756938) (xy 379.788855 -256.756938)
			(xy 379.734907 -256.749182) (xy 379.682612 -256.733827) (xy 379.633035 -256.711185) (xy 379.587185 -256.681719)
			(xy 379.545994 -256.646028) (xy 379.510303 -256.604837) (xy 379.480837 -256.558987) (xy 379.458195 -256.50941)
			(xy 379.44284 -256.457115) (xy 379.435084 -256.403167) (xy 379.434598 -256.375916) (xy 379.435133 -256.347442)
			(xy 379.443613 -256.291128) (xy 379.460372 -256.236701) (xy 379.485038 -256.185371) (xy 379.517061 -256.138279)
			(xy 379.555731 -256.096473) (xy 379.5776 -256.078228) (xy 379.590046 -256.068068) (xy 379.598936 -256.03708)
			(xy 379.561852 -255.931416) (xy 379.557902 -255.921672) (xy 379.543613 -255.90628) (xy 379.524349 -255.897913)
			(xy 379.513846 -255.89738) (xy 379.229366 -255.89738) (xy 379.218867 -255.8979) (xy 379.19962 -255.906297)
			(xy 379.185326 -255.921681) (xy 379.18136 -255.931416) (xy 379.144276 -256.03708) (xy 379.153166 -256.068068)
			(xy 379.165612 -256.078228) (xy 379.187517 -256.096434) (xy 379.226196 -256.13824) (xy 379.258224 -256.185338)
			(xy 379.282885 -256.236677) (xy 379.299632 -256.291114) (xy 379.308091 -256.347438) (xy 379.308614 -256.375916)
			(xy 379.308128 -256.403167) (xy 379.300372 -256.457115) (xy 379.285017 -256.50941) (xy 379.262375 -256.558987)
			(xy 379.232909 -256.604837) (xy 379.197218 -256.646028) (xy 379.156027 -256.681719) (xy 379.110177 -256.711185)
			(xy 379.0606 -256.733827) (xy 379.008305 -256.749182) (xy 378.954357 -256.756938) (xy 378.899855 -256.756938)
			(xy 378.845907 -256.749182) (xy 378.793612 -256.733827) (xy 378.744035 -256.711185) (xy 378.698185 -256.681719)
			(xy 378.656994 -256.646028) (xy 378.621303 -256.604837) (xy 378.591837 -256.558987) (xy 378.569195 -256.50941)
			(xy 378.55384 -256.457115) (xy 378.546084 -256.403167) (xy 378.545598 -256.375916) (xy 378.546133 -256.347442)
			(xy 378.554613 -256.291128) (xy 378.571372 -256.236701) (xy 378.596038 -256.185371) (xy 378.628061 -256.138279)
			(xy 378.666731 -256.096473) (xy 378.6886 -256.078228) (xy 378.701046 -256.068068) (xy 378.709936 -256.03708)
			(xy 378.672852 -255.931416) (xy 378.668902 -255.921672) (xy 378.654613 -255.90628) (xy 378.635349 -255.897913)
			(xy 378.624846 -255.89738) (xy 377.75388 -255.89738) (xy 377.743379 -255.897897) (xy 377.724127 -255.906292)
			(xy 377.709829 -255.921675) (xy 377.705874 -255.931416) (xy 377.66879 -256.03708) (xy 377.67768 -256.068068)
			(xy 377.690126 -256.078228) (xy 377.71203 -256.096434) (xy 377.750708 -256.138241) (xy 377.782735 -256.185339)
			(xy 377.807395 -256.236678) (xy 377.824141 -256.291115) (xy 377.8326 -256.347438) (xy 377.833128 -256.375916)
			(xy 377.832642 -256.403167) (xy 377.824886 -256.457115) (xy 377.809531 -256.50941) (xy 377.786889 -256.558987)
			(xy 377.757423 -256.604837) (xy 377.721732 -256.646028) (xy 377.680541 -256.681719) (xy 377.634691 -256.711185)
			(xy 377.585114 -256.733827) (xy 377.532819 -256.749182) (xy 377.478871 -256.756938) (xy 377.424369 -256.756938)
			(xy 377.370421 -256.749182) (xy 377.318126 -256.733827) (xy 377.268549 -256.711185) (xy 377.222699 -256.681719)
			(xy 377.181508 -256.646028) (xy 377.145817 -256.604837) (xy 377.116351 -256.558987) (xy 377.093709 -256.50941)
			(xy 377.078354 -256.457115) (xy 377.070598 -256.403167) (xy 377.070112 -256.375916) (xy 377.070647 -256.347442)
			(xy 377.079127 -256.291128) (xy 377.095887 -256.236702) (xy 377.120553 -256.185373) (xy 377.152577 -256.138282)
			(xy 377.191248 -256.096476) (xy 377.213114 -256.078228) (xy 377.22556 -256.068068) (xy 377.23445 -256.03708)
			(xy 377.197366 -255.931416) (xy 377.193417 -255.92167) (xy 377.179128 -255.906274) (xy 377.159864 -255.897902)
			(xy 377.14936 -255.89738) (xy 377.036584 -255.89738) (xy 377.025252 -255.897982) (xy 377.004797 -255.907735)
			(xy 376.997214 -255.916176) (xy 376.940318 -255.98628) (xy 376.93473 -256.008632) (xy 376.93727 -256.019808)
			(xy 376.941084 -256.039269) (xy 376.945152 -256.078718) (xy 376.945398 -256.098548) (xy 376.944912 -256.125799)
			(xy 376.937156 -256.179747) (xy 376.921801 -256.232042) (xy 376.899159 -256.281619) (xy 376.869693 -256.327469)
			(xy 376.834002 -256.36866) (xy 376.792811 -256.404351) (xy 376.746961 -256.433817) (xy 376.697384 -256.456459)
			(xy 376.645089 -256.471814) (xy 376.591141 -256.47957) (xy 376.536639 -256.47957) (xy 376.482691 -256.471814)
			(xy 376.430396 -256.456459) (xy 376.380819 -256.433817) (xy 376.334969 -256.404351) (xy 376.293778 -256.36866)
			(xy 376.258087 -256.327469) (xy 376.228621 -256.281619) (xy 376.205979 -256.232042) (xy 376.190624 -256.179747)
			(xy 376.182868 -256.125799) (xy 376.182382 -256.098548) (xy 376.18287 -256.071305) (xy 376.190625 -256.017373)
			(xy 376.205971 -255.965092) (xy 376.228594 -255.915524) (xy 376.258036 -255.869677) (xy 376.293698 -255.828482)
			(xy 376.313954 -255.810258) (xy 376.321828 -255.8034) (xy 376.330972 -255.78435) (xy 376.33402 -255.699514)
			(xy 376.333877 -255.688986) (xy 376.326149 -255.669426) (xy 376.319034 -255.661668) (xy 375.39422 -254.736854)
			(xy 375.390785 -254.733238) (xy 375.38528 -254.724921) (xy 375.383298 -254.720344) (xy 375.372122 -254.693674)
			(xy 375.36501 -254.686562) (xy 374.951752 -254.27305) (xy 374.94464 -254.265684) (xy 374.925844 -254.258064)
			(xy 374.598692 -254.258064) (xy 374.588624 -254.25849) (xy 374.570028 -254.266214) (xy 374.562624 -254.27305)
			(xy 374.065546 -254.770128) (xy 374.058699 -254.777526) (xy 374.050968 -254.796124) (xy 374.05056 -254.806196)
			(xy 374.05056 -256.987548) (xy 376.181872 -256.987548) (xy 376.185943 -256.931926) (xy 376.198069 -256.877489)
			(xy 376.217992 -256.825398) (xy 376.245288 -256.776763) (xy 376.279374 -256.73262) (xy 376.319523 -256.693911)
			(xy 376.364881 -256.66146) (xy 376.414481 -256.635959) (xy 376.467265 -256.617952) (xy 376.522108 -256.607822)
			(xy 376.577842 -256.605785) (xy 376.633279 -256.611885) (xy 376.687236 -256.625991) (xy 376.738565 -256.647803)
			(xy 376.786171 -256.676857) (xy 376.829039 -256.712532) (xy 376.866256 -256.754069) (xy 376.897029 -256.800582)
			(xy 376.920701 -256.851079) (xy 376.936769 -256.904486) (xy 376.944889 -256.959662) (xy 376.945398 -256.987548)
			(xy 376.944889 -257.015434) (xy 376.936769 -257.07061) (xy 376.920701 -257.124017) (xy 376.897029 -257.174514)
			(xy 376.866256 -257.221027) (xy 376.829039 -257.262564) (xy 376.786171 -257.298239) (xy 376.738565 -257.327293)
			(xy 376.687236 -257.349105) (xy 376.633279 -257.363211) (xy 376.577842 -257.369311) (xy 376.522108 -257.367274)
			(xy 376.467265 -257.357144) (xy 376.414481 -257.339137) (xy 376.364881 -257.313636) (xy 376.319523 -257.281185)
			(xy 376.279374 -257.242476) (xy 376.245288 -257.198333) (xy 376.217992 -257.149698) (xy 376.198069 -257.097607)
			(xy 376.185943 -257.04317) (xy 376.181872 -256.987548) (xy 374.05056 -256.987548) (xy 374.05056 -258.075938)
			(xy 374.050992 -258.086004) (xy 374.058722 -258.104593) (xy 374.065546 -258.112006) (xy 374.360694 -258.407408)
			(xy 375.529602 -259.576316) (xy 377.069602 -259.576316) (xy 377.073673 -259.520694) (xy 377.085799 -259.466257)
			(xy 377.105722 -259.414166) (xy 377.133018 -259.365531) (xy 377.167104 -259.321388) (xy 377.207253 -259.282679)
			(xy 377.252611 -259.250228) (xy 377.302211 -259.224727) (xy 377.354995 -259.20672) (xy 377.409838 -259.19659)
			(xy 377.465572 -259.194553) (xy 377.521009 -259.200653) (xy 377.574966 -259.214759) (xy 377.626295 -259.236571)
			(xy 377.673901 -259.265625) (xy 377.716769 -259.3013) (xy 377.753986 -259.342837) (xy 377.784759 -259.38935)
			(xy 377.808431 -259.439847) (xy 377.824499 -259.493254) (xy 377.832619 -259.54843) (xy 377.833128 -259.576316)
			(xy 378.545088 -259.576316) (xy 378.549159 -259.520694) (xy 378.561285 -259.466257) (xy 378.581208 -259.414166)
			(xy 378.608504 -259.365531) (xy 378.64259 -259.321388) (xy 378.682739 -259.282679) (xy 378.728097 -259.250228)
			(xy 378.777697 -259.224727) (xy 378.830481 -259.20672) (xy 378.885324 -259.19659) (xy 378.941058 -259.194553)
			(xy 378.996495 -259.200653) (xy 379.050452 -259.214759) (xy 379.101781 -259.236571) (xy 379.149387 -259.265625)
			(xy 379.192255 -259.3013) (xy 379.229472 -259.342837) (xy 379.260245 -259.38935) (xy 379.283917 -259.439847)
			(xy 379.299985 -259.493254) (xy 379.308105 -259.54843) (xy 379.308614 -259.576316) (xy 379.434088 -259.576316)
			(xy 379.438159 -259.520694) (xy 379.450285 -259.466257) (xy 379.470208 -259.414166) (xy 379.497504 -259.365531)
			(xy 379.53159 -259.321388) (xy 379.571739 -259.282679) (xy 379.617097 -259.250228) (xy 379.666697 -259.224727)
			(xy 379.719481 -259.20672) (xy 379.774324 -259.19659) (xy 379.830058 -259.194553) (xy 379.885495 -259.200653)
			(xy 379.939452 -259.214759) (xy 379.990781 -259.236571) (xy 380.038387 -259.265625) (xy 380.081255 -259.3013)
			(xy 380.118472 -259.342837) (xy 380.149245 -259.38935) (xy 380.172917 -259.439847) (xy 380.188985 -259.493254)
			(xy 380.197105 -259.54843) (xy 380.197614 -259.576316) (xy 380.197105 -259.604202) (xy 380.188985 -259.659378)
			(xy 380.172917 -259.712785) (xy 380.149245 -259.763282) (xy 380.118472 -259.809795) (xy 380.081255 -259.851332)
			(xy 380.038387 -259.887007) (xy 379.990781 -259.916061) (xy 379.939452 -259.937873) (xy 379.885495 -259.951979)
			(xy 379.830058 -259.958079) (xy 379.774324 -259.956042) (xy 379.719481 -259.945912) (xy 379.666697 -259.927905)
			(xy 379.617097 -259.902404) (xy 379.571739 -259.869953) (xy 379.53159 -259.831244) (xy 379.497504 -259.787101)
			(xy 379.470208 -259.738466) (xy 379.450285 -259.686375) (xy 379.438159 -259.631938) (xy 379.434088 -259.576316)
			(xy 379.308614 -259.576316) (xy 379.308105 -259.604202) (xy 379.299985 -259.659378) (xy 379.283917 -259.712785)
			(xy 379.260245 -259.763282) (xy 379.229472 -259.809795) (xy 379.192255 -259.851332) (xy 379.149387 -259.887007)
			(xy 379.101781 -259.916061) (xy 379.050452 -259.937873) (xy 378.996495 -259.951979) (xy 378.941058 -259.958079)
			(xy 378.885324 -259.956042) (xy 378.830481 -259.945912) (xy 378.777697 -259.927905) (xy 378.728097 -259.902404)
			(xy 378.682739 -259.869953) (xy 378.64259 -259.831244) (xy 378.608504 -259.787101) (xy 378.581208 -259.738466)
			(xy 378.561285 -259.686375) (xy 378.549159 -259.631938) (xy 378.545088 -259.576316) (xy 377.833128 -259.576316)
			(xy 377.832619 -259.604202) (xy 377.824499 -259.659378) (xy 377.808431 -259.712785) (xy 377.784759 -259.763282)
			(xy 377.753986 -259.809795) (xy 377.716769 -259.851332) (xy 377.673901 -259.887007) (xy 377.626295 -259.916061)
			(xy 377.574966 -259.937873) (xy 377.521009 -259.951979) (xy 377.465572 -259.958079) (xy 377.409838 -259.956042)
			(xy 377.354995 -259.945912) (xy 377.302211 -259.927905) (xy 377.252611 -259.902404) (xy 377.207253 -259.869953)
			(xy 377.167104 -259.831244) (xy 377.133018 -259.787101) (xy 377.105722 -259.738466) (xy 377.085799 -259.686375)
			(xy 377.073673 -259.631938) (xy 377.069602 -259.576316) (xy 375.529602 -259.576316) (xy 375.680986 -259.7277)
			(xy 375.687834 -259.735098) (xy 375.69557 -259.753696) (xy 375.695972 -259.763768) (xy 375.695972 -260.160516)
			(xy 376.181872 -260.160516) (xy 376.185943 -260.104894) (xy 376.198069 -260.050457) (xy 376.217992 -259.998366)
			(xy 376.245288 -259.949731) (xy 376.279374 -259.905588) (xy 376.319523 -259.866879) (xy 376.364881 -259.834428)
			(xy 376.414481 -259.808927) (xy 376.467265 -259.79092) (xy 376.522108 -259.78079) (xy 376.577842 -259.778753)
			(xy 376.633279 -259.784853) (xy 376.687236 -259.798959) (xy 376.738565 -259.820771) (xy 376.786171 -259.849825)
			(xy 376.829039 -259.8855) (xy 376.866256 -259.927037) (xy 376.897029 -259.97355) (xy 376.920701 -260.024047)
			(xy 376.936769 -260.077454) (xy 376.944889 -260.13263) (xy 376.945398 -260.160516) (xy 376.944889 -260.188402)
			(xy 376.936769 -260.243578) (xy 376.920701 -260.296985) (xy 376.901326 -260.338316) (xy 382.596136 -260.338316)
			(xy 382.596671 -260.308933) (xy 382.605701 -260.250865) (xy 382.623533 -260.194871) (xy 382.649745 -260.142275)
			(xy 382.683717 -260.094324) (xy 382.724644 -260.052153) (xy 382.747774 -260.034024) (xy 382.757172 -260.026658)
			(xy 382.767586 -260.006084) (xy 382.76911 -259.902198) (xy 382.759204 -259.881116) (xy 382.75006 -259.87375)
			(xy 382.728198 -259.855561) (xy 382.68966 -259.813737) (xy 382.657756 -259.766658) (xy 382.633192 -259.715365)
			(xy 382.616511 -259.660995) (xy 382.608084 -259.604752) (xy 382.607566 -259.576316) (xy 382.608052 -259.549065)
			(xy 382.615808 -259.495117) (xy 382.631163 -259.442822) (xy 382.653805 -259.393245) (xy 382.683271 -259.347395)
			(xy 382.718962 -259.306204) (xy 382.760153 -259.270513) (xy 382.806003 -259.241047) (xy 382.85558 -259.218405)
			(xy 382.907875 -259.20305) (xy 382.961823 -259.195294) (xy 383.016325 -259.195294) (xy 383.070273 -259.20305)
			(xy 383.122568 -259.218405) (xy 383.172145 -259.241047) (xy 383.217995 -259.270513) (xy 383.259186 -259.306204)
			(xy 383.294877 -259.347395) (xy 383.324343 -259.393245) (xy 383.346985 -259.442822) (xy 383.36234 -259.495117)
			(xy 383.370096 -259.549065) (xy 383.370582 -259.576316) (xy 383.370063 -259.605699) (xy 383.361029 -259.663767)
			(xy 383.343193 -259.719762) (xy 383.316978 -259.772358) (xy 383.283003 -259.820308) (xy 383.242074 -259.862479)
			(xy 383.218944 -259.880608) (xy 383.209546 -259.887974) (xy 383.199132 -259.908548) (xy 383.197608 -260.012434)
			(xy 383.207514 -260.033516) (xy 383.216658 -260.040882) (xy 383.238471 -260.059128) (xy 383.277015 -260.100938)
			(xy 383.308928 -260.148004) (xy 383.333501 -260.199286) (xy 383.350191 -260.253647) (xy 383.358629 -260.309883)
			(xy 383.359152 -260.338316) (xy 383.992626 -260.338316) (xy 383.996697 -260.282694) (xy 384.008823 -260.228257)
			(xy 384.028746 -260.176166) (xy 384.056042 -260.127531) (xy 384.090128 -260.083388) (xy 384.130277 -260.044679)
			(xy 384.175635 -260.012228) (xy 384.225235 -259.986727) (xy 384.278019 -259.96872) (xy 384.332862 -259.95859)
			(xy 384.388596 -259.956553) (xy 384.444033 -259.962653) (xy 384.49799 -259.976759) (xy 384.549319 -259.998571)
			(xy 384.596925 -260.027625) (xy 384.639793 -260.0633) (xy 384.67701 -260.104837) (xy 384.707783 -260.15135)
			(xy 384.731455 -260.201847) (xy 384.747523 -260.255254) (xy 384.755643 -260.31043) (xy 384.756152 -260.338316)
			(xy 384.879086 -260.338316) (xy 384.883157 -260.282694) (xy 384.895283 -260.228257) (xy 384.915206 -260.176166)
			(xy 384.942502 -260.127531) (xy 384.976588 -260.083388) (xy 385.016737 -260.044679) (xy 385.062095 -260.012228)
			(xy 385.111695 -259.986727) (xy 385.164479 -259.96872) (xy 385.219322 -259.95859) (xy 385.275056 -259.956553)
			(xy 385.330493 -259.962653) (xy 385.38445 -259.976759) (xy 385.435779 -259.998571) (xy 385.483385 -260.027625)
			(xy 385.526253 -260.0633) (xy 385.56347 -260.104837) (xy 385.594243 -260.15135) (xy 385.617915 -260.201847)
			(xy 385.633983 -260.255254) (xy 385.642103 -260.31043) (xy 385.642612 -260.338316) (xy 385.642103 -260.366202)
			(xy 385.633983 -260.421378) (xy 385.617915 -260.474785) (xy 385.594243 -260.525282) (xy 385.56347 -260.571795)
			(xy 385.526253 -260.613332) (xy 385.483385 -260.649007) (xy 385.435779 -260.678061) (xy 385.38445 -260.699873)
			(xy 385.330493 -260.713979) (xy 385.275056 -260.720079) (xy 385.219322 -260.718042) (xy 385.164479 -260.707912)
			(xy 385.111695 -260.689905) (xy 385.062095 -260.664404) (xy 385.016737 -260.631953) (xy 384.976588 -260.593244)
			(xy 384.942502 -260.549101) (xy 384.915206 -260.500466) (xy 384.895283 -260.448375) (xy 384.883157 -260.393938)
			(xy 384.879086 -260.338316) (xy 384.756152 -260.338316) (xy 384.755643 -260.366202) (xy 384.747523 -260.421378)
			(xy 384.731455 -260.474785) (xy 384.707783 -260.525282) (xy 384.67701 -260.571795) (xy 384.639793 -260.613332)
			(xy 384.596925 -260.649007) (xy 384.549319 -260.678061) (xy 384.49799 -260.699873) (xy 384.444033 -260.713979)
			(xy 384.388596 -260.720079) (xy 384.332862 -260.718042) (xy 384.278019 -260.707912) (xy 384.225235 -260.689905)
			(xy 384.175635 -260.664404) (xy 384.130277 -260.631953) (xy 384.090128 -260.593244) (xy 384.056042 -260.549101)
			(xy 384.028746 -260.500466) (xy 384.008823 -260.448375) (xy 383.996697 -260.393938) (xy 383.992626 -260.338316)
			(xy 383.359152 -260.338316) (xy 383.358666 -260.365567) (xy 383.35091 -260.419515) (xy 383.335555 -260.47181)
			(xy 383.312913 -260.521387) (xy 383.283447 -260.567237) (xy 383.247756 -260.608428) (xy 383.206565 -260.644119)
			(xy 383.160715 -260.673585) (xy 383.111138 -260.696227) (xy 383.058843 -260.711582) (xy 383.004895 -260.719338)
			(xy 382.950393 -260.719338) (xy 382.896445 -260.711582) (xy 382.84415 -260.696227) (xy 382.794573 -260.673585)
			(xy 382.748723 -260.644119) (xy 382.707532 -260.608428) (xy 382.671841 -260.567237) (xy 382.642375 -260.521387)
			(xy 382.619733 -260.47181) (xy 382.604378 -260.419515) (xy 382.596622 -260.365567) (xy 382.596136 -260.338316)
			(xy 376.901326 -260.338316) (xy 376.897029 -260.347482) (xy 376.866256 -260.393995) (xy 376.829039 -260.435532)
			(xy 376.786171 -260.471207) (xy 376.738565 -260.500261) (xy 376.687236 -260.522073) (xy 376.633279 -260.536179)
			(xy 376.577842 -260.542279) (xy 376.522108 -260.540242) (xy 376.467265 -260.530112) (xy 376.414481 -260.512105)
			(xy 376.364881 -260.486604) (xy 376.319523 -260.454153) (xy 376.279374 -260.415444) (xy 376.245288 -260.371301)
			(xy 376.217992 -260.322666) (xy 376.198069 -260.270575) (xy 376.185943 -260.216138) (xy 376.181872 -260.160516)
			(xy 375.695972 -260.160516) (xy 375.695972 -262.433562) (xy 375.696523 -262.443917) (xy 375.70479 -262.462912)
			(xy 375.711974 -262.470392) (xy 375.773188 -262.528558) (xy 375.792492 -262.53567) (xy 375.80316 -262.534908)
			(xy 375.824496 -262.5344) (xy 375.851748 -262.534863) (xy 375.905699 -262.542619) (xy 375.957996 -262.557975)
			(xy 376.007576 -262.580617) (xy 376.053428 -262.610084) (xy 376.09462 -262.645777) (xy 376.130314 -262.686969)
			(xy 376.159782 -262.732821) (xy 376.177972 -262.772652) (xy 381.52527 -262.772652) (xy 381.529341 -262.71703)
			(xy 381.541467 -262.662593) (xy 381.56139 -262.610502) (xy 381.588686 -262.561867) (xy 381.622772 -262.517724)
			(xy 381.662921 -262.479015) (xy 381.708279 -262.446564) (xy 381.757879 -262.421063) (xy 381.810663 -262.403056)
			(xy 381.865506 -262.392926) (xy 381.92124 -262.390889) (xy 381.976677 -262.396989) (xy 382.030634 -262.411095)
			(xy 382.081963 -262.432907) (xy 382.129569 -262.461961) (xy 382.172437 -262.497636) (xy 382.209654 -262.539173)
			(xy 382.240427 -262.585686) (xy 382.264099 -262.636183) (xy 382.280167 -262.68959) (xy 382.288287 -262.744766)
			(xy 382.288796 -262.772652) (xy 382.288287 -262.800538) (xy 382.280167 -262.855714) (xy 382.264099 -262.909121)
			(xy 382.240427 -262.959618) (xy 382.209654 -263.006131) (xy 382.195136 -263.022334) (xy 386.231128 -263.022334)
			(xy 386.235199 -262.966712) (xy 386.247325 -262.912275) (xy 386.267248 -262.860184) (xy 386.294544 -262.811549)
			(xy 386.32863 -262.767406) (xy 386.368779 -262.728697) (xy 386.414137 -262.696246) (xy 386.463737 -262.670745)
			(xy 386.516521 -262.652738) (xy 386.571364 -262.642608) (xy 386.627098 -262.640571) (xy 386.682535 -262.646671)
			(xy 386.736492 -262.660777) (xy 386.787821 -262.682589) (xy 386.835427 -262.711643) (xy 386.878295 -262.747318)
			(xy 386.915512 -262.788855) (xy 386.946285 -262.835368) (xy 386.969957 -262.885865) (xy 386.986025 -262.939272)
			(xy 386.994145 -262.994448) (xy 386.994654 -263.022334) (xy 386.994145 -263.05022) (xy 386.986025 -263.105396)
			(xy 386.969957 -263.158803) (xy 386.946285 -263.2093) (xy 386.915512 -263.255813) (xy 386.878295 -263.29735)
			(xy 386.835427 -263.333025) (xy 386.787821 -263.362079) (xy 386.736492 -263.383891) (xy 386.682535 -263.397997)
			(xy 386.627098 -263.404097) (xy 386.571364 -263.40206) (xy 386.516521 -263.39193) (xy 386.463737 -263.373923)
			(xy 386.414137 -263.348422) (xy 386.368779 -263.315971) (xy 386.32863 -263.277262) (xy 386.294544 -263.233119)
			(xy 386.267248 -263.184484) (xy 386.247325 -263.132393) (xy 386.235199 -263.077956) (xy 386.231128 -263.022334)
			(xy 382.195136 -263.022334) (xy 382.172437 -263.047668) (xy 382.129569 -263.083343) (xy 382.081963 -263.112397)
			(xy 382.030634 -263.134209) (xy 381.976677 -263.148315) (xy 381.92124 -263.154415) (xy 381.865506 -263.152378)
			(xy 381.810663 -263.142248) (xy 381.757879 -263.124241) (xy 381.708279 -263.09874) (xy 381.662921 -263.066289)
			(xy 381.622772 -263.02758) (xy 381.588686 -262.983437) (xy 381.56139 -262.934802) (xy 381.541467 -262.882711)
			(xy 381.529341 -262.828274) (xy 381.52527 -262.772652) (xy 376.177972 -262.772652) (xy 376.182424 -262.7824)
			(xy 376.19778 -262.834697) (xy 376.205537 -262.888648) (xy 376.205537 -262.943152) (xy 376.19778 -262.997103)
			(xy 376.182424 -263.0494) (xy 376.159782 -263.098979) (xy 376.130314 -263.144831) (xy 376.09462 -263.186023)
			(xy 376.053428 -263.221716) (xy 376.007576 -263.251183) (xy 375.957996 -263.273825) (xy 375.905699 -263.289181)
			(xy 375.851748 -263.296937) (xy 375.824496 -263.297416) (xy 375.80316 -263.296908) (xy 375.792492 -263.296146)
			(xy 375.773188 -263.303258) (xy 375.711974 -263.361424) (xy 375.704748 -263.368872) (xy 375.696492 -263.387889)
			(xy 375.695972 -263.398254) (xy 375.695972 -264.367772) (xy 386.190488 -264.367772) (xy 386.194559 -264.31215)
			(xy 386.206685 -264.257713) (xy 386.226608 -264.205622) (xy 386.253904 -264.156987) (xy 386.28799 -264.112844)
			(xy 386.328139 -264.074135) (xy 386.373497 -264.041684) (xy 386.423097 -264.016183) (xy 386.475881 -263.998176)
			(xy 386.530724 -263.988046) (xy 386.586458 -263.986009) (xy 386.641895 -263.992109) (xy 386.695852 -264.006215)
			(xy 386.747181 -264.028027) (xy 386.794787 -264.057081) (xy 386.837655 -264.092756) (xy 386.874872 -264.134293)
			(xy 386.905645 -264.180806) (xy 386.929317 -264.231303) (xy 386.945385 -264.28471) (xy 386.953505 -264.339886)
			(xy 386.954014 -264.367772) (xy 386.953505 -264.395658) (xy 386.945385 -264.450834) (xy 386.929317 -264.504241)
			(xy 386.905645 -264.554738) (xy 386.874872 -264.601251) (xy 386.837655 -264.642788) (xy 386.794787 -264.678463)
			(xy 386.747181 -264.707517) (xy 386.695852 -264.729329) (xy 386.641895 -264.743435) (xy 386.586458 -264.749535)
			(xy 386.530724 -264.747498) (xy 386.475881 -264.737368) (xy 386.423097 -264.719361) (xy 386.373497 -264.69386)
			(xy 386.328139 -264.661409) (xy 386.28799 -264.6227) (xy 386.253904 -264.578557) (xy 386.226608 -264.529922)
			(xy 386.206685 -264.477831) (xy 386.194559 -264.423394) (xy 386.190488 -264.367772) (xy 375.695972 -264.367772)
			(xy 375.695972 -266.522708) (xy 375.696319 -266.531312) (xy 375.702022 -266.547551) (xy 375.712754 -266.561005)
			(xy 375.719848 -266.565888) (xy 375.80443 -266.618466) (xy 375.830592 -266.619736) (xy 375.842276 -266.613894)
			(xy 375.931526 -266.570586) (xy 376.113054 -266.49052) (xy 376.29775 -266.418062) (xy 376.485297 -266.353337)
			(xy 376.67537 -266.296457) (xy 376.867641 -266.24752) (xy 377.061779 -266.20661) (xy 377.257448 -266.173799)
			(xy 377.454312 -266.149143) (xy 377.652029 -266.132684) (xy 377.850259 -266.12445) (xy 377.94946 -266.123928)
			(xy 377.949714 -266.123928) (xy 378.047147 -266.124425) (xy 378.24185 -266.132374) (xy 378.436067 -266.148258)
			(xy 378.629475 -266.17205) (xy 378.821751 -266.203712) (xy 379.012576 -266.24319) (xy 379.201632 -266.290418)
			(xy 379.388604 -266.345319) (xy 379.573181 -266.4078) (xy 379.755056 -266.477757) (xy 379.933926 -266.555075)
			(xy 380.109494 -266.639625) (xy 380.281467 -266.731265) (xy 380.449559 -266.829843) (xy 380.61349 -266.935196)
			(xy 380.772987 -267.047147) (xy 380.927786 -267.165511) (xy 381.077628 -267.290091) (xy 381.222263 -267.420678)
			(xy 381.361452 -267.557057) (xy 381.381224 -267.578078) (xy 385.153152 -267.578078) (xy 385.157223 -267.522456)
			(xy 385.169349 -267.468019) (xy 385.189272 -267.415928) (xy 385.216568 -267.367293) (xy 385.250654 -267.32315)
			(xy 385.290803 -267.284441) (xy 385.336161 -267.25199) (xy 385.385761 -267.226489) (xy 385.438545 -267.208482)
			(xy 385.493388 -267.198352) (xy 385.549122 -267.196315) (xy 385.604559 -267.202415) (xy 385.658516 -267.216521)
			(xy 385.709845 -267.238333) (xy 385.757451 -267.267387) (xy 385.800319 -267.303062) (xy 385.837536 -267.344599)
			(xy 385.868309 -267.391112) (xy 385.891981 -267.441609) (xy 385.908049 -267.495016) (xy 385.916169 -267.550192)
			(xy 385.916678 -267.578078) (xy 385.916169 -267.605964) (xy 385.908049 -267.66114) (xy 385.891981 -267.714547)
			(xy 385.868309 -267.765044) (xy 385.837536 -267.811557) (xy 385.800319 -267.853094) (xy 385.757451 -267.888769)
			(xy 385.709845 -267.917823) (xy 385.658516 -267.939635) (xy 385.604559 -267.953741) (xy 385.549122 -267.959841)
			(xy 385.493388 -267.957804) (xy 385.438545 -267.947674) (xy 385.385761 -267.929667) (xy 385.336161 -267.904166)
			(xy 385.290803 -267.871715) (xy 385.250654 -267.833006) (xy 385.216568 -267.788863) (xy 385.189272 -267.740228)
			(xy 385.169349 -267.688137) (xy 385.157223 -267.6337) (xy 385.153152 -267.578078) (xy 381.381224 -267.578078)
			(xy 381.494963 -267.698999) (xy 381.622572 -267.846269) (xy 381.744069 -267.998621) (xy 381.85925 -268.155802)
			(xy 381.967924 -268.31755) (xy 382.06991 -268.483597) (xy 382.165039 -268.653665) (xy 382.253152 -268.827471)
			(xy 382.334102 -269.004727) (xy 382.407754 -269.185138) (xy 382.473987 -269.368402) (xy 382.532689 -269.554216)
			(xy 382.583764 -269.742269) (xy 382.627125 -269.932249) (xy 382.662702 -270.123839) (xy 382.690434 -270.316721)
			(xy 382.710276 -270.510574) (xy 382.722194 -270.705075) (xy 382.726169 -270.8999) (xy 382.722194 -271.094725)
			(xy 382.710276 -271.289226) (xy 382.690434 -271.483079) (xy 382.662702 -271.675961) (xy 382.627125 -271.867551)
			(xy 382.583764 -272.057531) (xy 382.532689 -272.245584) (xy 382.473987 -272.431398) (xy 382.407754 -272.614662)
			(xy 382.403614 -272.624804) (xy 386.269242 -272.624804) (xy 386.273202 -272.57575) (xy 386.284979 -272.527966)
			(xy 386.30427 -272.48269) (xy 386.330573 -272.441094) (xy 386.363208 -272.404257) (xy 386.401329 -272.373132)
			(xy 386.44395 -272.348525) (xy 386.489966 -272.331073) (xy 386.538185 -272.321229) (xy 386.58736 -272.319248)
			(xy 386.636215 -272.32518) (xy 386.683486 -272.338872) (xy 386.727948 -272.35997) (xy 386.768451 -272.387926)
			(xy 386.803944 -272.422018) (xy 386.833509 -272.461362) (xy 386.85638 -272.504939) (xy 386.871964 -272.55162)
			(xy 386.879859 -272.600197) (xy 386.880354 -272.624804) (xy 386.879859 -272.649411) (xy 386.871964 -272.697988)
			(xy 386.85638 -272.744669) (xy 386.833509 -272.788246) (xy 386.803944 -272.82759) (xy 386.768451 -272.861682)
			(xy 386.727948 -272.889638) (xy 386.683486 -272.910736) (xy 386.636215 -272.924428) (xy 386.58736 -272.93036)
			(xy 386.538185 -272.928379) (xy 386.489966 -272.918535) (xy 386.44395 -272.901083) (xy 386.401329 -272.876476)
			(xy 386.363208 -272.845351) (xy 386.330573 -272.808514) (xy 386.30427 -272.766918) (xy 386.284979 -272.721642)
			(xy 386.273202 -272.673858) (xy 386.269242 -272.624804) (xy 382.403614 -272.624804) (xy 382.334102 -272.795073)
			(xy 382.253152 -272.972329) (xy 382.165039 -273.146135) (xy 382.06991 -273.316203) (xy 381.967924 -273.48225)
			(xy 381.905766 -273.574764) (xy 385.319028 -273.574764) (xy 385.322988 -273.52571) (xy 385.334765 -273.477926)
			(xy 385.354056 -273.43265) (xy 385.380359 -273.391054) (xy 385.412994 -273.354217) (xy 385.451115 -273.323092)
			(xy 385.493736 -273.298485) (xy 385.539752 -273.281033) (xy 385.587971 -273.271189) (xy 385.637146 -273.269208)
			(xy 385.686001 -273.27514) (xy 385.733272 -273.288832) (xy 385.777734 -273.30993) (xy 385.818237 -273.337886)
			(xy 385.85373 -273.371978) (xy 385.883295 -273.411322) (xy 385.906166 -273.454899) (xy 385.92175 -273.50158)
			(xy 385.929645 -273.550157) (xy 385.93014 -273.574764) (xy 386.268988 -273.574764) (xy 386.272948 -273.52571)
			(xy 386.284725 -273.477926) (xy 386.304016 -273.43265) (xy 386.330319 -273.391054) (xy 386.362954 -273.354217)
			(xy 386.401075 -273.323092) (xy 386.443696 -273.298485) (xy 386.489712 -273.281033) (xy 386.537931 -273.271189)
			(xy 386.587106 -273.269208) (xy 386.635961 -273.27514) (xy 386.683232 -273.288832) (xy 386.727694 -273.30993)
			(xy 386.768197 -273.337886) (xy 386.80369 -273.371978) (xy 386.833255 -273.411322) (xy 386.856126 -273.454899)
			(xy 386.87171 -273.50158) (xy 386.879605 -273.550157) (xy 386.8801 -273.574764) (xy 386.879605 -273.599371)
			(xy 386.87171 -273.647948) (xy 386.856126 -273.694629) (xy 386.833255 -273.738206) (xy 386.80369 -273.77755)
			(xy 386.768197 -273.811642) (xy 386.727694 -273.839598) (xy 386.683232 -273.860696) (xy 386.635961 -273.874388)
			(xy 386.587106 -273.88032) (xy 386.537931 -273.878339) (xy 386.489712 -273.868495) (xy 386.443696 -273.851043)
			(xy 386.401075 -273.826436) (xy 386.362954 -273.795311) (xy 386.330319 -273.758474) (xy 386.304016 -273.716878)
			(xy 386.284725 -273.671602) (xy 386.272948 -273.623818) (xy 386.268988 -273.574764) (xy 385.93014 -273.574764)
			(xy 385.929645 -273.599371) (xy 385.92175 -273.647948) (xy 385.906166 -273.694629) (xy 385.883295 -273.738206)
			(xy 385.85373 -273.77755) (xy 385.818237 -273.811642) (xy 385.777734 -273.839598) (xy 385.733272 -273.860696)
			(xy 385.686001 -273.874388) (xy 385.637146 -273.88032) (xy 385.587971 -273.878339) (xy 385.539752 -273.868495)
			(xy 385.493736 -273.851043) (xy 385.451115 -273.826436) (xy 385.412994 -273.795311) (xy 385.380359 -273.758474)
			(xy 385.354056 -273.716878) (xy 385.334765 -273.671602) (xy 385.322988 -273.623818) (xy 385.319028 -273.574764)
			(xy 381.905766 -273.574764) (xy 381.85925 -273.643998) (xy 381.744069 -273.801179) (xy 381.622572 -273.953531)
			(xy 381.494963 -274.100801) (xy 381.361452 -274.242743) (xy 381.222263 -274.379122) (xy 381.077628 -274.509709)
			(xy 381.059568 -274.524724) (xy 385.319028 -274.524724) (xy 385.322988 -274.47567) (xy 385.334765 -274.427886)
			(xy 385.354056 -274.38261) (xy 385.380359 -274.341014) (xy 385.412994 -274.304177) (xy 385.451115 -274.273052)
			(xy 385.493736 -274.248445) (xy 385.539752 -274.230993) (xy 385.587971 -274.221149) (xy 385.637146 -274.219168)
			(xy 385.686001 -274.2251) (xy 385.733272 -274.238792) (xy 385.777734 -274.25989) (xy 385.818237 -274.287846)
			(xy 385.85373 -274.321938) (xy 385.883295 -274.361282) (xy 385.906166 -274.404859) (xy 385.92175 -274.45154)
			(xy 385.929645 -274.500117) (xy 385.93014 -274.524724) (xy 385.930135 -274.524978) (xy 386.269242 -274.524978)
			(xy 386.273202 -274.475924) (xy 386.284979 -274.42814) (xy 386.30427 -274.382864) (xy 386.330573 -274.341268)
			(xy 386.363208 -274.304431) (xy 386.401329 -274.273306) (xy 386.44395 -274.248699) (xy 386.489966 -274.231247)
			(xy 386.538185 -274.221403) (xy 386.58736 -274.219422) (xy 386.636215 -274.225354) (xy 386.683486 -274.239046)
			(xy 386.727948 -274.260144) (xy 386.768451 -274.2881) (xy 386.803944 -274.322192) (xy 386.833509 -274.361536)
			(xy 386.85638 -274.405113) (xy 386.871964 -274.451794) (xy 386.879859 -274.500371) (xy 386.880354 -274.524978)
			(xy 386.879859 -274.549585) (xy 386.871964 -274.598162) (xy 386.85638 -274.644843) (xy 386.833509 -274.68842)
			(xy 386.803944 -274.727764) (xy 386.768451 -274.761856) (xy 386.727948 -274.789812) (xy 386.683486 -274.81091)
			(xy 386.636215 -274.824602) (xy 386.58736 -274.830534) (xy 386.538185 -274.828553) (xy 386.489966 -274.818709)
			(xy 386.44395 -274.801257) (xy 386.401329 -274.77665) (xy 386.363208 -274.745525) (xy 386.330573 -274.708688)
			(xy 386.30427 -274.667092) (xy 386.284979 -274.621816) (xy 386.273202 -274.574032) (xy 386.269242 -274.524978)
			(xy 385.930135 -274.524978) (xy 385.929645 -274.549331) (xy 385.92175 -274.597908) (xy 385.906166 -274.644589)
			(xy 385.883295 -274.688166) (xy 385.85373 -274.72751) (xy 385.818237 -274.761602) (xy 385.777734 -274.789558)
			(xy 385.733272 -274.810656) (xy 385.686001 -274.824348) (xy 385.637146 -274.83028) (xy 385.587971 -274.828299)
			(xy 385.539752 -274.818455) (xy 385.493736 -274.801003) (xy 385.451115 -274.776396) (xy 385.412994 -274.745271)
			(xy 385.380359 -274.708434) (xy 385.354056 -274.666838) (xy 385.334765 -274.621562) (xy 385.322988 -274.573778)
			(xy 385.319028 -274.524724) (xy 381.059568 -274.524724) (xy 380.927786 -274.634289) (xy 380.772987 -274.752653)
			(xy 380.61349 -274.864604) (xy 380.449559 -274.969957) (xy 380.281467 -275.068535) (xy 380.109494 -275.160175)
			(xy 379.933926 -275.244725) (xy 379.755056 -275.322043) (xy 379.573181 -275.392) (xy 379.388604 -275.454481)
			(xy 379.318935 -275.474938) (xy 384.369068 -275.474938) (xy 384.373028 -275.425884) (xy 384.384805 -275.3781)
			(xy 384.404096 -275.332824) (xy 384.430399 -275.291228) (xy 384.463034 -275.254391) (xy 384.501155 -275.223266)
			(xy 384.543776 -275.198659) (xy 384.589792 -275.181207) (xy 384.638011 -275.171363) (xy 384.687186 -275.169382)
			(xy 384.736041 -275.175314) (xy 384.783312 -275.189006) (xy 384.827774 -275.210104) (xy 384.868277 -275.23806)
			(xy 384.90377 -275.272152) (xy 384.933335 -275.311496) (xy 384.956206 -275.355073) (xy 384.97179 -275.401754)
			(xy 384.979685 -275.450331) (xy 384.98018 -275.474938) (xy 385.319028 -275.474938) (xy 385.322988 -275.425884)
			(xy 385.334765 -275.3781) (xy 385.354056 -275.332824) (xy 385.380359 -275.291228) (xy 385.412994 -275.254391)
			(xy 385.451115 -275.223266) (xy 385.493736 -275.198659) (xy 385.539752 -275.181207) (xy 385.587971 -275.171363)
			(xy 385.637146 -275.169382) (xy 385.686001 -275.175314) (xy 385.733272 -275.189006) (xy 385.777734 -275.210104)
			(xy 385.818237 -275.23806) (xy 385.85373 -275.272152) (xy 385.883295 -275.311496) (xy 385.906166 -275.355073)
			(xy 385.92175 -275.401754) (xy 385.929645 -275.450331) (xy 385.93014 -275.474938) (xy 386.269242 -275.474938)
			(xy 386.273202 -275.425884) (xy 386.284979 -275.3781) (xy 386.30427 -275.332824) (xy 386.330573 -275.291228)
			(xy 386.363208 -275.254391) (xy 386.401329 -275.223266) (xy 386.44395 -275.198659) (xy 386.489966 -275.181207)
			(xy 386.538185 -275.171363) (xy 386.58736 -275.169382) (xy 386.636215 -275.175314) (xy 386.683486 -275.189006)
			(xy 386.727948 -275.210104) (xy 386.768451 -275.23806) (xy 386.803944 -275.272152) (xy 386.833509 -275.311496)
			(xy 386.85638 -275.355073) (xy 386.871964 -275.401754) (xy 386.879859 -275.450331) (xy 386.880354 -275.474938)
			(xy 386.879859 -275.499545) (xy 386.871964 -275.548122) (xy 386.85638 -275.594803) (xy 386.833509 -275.63838)
			(xy 386.803944 -275.677724) (xy 386.768451 -275.711816) (xy 386.727948 -275.739772) (xy 386.683486 -275.76087)
			(xy 386.636215 -275.774562) (xy 386.58736 -275.780494) (xy 386.538185 -275.778513) (xy 386.489966 -275.768669)
			(xy 386.44395 -275.751217) (xy 386.401329 -275.72661) (xy 386.363208 -275.695485) (xy 386.330573 -275.658648)
			(xy 386.30427 -275.617052) (xy 386.284979 -275.571776) (xy 386.273202 -275.523992) (xy 386.269242 -275.474938)
			(xy 385.93014 -275.474938) (xy 385.929645 -275.499545) (xy 385.92175 -275.548122) (xy 385.906166 -275.594803)
			(xy 385.883295 -275.63838) (xy 385.85373 -275.677724) (xy 385.818237 -275.711816) (xy 385.777734 -275.739772)
			(xy 385.733272 -275.76087) (xy 385.686001 -275.774562) (xy 385.637146 -275.780494) (xy 385.587971 -275.778513)
			(xy 385.539752 -275.768669) (xy 385.493736 -275.751217) (xy 385.451115 -275.72661) (xy 385.412994 -275.695485)
			(xy 385.380359 -275.658648) (xy 385.354056 -275.617052) (xy 385.334765 -275.571776) (xy 385.322988 -275.523992)
			(xy 385.319028 -275.474938) (xy 384.98018 -275.474938) (xy 384.979685 -275.499545) (xy 384.97179 -275.548122)
			(xy 384.956206 -275.594803) (xy 384.933335 -275.63838) (xy 384.90377 -275.677724) (xy 384.868277 -275.711816)
			(xy 384.827774 -275.739772) (xy 384.783312 -275.76087) (xy 384.736041 -275.774562) (xy 384.687186 -275.780494)
			(xy 384.638011 -275.778513) (xy 384.589792 -275.768669) (xy 384.543776 -275.751217) (xy 384.501155 -275.72661)
			(xy 384.463034 -275.695485) (xy 384.430399 -275.658648) (xy 384.404096 -275.617052) (xy 384.384805 -275.571776)
			(xy 384.373028 -275.523992) (xy 384.369068 -275.474938) (xy 379.318935 -275.474938) (xy 379.201632 -275.509382)
			(xy 379.012576 -275.55661) (xy 378.821751 -275.596088) (xy 378.629475 -275.62775) (xy 378.436067 -275.651542)
			(xy 378.24185 -275.667426) (xy 378.047147 -275.675375) (xy 377.949714 -275.675852) (xy 377.947936 -275.675852)
			(xy 377.885232 -275.675645) (xy 377.759866 -275.672342) (xy 377.697238 -275.669248) (xy 377.686316 -275.66874)
			(xy 377.676156 -275.67255) (xy 377.671192 -275.674592) (xy 377.662227 -275.680493) (xy 377.658376 -275.684234)
			(xy 376.917712 -276.424898) (xy 384.369068 -276.424898) (xy 384.373028 -276.375844) (xy 384.384805 -276.32806)
			(xy 384.404096 -276.282784) (xy 384.430399 -276.241188) (xy 384.463034 -276.204351) (xy 384.501155 -276.173226)
			(xy 384.543776 -276.148619) (xy 384.589792 -276.131167) (xy 384.638011 -276.121323) (xy 384.687186 -276.119342)
			(xy 384.736041 -276.125274) (xy 384.783312 -276.138966) (xy 384.827774 -276.160064) (xy 384.868277 -276.18802)
			(xy 384.90377 -276.222112) (xy 384.933335 -276.261456) (xy 384.956206 -276.305033) (xy 384.97179 -276.351714)
			(xy 384.979685 -276.400291) (xy 384.98018 -276.424898) (xy 385.319028 -276.424898) (xy 385.322988 -276.375844)
			(xy 385.334765 -276.32806) (xy 385.354056 -276.282784) (xy 385.380359 -276.241188) (xy 385.412994 -276.204351)
			(xy 385.451115 -276.173226) (xy 385.493736 -276.148619) (xy 385.539752 -276.131167) (xy 385.587971 -276.121323)
			(xy 385.637146 -276.119342) (xy 385.686001 -276.125274) (xy 385.733272 -276.138966) (xy 385.777734 -276.160064)
			(xy 385.818237 -276.18802) (xy 385.85373 -276.222112) (xy 385.883295 -276.261456) (xy 385.906166 -276.305033)
			(xy 385.92175 -276.351714) (xy 385.929645 -276.400291) (xy 385.93014 -276.424898) (xy 386.269242 -276.424898)
			(xy 386.273202 -276.375844) (xy 386.284979 -276.32806) (xy 386.30427 -276.282784) (xy 386.330573 -276.241188)
			(xy 386.363208 -276.204351) (xy 386.401329 -276.173226) (xy 386.44395 -276.148619) (xy 386.489966 -276.131167)
			(xy 386.538185 -276.121323) (xy 386.58736 -276.119342) (xy 386.636215 -276.125274) (xy 386.683486 -276.138966)
			(xy 386.727948 -276.160064) (xy 386.768451 -276.18802) (xy 386.803944 -276.222112) (xy 386.833509 -276.261456)
			(xy 386.85638 -276.305033) (xy 386.871964 -276.351714) (xy 386.879859 -276.400291) (xy 386.880354 -276.424898)
			(xy 386.879859 -276.449505) (xy 386.871964 -276.498082) (xy 386.85638 -276.544763) (xy 386.833509 -276.58834)
			(xy 386.803944 -276.627684) (xy 386.768451 -276.661776) (xy 386.727948 -276.689732) (xy 386.683486 -276.71083)
			(xy 386.636215 -276.724522) (xy 386.58736 -276.730454) (xy 386.538185 -276.728473) (xy 386.489966 -276.718629)
			(xy 386.44395 -276.701177) (xy 386.401329 -276.67657) (xy 386.363208 -276.645445) (xy 386.330573 -276.608608)
			(xy 386.30427 -276.567012) (xy 386.284979 -276.521736) (xy 386.273202 -276.473952) (xy 386.269242 -276.424898)
			(xy 385.93014 -276.424898) (xy 385.929645 -276.449505) (xy 385.92175 -276.498082) (xy 385.906166 -276.544763)
			(xy 385.883295 -276.58834) (xy 385.85373 -276.627684) (xy 385.818237 -276.661776) (xy 385.777734 -276.689732)
			(xy 385.733272 -276.71083) (xy 385.686001 -276.724522) (xy 385.637146 -276.730454) (xy 385.587971 -276.728473)
			(xy 385.539752 -276.718629) (xy 385.493736 -276.701177) (xy 385.451115 -276.67657) (xy 385.412994 -276.645445)
			(xy 385.380359 -276.608608) (xy 385.354056 -276.567012) (xy 385.334765 -276.521736) (xy 385.322988 -276.473952)
			(xy 385.319028 -276.424898) (xy 384.98018 -276.424898) (xy 384.979685 -276.449505) (xy 384.97179 -276.498082)
			(xy 384.956206 -276.544763) (xy 384.933335 -276.58834) (xy 384.90377 -276.627684) (xy 384.868277 -276.661776)
			(xy 384.827774 -276.689732) (xy 384.783312 -276.71083) (xy 384.736041 -276.724522) (xy 384.687186 -276.730454)
			(xy 384.638011 -276.728473) (xy 384.589792 -276.718629) (xy 384.543776 -276.701177) (xy 384.501155 -276.67657)
			(xy 384.463034 -276.645445) (xy 384.430399 -276.608608) (xy 384.404096 -276.567012) (xy 384.384805 -276.521736)
			(xy 384.373028 -276.473952) (xy 384.369068 -276.424898) (xy 376.917712 -276.424898) (xy 375.967752 -277.374858)
			(xy 384.369068 -277.374858) (xy 384.373028 -277.325804) (xy 384.384805 -277.27802) (xy 384.404096 -277.232744)
			(xy 384.430399 -277.191148) (xy 384.463034 -277.154311) (xy 384.501155 -277.123186) (xy 384.543776 -277.098579)
			(xy 384.589792 -277.081127) (xy 384.638011 -277.071283) (xy 384.687186 -277.069302) (xy 384.736041 -277.075234)
			(xy 384.783312 -277.088926) (xy 384.827774 -277.110024) (xy 384.868277 -277.13798) (xy 384.90377 -277.172072)
			(xy 384.933335 -277.211416) (xy 384.956206 -277.254993) (xy 384.97179 -277.301674) (xy 384.979685 -277.350251)
			(xy 384.98018 -277.374858) (xy 385.319028 -277.374858) (xy 385.322988 -277.325804) (xy 385.334765 -277.27802)
			(xy 385.354056 -277.232744) (xy 385.380359 -277.191148) (xy 385.412994 -277.154311) (xy 385.451115 -277.123186)
			(xy 385.493736 -277.098579) (xy 385.539752 -277.081127) (xy 385.587971 -277.071283) (xy 385.637146 -277.069302)
			(xy 385.686001 -277.075234) (xy 385.733272 -277.088926) (xy 385.777734 -277.110024) (xy 385.818237 -277.13798)
			(xy 385.85373 -277.172072) (xy 385.883295 -277.211416) (xy 385.906166 -277.254993) (xy 385.92175 -277.301674)
			(xy 385.929645 -277.350251) (xy 385.93014 -277.374858) (xy 386.269242 -277.374858) (xy 386.273202 -277.325804)
			(xy 386.284979 -277.27802) (xy 386.30427 -277.232744) (xy 386.330573 -277.191148) (xy 386.363208 -277.154311)
			(xy 386.401329 -277.123186) (xy 386.44395 -277.098579) (xy 386.489966 -277.081127) (xy 386.538185 -277.071283)
			(xy 386.58736 -277.069302) (xy 386.636215 -277.075234) (xy 386.683486 -277.088926) (xy 386.727948 -277.110024)
			(xy 386.768451 -277.13798) (xy 386.803944 -277.172072) (xy 386.833509 -277.211416) (xy 386.85638 -277.254993)
			(xy 386.871964 -277.301674) (xy 386.879859 -277.350251) (xy 386.880354 -277.374858) (xy 386.879859 -277.399465)
			(xy 386.871964 -277.448042) (xy 386.85638 -277.494723) (xy 386.833509 -277.5383) (xy 386.803944 -277.577644)
			(xy 386.768451 -277.611736) (xy 386.727948 -277.639692) (xy 386.683486 -277.66079) (xy 386.636215 -277.674482)
			(xy 386.58736 -277.680414) (xy 386.538185 -277.678433) (xy 386.489966 -277.668589) (xy 386.44395 -277.651137)
			(xy 386.401329 -277.62653) (xy 386.363208 -277.595405) (xy 386.330573 -277.558568) (xy 386.30427 -277.516972)
			(xy 386.284979 -277.471696) (xy 386.273202 -277.423912) (xy 386.269242 -277.374858) (xy 385.93014 -277.374858)
			(xy 385.929645 -277.399465) (xy 385.92175 -277.448042) (xy 385.906166 -277.494723) (xy 385.883295 -277.5383)
			(xy 385.85373 -277.577644) (xy 385.818237 -277.611736) (xy 385.777734 -277.639692) (xy 385.733272 -277.66079)
			(xy 385.686001 -277.674482) (xy 385.637146 -277.680414) (xy 385.587971 -277.678433) (xy 385.539752 -277.668589)
			(xy 385.493736 -277.651137) (xy 385.451115 -277.62653) (xy 385.412994 -277.595405) (xy 385.380359 -277.558568)
			(xy 385.354056 -277.516972) (xy 385.334765 -277.471696) (xy 385.322988 -277.423912) (xy 385.319028 -277.374858)
			(xy 384.98018 -277.374858) (xy 384.979685 -277.399465) (xy 384.97179 -277.448042) (xy 384.956206 -277.494723)
			(xy 384.933335 -277.5383) (xy 384.90377 -277.577644) (xy 384.868277 -277.611736) (xy 384.827774 -277.639692)
			(xy 384.783312 -277.66079) (xy 384.736041 -277.674482) (xy 384.687186 -277.680414) (xy 384.638011 -277.678433)
			(xy 384.589792 -277.668589) (xy 384.543776 -277.651137) (xy 384.501155 -277.62653) (xy 384.463034 -277.595405)
			(xy 384.430399 -277.558568) (xy 384.404096 -277.516972) (xy 384.384805 -277.471696) (xy 384.373028 -277.423912)
			(xy 384.369068 -277.374858) (xy 375.967752 -277.374858) (xy 375.017792 -278.324818) (xy 384.369068 -278.324818)
			(xy 384.373028 -278.275764) (xy 384.384805 -278.22798) (xy 384.404096 -278.182704) (xy 384.430399 -278.141108)
			(xy 384.463034 -278.104271) (xy 384.501155 -278.073146) (xy 384.543776 -278.048539) (xy 384.589792 -278.031087)
			(xy 384.638011 -278.021243) (xy 384.687186 -278.019262) (xy 384.736041 -278.025194) (xy 384.783312 -278.038886)
			(xy 384.827774 -278.059984) (xy 384.868277 -278.08794) (xy 384.90377 -278.122032) (xy 384.933335 -278.161376)
			(xy 384.956206 -278.204953) (xy 384.97179 -278.251634) (xy 384.979685 -278.300211) (xy 384.98018 -278.324818)
			(xy 385.319028 -278.324818) (xy 385.322988 -278.275764) (xy 385.334765 -278.22798) (xy 385.354056 -278.182704)
			(xy 385.380359 -278.141108) (xy 385.412994 -278.104271) (xy 385.451115 -278.073146) (xy 385.493736 -278.048539)
			(xy 385.539752 -278.031087) (xy 385.587971 -278.021243) (xy 385.637146 -278.019262) (xy 385.686001 -278.025194)
			(xy 385.733272 -278.038886) (xy 385.777734 -278.059984) (xy 385.818237 -278.08794) (xy 385.85373 -278.122032)
			(xy 385.883295 -278.161376) (xy 385.906166 -278.204953) (xy 385.92175 -278.251634) (xy 385.929645 -278.300211)
			(xy 385.93014 -278.324818) (xy 386.269242 -278.324818) (xy 386.273202 -278.275764) (xy 386.284979 -278.22798)
			(xy 386.30427 -278.182704) (xy 386.330573 -278.141108) (xy 386.363208 -278.104271) (xy 386.401329 -278.073146)
			(xy 386.44395 -278.048539) (xy 386.489966 -278.031087) (xy 386.538185 -278.021243) (xy 386.58736 -278.019262)
			(xy 386.636215 -278.025194) (xy 386.683486 -278.038886) (xy 386.727948 -278.059984) (xy 386.768451 -278.08794)
			(xy 386.803944 -278.122032) (xy 386.833509 -278.161376) (xy 386.85638 -278.204953) (xy 386.871964 -278.251634)
			(xy 386.879859 -278.300211) (xy 386.880354 -278.324818) (xy 386.879859 -278.349425) (xy 386.871964 -278.398002)
			(xy 386.85638 -278.444683) (xy 386.833509 -278.48826) (xy 386.803944 -278.527604) (xy 386.768451 -278.561696)
			(xy 386.727948 -278.589652) (xy 386.683486 -278.61075) (xy 386.636215 -278.624442) (xy 386.58736 -278.630374)
			(xy 386.538185 -278.628393) (xy 386.489966 -278.618549) (xy 386.44395 -278.601097) (xy 386.401329 -278.57649)
			(xy 386.363208 -278.545365) (xy 386.330573 -278.508528) (xy 386.30427 -278.466932) (xy 386.284979 -278.421656)
			(xy 386.273202 -278.373872) (xy 386.269242 -278.324818) (xy 385.93014 -278.324818) (xy 385.929645 -278.349425)
			(xy 385.92175 -278.398002) (xy 385.906166 -278.444683) (xy 385.883295 -278.48826) (xy 385.85373 -278.527604)
			(xy 385.818237 -278.561696) (xy 385.777734 -278.589652) (xy 385.733272 -278.61075) (xy 385.686001 -278.624442)
			(xy 385.637146 -278.630374) (xy 385.587971 -278.628393) (xy 385.539752 -278.618549) (xy 385.493736 -278.601097)
			(xy 385.451115 -278.57649) (xy 385.412994 -278.545365) (xy 385.380359 -278.508528) (xy 385.354056 -278.466932)
			(xy 385.334765 -278.421656) (xy 385.322988 -278.373872) (xy 385.319028 -278.324818) (xy 384.98018 -278.324818)
			(xy 384.979685 -278.349425) (xy 384.97179 -278.398002) (xy 384.956206 -278.444683) (xy 384.933335 -278.48826)
			(xy 384.90377 -278.527604) (xy 384.868277 -278.561696) (xy 384.827774 -278.589652) (xy 384.783312 -278.61075)
			(xy 384.736041 -278.624442) (xy 384.687186 -278.630374) (xy 384.638011 -278.628393) (xy 384.589792 -278.618549)
			(xy 384.543776 -278.601097) (xy 384.501155 -278.57649) (xy 384.463034 -278.545365) (xy 384.430399 -278.508528)
			(xy 384.404096 -278.466932) (xy 384.384805 -278.421656) (xy 384.373028 -278.373872) (xy 384.369068 -278.324818)
			(xy 375.017792 -278.324818) (xy 374.078754 -279.263856) (xy 374.074436 -279.268936) (xy 374.07342 -279.270206)
			(xy 374.069855 -279.274778) (xy 384.369068 -279.274778) (xy 384.373028 -279.225724) (xy 384.384805 -279.17794)
			(xy 384.404096 -279.132664) (xy 384.430399 -279.091068) (xy 384.463034 -279.054231) (xy 384.501155 -279.023106)
			(xy 384.543776 -278.998499) (xy 384.589792 -278.981047) (xy 384.638011 -278.971203) (xy 384.687186 -278.969222)
			(xy 384.736041 -278.975154) (xy 384.783312 -278.988846) (xy 384.827774 -279.009944) (xy 384.868277 -279.0379)
			(xy 384.90377 -279.071992) (xy 384.933335 -279.111336) (xy 384.956206 -279.154913) (xy 384.97179 -279.201594)
			(xy 384.979685 -279.250171) (xy 384.98018 -279.274778) (xy 385.319028 -279.274778) (xy 385.322988 -279.225724)
			(xy 385.334765 -279.17794) (xy 385.354056 -279.132664) (xy 385.380359 -279.091068) (xy 385.412994 -279.054231)
			(xy 385.451115 -279.023106) (xy 385.493736 -278.998499) (xy 385.539752 -278.981047) (xy 385.587971 -278.971203)
			(xy 385.637146 -278.969222) (xy 385.686001 -278.975154) (xy 385.733272 -278.988846) (xy 385.777734 -279.009944)
			(xy 385.818237 -279.0379) (xy 385.85373 -279.071992) (xy 385.883295 -279.111336) (xy 385.906166 -279.154913)
			(xy 385.92175 -279.201594) (xy 385.929645 -279.250171) (xy 385.93014 -279.274778) (xy 386.269242 -279.274778)
			(xy 386.273202 -279.225724) (xy 386.284979 -279.17794) (xy 386.30427 -279.132664) (xy 386.330573 -279.091068)
			(xy 386.363208 -279.054231) (xy 386.401329 -279.023106) (xy 386.44395 -278.998499) (xy 386.489966 -278.981047)
			(xy 386.538185 -278.971203) (xy 386.58736 -278.969222) (xy 386.636215 -278.975154) (xy 386.683486 -278.988846)
			(xy 386.727948 -279.009944) (xy 386.768451 -279.0379) (xy 386.803944 -279.071992) (xy 386.833509 -279.111336)
			(xy 386.85638 -279.154913) (xy 386.871964 -279.201594) (xy 386.879859 -279.250171) (xy 386.880354 -279.274778)
			(xy 386.879859 -279.299385) (xy 386.871964 -279.347962) (xy 386.85638 -279.394643) (xy 386.833509 -279.43822)
			(xy 386.803944 -279.477564) (xy 386.768451 -279.511656) (xy 386.727948 -279.539612) (xy 386.683486 -279.56071)
			(xy 386.636215 -279.574402) (xy 386.58736 -279.580334) (xy 386.538185 -279.578353) (xy 386.489966 -279.568509)
			(xy 386.44395 -279.551057) (xy 386.401329 -279.52645) (xy 386.363208 -279.495325) (xy 386.330573 -279.458488)
			(xy 386.30427 -279.416892) (xy 386.284979 -279.371616) (xy 386.273202 -279.323832) (xy 386.269242 -279.274778)
			(xy 385.93014 -279.274778) (xy 385.929645 -279.299385) (xy 385.92175 -279.347962) (xy 385.906166 -279.394643)
			(xy 385.883295 -279.43822) (xy 385.85373 -279.477564) (xy 385.818237 -279.511656) (xy 385.777734 -279.539612)
			(xy 385.733272 -279.56071) (xy 385.686001 -279.574402) (xy 385.637146 -279.580334) (xy 385.587971 -279.578353)
			(xy 385.539752 -279.568509) (xy 385.493736 -279.551057) (xy 385.451115 -279.52645) (xy 385.412994 -279.495325)
			(xy 385.380359 -279.458488) (xy 385.354056 -279.416892) (xy 385.334765 -279.371616) (xy 385.322988 -279.323832)
			(xy 385.319028 -279.274778) (xy 384.98018 -279.274778) (xy 384.979685 -279.299385) (xy 384.97179 -279.347962)
			(xy 384.956206 -279.394643) (xy 384.933335 -279.43822) (xy 384.90377 -279.477564) (xy 384.868277 -279.511656)
			(xy 384.827774 -279.539612) (xy 384.783312 -279.56071) (xy 384.736041 -279.574402) (xy 384.687186 -279.580334)
			(xy 384.638011 -279.578353) (xy 384.589792 -279.568509) (xy 384.543776 -279.551057) (xy 384.501155 -279.52645)
			(xy 384.463034 -279.495325) (xy 384.430399 -279.458488) (xy 384.404096 -279.416892) (xy 384.384805 -279.371616)
			(xy 384.373028 -279.323832) (xy 384.369068 -279.274778) (xy 374.069855 -279.274778) (xy 374.066968 -279.278481)
			(xy 374.053113 -279.294242) (xy 374.045734 -279.301702) (xy 373.754396 -279.593294) (xy 373.668544 -279.679146)
			(xy 373.668036 -279.680416) (xy 373.668036 -279.931114) (xy 374.111518 -279.931114) (xy 374.115589 -279.875492)
			(xy 374.127715 -279.821055) (xy 374.147638 -279.768964) (xy 374.174934 -279.720329) (xy 374.20902 -279.676186)
			(xy 374.249169 -279.637477) (xy 374.294527 -279.605026) (xy 374.344127 -279.579525) (xy 374.396911 -279.561518)
			(xy 374.451754 -279.551388) (xy 374.507488 -279.549351) (xy 374.562925 -279.555451) (xy 374.616882 -279.569557)
			(xy 374.668211 -279.591369) (xy 374.715817 -279.620423) (xy 374.758685 -279.656098) (xy 374.795902 -279.697635)
			(xy 374.826675 -279.744148) (xy 374.850347 -279.794645) (xy 374.866415 -279.848052) (xy 374.874535 -279.903228)
			(xy 374.875044 -279.931114) (xy 375.587004 -279.931114) (xy 375.591075 -279.875492) (xy 375.603201 -279.821055)
			(xy 375.623124 -279.768964) (xy 375.65042 -279.720329) (xy 375.684506 -279.676186) (xy 375.724655 -279.637477)
			(xy 375.770013 -279.605026) (xy 375.819613 -279.579525) (xy 375.872397 -279.561518) (xy 375.92724 -279.551388)
			(xy 375.982974 -279.549351) (xy 376.038411 -279.555451) (xy 376.092368 -279.569557) (xy 376.143697 -279.591369)
			(xy 376.191303 -279.620423) (xy 376.234171 -279.656098) (xy 376.271388 -279.697635) (xy 376.302161 -279.744148)
			(xy 376.325833 -279.794645) (xy 376.341901 -279.848052) (xy 376.350021 -279.903228) (xy 376.35053 -279.931114)
			(xy 376.476004 -279.931114) (xy 376.480075 -279.875492) (xy 376.492201 -279.821055) (xy 376.512124 -279.768964)
			(xy 376.53942 -279.720329) (xy 376.573506 -279.676186) (xy 376.613655 -279.637477) (xy 376.659013 -279.605026)
			(xy 376.708613 -279.579525) (xy 376.761397 -279.561518) (xy 376.81624 -279.551388) (xy 376.871974 -279.549351)
			(xy 376.927411 -279.555451) (xy 376.981368 -279.569557) (xy 377.032697 -279.591369) (xy 377.080303 -279.620423)
			(xy 377.123171 -279.656098) (xy 377.160388 -279.697635) (xy 377.191161 -279.744148) (xy 377.214833 -279.794645)
			(xy 377.230901 -279.848052) (xy 377.239021 -279.903228) (xy 377.23953 -279.931114) (xy 377.239021 -279.959)
			(xy 377.230901 -280.014176) (xy 377.214833 -280.067583) (xy 377.191161 -280.11808) (xy 377.160388 -280.164593)
			(xy 377.123171 -280.20613) (xy 377.080303 -280.241805) (xy 377.032697 -280.270859) (xy 376.981368 -280.292671)
			(xy 376.927411 -280.306777) (xy 376.871974 -280.312877) (xy 376.81624 -280.31084) (xy 376.761397 -280.30071)
			(xy 376.708613 -280.282703) (xy 376.659013 -280.257202) (xy 376.613655 -280.224751) (xy 376.573506 -280.186042)
			(xy 376.53942 -280.141899) (xy 376.512124 -280.093264) (xy 376.492201 -280.041173) (xy 376.480075 -279.986736)
			(xy 376.476004 -279.931114) (xy 376.35053 -279.931114) (xy 376.350021 -279.959) (xy 376.341901 -280.014176)
			(xy 376.325833 -280.067583) (xy 376.302161 -280.11808) (xy 376.271388 -280.164593) (xy 376.234171 -280.20613)
			(xy 376.191303 -280.241805) (xy 376.143697 -280.270859) (xy 376.092368 -280.292671) (xy 376.038411 -280.306777)
			(xy 375.982974 -280.312877) (xy 375.92724 -280.31084) (xy 375.872397 -280.30071) (xy 375.819613 -280.282703)
			(xy 375.770013 -280.257202) (xy 375.724655 -280.224751) (xy 375.684506 -280.186042) (xy 375.65042 -280.141899)
			(xy 375.623124 -280.093264) (xy 375.603201 -280.041173) (xy 375.591075 -279.986736) (xy 375.587004 -279.931114)
			(xy 374.875044 -279.931114) (xy 374.874535 -279.959) (xy 374.866415 -280.014176) (xy 374.850347 -280.067583)
			(xy 374.826675 -280.11808) (xy 374.795902 -280.164593) (xy 374.758685 -280.20613) (xy 374.715817 -280.241805)
			(xy 374.668211 -280.270859) (xy 374.616882 -280.292671) (xy 374.562925 -280.306777) (xy 374.507488 -280.312877)
			(xy 374.451754 -280.31084) (xy 374.396911 -280.30071) (xy 374.344127 -280.282703) (xy 374.294527 -280.257202)
			(xy 374.249169 -280.224751) (xy 374.20902 -280.186042) (xy 374.174934 -280.141899) (xy 374.147638 -280.093264)
			(xy 374.127715 -280.041173) (xy 374.115589 -279.986736) (xy 374.111518 -279.931114) (xy 373.668036 -279.931114)
			(xy 373.668036 -280.693114) (xy 379.638052 -280.693114) (xy 379.638619 -280.663733) (xy 379.647646 -280.605668)
			(xy 379.665474 -280.549675) (xy 379.691681 -280.49708) (xy 379.725646 -280.449128) (xy 379.766565 -280.406954)
			(xy 379.78969 -280.388822) (xy 379.799088 -280.381456) (xy 379.809502 -280.360882) (xy 379.811026 -280.256996)
			(xy 379.80112 -280.235914) (xy 379.791976 -280.228548) (xy 379.770116 -280.210356) (xy 379.731578 -280.168534)
			(xy 379.699673 -280.121455) (xy 379.675108 -280.070163) (xy 379.658427 -280.015793) (xy 379.65 -279.95955)
			(xy 379.649482 -279.931114) (xy 379.649968 -279.903863) (xy 379.657724 -279.849915) (xy 379.673079 -279.79762)
			(xy 379.695721 -279.748043) (xy 379.725187 -279.702193) (xy 379.760878 -279.661002) (xy 379.802069 -279.625311)
			(xy 379.847919 -279.595845) (xy 379.897496 -279.573203) (xy 379.949791 -279.557848) (xy 380.003739 -279.550092)
			(xy 380.058241 -279.550092) (xy 380.112189 -279.557848) (xy 380.164484 -279.573203) (xy 380.214061 -279.595845)
			(xy 380.259911 -279.625311) (xy 380.301102 -279.661002) (xy 380.336793 -279.702193) (xy 380.366259 -279.748043)
			(xy 380.388901 -279.79762) (xy 380.404256 -279.849915) (xy 380.412012 -279.903863) (xy 380.412498 -279.931114)
			(xy 380.411971 -279.960497) (xy 380.402938 -280.018564) (xy 380.385103 -280.074559) (xy 380.358889 -280.127154)
			(xy 380.324916 -280.175105) (xy 380.283989 -280.217276) (xy 380.274469 -280.224738) (xy 384.369068 -280.224738)
			(xy 384.373028 -280.175684) (xy 384.384805 -280.1279) (xy 384.404096 -280.082624) (xy 384.430399 -280.041028)
			(xy 384.463034 -280.004191) (xy 384.501155 -279.973066) (xy 384.543776 -279.948459) (xy 384.589792 -279.931007)
			(xy 384.638011 -279.921163) (xy 384.687186 -279.919182) (xy 384.736041 -279.925114) (xy 384.783312 -279.938806)
			(xy 384.827774 -279.959904) (xy 384.868277 -279.98786) (xy 384.90377 -280.021952) (xy 384.933335 -280.061296)
			(xy 384.956206 -280.104873) (xy 384.97179 -280.151554) (xy 384.979685 -280.200131) (xy 384.98018 -280.224738)
			(xy 385.319028 -280.224738) (xy 385.322988 -280.175684) (xy 385.334765 -280.1279) (xy 385.354056 -280.082624)
			(xy 385.380359 -280.041028) (xy 385.412994 -280.004191) (xy 385.451115 -279.973066) (xy 385.493736 -279.948459)
			(xy 385.539752 -279.931007) (xy 385.587971 -279.921163) (xy 385.637146 -279.919182) (xy 385.686001 -279.925114)
			(xy 385.733272 -279.938806) (xy 385.777734 -279.959904) (xy 385.818237 -279.98786) (xy 385.85373 -280.021952)
			(xy 385.883295 -280.061296) (xy 385.906166 -280.104873) (xy 385.92175 -280.151554) (xy 385.929645 -280.200131)
			(xy 385.93014 -280.224738) (xy 385.929645 -280.249345) (xy 385.92175 -280.297922) (xy 385.906166 -280.344603)
			(xy 385.883295 -280.38818) (xy 385.85373 -280.427524) (xy 385.818237 -280.461616) (xy 385.777734 -280.489572)
			(xy 385.733272 -280.51067) (xy 385.686001 -280.524362) (xy 385.637146 -280.530294) (xy 385.587971 -280.528313)
			(xy 385.539752 -280.518469) (xy 385.493736 -280.501017) (xy 385.451115 -280.47641) (xy 385.412994 -280.445285)
			(xy 385.380359 -280.408448) (xy 385.354056 -280.366852) (xy 385.334765 -280.321576) (xy 385.322988 -280.273792)
			(xy 385.319028 -280.224738) (xy 384.98018 -280.224738) (xy 384.979685 -280.249345) (xy 384.97179 -280.297922)
			(xy 384.956206 -280.344603) (xy 384.933335 -280.38818) (xy 384.90377 -280.427524) (xy 384.868277 -280.461616)
			(xy 384.827774 -280.489572) (xy 384.783312 -280.51067) (xy 384.736041 -280.524362) (xy 384.687186 -280.530294)
			(xy 384.638011 -280.528313) (xy 384.589792 -280.518469) (xy 384.543776 -280.501017) (xy 384.501155 -280.47641)
			(xy 384.463034 -280.445285) (xy 384.430399 -280.408448) (xy 384.404096 -280.366852) (xy 384.384805 -280.321576)
			(xy 384.373028 -280.273792) (xy 384.369068 -280.224738) (xy 380.274469 -280.224738) (xy 380.26086 -280.235406)
			(xy 380.251462 -280.242772) (xy 380.241048 -280.263346) (xy 380.239524 -280.367232) (xy 380.24943 -280.388314)
			(xy 380.258574 -280.39568) (xy 380.280389 -280.413924) (xy 380.318933 -280.455734) (xy 380.350844 -280.502801)
			(xy 380.375417 -280.554084) (xy 380.392107 -280.608445) (xy 380.400545 -280.664681) (xy 380.401068 -280.693114)
			(xy 381.034542 -280.693114) (xy 381.038613 -280.637492) (xy 381.050739 -280.583055) (xy 381.070662 -280.530964)
			(xy 381.097958 -280.482329) (xy 381.132044 -280.438186) (xy 381.172193 -280.399477) (xy 381.217551 -280.367026)
			(xy 381.267151 -280.341525) (xy 381.319935 -280.323518) (xy 381.374778 -280.313388) (xy 381.430512 -280.311351)
			(xy 381.485949 -280.317451) (xy 381.539906 -280.331557) (xy 381.591235 -280.353369) (xy 381.638841 -280.382423)
			(xy 381.681709 -280.418098) (xy 381.718926 -280.459635) (xy 381.749699 -280.506148) (xy 381.773371 -280.556645)
			(xy 381.789439 -280.610052) (xy 381.797559 -280.665228) (xy 381.798068 -280.693114) (xy 381.921002 -280.693114)
			(xy 381.925073 -280.637492) (xy 381.937199 -280.583055) (xy 381.957122 -280.530964) (xy 381.984418 -280.482329)
			(xy 382.018504 -280.438186) (xy 382.058653 -280.399477) (xy 382.104011 -280.367026) (xy 382.153611 -280.341525)
			(xy 382.206395 -280.323518) (xy 382.261238 -280.313388) (xy 382.316972 -280.311351) (xy 382.372409 -280.317451)
			(xy 382.426366 -280.331557) (xy 382.477695 -280.353369) (xy 382.525301 -280.382423) (xy 382.568169 -280.418098)
			(xy 382.605386 -280.459635) (xy 382.636159 -280.506148) (xy 382.659831 -280.556645) (xy 382.675899 -280.610052)
			(xy 382.684019 -280.665228) (xy 382.684528 -280.693114) (xy 382.684019 -280.721) (xy 382.675899 -280.776176)
			(xy 382.659831 -280.829583) (xy 382.636159 -280.88008) (xy 382.605386 -280.926593) (xy 382.568169 -280.96813)
			(xy 382.525301 -281.003805) (xy 382.477695 -281.032859) (xy 382.426366 -281.054671) (xy 382.372409 -281.068777)
			(xy 382.316972 -281.074877) (xy 382.261238 -281.07284) (xy 382.206395 -281.06271) (xy 382.153611 -281.044703)
			(xy 382.104011 -281.019202) (xy 382.058653 -280.986751) (xy 382.018504 -280.948042) (xy 381.984418 -280.903899)
			(xy 381.957122 -280.855264) (xy 381.937199 -280.803173) (xy 381.925073 -280.748736) (xy 381.921002 -280.693114)
			(xy 381.798068 -280.693114) (xy 381.797559 -280.721) (xy 381.789439 -280.776176) (xy 381.773371 -280.829583)
			(xy 381.749699 -280.88008) (xy 381.718926 -280.926593) (xy 381.681709 -280.96813) (xy 381.638841 -281.003805)
			(xy 381.591235 -281.032859) (xy 381.539906 -281.054671) (xy 381.485949 -281.068777) (xy 381.430512 -281.074877)
			(xy 381.374778 -281.07284) (xy 381.319935 -281.06271) (xy 381.267151 -281.044703) (xy 381.217551 -281.019202)
			(xy 381.172193 -280.986751) (xy 381.132044 -280.948042) (xy 381.097958 -280.903899) (xy 381.070662 -280.855264)
			(xy 381.050739 -280.803173) (xy 381.038613 -280.748736) (xy 381.034542 -280.693114) (xy 380.401068 -280.693114)
			(xy 380.400582 -280.720365) (xy 380.392826 -280.774313) (xy 380.377471 -280.826608) (xy 380.354829 -280.876185)
			(xy 380.325363 -280.922035) (xy 380.289672 -280.963226) (xy 380.248481 -280.998917) (xy 380.202631 -281.028383)
			(xy 380.153054 -281.051025) (xy 380.100759 -281.06638) (xy 380.046811 -281.074136) (xy 379.992309 -281.074136)
			(xy 379.938361 -281.06638) (xy 379.886066 -281.051025) (xy 379.836489 -281.028383) (xy 379.790639 -280.998917)
			(xy 379.749448 -280.963226) (xy 379.713757 -280.922035) (xy 379.684291 -280.876185) (xy 379.661649 -280.826608)
			(xy 379.646294 -280.774313) (xy 379.638538 -280.720365) (xy 379.638052 -280.693114) (xy 373.668036 -280.693114)
			(xy 373.668036 -281.174952) (xy 384.369068 -281.174952) (xy 384.373028 -281.125898) (xy 384.384805 -281.078114)
			(xy 384.404096 -281.032838) (xy 384.430399 -280.991242) (xy 384.463034 -280.954405) (xy 384.501155 -280.92328)
			(xy 384.543776 -280.898673) (xy 384.589792 -280.881221) (xy 384.638011 -280.871377) (xy 384.687186 -280.869396)
			(xy 384.736041 -280.875328) (xy 384.783312 -280.88902) (xy 384.827774 -280.910118) (xy 384.868277 -280.938074)
			(xy 384.90377 -280.972166) (xy 384.933335 -281.01151) (xy 384.956206 -281.055087) (xy 384.97179 -281.101768)
			(xy 384.979685 -281.150345) (xy 384.98018 -281.174952) (xy 384.979685 -281.199559) (xy 384.97179 -281.248136)
			(xy 384.956206 -281.294817) (xy 384.933335 -281.338394) (xy 384.90377 -281.377738) (xy 384.868277 -281.41183)
			(xy 384.827774 -281.439786) (xy 384.783312 -281.460884) (xy 384.736041 -281.474576) (xy 384.687186 -281.480508)
			(xy 384.638011 -281.478527) (xy 384.589792 -281.468683) (xy 384.543776 -281.451231) (xy 384.501155 -281.426624)
			(xy 384.463034 -281.395499) (xy 384.430399 -281.358662) (xy 384.404096 -281.317066) (xy 384.384805 -281.27179)
			(xy 384.373028 -281.224006) (xy 384.369068 -281.174952) (xy 373.668036 -281.174952) (xy 373.668036 -283.131514)
			(xy 374.111518 -283.131514) (xy 374.115589 -283.075892) (xy 374.127715 -283.021455) (xy 374.147638 -282.969364)
			(xy 374.174934 -282.920729) (xy 374.20902 -282.876586) (xy 374.249169 -282.837877) (xy 374.294527 -282.805426)
			(xy 374.344127 -282.779925) (xy 374.396911 -282.761918) (xy 374.451754 -282.751788) (xy 374.507488 -282.749751)
			(xy 374.562925 -282.755851) (xy 374.616882 -282.769957) (xy 374.668211 -282.791769) (xy 374.715817 -282.820823)
			(xy 374.758685 -282.856498) (xy 374.795902 -282.898035) (xy 374.826675 -282.944548) (xy 374.850347 -282.995045)
			(xy 374.866415 -283.048452) (xy 374.874535 -283.103628) (xy 374.875044 -283.131514) (xy 375.587004 -283.131514)
			(xy 375.591075 -283.075892) (xy 375.603201 -283.021455) (xy 375.623124 -282.969364) (xy 375.65042 -282.920729)
			(xy 375.684506 -282.876586) (xy 375.724655 -282.837877) (xy 375.770013 -282.805426) (xy 375.819613 -282.779925)
			(xy 375.872397 -282.761918) (xy 375.92724 -282.751788) (xy 375.982974 -282.749751) (xy 376.038411 -282.755851)
			(xy 376.092368 -282.769957) (xy 376.143697 -282.791769) (xy 376.191303 -282.820823) (xy 376.234171 -282.856498)
			(xy 376.271388 -282.898035) (xy 376.302161 -282.944548) (xy 376.325833 -282.995045) (xy 376.341901 -283.048452)
			(xy 376.350021 -283.103628) (xy 376.35053 -283.131514) (xy 376.476004 -283.131514) (xy 376.480075 -283.075892)
			(xy 376.492201 -283.021455) (xy 376.512124 -282.969364) (xy 376.53942 -282.920729) (xy 376.573506 -282.876586)
			(xy 376.613655 -282.837877) (xy 376.659013 -282.805426) (xy 376.708613 -282.779925) (xy 376.761397 -282.761918)
			(xy 376.81624 -282.751788) (xy 376.871974 -282.749751) (xy 376.927411 -282.755851) (xy 376.981368 -282.769957)
			(xy 377.032697 -282.791769) (xy 377.080303 -282.820823) (xy 377.123171 -282.856498) (xy 377.160388 -282.898035)
			(xy 377.191161 -282.944548) (xy 377.214833 -282.995045) (xy 377.230901 -283.048452) (xy 377.239021 -283.103628)
			(xy 377.23953 -283.131514) (xy 377.239021 -283.1594) (xy 377.230901 -283.214576) (xy 377.214833 -283.267983)
			(xy 377.191161 -283.31848) (xy 377.160388 -283.364993) (xy 377.123171 -283.40653) (xy 377.080303 -283.442205)
			(xy 377.032697 -283.471259) (xy 376.981368 -283.493071) (xy 376.927411 -283.507177) (xy 376.871974 -283.513277)
			(xy 376.81624 -283.51124) (xy 376.761397 -283.50111) (xy 376.708613 -283.483103) (xy 376.659013 -283.457602)
			(xy 376.613655 -283.425151) (xy 376.573506 -283.386442) (xy 376.53942 -283.342299) (xy 376.512124 -283.293664)
			(xy 376.492201 -283.241573) (xy 376.480075 -283.187136) (xy 376.476004 -283.131514) (xy 376.35053 -283.131514)
			(xy 376.350021 -283.1594) (xy 376.341901 -283.214576) (xy 376.325833 -283.267983) (xy 376.302161 -283.31848)
			(xy 376.271388 -283.364993) (xy 376.234171 -283.40653) (xy 376.191303 -283.442205) (xy 376.143697 -283.471259)
			(xy 376.092368 -283.493071) (xy 376.038411 -283.507177) (xy 375.982974 -283.513277) (xy 375.92724 -283.51124)
			(xy 375.872397 -283.50111) (xy 375.819613 -283.483103) (xy 375.770013 -283.457602) (xy 375.724655 -283.425151)
			(xy 375.684506 -283.386442) (xy 375.65042 -283.342299) (xy 375.623124 -283.293664) (xy 375.603201 -283.241573)
			(xy 375.591075 -283.187136) (xy 375.587004 -283.131514) (xy 374.875044 -283.131514) (xy 374.874535 -283.1594)
			(xy 374.866415 -283.214576) (xy 374.850347 -283.267983) (xy 374.826675 -283.31848) (xy 374.795902 -283.364993)
			(xy 374.758685 -283.40653) (xy 374.715817 -283.442205) (xy 374.668211 -283.471259) (xy 374.616882 -283.493071)
			(xy 374.562925 -283.507177) (xy 374.507488 -283.513277) (xy 374.451754 -283.51124) (xy 374.396911 -283.50111)
			(xy 374.344127 -283.483103) (xy 374.294527 -283.457602) (xy 374.249169 -283.425151) (xy 374.20902 -283.386442)
			(xy 374.174934 -283.342299) (xy 374.147638 -283.293664) (xy 374.127715 -283.241573) (xy 374.115589 -283.187136)
			(xy 374.111518 -283.131514) (xy 373.668036 -283.131514) (xy 373.668036 -283.656024) (xy 373.668301 -283.662911)
			(xy 373.672037 -283.676171) (xy 373.675402 -283.682186) (xy 373.678704 -283.687774) (xy 373.685054 -283.69768)
			(xy 373.690642 -283.705046) (xy 373.724678 -283.741368) (xy 373.729504 -283.746281) (xy 373.741235 -283.753485)
			(xy 373.747792 -283.755592) (xy 373.754142 -283.75737) (xy 373.759222 -283.757624) (xy 373.787567 -283.760411)
			(xy 373.843039 -283.773318) (xy 373.895977 -283.794322) (xy 373.945208 -283.822958) (xy 373.989639 -283.85859)
			(xy 374.021898 -283.893514) (xy 379.638052 -283.893514) (xy 379.638619 -283.864133) (xy 379.647646 -283.806068)
			(xy 379.665474 -283.750075) (xy 379.691681 -283.69748) (xy 379.725646 -283.649528) (xy 379.766565 -283.607354)
			(xy 379.78969 -283.589222) (xy 379.799088 -283.581856) (xy 379.809502 -283.561282) (xy 379.811026 -283.457396)
			(xy 379.80112 -283.436314) (xy 379.791976 -283.428948) (xy 379.770116 -283.410756) (xy 379.731578 -283.368934)
			(xy 379.699673 -283.321855) (xy 379.675108 -283.270563) (xy 379.658427 -283.216193) (xy 379.65 -283.15995)
			(xy 379.649482 -283.131514) (xy 379.649968 -283.104263) (xy 379.657724 -283.050315) (xy 379.673079 -282.99802)
			(xy 379.695721 -282.948443) (xy 379.725187 -282.902593) (xy 379.760878 -282.861402) (xy 379.802069 -282.825711)
			(xy 379.847919 -282.796245) (xy 379.897496 -282.773603) (xy 379.949791 -282.758248) (xy 380.003739 -282.750492)
			(xy 380.058241 -282.750492) (xy 380.112189 -282.758248) (xy 380.164484 -282.773603) (xy 380.214061 -282.796245)
			(xy 380.259911 -282.825711) (xy 380.301102 -282.861402) (xy 380.336793 -282.902593) (xy 380.366259 -282.948443)
			(xy 380.388901 -282.99802) (xy 380.404256 -283.050315) (xy 380.412012 -283.104263) (xy 380.412498 -283.131514)
			(xy 380.411971 -283.160897) (xy 380.402938 -283.218964) (xy 380.385103 -283.274959) (xy 380.358889 -283.327554)
			(xy 380.324916 -283.375505) (xy 380.283989 -283.417676) (xy 380.26086 -283.435806) (xy 380.251462 -283.443172)
			(xy 380.241048 -283.463746) (xy 380.239524 -283.567632) (xy 380.24943 -283.588714) (xy 380.258574 -283.59608)
			(xy 380.280389 -283.614324) (xy 380.318933 -283.656134) (xy 380.350844 -283.703201) (xy 380.375417 -283.754484)
			(xy 380.392107 -283.808845) (xy 380.400545 -283.865081) (xy 380.401068 -283.893514) (xy 380.400582 -283.920765)
			(xy 380.392826 -283.974713) (xy 380.377471 -284.027008) (xy 380.354829 -284.076585) (xy 380.325363 -284.122435)
			(xy 380.289672 -284.163626) (xy 380.248481 -284.199317) (xy 380.202631 -284.228783) (xy 380.153054 -284.251425)
			(xy 380.100759 -284.26678) (xy 380.046811 -284.274536) (xy 379.992309 -284.274536) (xy 379.938361 -284.26678)
			(xy 379.886066 -284.251425) (xy 379.836489 -284.228783) (xy 379.790639 -284.199317) (xy 379.749448 -284.163626)
			(xy 379.713757 -284.122435) (xy 379.684291 -284.076585) (xy 379.661649 -284.027008) (xy 379.646294 -283.974713)
			(xy 379.638538 -283.920765) (xy 379.638052 -283.893514) (xy 374.021898 -283.893514) (xy 374.028283 -283.900426)
			(xy 374.060284 -283.947539) (xy 374.08493 -283.998884) (xy 374.101676 -284.05332) (xy 374.110149 -284.109639)
			(xy 374.110758 -284.138116) (xy 374.110225 -284.166668) (xy 374.101721 -284.223136) (xy 374.084905 -284.277708)
			(xy 374.060152 -284.329169) (xy 374.028013 -284.376371) (xy 373.989205 -284.418262) (xy 373.944593 -284.453908)
			(xy 373.895171 -284.482515) (xy 373.842041 -284.503446) (xy 373.786387 -284.516234) (xy 373.757952 -284.518862)
			(xy 373.7483 -284.519624) (xy 373.731282 -284.527752) (xy 373.711978 -284.54858) (xy 373.690896 -284.571186)
			(xy 373.685054 -284.578552) (xy 373.678958 -284.58795) (xy 373.67845 -284.588966) (xy 373.675402 -284.594046)
			(xy 373.67201 -284.60005) (xy 373.668268 -284.613316) (xy 373.668036 -284.620208) (xy 373.668036 -286.331914)
			(xy 374.111518 -286.331914) (xy 374.115589 -286.276292) (xy 374.127715 -286.221855) (xy 374.147638 -286.169764)
			(xy 374.174934 -286.121129) (xy 374.20902 -286.076986) (xy 374.249169 -286.038277) (xy 374.294527 -286.005826)
			(xy 374.344127 -285.980325) (xy 374.396911 -285.962318) (xy 374.451754 -285.952188) (xy 374.507488 -285.950151)
			(xy 374.562925 -285.956251) (xy 374.616882 -285.970357) (xy 374.668211 -285.992169) (xy 374.715817 -286.021223)
			(xy 374.758685 -286.056898) (xy 374.795902 -286.098435) (xy 374.826675 -286.144948) (xy 374.850347 -286.195445)
			(xy 374.866415 -286.248852) (xy 374.874535 -286.304028) (xy 374.875044 -286.331914) (xy 375.587004 -286.331914)
			(xy 375.591075 -286.276292) (xy 375.603201 -286.221855) (xy 375.623124 -286.169764) (xy 375.65042 -286.121129)
			(xy 375.684506 -286.076986) (xy 375.724655 -286.038277) (xy 375.770013 -286.005826) (xy 375.819613 -285.980325)
			(xy 375.872397 -285.962318) (xy 375.92724 -285.952188) (xy 375.982974 -285.950151) (xy 376.038411 -285.956251)
			(xy 376.092368 -285.970357) (xy 376.143697 -285.992169) (xy 376.191303 -286.021223) (xy 376.234171 -286.056898)
			(xy 376.271388 -286.098435) (xy 376.302161 -286.144948) (xy 376.325833 -286.195445) (xy 376.341901 -286.248852)
			(xy 376.350021 -286.304028) (xy 376.35053 -286.331914) (xy 376.476004 -286.331914) (xy 376.480075 -286.276292)
			(xy 376.492201 -286.221855) (xy 376.512124 -286.169764) (xy 376.53942 -286.121129) (xy 376.573506 -286.076986)
			(xy 376.613655 -286.038277) (xy 376.659013 -286.005826) (xy 376.708613 -285.980325) (xy 376.761397 -285.962318)
			(xy 376.81624 -285.952188) (xy 376.871974 -285.950151) (xy 376.927411 -285.956251) (xy 376.981368 -285.970357)
			(xy 377.032697 -285.992169) (xy 377.080303 -286.021223) (xy 377.123171 -286.056898) (xy 377.160388 -286.098435)
			(xy 377.191161 -286.144948) (xy 377.214833 -286.195445) (xy 377.230901 -286.248852) (xy 377.239021 -286.304028)
			(xy 377.23953 -286.331914) (xy 377.239021 -286.3598) (xy 377.230901 -286.414976) (xy 377.214833 -286.468383)
			(xy 377.191161 -286.51888) (xy 377.160388 -286.565393) (xy 377.123171 -286.60693) (xy 377.080303 -286.642605)
			(xy 377.032697 -286.671659) (xy 376.981368 -286.693471) (xy 376.927411 -286.707577) (xy 376.871974 -286.713677)
			(xy 376.81624 -286.71164) (xy 376.761397 -286.70151) (xy 376.708613 -286.683503) (xy 376.659013 -286.658002)
			(xy 376.613655 -286.625551) (xy 376.573506 -286.586842) (xy 376.53942 -286.542699) (xy 376.512124 -286.494064)
			(xy 376.492201 -286.441973) (xy 376.480075 -286.387536) (xy 376.476004 -286.331914) (xy 376.35053 -286.331914)
			(xy 376.350021 -286.3598) (xy 376.341901 -286.414976) (xy 376.325833 -286.468383) (xy 376.302161 -286.51888)
			(xy 376.271388 -286.565393) (xy 376.234171 -286.60693) (xy 376.191303 -286.642605) (xy 376.143697 -286.671659)
			(xy 376.092368 -286.693471) (xy 376.038411 -286.707577) (xy 375.982974 -286.713677) (xy 375.92724 -286.71164)
			(xy 375.872397 -286.70151) (xy 375.819613 -286.683503) (xy 375.770013 -286.658002) (xy 375.724655 -286.625551)
			(xy 375.684506 -286.586842) (xy 375.65042 -286.542699) (xy 375.623124 -286.494064) (xy 375.603201 -286.441973)
			(xy 375.591075 -286.387536) (xy 375.587004 -286.331914) (xy 374.875044 -286.331914) (xy 374.874535 -286.3598)
			(xy 374.866415 -286.414976) (xy 374.850347 -286.468383) (xy 374.826675 -286.51888) (xy 374.795902 -286.565393)
			(xy 374.758685 -286.60693) (xy 374.715817 -286.642605) (xy 374.668211 -286.671659) (xy 374.616882 -286.693471)
			(xy 374.562925 -286.707577) (xy 374.507488 -286.713677) (xy 374.451754 -286.71164) (xy 374.396911 -286.70151)
			(xy 374.344127 -286.683503) (xy 374.294527 -286.658002) (xy 374.249169 -286.625551) (xy 374.20902 -286.586842)
			(xy 374.174934 -286.542699) (xy 374.147638 -286.494064) (xy 374.127715 -286.441973) (xy 374.115589 -286.387536)
			(xy 374.111518 -286.331914) (xy 373.668036 -286.331914) (xy 373.668036 -287.093914) (xy 379.638052 -287.093914)
			(xy 379.638619 -287.064533) (xy 379.647646 -287.006468) (xy 379.665474 -286.950475) (xy 379.691681 -286.89788)
			(xy 379.725646 -286.849928) (xy 379.766565 -286.807754) (xy 379.78969 -286.789622) (xy 379.799088 -286.782256)
			(xy 379.809502 -286.761682) (xy 379.811026 -286.657796) (xy 379.80112 -286.636714) (xy 379.791976 -286.629348)
			(xy 379.770116 -286.611156) (xy 379.731578 -286.569334) (xy 379.699673 -286.522255) (xy 379.675108 -286.470963)
			(xy 379.658427 -286.416593) (xy 379.65 -286.36035) (xy 379.649482 -286.331914) (xy 379.649968 -286.304663)
			(xy 379.657724 -286.250715) (xy 379.673079 -286.19842) (xy 379.695721 -286.148843) (xy 379.725187 -286.102993)
			(xy 379.760878 -286.061802) (xy 379.802069 -286.026111) (xy 379.847919 -285.996645) (xy 379.897496 -285.974003)
			(xy 379.949791 -285.958648) (xy 380.003739 -285.950892) (xy 380.058241 -285.950892) (xy 380.112189 -285.958648)
			(xy 380.164484 -285.974003) (xy 380.214061 -285.996645) (xy 380.259911 -286.026111) (xy 380.301102 -286.061802)
			(xy 380.336793 -286.102993) (xy 380.366259 -286.148843) (xy 380.388901 -286.19842) (xy 380.404256 -286.250715)
			(xy 380.412012 -286.304663) (xy 380.412498 -286.331914) (xy 380.411971 -286.361297) (xy 380.402938 -286.419364)
			(xy 380.385103 -286.475359) (xy 380.358889 -286.527954) (xy 380.324916 -286.575905) (xy 380.283989 -286.618076)
			(xy 380.26086 -286.636206) (xy 380.251462 -286.643572) (xy 380.241048 -286.664146) (xy 380.239524 -286.768032)
			(xy 380.24943 -286.789114) (xy 380.258574 -286.79648) (xy 380.280389 -286.814724) (xy 380.318933 -286.856534)
			(xy 380.350844 -286.903601) (xy 380.375417 -286.954884) (xy 380.392107 -287.009245) (xy 380.400545 -287.065481)
			(xy 380.401068 -287.093914) (xy 380.400582 -287.121165) (xy 380.392826 -287.175113) (xy 380.377471 -287.227408)
			(xy 380.354829 -287.276985) (xy 380.325363 -287.322835) (xy 380.289672 -287.364026) (xy 380.248481 -287.399717)
			(xy 380.202631 -287.429183) (xy 380.153054 -287.451825) (xy 380.100759 -287.46718) (xy 380.046811 -287.474936)
			(xy 379.992309 -287.474936) (xy 379.938361 -287.46718) (xy 379.886066 -287.451825) (xy 379.836489 -287.429183)
			(xy 379.790639 -287.399717) (xy 379.749448 -287.364026) (xy 379.713757 -287.322835) (xy 379.684291 -287.276985)
			(xy 379.661649 -287.227408) (xy 379.646294 -287.175113) (xy 379.638538 -287.121165) (xy 379.638052 -287.093914)
			(xy 373.668036 -287.093914) (xy 373.668036 -289.532314) (xy 374.111518 -289.532314) (xy 374.115589 -289.476692)
			(xy 374.127715 -289.422255) (xy 374.147638 -289.370164) (xy 374.174934 -289.321529) (xy 374.20902 -289.277386)
			(xy 374.249169 -289.238677) (xy 374.294527 -289.206226) (xy 374.344127 -289.180725) (xy 374.396911 -289.162718)
			(xy 374.451754 -289.152588) (xy 374.507488 -289.150551) (xy 374.562925 -289.156651) (xy 374.616882 -289.170757)
			(xy 374.668211 -289.192569) (xy 374.715817 -289.221623) (xy 374.758685 -289.257298) (xy 374.795902 -289.298835)
			(xy 374.826675 -289.345348) (xy 374.850347 -289.395845) (xy 374.866415 -289.449252) (xy 374.874535 -289.504428)
			(xy 374.875044 -289.532314) (xy 375.587004 -289.532314) (xy 375.591075 -289.476692) (xy 375.603201 -289.422255)
			(xy 375.623124 -289.370164) (xy 375.65042 -289.321529) (xy 375.684506 -289.277386) (xy 375.724655 -289.238677)
			(xy 375.770013 -289.206226) (xy 375.819613 -289.180725) (xy 375.872397 -289.162718) (xy 375.92724 -289.152588)
			(xy 375.982974 -289.150551) (xy 376.038411 -289.156651) (xy 376.092368 -289.170757) (xy 376.143697 -289.192569)
			(xy 376.191303 -289.221623) (xy 376.234171 -289.257298) (xy 376.271388 -289.298835) (xy 376.302161 -289.345348)
			(xy 376.325833 -289.395845) (xy 376.341901 -289.449252) (xy 376.350021 -289.504428) (xy 376.35053 -289.532314)
			(xy 376.476004 -289.532314) (xy 376.480075 -289.476692) (xy 376.492201 -289.422255) (xy 376.512124 -289.370164)
			(xy 376.53942 -289.321529) (xy 376.573506 -289.277386) (xy 376.613655 -289.238677) (xy 376.659013 -289.206226)
			(xy 376.708613 -289.180725) (xy 376.761397 -289.162718) (xy 376.81624 -289.152588) (xy 376.871974 -289.150551)
			(xy 376.927411 -289.156651) (xy 376.981368 -289.170757) (xy 377.032697 -289.192569) (xy 377.080303 -289.221623)
			(xy 377.123171 -289.257298) (xy 377.160388 -289.298835) (xy 377.191161 -289.345348) (xy 377.214833 -289.395845)
			(xy 377.230901 -289.449252) (xy 377.239021 -289.504428) (xy 377.23953 -289.532314) (xy 377.239021 -289.5602)
			(xy 377.230901 -289.615376) (xy 377.214833 -289.668783) (xy 377.191161 -289.71928) (xy 377.160388 -289.765793)
			(xy 377.123171 -289.80733) (xy 377.080303 -289.843005) (xy 377.032697 -289.872059) (xy 376.981368 -289.893871)
			(xy 376.927411 -289.907977) (xy 376.871974 -289.914077) (xy 376.81624 -289.91204) (xy 376.761397 -289.90191)
			(xy 376.708613 -289.883903) (xy 376.659013 -289.858402) (xy 376.613655 -289.825951) (xy 376.573506 -289.787242)
			(xy 376.53942 -289.743099) (xy 376.512124 -289.694464) (xy 376.492201 -289.642373) (xy 376.480075 -289.587936)
			(xy 376.476004 -289.532314) (xy 376.35053 -289.532314) (xy 376.350021 -289.5602) (xy 376.341901 -289.615376)
			(xy 376.325833 -289.668783) (xy 376.302161 -289.71928) (xy 376.271388 -289.765793) (xy 376.234171 -289.80733)
			(xy 376.191303 -289.843005) (xy 376.143697 -289.872059) (xy 376.092368 -289.893871) (xy 376.038411 -289.907977)
			(xy 375.982974 -289.914077) (xy 375.92724 -289.91204) (xy 375.872397 -289.90191) (xy 375.819613 -289.883903)
			(xy 375.770013 -289.858402) (xy 375.724655 -289.825951) (xy 375.684506 -289.787242) (xy 375.65042 -289.743099)
			(xy 375.623124 -289.694464) (xy 375.603201 -289.642373) (xy 375.591075 -289.587936) (xy 375.587004 -289.532314)
			(xy 374.875044 -289.532314) (xy 374.874535 -289.5602) (xy 374.866415 -289.615376) (xy 374.850347 -289.668783)
			(xy 374.826675 -289.71928) (xy 374.795902 -289.765793) (xy 374.758685 -289.80733) (xy 374.715817 -289.843005)
			(xy 374.668211 -289.872059) (xy 374.616882 -289.893871) (xy 374.562925 -289.907977) (xy 374.507488 -289.914077)
			(xy 374.451754 -289.91204) (xy 374.396911 -289.90191) (xy 374.344127 -289.883903) (xy 374.294527 -289.858402)
			(xy 374.249169 -289.825951) (xy 374.20902 -289.787242) (xy 374.174934 -289.743099) (xy 374.147638 -289.694464)
			(xy 374.127715 -289.642373) (xy 374.115589 -289.587936) (xy 374.111518 -289.532314) (xy 373.668036 -289.532314)
			(xy 373.668036 -290.294314) (xy 379.638052 -290.294314) (xy 379.638619 -290.264933) (xy 379.647646 -290.206868)
			(xy 379.665474 -290.150875) (xy 379.691681 -290.09828) (xy 379.725646 -290.050328) (xy 379.766565 -290.008154)
			(xy 379.78969 -289.990022) (xy 379.799088 -289.982656) (xy 379.809502 -289.962082) (xy 379.811026 -289.858196)
			(xy 379.80112 -289.837114) (xy 379.791976 -289.829748) (xy 379.770116 -289.811556) (xy 379.731578 -289.769734)
			(xy 379.699673 -289.722655) (xy 379.675108 -289.671363) (xy 379.658427 -289.616993) (xy 379.65 -289.56075)
			(xy 379.649482 -289.532314) (xy 379.649968 -289.505063) (xy 379.657724 -289.451115) (xy 379.673079 -289.39882)
			(xy 379.695721 -289.349243) (xy 379.725187 -289.303393) (xy 379.760878 -289.262202) (xy 379.802069 -289.226511)
			(xy 379.847919 -289.197045) (xy 379.897496 -289.174403) (xy 379.949791 -289.159048) (xy 380.003739 -289.151292)
			(xy 380.058241 -289.151292) (xy 380.112189 -289.159048) (xy 380.164484 -289.174403) (xy 380.214061 -289.197045)
			(xy 380.259911 -289.226511) (xy 380.301102 -289.262202) (xy 380.336793 -289.303393) (xy 380.366259 -289.349243)
			(xy 380.388901 -289.39882) (xy 380.404256 -289.451115) (xy 380.412012 -289.505063) (xy 380.412498 -289.532314)
			(xy 380.411971 -289.561697) (xy 380.402938 -289.619764) (xy 380.385103 -289.675759) (xy 380.358889 -289.728354)
			(xy 380.324916 -289.776305) (xy 380.283989 -289.818476) (xy 380.26086 -289.836606) (xy 380.251462 -289.843972)
			(xy 380.241048 -289.864546) (xy 380.239524 -289.968432) (xy 380.24943 -289.989514) (xy 380.258574 -289.99688)
			(xy 380.280389 -290.015124) (xy 380.318933 -290.056934) (xy 380.350844 -290.104001) (xy 380.375417 -290.155284)
			(xy 380.392107 -290.209645) (xy 380.400545 -290.265881) (xy 380.401068 -290.294314) (xy 380.400582 -290.321565)
			(xy 380.392826 -290.375513) (xy 380.377471 -290.427808) (xy 380.354829 -290.477385) (xy 380.325363 -290.523235)
			(xy 380.289672 -290.564426) (xy 380.248481 -290.600117) (xy 380.202631 -290.629583) (xy 380.153054 -290.652225)
			(xy 380.100759 -290.66758) (xy 380.046811 -290.675336) (xy 379.992309 -290.675336) (xy 379.938361 -290.66758)
			(xy 379.886066 -290.652225) (xy 379.836489 -290.629583) (xy 379.790639 -290.600117) (xy 379.749448 -290.564426)
			(xy 379.713757 -290.523235) (xy 379.684291 -290.477385) (xy 379.661649 -290.427808) (xy 379.646294 -290.375513)
			(xy 379.638538 -290.321565) (xy 379.638052 -290.294314) (xy 373.668036 -290.294314) (xy 373.668036 -292.732714)
			(xy 374.111518 -292.732714) (xy 374.115589 -292.677092) (xy 374.127715 -292.622655) (xy 374.147638 -292.570564)
			(xy 374.174934 -292.521929) (xy 374.20902 -292.477786) (xy 374.249169 -292.439077) (xy 374.294527 -292.406626)
			(xy 374.344127 -292.381125) (xy 374.396911 -292.363118) (xy 374.451754 -292.352988) (xy 374.507488 -292.350951)
			(xy 374.562925 -292.357051) (xy 374.616882 -292.371157) (xy 374.668211 -292.392969) (xy 374.715817 -292.422023)
			(xy 374.758685 -292.457698) (xy 374.795902 -292.499235) (xy 374.826675 -292.545748) (xy 374.850347 -292.596245)
			(xy 374.866415 -292.649652) (xy 374.874535 -292.704828) (xy 374.875044 -292.732714) (xy 375.587004 -292.732714)
			(xy 375.591075 -292.677092) (xy 375.603201 -292.622655) (xy 375.623124 -292.570564) (xy 375.65042 -292.521929)
			(xy 375.684506 -292.477786) (xy 375.724655 -292.439077) (xy 375.770013 -292.406626) (xy 375.819613 -292.381125)
			(xy 375.872397 -292.363118) (xy 375.92724 -292.352988) (xy 375.982974 -292.350951) (xy 376.038411 -292.357051)
			(xy 376.092368 -292.371157) (xy 376.143697 -292.392969) (xy 376.191303 -292.422023) (xy 376.234171 -292.457698)
			(xy 376.271388 -292.499235) (xy 376.302161 -292.545748) (xy 376.325833 -292.596245) (xy 376.341901 -292.649652)
			(xy 376.350021 -292.704828) (xy 376.35053 -292.732714) (xy 376.476004 -292.732714) (xy 376.480075 -292.677092)
			(xy 376.492201 -292.622655) (xy 376.512124 -292.570564) (xy 376.53942 -292.521929) (xy 376.573506 -292.477786)
			(xy 376.613655 -292.439077) (xy 376.659013 -292.406626) (xy 376.708613 -292.381125) (xy 376.761397 -292.363118)
			(xy 376.81624 -292.352988) (xy 376.871974 -292.350951) (xy 376.927411 -292.357051) (xy 376.981368 -292.371157)
			(xy 377.032697 -292.392969) (xy 377.080303 -292.422023) (xy 377.123171 -292.457698) (xy 377.160388 -292.499235)
			(xy 377.191161 -292.545748) (xy 377.214833 -292.596245) (xy 377.230901 -292.649652) (xy 377.239021 -292.704828)
			(xy 377.23953 -292.732714) (xy 377.239021 -292.7606) (xy 377.230901 -292.815776) (xy 377.214833 -292.869183)
			(xy 377.191161 -292.91968) (xy 377.160388 -292.966193) (xy 377.123171 -293.00773) (xy 377.080303 -293.043405)
			(xy 377.032697 -293.072459) (xy 376.981368 -293.094271) (xy 376.927411 -293.108377) (xy 376.871974 -293.114477)
			(xy 376.81624 -293.11244) (xy 376.761397 -293.10231) (xy 376.708613 -293.084303) (xy 376.659013 -293.058802)
			(xy 376.613655 -293.026351) (xy 376.573506 -292.987642) (xy 376.53942 -292.943499) (xy 376.512124 -292.894864)
			(xy 376.492201 -292.842773) (xy 376.480075 -292.788336) (xy 376.476004 -292.732714) (xy 376.35053 -292.732714)
			(xy 376.350021 -292.7606) (xy 376.341901 -292.815776) (xy 376.325833 -292.869183) (xy 376.302161 -292.91968)
			(xy 376.271388 -292.966193) (xy 376.234171 -293.00773) (xy 376.191303 -293.043405) (xy 376.143697 -293.072459)
			(xy 376.092368 -293.094271) (xy 376.038411 -293.108377) (xy 375.982974 -293.114477) (xy 375.92724 -293.11244)
			(xy 375.872397 -293.10231) (xy 375.819613 -293.084303) (xy 375.770013 -293.058802) (xy 375.724655 -293.026351)
			(xy 375.684506 -292.987642) (xy 375.65042 -292.943499) (xy 375.623124 -292.894864) (xy 375.603201 -292.842773)
			(xy 375.591075 -292.788336) (xy 375.587004 -292.732714) (xy 374.875044 -292.732714) (xy 374.874535 -292.7606)
			(xy 374.866415 -292.815776) (xy 374.850347 -292.869183) (xy 374.826675 -292.91968) (xy 374.795902 -292.966193)
			(xy 374.758685 -293.00773) (xy 374.715817 -293.043405) (xy 374.668211 -293.072459) (xy 374.616882 -293.094271)
			(xy 374.562925 -293.108377) (xy 374.507488 -293.114477) (xy 374.451754 -293.11244) (xy 374.396911 -293.10231)
			(xy 374.344127 -293.084303) (xy 374.294527 -293.058802) (xy 374.249169 -293.026351) (xy 374.20902 -292.987642)
			(xy 374.174934 -292.943499) (xy 374.147638 -292.894864) (xy 374.127715 -292.842773) (xy 374.115589 -292.788336)
			(xy 374.111518 -292.732714) (xy 373.668036 -292.732714) (xy 373.668036 -293.494714) (xy 379.638052 -293.494714)
			(xy 379.638619 -293.465333) (xy 379.647646 -293.407268) (xy 379.665474 -293.351275) (xy 379.691681 -293.29868)
			(xy 379.725646 -293.250728) (xy 379.766565 -293.208554) (xy 379.78969 -293.190422) (xy 379.799088 -293.183056)
			(xy 379.809502 -293.162482) (xy 379.811026 -293.058596) (xy 379.80112 -293.037514) (xy 379.791976 -293.030148)
			(xy 379.770116 -293.011956) (xy 379.731578 -292.970134) (xy 379.699673 -292.923055) (xy 379.675108 -292.871763)
			(xy 379.658427 -292.817393) (xy 379.65 -292.76115) (xy 379.649482 -292.732714) (xy 379.649968 -292.705463)
			(xy 379.657724 -292.651515) (xy 379.673079 -292.59922) (xy 379.695721 -292.549643) (xy 379.725187 -292.503793)
			(xy 379.760878 -292.462602) (xy 379.802069 -292.426911) (xy 379.847919 -292.397445) (xy 379.897496 -292.374803)
			(xy 379.949791 -292.359448) (xy 380.003739 -292.351692) (xy 380.058241 -292.351692) (xy 380.112189 -292.359448)
			(xy 380.164484 -292.374803) (xy 380.214061 -292.397445) (xy 380.259911 -292.426911) (xy 380.301102 -292.462602)
			(xy 380.336793 -292.503793) (xy 380.366259 -292.549643) (xy 380.388901 -292.59922) (xy 380.404256 -292.651515)
			(xy 380.412012 -292.705463) (xy 380.412498 -292.732714) (xy 380.411971 -292.762097) (xy 380.402938 -292.820164)
			(xy 380.385103 -292.876159) (xy 380.358889 -292.928754) (xy 380.324916 -292.976705) (xy 380.283989 -293.018876)
			(xy 380.26086 -293.037006) (xy 380.251462 -293.044372) (xy 380.241048 -293.064946) (xy 380.239524 -293.168832)
			(xy 380.24943 -293.189914) (xy 380.258574 -293.19728) (xy 380.280389 -293.215524) (xy 380.318933 -293.257334)
			(xy 380.350844 -293.304401) (xy 380.375417 -293.355684) (xy 380.392107 -293.410045) (xy 380.400545 -293.466281)
			(xy 380.401068 -293.494714) (xy 380.400582 -293.521965) (xy 380.392826 -293.575913) (xy 380.377471 -293.628208)
			(xy 380.354829 -293.677785) (xy 380.325363 -293.723635) (xy 380.289672 -293.764826) (xy 380.248481 -293.800517)
			(xy 380.202631 -293.829983) (xy 380.153054 -293.852625) (xy 380.100759 -293.86798) (xy 380.046811 -293.875736)
			(xy 379.992309 -293.875736) (xy 379.938361 -293.86798) (xy 379.886066 -293.852625) (xy 379.836489 -293.829983)
			(xy 379.790639 -293.800517) (xy 379.749448 -293.764826) (xy 379.713757 -293.723635) (xy 379.684291 -293.677785)
			(xy 379.661649 -293.628208) (xy 379.646294 -293.575913) (xy 379.638538 -293.521965) (xy 379.638052 -293.494714)
			(xy 373.668036 -293.494714) (xy 373.668036 -295.933114) (xy 374.111518 -295.933114) (xy 374.115589 -295.877492)
			(xy 374.127715 -295.823055) (xy 374.147638 -295.770964) (xy 374.174934 -295.722329) (xy 374.20902 -295.678186)
			(xy 374.249169 -295.639477) (xy 374.294527 -295.607026) (xy 374.344127 -295.581525) (xy 374.396911 -295.563518)
			(xy 374.451754 -295.553388) (xy 374.507488 -295.551351) (xy 374.562925 -295.557451) (xy 374.616882 -295.571557)
			(xy 374.668211 -295.593369) (xy 374.715817 -295.622423) (xy 374.758685 -295.658098) (xy 374.795902 -295.699635)
			(xy 374.826675 -295.746148) (xy 374.850347 -295.796645) (xy 374.866415 -295.850052) (xy 374.874535 -295.905228)
			(xy 374.875044 -295.933114) (xy 375.587004 -295.933114) (xy 375.591075 -295.877492) (xy 375.603201 -295.823055)
			(xy 375.623124 -295.770964) (xy 375.65042 -295.722329) (xy 375.684506 -295.678186) (xy 375.724655 -295.639477)
			(xy 375.770013 -295.607026) (xy 375.819613 -295.581525) (xy 375.872397 -295.563518) (xy 375.92724 -295.553388)
			(xy 375.982974 -295.551351) (xy 376.038411 -295.557451) (xy 376.092368 -295.571557) (xy 376.143697 -295.593369)
			(xy 376.191303 -295.622423) (xy 376.234171 -295.658098) (xy 376.271388 -295.699635) (xy 376.302161 -295.746148)
			(xy 376.325833 -295.796645) (xy 376.341901 -295.850052) (xy 376.350021 -295.905228) (xy 376.35053 -295.933114)
			(xy 376.476004 -295.933114) (xy 376.480075 -295.877492) (xy 376.492201 -295.823055) (xy 376.512124 -295.770964)
			(xy 376.53942 -295.722329) (xy 376.573506 -295.678186) (xy 376.613655 -295.639477) (xy 376.659013 -295.607026)
			(xy 376.708613 -295.581525) (xy 376.761397 -295.563518) (xy 376.81624 -295.553388) (xy 376.871974 -295.551351)
			(xy 376.927411 -295.557451) (xy 376.981368 -295.571557) (xy 377.032697 -295.593369) (xy 377.080303 -295.622423)
			(xy 377.123171 -295.658098) (xy 377.160388 -295.699635) (xy 377.191161 -295.746148) (xy 377.214833 -295.796645)
			(xy 377.230901 -295.850052) (xy 377.239021 -295.905228) (xy 377.23953 -295.933114) (xy 377.239021 -295.961)
			(xy 377.230901 -296.016176) (xy 377.214833 -296.069583) (xy 377.191161 -296.12008) (xy 377.160388 -296.166593)
			(xy 377.123171 -296.20813) (xy 377.080303 -296.243805) (xy 377.032697 -296.272859) (xy 376.981368 -296.294671)
			(xy 376.927411 -296.308777) (xy 376.871974 -296.314877) (xy 376.81624 -296.31284) (xy 376.761397 -296.30271)
			(xy 376.708613 -296.284703) (xy 376.659013 -296.259202) (xy 376.613655 -296.226751) (xy 376.573506 -296.188042)
			(xy 376.53942 -296.143899) (xy 376.512124 -296.095264) (xy 376.492201 -296.043173) (xy 376.480075 -295.988736)
			(xy 376.476004 -295.933114) (xy 376.35053 -295.933114) (xy 376.350021 -295.961) (xy 376.341901 -296.016176)
			(xy 376.325833 -296.069583) (xy 376.302161 -296.12008) (xy 376.271388 -296.166593) (xy 376.234171 -296.20813)
			(xy 376.191303 -296.243805) (xy 376.143697 -296.272859) (xy 376.092368 -296.294671) (xy 376.038411 -296.308777)
			(xy 375.982974 -296.314877) (xy 375.92724 -296.31284) (xy 375.872397 -296.30271) (xy 375.819613 -296.284703)
			(xy 375.770013 -296.259202) (xy 375.724655 -296.226751) (xy 375.684506 -296.188042) (xy 375.65042 -296.143899)
			(xy 375.623124 -296.095264) (xy 375.603201 -296.043173) (xy 375.591075 -295.988736) (xy 375.587004 -295.933114)
			(xy 374.875044 -295.933114) (xy 374.874535 -295.961) (xy 374.866415 -296.016176) (xy 374.850347 -296.069583)
			(xy 374.826675 -296.12008) (xy 374.795902 -296.166593) (xy 374.758685 -296.20813) (xy 374.715817 -296.243805)
			(xy 374.668211 -296.272859) (xy 374.616882 -296.294671) (xy 374.562925 -296.308777) (xy 374.507488 -296.314877)
			(xy 374.451754 -296.31284) (xy 374.396911 -296.30271) (xy 374.344127 -296.284703) (xy 374.294527 -296.259202)
			(xy 374.249169 -296.226751) (xy 374.20902 -296.188042) (xy 374.174934 -296.143899) (xy 374.147638 -296.095264)
			(xy 374.127715 -296.043173) (xy 374.115589 -295.988736) (xy 374.111518 -295.933114) (xy 373.668036 -295.933114)
			(xy 373.668036 -299.133514) (xy 374.111518 -299.133514) (xy 374.115589 -299.077892) (xy 374.127715 -299.023455)
			(xy 374.147638 -298.971364) (xy 374.174934 -298.922729) (xy 374.20902 -298.878586) (xy 374.249169 -298.839877)
			(xy 374.294527 -298.807426) (xy 374.344127 -298.781925) (xy 374.396911 -298.763918) (xy 374.451754 -298.753788)
			(xy 374.507488 -298.751751) (xy 374.562925 -298.757851) (xy 374.616882 -298.771957) (xy 374.668211 -298.793769)
			(xy 374.715817 -298.822823) (xy 374.758685 -298.858498) (xy 374.795902 -298.900035) (xy 374.826675 -298.946548)
			(xy 374.850347 -298.997045) (xy 374.866415 -299.050452) (xy 374.874535 -299.105628) (xy 374.875044 -299.133514)
			(xy 375.587004 -299.133514) (xy 375.591075 -299.077892) (xy 375.603201 -299.023455) (xy 375.623124 -298.971364)
			(xy 375.65042 -298.922729) (xy 375.684506 -298.878586) (xy 375.724655 -298.839877) (xy 375.770013 -298.807426)
			(xy 375.819613 -298.781925) (xy 375.872397 -298.763918) (xy 375.92724 -298.753788) (xy 375.982974 -298.751751)
			(xy 376.038411 -298.757851) (xy 376.092368 -298.771957) (xy 376.143697 -298.793769) (xy 376.191303 -298.822823)
			(xy 376.234171 -298.858498) (xy 376.271388 -298.900035) (xy 376.302161 -298.946548) (xy 376.325833 -298.997045)
			(xy 376.341901 -299.050452) (xy 376.350021 -299.105628) (xy 376.35053 -299.133514) (xy 376.476004 -299.133514)
			(xy 376.480075 -299.077892) (xy 376.492201 -299.023455) (xy 376.512124 -298.971364) (xy 376.53942 -298.922729)
			(xy 376.573506 -298.878586) (xy 376.613655 -298.839877) (xy 376.659013 -298.807426) (xy 376.708613 -298.781925)
			(xy 376.761397 -298.763918) (xy 376.81624 -298.753788) (xy 376.871974 -298.751751) (xy 376.927411 -298.757851)
			(xy 376.981368 -298.771957) (xy 377.032697 -298.793769) (xy 377.080303 -298.822823) (xy 377.123171 -298.858498)
			(xy 377.160388 -298.900035) (xy 377.191161 -298.946548) (xy 377.214833 -298.997045) (xy 377.230901 -299.050452)
			(xy 377.239021 -299.105628) (xy 377.23953 -299.133514) (xy 377.239021 -299.1614) (xy 377.230901 -299.216576)
			(xy 377.214833 -299.269983) (xy 377.191161 -299.32048) (xy 377.160388 -299.366993) (xy 377.123171 -299.40853)
			(xy 377.080303 -299.444205) (xy 377.032697 -299.473259) (xy 376.981368 -299.495071) (xy 376.927411 -299.509177)
			(xy 376.871974 -299.515277) (xy 376.81624 -299.51324) (xy 376.761397 -299.50311) (xy 376.708613 -299.485103)
			(xy 376.659013 -299.459602) (xy 376.613655 -299.427151) (xy 376.573506 -299.388442) (xy 376.53942 -299.344299)
			(xy 376.512124 -299.295664) (xy 376.492201 -299.243573) (xy 376.480075 -299.189136) (xy 376.476004 -299.133514)
			(xy 376.35053 -299.133514) (xy 376.350021 -299.1614) (xy 376.341901 -299.216576) (xy 376.325833 -299.269983)
			(xy 376.302161 -299.32048) (xy 376.271388 -299.366993) (xy 376.234171 -299.40853) (xy 376.191303 -299.444205)
			(xy 376.143697 -299.473259) (xy 376.092368 -299.495071) (xy 376.038411 -299.509177) (xy 375.982974 -299.515277)
			(xy 375.92724 -299.51324) (xy 375.872397 -299.50311) (xy 375.819613 -299.485103) (xy 375.770013 -299.459602)
			(xy 375.724655 -299.427151) (xy 375.684506 -299.388442) (xy 375.65042 -299.344299) (xy 375.623124 -299.295664)
			(xy 375.603201 -299.243573) (xy 375.591075 -299.189136) (xy 375.587004 -299.133514) (xy 374.875044 -299.133514)
			(xy 374.874535 -299.1614) (xy 374.866415 -299.216576) (xy 374.850347 -299.269983) (xy 374.826675 -299.32048)
			(xy 374.795902 -299.366993) (xy 374.758685 -299.40853) (xy 374.715817 -299.444205) (xy 374.668211 -299.473259)
			(xy 374.616882 -299.495071) (xy 374.562925 -299.509177) (xy 374.507488 -299.515277) (xy 374.451754 -299.51324)
			(xy 374.396911 -299.50311) (xy 374.344127 -299.485103) (xy 374.294527 -299.459602) (xy 374.249169 -299.427151)
			(xy 374.20902 -299.388442) (xy 374.174934 -299.344299) (xy 374.147638 -299.295664) (xy 374.127715 -299.243573)
			(xy 374.115589 -299.189136) (xy 374.111518 -299.133514) (xy 373.668036 -299.133514) (xy 373.668036 -300.723808)
			(xy 373.668461 -300.733877) (xy 373.676182 -300.752476) (xy 373.683022 -300.759876) (xy 373.846344 -300.923198)
			(xy 374.046496 -301.123604) (xy 374.053671 -301.130887) (xy 374.067142 -301.146269) (xy 374.07342 -301.154338)
			(xy 374.074436 -301.155608) (xy 374.078754 -301.160688) (xy 374.363742 -301.445676) (xy 374.37021 -301.451714)
			(xy 374.386212 -301.459238) (xy 374.394984 -301.460408) (xy 374.397524 -301.460662)
		)
		(stroke
			(width 0)
			(type solid)
		)
		(fill yes)
		(layer "In9.Cu")
		(net "P1V8_PLL0_PEX3")
	)
	(gr_poly
		(pts
			(xy 336.683858 -95.124778) (xy 336.693923 -95.124344) (xy 336.71251 -95.116612) (xy 336.719926 -95.109792)
			(xy 336.93735 -94.892368) (xy 336.944197 -94.88497) (xy 336.951927 -94.866371) (xy 336.952336 -94.8563)
			(xy 336.952336 -92.62364) (xy 334.130396 -89.8017) (xy 334.130396 -89.254584) (xy 334.122776 -89.235788)
			(xy 334.11541 -89.228676) (xy 334.101948 -89.215214) (xy 334.094836 -89.211404) (xy 334.070174 -89.198248)
			(xy 334.02465 -89.165815) (xy 333.984346 -89.127088) (xy 333.950124 -89.082894) (xy 333.922716 -89.03418)
			(xy 333.902709 -88.981988) (xy 333.890532 -88.927436) (xy 333.886444 -88.87169) (xy 333.890535 -88.815945)
			(xy 333.902715 -88.761393) (xy 333.922724 -88.709203) (xy 333.950134 -88.66049) (xy 333.984359 -88.616298)
			(xy 334.024665 -88.577572) (xy 334.07019 -88.545142) (xy 334.094836 -88.531954) (xy 334.101948 -88.528144)
			(xy 334.11541 -88.514682) (xy 334.115918 -88.514174) (xy 334.122508 -88.506796) (xy 334.129974 -88.488497)
			(xy 334.130396 -88.478614) (xy 334.130396 -85.92693) (xy 334.12996 -85.916866) (xy 334.122227 -85.89828)
			(xy 334.11541 -85.890862) (xy 334.087216 -85.862668) (xy 334.077818 -85.858858) (xy 334.069436 -85.855302)
			(xy 334.060038 -85.854794) (xy 334.033505 -85.853293) (xy 333.981206 -85.843858) (xy 333.930723 -85.827256)
			(xy 333.883032 -85.803807) (xy 333.839058 -85.773967) (xy 333.799652 -85.738311) (xy 333.765576 -85.697531)
			(xy 333.73749 -85.652416) (xy 333.715937 -85.603839) (xy 333.701336 -85.552742) (xy 333.693968 -85.500112)
			(xy 333.693516 -85.47354) (xy 333.694012 -85.4458) (xy 333.702045 -85.390905) (xy 333.717947 -85.337752)
			(xy 333.741382 -85.287465) (xy 333.771857 -85.241104) (xy 333.808727 -85.199648) (xy 333.82966 -85.18144)
			(xy 333.831438 -85.179916) (xy 333.835248 -85.176106) (xy 333.841535 -85.169195) (xy 333.84911 -85.152133)
			(xy 333.84998 -85.142832) (xy 333.851504 -85.111336) (xy 333.851504 -85.110828) (xy 333.85379 -85.06841)
			(xy 333.853906 -85.057703) (xy 333.846266 -85.037721) (xy 333.839058 -85.029802) (xy 333.838804 -85.029548)
			(xy 333.825502 -85.01565) (xy 333.801453 -84.985621) (xy 333.790798 -84.969604) (xy 333.787496 -84.964524)
			(xy 333.782924 -84.960206) (xy 333.778098 -84.955634) (xy 333.76616 -84.94903) (xy 333.757282 -84.944584)
			(xy 333.737593 -84.942164) (xy 333.71846 -84.947398) (xy 333.702746 -84.959504) (xy 333.697326 -84.967826)
			(xy 333.689706 -84.981034) (xy 333.690214 -84.995766) (xy 333.690468 -85.008974) (xy 333.689984 -85.036222)
			(xy 333.682232 -85.090164) (xy 333.666882 -85.142454) (xy 333.644247 -85.192027) (xy 333.614787 -85.237875)
			(xy 333.579103 -85.279063) (xy 333.53792 -85.314753) (xy 333.492077 -85.34422) (xy 333.442507 -85.366862)
			(xy 333.39022 -85.38222) (xy 333.336279 -85.38998) (xy 333.281782 -85.389984) (xy 333.22784 -85.382233)
			(xy 333.17555 -85.366884) (xy 333.125977 -85.344249) (xy 333.080129 -85.31479) (xy 333.03894 -85.279106)
			(xy 333.003249 -85.237924) (xy 332.973782 -85.192081) (xy 332.951139 -85.142512) (xy 332.935781 -85.090224)
			(xy 332.928021 -85.036283) (xy 332.928016 -84.981787) (xy 332.935766 -84.927845) (xy 332.951115 -84.875555)
			(xy 332.973748 -84.825981) (xy 333.003207 -84.780133) (xy 333.03889 -84.738944) (xy 333.080072 -84.703252)
			(xy 333.125915 -84.673785) (xy 333.175484 -84.651141) (xy 333.227771 -84.635782) (xy 333.281712 -84.628021)
			(xy 333.30896 -84.627466) (xy 333.3377 -84.627985) (xy 333.394529 -84.636603) (xy 333.449422 -84.653651)
			(xy 333.501136 -84.678743) (xy 333.548499 -84.711309) (xy 333.569818 -84.73059) (xy 333.579724 -84.739988)
			(xy 333.606394 -84.746084) (xy 333.703676 -84.716112) (xy 333.71322 -84.712786) (xy 333.728811 -84.699951)
			(xy 333.733902 -84.69122) (xy 333.73695 -84.685124) (xy 333.738474 -84.67852) (xy 333.738474 -84.678266)
			(xy 333.745278 -84.650464) (xy 333.766083 -84.597142) (xy 333.794614 -84.547523) (xy 333.830232 -84.502719)
			(xy 333.872138 -84.463733) (xy 333.919395 -84.43144) (xy 333.970942 -84.406562) (xy 334.025626 -84.389657)
			(xy 334.08222 -84.381104) (xy 334.110838 -84.380578) (xy 334.136978 -84.38101) (xy 334.188768 -84.388154)
			(xy 334.239097 -84.402302) (xy 334.287023 -84.42319) (xy 334.331648 -84.450426) (xy 334.372137 -84.4835)
			(xy 334.40773 -84.521793) (xy 334.437761 -84.564587) (xy 334.461668 -84.611081) (xy 334.470756 -84.635594)
			(xy 334.472762 -84.640905) (xy 334.47879 -84.650523) (xy 334.482694 -84.654644) (xy 334.577944 -84.749894)
			(xy 334.585345 -84.756734) (xy 334.603943 -84.764454) (xy 334.614012 -84.76488) (xy 334.617822 -84.76488)
			(xy 334.627825 -84.764388) (xy 334.646306 -84.756724) (xy 334.660447 -84.742571) (xy 334.668096 -84.724084)
			(xy 334.668622 -84.71408) (xy 334.668622 -83.421474) (xy 334.304894 -83.057746) (xy 331.874622 -83.057746)
			(xy 327.635362 -78.818486) (xy 321.074034 -78.818486) (xy 321.052436 -78.830303) (xy 321.006852 -78.848901)
			(xy 320.959255 -78.861488) (xy 320.910436 -78.867855) (xy 320.88582 -78.86827) (xy 320.885312 -78.86827)
			(xy 320.858061 -78.867808) (xy 320.804114 -78.860053) (xy 320.75182 -78.844699) (xy 320.702244 -78.82206)
			(xy 320.656394 -78.792595) (xy 320.615204 -78.756905) (xy 320.579512 -78.715716) (xy 320.550046 -78.669867)
			(xy 320.527405 -78.620291) (xy 320.51205 -78.567997) (xy 320.504293 -78.514051) (xy 320.504293 -78.459549)
			(xy 320.51205 -78.405603) (xy 320.527405 -78.353309) (xy 320.550046 -78.303733) (xy 320.579512 -78.257884)
			(xy 320.615204 -78.216695) (xy 320.656394 -78.181005) (xy 320.702244 -78.15154) (xy 320.75182 -78.128901)
			(xy 320.804114 -78.113547) (xy 320.858061 -78.105792) (xy 320.885312 -78.105254) (xy 320.88582 -78.105254)
			(xy 320.910437 -78.105653) (xy 320.959259 -78.112014) (xy 321.006858 -78.124603) (xy 321.052441 -78.14321)
			(xy 321.074034 -78.155038) (xy 327.91019 -78.155038) (xy 330.557706 -80.802554) (xy 332.884457 -80.802554)
			(xy 332.884457 -80.748046) (xy 332.892215 -80.694093) (xy 332.907572 -80.641794) (xy 332.930217 -80.592212)
			(xy 332.959687 -80.546358) (xy 332.995383 -80.505165) (xy 333.036579 -80.469471) (xy 333.082435 -80.440004)
			(xy 333.132018 -80.417363) (xy 333.184319 -80.402009) (xy 333.238272 -80.394256) (xy 333.265526 -80.393794)
			(xy 333.292897 -80.394246) (xy 333.347076 -80.402068) (xy 333.39958 -80.41756) (xy 333.449326 -80.440405)
			(xy 333.495293 -80.470132) (xy 333.516224 -80.487774) (xy 333.516478 -80.488028) (xy 333.523564 -80.493615)
			(xy 333.540481 -80.49986) (xy 333.549498 -80.50022) (xy 333.616554 -80.50022) (xy 333.625568 -80.499837)
			(xy 333.642485 -80.493607) (xy 333.649574 -80.488028) (xy 333.649574 -80.487774) (xy 333.649828 -80.487774)
			(xy 333.670773 -80.470151) (xy 333.716743 -80.440438) (xy 333.766487 -80.417599) (xy 333.818985 -80.402104)
			(xy 333.873158 -80.394271) (xy 333.900526 -80.393794) (xy 333.927776 -80.394278) (xy 333.981721 -80.402037)
			(xy 334.034013 -80.417395) (xy 334.083587 -80.440037) (xy 334.129435 -80.469504) (xy 334.170622 -80.505196)
			(xy 334.206311 -80.546386) (xy 334.235775 -80.592235) (xy 334.258415 -80.641811) (xy 334.273768 -80.694104)
			(xy 334.281524 -80.74805) (xy 334.281524 -80.80255) (xy 334.273768 -80.856496) (xy 334.258415 -80.908789)
			(xy 334.235775 -80.958365) (xy 334.206311 -81.004214) (xy 334.170622 -81.045404) (xy 334.129435 -81.081096)
			(xy 334.083587 -81.110563) (xy 334.034013 -81.133205) (xy 333.981721 -81.148563) (xy 333.927776 -81.156322)
			(xy 333.900526 -81.15681) (xy 333.873156 -81.156326) (xy 333.818978 -81.148512) (xy 333.766475 -81.133027)
			(xy 333.716728 -81.11019) (xy 333.67076 -81.080469) (xy 333.649828 -81.06283) (xy 333.649574 -81.062576)
			(xy 333.642472 -81.057012) (xy 333.625567 -81.050752) (xy 333.616554 -81.050384) (xy 333.549498 -81.050384)
			(xy 333.540481 -81.050744) (xy 333.523565 -81.05699) (xy 333.516478 -81.062576) (xy 333.516478 -81.06283)
			(xy 333.516224 -81.06283) (xy 333.495298 -81.080476) (xy 333.449323 -81.110186) (xy 333.399574 -81.13302)
			(xy 333.347072 -81.148509) (xy 333.292895 -81.156336) (xy 333.265526 -81.15681) (xy 333.238272 -81.156344)
			(xy 333.184319 -81.148591) (xy 333.132018 -81.133237) (xy 333.082435 -81.110596) (xy 333.036579 -81.081129)
			(xy 332.995383 -81.045435) (xy 332.959687 -81.004242) (xy 332.930217 -80.958388) (xy 332.907572 -80.908806)
			(xy 332.892215 -80.856507) (xy 332.884457 -80.802554) (xy 330.557706 -80.802554) (xy 332.14945 -82.394298)
			(xy 333.43342 -82.394298) (xy 333.603854 -82.223864) (xy 334.44688 -82.223864) (xy 334.668622 -82.002122)
			(xy 334.668622 -79.988664) (xy 334.668084 -79.976916) (xy 334.657758 -79.955816) (xy 334.639133 -79.941501)
			(xy 334.627728 -79.938626) (xy 334.61833 -79.936848) (xy 334.591406 -79.897986) (xy 334.576928 -79.887826)
			(xy 334.568038 -79.88554) (xy 334.54132 -79.877882) (xy 334.490274 -79.8559) (xy 334.442954 -79.826748)
			(xy 334.400361 -79.791044) (xy 334.363396 -79.749541) (xy 334.332839 -79.703116) (xy 334.309336 -79.652752)
			(xy 334.293385 -79.599512) (xy 334.285321 -79.544521) (xy 334.284828 -79.516732) (xy 334.285381 -79.487181)
			(xy 334.294496 -79.428787) (xy 334.312512 -79.372499) (xy 334.338998 -79.319665) (xy 334.37332 -79.271551)
			(xy 334.414655 -79.229309) (xy 334.43799 -79.21117) (xy 334.445102 -79.205836) (xy 334.464914 -79.176118)
			(xy 334.466946 -79.16672) (xy 334.47355 -79.138272) (xy 334.472026 -79.122016) (xy 334.46847 -79.114142)
			(xy 334.467454 -79.111602) (xy 334.465676 -79.1083) (xy 334.464406 -79.10576) (xy 334.454822 -79.088193)
			(xy 334.438418 -79.05169) (xy 334.43164 -79.032862) (xy 334.425529 -79.014757) (xy 334.415987 -78.977752)
			(xy 334.41259 -78.958948) (xy 334.40963 -78.940165) (xy 334.406455 -78.90227) (xy 334.40624 -78.883256)
			(xy 334.40624 -78.882748) (xy 334.406766 -78.851619) (xy 334.415206 -78.789936) (xy 334.431922 -78.729965)
			(xy 334.456607 -78.67281) (xy 334.488806 -78.619525) (xy 334.527925 -78.571093) (xy 334.573244 -78.528405)
			(xy 334.598264 -78.509876) (xy 334.598772 -78.509876) (xy 334.626966 -78.490826) (xy 334.632046 -78.487778)
			(xy 334.645254 -78.47457) (xy 334.653128 -78.46441) (xy 334.658462 -78.455266) (xy 334.658716 -78.455012)
			(xy 334.659986 -78.452726) (xy 334.664304 -78.44663) (xy 334.668622 -78.432152) (xy 334.668622 -74.212704)
			(xy 334.661002 -74.193908) (xy 334.653636 -74.186796) (xy 334.599788 -74.132948) (xy 334.597209 -74.130443)
			(xy 334.59147 -74.126113) (xy 334.588358 -74.124312) (xy 334.588104 -74.124312) (xy 334.582261 -74.12131)
			(xy 334.569526 -74.118102) (xy 334.562958 -74.117962) (xy 334.49006 -74.118978) (xy 334.47101 -74.127614)
			(xy 334.463898 -74.135488) (xy 334.457167 -74.142786) (xy 334.443063 -74.156764) (xy 334.435704 -74.163428)
			(xy 334.43545 -74.163682) (xy 334.430116 -74.168762) (xy 334.423258 -74.177906) (xy 334.42021 -74.185526)
			(xy 334.416654 -74.194924) (xy 334.416654 -74.257408) (xy 334.41682 -74.262783) (xy 334.419133 -74.273282)
			(xy 334.421226 -74.278236) (xy 334.43291 -74.304398) (xy 334.440022 -74.311256) (xy 334.45809 -74.329285)
			(xy 334.489736 -74.369334) (xy 334.515757 -74.413246) (xy 334.535688 -74.460237) (xy 334.549173 -74.509466)
			(xy 334.555971 -74.560054) (xy 334.556354 -74.585576) (xy 334.556354 -74.595482) (xy 334.555224 -74.62228)
			(xy 334.546377 -74.675182) (xy 334.530205 -74.726322) (xy 334.507027 -74.774692) (xy 334.477301 -74.819337)
			(xy 334.441612 -74.859377) (xy 334.400665 -74.894021) (xy 334.355268 -74.922586) (xy 334.306317 -74.944509)
			(xy 334.254777 -74.959356) (xy 334.201664 -74.966836) (xy 334.174846 -74.967338) (xy 334.147478 -74.966862)
			(xy 334.093304 -74.959031) (xy 334.040806 -74.943536) (xy 333.991062 -74.920696) (xy 333.945094 -74.89098)
			(xy 333.924148 -74.873358) (xy 333.917036 -74.867262) (xy 333.900272 -74.860912) (xy 333.827628 -74.860912)
			(xy 333.821682 -74.861098) (xy 333.810126 -74.863915) (xy 333.804768 -74.8665) (xy 333.790544 -74.873612)
			(xy 333.785718 -74.877422) (xy 333.78521 -74.87793) (xy 333.764505 -74.894739) (xy 333.71929 -74.923019)
			(xy 333.670579 -74.944731) (xy 333.61932 -74.959452) (xy 333.566511 -74.966895) (xy 333.539846 -74.967338)
			(xy 333.51303 -74.96688) (xy 333.459926 -74.959365) (xy 333.408396 -74.944492) (xy 333.359456 -74.922552)
			(xy 333.314069 -74.893978) (xy 333.273128 -74.859332) (xy 333.23744 -74.819296) (xy 333.207706 -74.77466)
			(xy 333.184513 -74.726301) (xy 333.168318 -74.675172) (xy 333.159438 -74.622279) (xy 333.158338 -74.595482)
			(xy 333.158338 -74.585576) (xy 333.158766 -74.560058) (xy 333.165571 -74.509476) (xy 333.179056 -74.460253)
			(xy 333.198982 -74.413267) (xy 333.224992 -74.369355) (xy 333.256622 -74.329302) (xy 333.27467 -74.311256)
			(xy 333.281782 -74.304398) (xy 333.293466 -74.278236) (xy 333.295576 -74.273288) (xy 333.297883 -74.262785)
			(xy 333.298038 -74.257408) (xy 333.298038 -74.203052) (xy 333.297879 -74.197675) (xy 333.295581 -74.187169)
			(xy 333.293466 -74.182224) (xy 333.281782 -74.156062) (xy 333.27467 -74.149204) (xy 333.256604 -74.131174)
			(xy 333.224963 -74.091124) (xy 333.198948 -74.047211) (xy 333.179022 -74.00022) (xy 333.165542 -73.950991)
			(xy 333.158749 -73.900405) (xy 333.158338 -73.874884) (xy 333.158338 -73.864978) (xy 333.159472 -73.838593)
			(xy 333.16811 -73.786492) (xy 333.183848 -73.73608) (xy 333.206386 -73.688319) (xy 333.235293 -73.644122)
			(xy 333.252318 -73.623932) (xy 333.258414 -73.61682) (xy 333.264764 -73.600056) (xy 333.264764 -73.527412)
			(xy 333.264576 -73.521466) (xy 333.261754 -73.509913) (xy 333.259176 -73.504552) (xy 333.252064 -73.490328)
			(xy 333.248254 -73.485502) (xy 333.247746 -73.484994) (xy 333.230939 -73.464288) (xy 333.202662 -73.419073)
			(xy 333.180954 -73.370361) (xy 333.166236 -73.319103) (xy 333.158796 -73.266295) (xy 333.158338 -73.23963)
			(xy 333.158338 -73.239376) (xy 333.158793 -73.213384) (xy 333.165883 -73.161886) (xy 333.179901 -73.111827)
			(xy 333.200587 -73.064136) (xy 333.227557 -73.019696) (xy 333.260313 -72.97933) (xy 333.278988 -72.961246)
			(xy 333.283052 -72.957436) (xy 333.289148 -72.9488) (xy 333.291434 -72.942958) (xy 333.293231 -72.938396)
			(xy 333.295271 -72.928806) (xy 333.295498 -72.923908) (xy 333.296514 -72.851772) (xy 333.296447 -72.845217)
			(xy 333.293367 -72.83248) (xy 333.290418 -72.826626) (xy 333.286608 -72.819768) (xy 332.262226 -71.795386)
			(xy 332.255114 -71.78802) (xy 332.236318 -71.7804) (xy 331.678026 -71.7804) (xy 331.67151 -71.780636)
			(xy 331.658911 -71.78398) (xy 331.653134 -71.787004) (xy 331.633068 -71.798434) (xy 331.6224 -71.806562)
			(xy 331.617828 -71.811134) (xy 331.614272 -71.816722) (xy 331.613764 -71.817484) (xy 331.612748 -71.818754)
			(xy 331.611478 -71.82104) (xy 331.596579 -71.844689) (xy 331.560948 -71.887754) (xy 331.519411 -71.925155)
			(xy 331.472858 -71.95609) (xy 331.422288 -71.979897) (xy 331.368783 -71.996064) (xy 331.313491 -72.004246)
			(xy 331.257597 -72.004267) (xy 331.202299 -71.996127) (xy 331.148782 -71.98) (xy 331.098194 -71.956232)
			(xy 331.051618 -71.925332) (xy 331.010052 -71.887963) (xy 330.974389 -71.844925) (xy 330.95946 -71.821294)
			(xy 330.956412 -71.816722) (xy 330.952856 -71.811134) (xy 330.948284 -71.806562) (xy 330.937616 -71.798434)
			(xy 330.91755 -71.787004) (xy 330.911785 -71.78395) (xy 330.899179 -71.780609) (xy 330.892658 -71.7804)
			(xy 330.12761 -71.7804) (xy 330.117704 -71.781416) (xy 330.105766 -71.783702) (xy 330.094082 -71.787512)
			(xy 330.081382 -71.793608) (xy 330.076718 -71.795936) (xy 330.068394 -71.80221) (xy 330.064872 -71.806054)
			(xy 330.064618 -71.806308) (xy 330.064618 -71.806562) (xy 330.0464 -71.826779) (xy 330.005222 -71.862359)
			(xy 329.959407 -71.891729) (xy 329.909885 -71.914294) (xy 329.857661 -71.929596) (xy 329.803792 -71.937326)
			(xy 329.749372 -71.937326) (xy 329.695503 -71.929596) (xy 329.643279 -71.914294) (xy 329.593757 -71.891729)
			(xy 329.547942 -71.862359) (xy 329.506764 -71.826779) (xy 329.488546 -71.806562) (xy 329.481688 -71.798688)
			(xy 329.443588 -71.7804) (xy 323.119242 -71.7804) (xy 323.111114 -71.781162) (xy 323.101208 -71.782686)
			(xy 323.1007 -71.782686) (xy 323.100192 -71.78294) (xy 323.096382 -71.78421) (xy 323.067928 -71.792741)
			(xy 323.009242 -71.801919) (xy 322.979542 -71.802498) (xy 322.979034 -71.802498) (xy 322.948394 -71.801863)
			(xy 322.887906 -71.792032) (xy 322.858638 -71.78294) (xy 322.850764 -71.7804) (xy 307.249068 -71.7804)
			(xy 307.236368 -71.781924) (xy 307.217826 -71.78675) (xy 307.212492 -71.789544) (xy 307.186128 -71.802803)
			(xy 307.130306 -71.82194) (xy 307.072206 -71.832273) (xy 307.013209 -71.833557) (xy 306.983892 -71.830184)
			(xy 306.950623 -71.825044) (xy 306.886488 -71.804608) (xy 306.856384 -71.789544) (xy 306.851304 -71.787004)
			(xy 306.83327 -71.782178) (xy 306.820316 -71.7804) (xy 305.678078 -71.7804) (xy 305.67156 -71.78063)
			(xy 305.658955 -71.783963) (xy 305.653186 -71.787004) (xy 305.63312 -71.798434) (xy 305.622452 -71.806562)
			(xy 305.61788 -71.811134) (xy 305.614324 -71.816722) (xy 305.613816 -71.817484) (xy 305.6128 -71.818754)
			(xy 305.61153 -71.82104) (xy 305.59663 -71.844693) (xy 305.560999 -71.887765) (xy 305.519459 -71.925173)
			(xy 305.472904 -71.956116) (xy 305.422329 -71.979928) (xy 305.368819 -71.996102) (xy 305.313521 -72.004289)
			(xy 305.257621 -72.004314) (xy 305.202316 -71.996176) (xy 305.148792 -71.980051) (xy 305.098195 -71.956284)
			(xy 305.051612 -71.925384) (xy 305.010039 -71.888013) (xy 304.974368 -71.844973) (xy 304.959512 -71.821294)
			(xy 304.956464 -71.816722) (xy 304.952908 -71.811134) (xy 304.948336 -71.806562) (xy 304.937668 -71.798434)
			(xy 304.917602 -71.787004) (xy 304.911838 -71.783944) (xy 304.899232 -71.78059) (xy 304.89271 -71.7804)
			(xy 304.127662 -71.7804) (xy 304.117756 -71.781416) (xy 304.105818 -71.783702) (xy 304.094134 -71.787512)
			(xy 304.081434 -71.793608) (xy 304.076767 -71.795933) (xy 304.068436 -71.802201) (xy 304.064924 -71.806054)
			(xy 304.06467 -71.806308) (xy 304.06467 -71.806562) (xy 304.046452 -71.826779) (xy 304.005274 -71.862359)
			(xy 303.959459 -71.891729) (xy 303.909937 -71.914294) (xy 303.857713 -71.929596) (xy 303.803844 -71.937326)
			(xy 303.749424 -71.937326) (xy 303.695555 -71.929596) (xy 303.643331 -71.914294) (xy 303.593809 -71.891729)
			(xy 303.547994 -71.862359) (xy 303.506816 -71.826779) (xy 303.488598 -71.806562) (xy 303.48174 -71.798688)
			(xy 303.44364 -71.7804) (xy 281.24912 -71.7804) (xy 281.23642 -71.781924) (xy 281.217878 -71.78675)
			(xy 281.212544 -71.789544) (xy 281.186179 -71.802799) (xy 281.130357 -71.821929) (xy 281.072258 -71.832255)
			(xy 281.013263 -71.833532) (xy 280.983944 -71.830184) (xy 280.950677 -71.82504) (xy 280.886546 -71.804597)
			(xy 280.856436 -71.789544) (xy 280.851356 -71.787004) (xy 280.833322 -71.782178) (xy 280.820368 -71.7804)
			(xy 279.67813 -71.7804) (xy 279.671614 -71.780636) (xy 279.659014 -71.783979) (xy 279.653238 -71.787004)
			(xy 279.633172 -71.798434) (xy 279.622504 -71.806562) (xy 279.617932 -71.811134) (xy 279.614376 -71.816722)
			(xy 279.613868 -71.817484) (xy 279.612852 -71.818754) (xy 279.611582 -71.82104) (xy 279.596683 -71.844689)
			(xy 279.561052 -71.887755) (xy 279.519515 -71.925156) (xy 279.472962 -71.956092) (xy 279.422391 -71.979899)
			(xy 279.368886 -71.996067) (xy 279.313593 -72.004249) (xy 279.257699 -72.004271) (xy 279.2024 -71.996131)
			(xy 279.148883 -71.980004) (xy 279.098294 -71.956236) (xy 279.051717 -71.925336) (xy 279.010151 -71.887966)
			(xy 278.974487 -71.844928) (xy 278.959564 -71.821294) (xy 278.956516 -71.816722) (xy 278.95296 -71.811134)
			(xy 278.948388 -71.806562) (xy 278.93772 -71.798434) (xy 278.917654 -71.787004) (xy 278.911889 -71.78395)
			(xy 278.899283 -71.780607) (xy 278.892762 -71.7804) (xy 278.127714 -71.7804) (xy 278.117808 -71.781416)
			(xy 278.10587 -71.783702) (xy 278.094186 -71.787512) (xy 278.081486 -71.793608) (xy 278.076821 -71.795936)
			(xy 278.068497 -71.80221) (xy 278.064976 -71.806054) (xy 278.064722 -71.806308) (xy 278.064722 -71.806562)
			(xy 278.046504 -71.826779) (xy 278.005326 -71.862359) (xy 277.959511 -71.891729) (xy 277.909989 -71.914294)
			(xy 277.857765 -71.929596) (xy 277.803896 -71.937326) (xy 277.749476 -71.937326) (xy 277.695607 -71.929596)
			(xy 277.643383 -71.914294) (xy 277.593861 -71.891729) (xy 277.548046 -71.862359) (xy 277.506868 -71.826779)
			(xy 277.48865 -71.806562) (xy 277.481792 -71.798688) (xy 277.443692 -71.7804) (xy 253.671324 -71.7804)
			(xy 253.658624 -71.783956) (xy 253.652528 -71.787512) (xy 253.625858 -71.80326) (xy 253.616968 -71.812404)
			(xy 253.614174 -71.81723) (xy 253.613412 -71.818246) (xy 253.612142 -71.820278) (xy 253.598331 -71.842431)
			(xy 253.565587 -71.883088) (xy 253.527599 -71.918895) (xy 253.485079 -71.949182) (xy 253.438823 -71.973381)
			(xy 253.389697 -71.991039) (xy 253.364238 -71.996808) (xy 253.356872 -71.998332) (xy 253.343918 -72.005444)
			(xy 253.126494 -72.222868) (xy 253.119128 -72.22998) (xy 253.111508 -72.248776) (xy 253.111508 -73.456038)
			(xy 253.111964 -73.465285) (xy 253.118612 -73.48255) (xy 253.130928 -73.496355) (xy 253.13894 -73.500996)
			(xy 253.23038 -73.549002) (xy 253.244604 -73.54824) (xy 253.259082 -73.547732) (xy 253.271528 -73.539096)
			(xy 253.29568 -73.522869) (xy 253.347872 -73.497151) (xy 253.403367 -73.47967) (xy 253.460876 -73.470832)
			(xy 253.489968 -73.470262) (xy 253.517225 -73.470723) (xy 253.571183 -73.478477) (xy 253.623489 -73.493831)
			(xy 253.673077 -73.516474) (xy 253.718938 -73.545943) (xy 253.760138 -73.58164) (xy 253.795838 -73.622836)
			(xy 253.825311 -73.668695) (xy 253.847958 -73.718281) (xy 253.863317 -73.770585) (xy 253.871075 -73.824544)
			(xy 253.871075 -73.879056) (xy 253.863317 -73.933015) (xy 253.847958 -73.985319) (xy 253.825311 -74.034905)
			(xy 253.795838 -74.080764) (xy 253.760138 -74.12196) (xy 253.718938 -74.157657) (xy 253.673077 -74.187126)
			(xy 253.623489 -74.209769) (xy 253.571183 -74.225123) (xy 253.517225 -74.232877) (xy 253.489968 -74.233278)
			(xy 253.460835 -74.232709) (xy 253.40325 -74.223813) (xy 253.347688 -74.206264) (xy 253.295441 -74.180469)
			(xy 253.271274 -74.16419) (xy 253.25959 -74.156062) (xy 253.231396 -74.154284) (xy 253.13894 -74.202544)
			(xy 253.130897 -74.207148) (xy 253.118548 -74.220946) (xy 253.111938 -74.238243) (xy 253.111508 -74.247502)
			(xy 253.111508 -74.58583) (xy 255.158494 -74.58583) (xy 255.158917 -74.559515) (xy 255.166161 -74.507384)
			(xy 255.180489 -74.456741) (xy 255.20163 -74.408542) (xy 255.229184 -74.3637) (xy 255.262629 -74.323062)
			(xy 255.281684 -74.304906) (xy 255.289083 -74.297382) (xy 255.297609 -74.278104) (xy 255.298194 -74.267568)
			(xy 255.298194 -74.192892) (xy 255.297685 -74.18234) (xy 255.289136 -74.163045) (xy 255.281684 -74.155554)
			(xy 255.26261 -74.137417) (xy 255.229155 -74.096783) (xy 255.201599 -74.051939) (xy 255.180464 -74.003734)
			(xy 255.16615 -73.953084) (xy 255.15893 -73.900947) (xy 255.158494 -73.87463) (xy 255.158979 -73.84726)
			(xy 255.166793 -73.793082) (xy 255.182277 -73.740579) (xy 255.205115 -73.690832) (xy 255.234835 -73.644864)
			(xy 255.252474 -73.623932) (xy 255.252728 -73.623678) (xy 255.258333 -73.616604) (xy 255.264568 -73.599678)
			(xy 255.26492 -73.590658) (xy 255.26492 -73.523602) (xy 255.264558 -73.514586) (xy 255.258313 -73.497669)
			(xy 255.252728 -73.490582) (xy 255.252474 -73.490582) (xy 255.252474 -73.490328) (xy 255.234831 -73.4694)
			(xy 255.20512 -73.423425) (xy 255.182286 -73.373677) (xy 255.166795 -73.321176) (xy 255.158968 -73.266999)
			(xy 255.158494 -73.23963) (xy 255.158983 -73.212378) (xy 255.166736 -73.158428) (xy 255.182088 -73.10613)
			(xy 255.204728 -73.05655) (xy 255.234193 -73.010697) (xy 255.269884 -72.969504) (xy 255.311074 -72.93381)
			(xy 255.356925 -72.904341) (xy 255.406504 -72.881698) (xy 255.4588 -72.866342) (xy 255.51275 -72.858585)
			(xy 255.540002 -72.858122) (xy 255.567373 -72.858582) (xy 255.621552 -72.8664) (xy 255.674056 -72.88189)
			(xy 255.723802 -72.904734) (xy 255.769769 -72.93446) (xy 255.7907 -72.952102) (xy 255.790954 -72.952356)
			(xy 255.798045 -72.957936) (xy 255.814959 -72.964185) (xy 255.823974 -72.964548) (xy 255.89103 -72.964548)
			(xy 255.90005 -72.964217) (xy 255.916967 -72.957953) (xy 255.92405 -72.952356) (xy 255.92405 -72.952102)
			(xy 255.924304 -72.952102) (xy 255.945224 -72.934448) (xy 255.9912 -72.904738) (xy 256.040951 -72.881905)
			(xy 256.093454 -72.866418) (xy 256.147632 -72.858594) (xy 256.175002 -72.858122) (xy 256.202256 -72.858554)
			(xy 256.25621 -72.866312) (xy 256.30851 -72.881669) (xy 256.358092 -72.904314) (xy 256.403947 -72.933785)
			(xy 256.44514 -72.969482) (xy 256.480834 -73.010679) (xy 256.510301 -73.056536) (xy 256.532942 -73.10612)
			(xy 256.548295 -73.158421) (xy 256.556049 -73.212376) (xy 256.55651 -73.23963) (xy 256.556059 -73.267001)
			(xy 256.548237 -73.32118) (xy 256.532744 -73.373684) (xy 256.509899 -73.42343) (xy 256.480172 -73.469397)
			(xy 256.46253 -73.490328) (xy 256.462276 -73.490582) (xy 256.456688 -73.497668) (xy 256.450443 -73.514585)
			(xy 256.450084 -73.523602) (xy 256.450084 -73.590658) (xy 256.450464 -73.599672) (xy 256.456696 -73.616589)
			(xy 256.462276 -73.623678) (xy 256.46253 -73.623678) (xy 256.46253 -73.623932) (xy 256.480155 -73.644875)
			(xy 256.509868 -73.690845) (xy 256.526259 -73.726548) (xy 259.359398 -73.726548) (xy 259.363469 -73.670926)
			(xy 259.375595 -73.616489) (xy 259.395518 -73.564398) (xy 259.422814 -73.515763) (xy 259.4569 -73.47162)
			(xy 259.497049 -73.432911) (xy 259.542407 -73.40046) (xy 259.592007 -73.374959) (xy 259.644791 -73.356952)
			(xy 259.699634 -73.346822) (xy 259.755368 -73.344785) (xy 259.810805 -73.350885) (xy 259.864762 -73.364991)
			(xy 259.916091 -73.386803) (xy 259.963697 -73.415857) (xy 260.006565 -73.451532) (xy 260.043782 -73.493069)
			(xy 260.074555 -73.539582) (xy 260.077119 -73.545052) (xy 260.531838 -73.545052) (xy 260.531838 -73.490548)
			(xy 260.539594 -73.436597) (xy 260.554949 -73.3843) (xy 260.57759 -73.33472) (xy 260.607056 -73.288866)
			(xy 260.642747 -73.247673) (xy 260.683938 -73.211978) (xy 260.729788 -73.182507) (xy 260.779366 -73.159862)
			(xy 260.831662 -73.144502) (xy 260.885612 -73.13674) (xy 260.912864 -73.136252) (xy 260.939259 -73.136728)
			(xy 260.991544 -73.144007) (xy 261.042329 -73.158417) (xy 261.090645 -73.179685) (xy 261.135572 -73.207404)
			(xy 261.156196 -73.223882) (xy 261.166959 -73.232137) (xy 261.191639 -73.243346) (xy 261.218401 -73.247657)
			(xy 261.245354 -73.244767) (xy 261.270593 -73.23488) (xy 261.292337 -73.218693) (xy 261.309048 -73.19735)
			(xy 261.314692 -73.18502) (xy 261.326017 -73.159373) (xy 261.354963 -73.111362) (xy 261.390623 -73.068104)
			(xy 261.43223 -73.03053) (xy 261.478887 -72.999449) (xy 261.529591 -72.975531) (xy 261.583249 -72.959291)
			(xy 261.638705 -72.951077) (xy 261.666736 -72.950578) (xy 261.693985 -72.951095) (xy 261.747926 -72.958855)
			(xy 261.800215 -72.974213) (xy 261.849786 -72.996855) (xy 261.89563 -73.026321) (xy 261.936814 -73.062011)
			(xy 261.9725 -73.103199) (xy 262.001962 -73.149046) (xy 262.0246 -73.198619) (xy 262.025082 -73.20026)
			(xy 274.656804 -73.20026) (xy 274.657304 -73.172891) (xy 274.665114 -73.118713) (xy 274.680595 -73.066211)
			(xy 274.703429 -73.016463) (xy 274.733146 -72.970495) (xy 274.750784 -72.949562) (xy 274.751038 -72.949308)
			(xy 274.756632 -72.942226) (xy 274.762873 -72.925306) (xy 274.76323 -72.916288) (xy 274.76323 -72.849232)
			(xy 274.762851 -72.840217) (xy 274.756618 -72.823301) (xy 274.751038 -72.816212) (xy 274.750784 -72.816212)
			(xy 274.750784 -72.815958) (xy 274.733156 -72.795017) (xy 274.703443 -72.749046) (xy 274.680605 -72.699301)
			(xy 274.665112 -72.646803) (xy 274.65728 -72.592629) (xy 274.656804 -72.56526) (xy 274.657241 -72.538007)
			(xy 274.665003 -72.484057) (xy 274.680364 -72.431761) (xy 274.70301 -72.382183) (xy 274.732482 -72.336332)
			(xy 274.768179 -72.295142) (xy 274.809373 -72.259451) (xy 274.855228 -72.229985) (xy 274.90481 -72.207346)
			(xy 274.957108 -72.191992) (xy 275.011059 -72.184237) (xy 275.038312 -72.183752) (xy 275.065683 -72.184198)
			(xy 275.119864 -72.192019) (xy 275.172367 -72.207512) (xy 275.222114 -72.230358) (xy 275.268079 -72.260088)
			(xy 275.28901 -72.277732) (xy 275.289264 -72.277986) (xy 275.296358 -72.283562) (xy 275.313269 -72.289816)
			(xy 275.322284 -72.290178) (xy 275.38934 -72.290178) (xy 275.398359 -72.289845) (xy 275.415276 -72.283581)
			(xy 275.42236 -72.277986) (xy 275.42236 -72.277732) (xy 275.422614 -72.277732) (xy 275.443572 -72.260125)
			(xy 275.489537 -72.230407) (xy 275.539278 -72.207564) (xy 275.591773 -72.192066) (xy 275.645945 -72.18423)
			(xy 275.673312 -72.183752) (xy 275.699627 -72.184195) (xy 275.751757 -72.191432) (xy 275.802401 -72.205755)
			(xy 275.8506 -72.226892) (xy 275.895443 -72.254443) (xy 275.936081 -72.287888) (xy 275.954236 -72.306942)
			(xy 275.96175 -72.314353) (xy 275.981035 -72.322874) (xy 275.991574 -72.323452) (xy 276.06625 -72.323452)
			(xy 276.0768 -72.322924) (xy 276.096096 -72.314389) (xy 276.103588 -72.306942) (xy 276.121745 -72.287888)
			(xy 276.162376 -72.254433) (xy 276.207216 -72.226875) (xy 276.255416 -72.205737) (xy 276.306063 -72.191419)
			(xy 276.358196 -72.184192) (xy 276.384512 -72.183752) (xy 276.411762 -72.184266) (xy 276.465706 -72.192024)
			(xy 276.517998 -72.207378) (xy 276.567573 -72.230018) (xy 276.613421 -72.259482) (xy 276.65461 -72.29517)
			(xy 276.690302 -72.336356) (xy 276.719769 -72.382203) (xy 276.742412 -72.431776) (xy 276.75777 -72.484066)
			(xy 276.765532 -72.53801) (xy 276.76602 -72.56526) (xy 276.76555 -72.59263) (xy 276.757736 -72.64681)
			(xy 276.742249 -72.699314) (xy 276.719408 -72.749061) (xy 276.689682 -72.795027) (xy 276.67204 -72.815958)
			(xy 276.671786 -72.816212) (xy 276.666187 -72.82329) (xy 276.659948 -72.840213) (xy 276.659594 -72.849232)
			(xy 276.659594 -72.916288) (xy 276.659958 -72.925304) (xy 276.666201 -72.942221) (xy 276.671786 -72.949308)
			(xy 276.67204 -72.949308) (xy 276.67204 -72.949562) (xy 276.689681 -72.970492) (xy 276.719392 -73.016466)
			(xy 276.742227 -73.066214) (xy 276.757717 -73.118715) (xy 276.765546 -73.172891) (xy 276.76602 -73.20026)
			(xy 276.765508 -73.227511) (xy 276.757756 -73.28146) (xy 276.742406 -73.333756) (xy 276.719769 -73.383335)
			(xy 276.690306 -73.429188) (xy 276.654618 -73.470381) (xy 276.61343 -73.506075) (xy 276.567581 -73.535544)
			(xy 276.518005 -73.558188) (xy 276.465711 -73.573545) (xy 276.411763 -73.581304) (xy 276.384512 -73.581768)
			(xy 276.358198 -73.581303) (xy 276.306069 -73.574069) (xy 276.255426 -73.55975) (xy 276.207226 -73.538617)
			(xy 276.162383 -73.51107) (xy 276.121744 -73.47763) (xy 276.103588 -73.458578) (xy 276.096076 -73.451166)
			(xy 276.076788 -73.442648) (xy 276.06625 -73.442068) (xy 275.991574 -73.442068) (xy 275.981029 -73.442633)
			(xy 275.961733 -73.451144) (xy 275.954236 -73.458578) (xy 275.9361 -73.477653) (xy 275.895467 -73.51111)
			(xy 275.850623 -73.538667) (xy 275.802418 -73.559802) (xy 275.751767 -73.574114) (xy 275.699629 -73.581333)
			(xy 275.673312 -73.581768) (xy 275.645942 -73.581303) (xy 275.591762 -73.573486) (xy 275.539259 -73.557997)
			(xy 275.489512 -73.535155) (xy 275.443545 -73.50543) (xy 275.422614 -73.487788) (xy 275.42236 -73.487534)
			(xy 275.415266 -73.481959) (xy 275.398355 -73.475707) (xy 275.38934 -73.475342) (xy 275.322284 -73.475342)
			(xy 275.313265 -73.475682) (xy 275.296348 -73.48194) (xy 275.289264 -73.487534) (xy 275.289264 -73.487788)
			(xy 275.28901 -73.487788) (xy 275.268083 -73.505434) (xy 275.222109 -73.535145) (xy 275.17236 -73.55798)
			(xy 275.119858 -73.573469) (xy 275.065682 -73.581295) (xy 275.038312 -73.581768) (xy 275.011058 -73.581333)
			(xy 274.957104 -73.573577) (xy 274.904803 -73.55822) (xy 274.85522 -73.535576) (xy 274.809365 -73.506106)
			(xy 274.768171 -73.470409) (xy 274.732477 -73.429213) (xy 274.70301 -73.383355) (xy 274.68037 -73.333771)
			(xy 274.665017 -73.281469) (xy 274.657265 -73.227514) (xy 274.656804 -73.20026) (xy 262.025082 -73.20026)
			(xy 262.039953 -73.250909) (xy 262.047708 -73.304851) (xy 262.047708 -73.359349) (xy 262.039953 -73.413291)
			(xy 262.0246 -73.465581) (xy 262.001962 -73.515154) (xy 261.9725 -73.561001) (xy 261.936814 -73.602189)
			(xy 261.89563 -73.637879) (xy 261.849786 -73.667345) (xy 261.800215 -73.689987) (xy 261.747926 -73.705345)
			(xy 261.693985 -73.713105) (xy 261.666736 -73.713594) (xy 261.640341 -73.713131) (xy 261.588054 -73.70585)
			(xy 261.537269 -73.691438) (xy 261.488953 -73.670167) (xy 261.444027 -73.642444) (xy 261.423404 -73.625964)
			(xy 261.412653 -73.617691) (xy 261.387969 -73.606475) (xy 261.361202 -73.60216) (xy 261.334244 -73.605051)
			(xy 261.309001 -73.614944) (xy 261.287256 -73.631139) (xy 261.270548 -73.652491) (xy 261.264908 -73.664826)
			(xy 261.253606 -73.690484) (xy 261.224654 -73.738493) (xy 261.18899 -73.781749) (xy 261.147379 -73.819321)
			(xy 261.100719 -73.8504) (xy 261.097814 -73.85177) (xy 277.075898 -73.85177) (xy 277.079969 -73.796148)
			(xy 277.092095 -73.741711) (xy 277.112018 -73.68962) (xy 277.139314 -73.640985) (xy 277.1734 -73.596842)
			(xy 277.213549 -73.558133) (xy 277.258907 -73.525682) (xy 277.308507 -73.500181) (xy 277.361291 -73.482174)
			(xy 277.416134 -73.472044) (xy 277.471868 -73.470007) (xy 277.527305 -73.476107) (xy 277.581262 -73.490213)
			(xy 277.632591 -73.512025) (xy 277.680197 -73.541079) (xy 277.723065 -73.576754) (xy 277.760282 -73.618291)
			(xy 277.791055 -73.664804) (xy 277.814727 -73.715301) (xy 277.830795 -73.768708) (xy 277.838915 -73.823884)
			(xy 277.839424 -73.85177) (xy 278.091898 -73.85177) (xy 278.095969 -73.796148) (xy 278.108095 -73.741711)
			(xy 278.128018 -73.68962) (xy 278.155314 -73.640985) (xy 278.1894 -73.596842) (xy 278.229549 -73.558133)
			(xy 278.274907 -73.525682) (xy 278.324507 -73.500181) (xy 278.377291 -73.482174) (xy 278.432134 -73.472044)
			(xy 278.487868 -73.470007) (xy 278.543305 -73.476107) (xy 278.597262 -73.490213) (xy 278.648591 -73.512025)
			(xy 278.696197 -73.541079) (xy 278.739065 -73.576754) (xy 278.776282 -73.618291) (xy 278.807055 -73.664804)
			(xy 278.830727 -73.715301) (xy 278.846795 -73.768708) (xy 278.854915 -73.823884) (xy 278.855424 -73.85177)
			(xy 279.107898 -73.85177) (xy 279.111969 -73.796148) (xy 279.124095 -73.741711) (xy 279.144018 -73.68962)
			(xy 279.171314 -73.640985) (xy 279.2054 -73.596842) (xy 279.245549 -73.558133) (xy 279.290907 -73.525682)
			(xy 279.340507 -73.500181) (xy 279.393291 -73.482174) (xy 279.448134 -73.472044) (xy 279.503868 -73.470007)
			(xy 279.559305 -73.476107) (xy 279.613262 -73.490213) (xy 279.664591 -73.512025) (xy 279.712197 -73.541079)
			(xy 279.755065 -73.576754) (xy 279.792282 -73.618291) (xy 279.823055 -73.664804) (xy 279.846727 -73.715301)
			(xy 279.862795 -73.768708) (xy 279.870915 -73.823884) (xy 279.871424 -73.85177) (xy 279.870915 -73.879656)
			(xy 279.862795 -73.934832) (xy 279.846727 -73.988239) (xy 279.823055 -74.038736) (xy 279.792282 -74.085249)
			(xy 279.755065 -74.126786) (xy 279.712197 -74.162461) (xy 279.664591 -74.191515) (xy 279.613262 -74.213327)
			(xy 279.559305 -74.227433) (xy 279.503868 -74.233533) (xy 279.448134 -74.231496) (xy 279.393291 -74.221366)
			(xy 279.340507 -74.203359) (xy 279.290907 -74.177858) (xy 279.245549 -74.145407) (xy 279.2054 -74.106698)
			(xy 279.171314 -74.062555) (xy 279.144018 -74.01392) (xy 279.124095 -73.961829) (xy 279.111969 -73.907392)
			(xy 279.107898 -73.85177) (xy 278.855424 -73.85177) (xy 278.854915 -73.879656) (xy 278.846795 -73.934832)
			(xy 278.830727 -73.988239) (xy 278.807055 -74.038736) (xy 278.776282 -74.085249) (xy 278.739065 -74.126786)
			(xy 278.696197 -74.162461) (xy 278.648591 -74.191515) (xy 278.597262 -74.213327) (xy 278.543305 -74.227433)
			(xy 278.487868 -74.233533) (xy 278.432134 -74.231496) (xy 278.377291 -74.221366) (xy 278.324507 -74.203359)
			(xy 278.274907 -74.177858) (xy 278.229549 -74.145407) (xy 278.1894 -74.106698) (xy 278.155314 -74.062555)
			(xy 278.128018 -74.01392) (xy 278.108095 -73.961829) (xy 278.095969 -73.907392) (xy 278.091898 -73.85177)
			(xy 277.839424 -73.85177) (xy 277.838915 -73.879656) (xy 277.830795 -73.934832) (xy 277.814727 -73.988239)
			(xy 277.791055 -74.038736) (xy 277.760282 -74.085249) (xy 277.723065 -74.126786) (xy 277.680197 -74.162461)
			(xy 277.632591 -74.191515) (xy 277.581262 -74.213327) (xy 277.527305 -74.227433) (xy 277.471868 -74.233533)
			(xy 277.416134 -74.231496) (xy 277.361291 -74.221366) (xy 277.308507 -74.203359) (xy 277.258907 -74.177858)
			(xy 277.213549 -74.145407) (xy 277.1734 -74.106698) (xy 277.139314 -74.062555) (xy 277.112018 -74.01392)
			(xy 277.092095 -73.961829) (xy 277.079969 -73.907392) (xy 277.075898 -73.85177) (xy 261.097814 -73.85177)
			(xy 261.050013 -73.874316) (xy 260.996354 -73.890556) (xy 260.940895 -73.898769) (xy 260.912864 -73.899268)
			(xy 260.885612 -73.89886) (xy 260.831662 -73.891098) (xy 260.779366 -73.875738) (xy 260.729788 -73.853093)
			(xy 260.683938 -73.823622) (xy 260.642747 -73.787927) (xy 260.607056 -73.746734) (xy 260.57759 -73.70088)
			(xy 260.554949 -73.6513) (xy 260.539594 -73.599003) (xy 260.531838 -73.545052) (xy 260.077119 -73.545052)
			(xy 260.098227 -73.590079) (xy 260.114295 -73.643486) (xy 260.122415 -73.698662) (xy 260.122924 -73.726548)
			(xy 260.122415 -73.754434) (xy 260.114295 -73.80961) (xy 260.098227 -73.863017) (xy 260.074555 -73.913514)
			(xy 260.043782 -73.960027) (xy 260.006565 -74.001564) (xy 259.963697 -74.037239) (xy 259.916091 -74.066293)
			(xy 259.864762 -74.088105) (xy 259.810805 -74.102211) (xy 259.755368 -74.108311) (xy 259.699634 -74.106274)
			(xy 259.644791 -74.096144) (xy 259.592007 -74.078137) (xy 259.542407 -74.052636) (xy 259.497049 -74.020185)
			(xy 259.4569 -73.981476) (xy 259.422814 -73.937333) (xy 259.395518 -73.888698) (xy 259.375595 -73.836607)
			(xy 259.363469 -73.78217) (xy 259.359398 -73.726548) (xy 256.526259 -73.726548) (xy 256.532706 -73.74059)
			(xy 256.548201 -73.793088) (xy 256.556033 -73.847262) (xy 256.55651 -73.87463) (xy 256.556059 -73.900944)
			(xy 256.548821 -73.953074) (xy 256.534498 -74.003717) (xy 256.513362 -74.051915) (xy 256.485814 -74.096758)
			(xy 256.452373 -74.137398) (xy 256.43332 -74.155554) (xy 256.425895 -74.163056) (xy 256.417384 -74.182351)
			(xy 256.41681 -74.192892) (xy 256.41681 -74.267568) (xy 256.41734 -74.278118) (xy 256.425874 -74.297413)
			(xy 256.43332 -74.304906) (xy 256.452375 -74.323062) (xy 256.485832 -74.363692) (xy 256.51339 -74.408532)
			(xy 256.534529 -74.456733) (xy 256.548846 -74.50738) (xy 256.556071 -74.559514) (xy 256.55651 -74.58583)
			(xy 256.55605 -74.613082) (xy 256.550531 -74.65145) (xy 272.621762 -74.65145) (xy 272.621762 -74.59695)
			(xy 272.629517 -74.543003) (xy 272.644871 -74.49071) (xy 272.66751 -74.441134) (xy 272.696973 -74.395283)
			(xy 272.732662 -74.354093) (xy 272.773848 -74.3184) (xy 272.819695 -74.288931) (xy 272.869269 -74.266286)
			(xy 272.92156 -74.250927) (xy 272.975506 -74.243165) (xy 273.002756 -74.242676) (xy 273.030126 -74.243149)
			(xy 273.084306 -74.250963) (xy 273.136809 -74.266449) (xy 273.186557 -74.28929) (xy 273.232523 -74.319014)
			(xy 273.253454 -74.336656) (xy 273.253708 -74.33691) (xy 273.260787 -74.342507) (xy 273.27771 -74.348747)
			(xy 273.286728 -74.349102) (xy 273.353784 -74.349102) (xy 273.3628 -74.348737) (xy 273.379717 -74.342495)
			(xy 273.386804 -74.33691) (xy 273.386804 -74.336656) (xy 273.387058 -74.336656) (xy 273.407989 -74.319016)
			(xy 273.453963 -74.289306) (xy 273.503711 -74.26647) (xy 273.556211 -74.250979) (xy 273.610387 -74.24315)
			(xy 273.637756 -74.242676) (xy 273.66501 -74.243168) (xy 273.718963 -74.25092) (xy 273.771264 -74.266271)
			(xy 273.820848 -74.28891) (xy 273.866704 -74.318376) (xy 273.907901 -74.354068) (xy 273.943598 -74.39526)
			(xy 273.973068 -74.441114) (xy 273.995713 -74.490695) (xy 274.011071 -74.542994) (xy 274.017231 -74.58583)
			(xy 281.158442 -74.58583) (xy 281.158849 -74.559514) (xy 281.166095 -74.507382) (xy 281.180425 -74.456738)
			(xy 281.201568 -74.408539) (xy 281.229125 -74.363697) (xy 281.262575 -74.32306) (xy 281.281632 -74.304906)
			(xy 281.289023 -74.297375) (xy 281.297556 -74.278103) (xy 281.298142 -74.267568) (xy 281.298142 -74.192892)
			(xy 281.297618 -74.182342) (xy 281.289078 -74.163048) (xy 281.281632 -74.155554) (xy 281.262567 -74.137408)
			(xy 281.22911 -74.096777) (xy 281.201551 -74.051935) (xy 281.180414 -74.003732) (xy 281.166099 -73.953083)
			(xy 281.158878 -73.900947) (xy 281.158442 -73.87463) (xy 281.158915 -73.84726) (xy 281.16673 -73.793081)
			(xy 281.182217 -73.740577) (xy 281.205057 -73.69083) (xy 281.234781 -73.644864) (xy 281.252422 -73.623932)
			(xy 281.252676 -73.623678) (xy 281.258287 -73.616608) (xy 281.264517 -73.599678) (xy 281.264868 -73.590658)
			(xy 281.264868 -73.523602) (xy 281.264517 -73.514584) (xy 281.258266 -73.497667) (xy 281.252676 -73.490582)
			(xy 281.252422 -73.490582) (xy 281.252422 -73.490328) (xy 281.234786 -73.469393) (xy 281.205073 -73.423422)
			(xy 281.182236 -73.373675) (xy 281.166744 -73.321175) (xy 281.158916 -73.266999) (xy 281.158442 -73.23963)
			(xy 281.158883 -73.212376) (xy 281.166638 -73.158421) (xy 281.181992 -73.10612) (xy 281.204635 -73.056537)
			(xy 281.234104 -73.010681) (xy 281.269801 -72.969487) (xy 281.310997 -72.933792) (xy 281.356854 -72.904325)
			(xy 281.406439 -72.881685) (xy 281.458741 -72.866333) (xy 281.512696 -72.858582) (xy 281.53995 -72.858122)
			(xy 281.567319 -72.858612) (xy 281.621498 -72.866423) (xy 281.674001 -72.881906) (xy 281.723748 -72.904743)
			(xy 281.769716 -72.934463) (xy 281.790648 -72.952102) (xy 281.790902 -72.952356) (xy 281.797979 -72.957956)
			(xy 281.814903 -72.964193) (xy 281.823922 -72.964548) (xy 281.890978 -72.964548) (xy 281.899995 -72.964192)
			(xy 281.916913 -72.957945) (xy 281.923998 -72.952356) (xy 281.923998 -72.952102) (xy 281.924252 -72.952102)
			(xy 281.945192 -72.934472) (xy 281.991162 -72.904759) (xy 282.040908 -72.881921) (xy 282.093407 -72.866428)
			(xy 282.147581 -72.858597) (xy 282.17495 -72.858122) (xy 282.202203 -72.858602) (xy 282.256155 -72.866353)
			(xy 282.308454 -72.881704) (xy 282.358036 -72.904343) (xy 282.403891 -72.933808) (xy 282.445085 -72.969501)
			(xy 282.48078 -73.010693) (xy 282.510247 -73.056546) (xy 282.532889 -73.106127) (xy 282.548243 -73.158426)
			(xy 282.554256 -73.20026) (xy 300.656752 -73.20026) (xy 300.657241 -73.17289) (xy 300.665051 -73.118712)
			(xy 300.680534 -73.066208) (xy 300.703371 -73.016461) (xy 300.733092 -72.970494) (xy 300.750732 -72.949562)
			(xy 300.750986 -72.949308) (xy 300.756574 -72.942222) (xy 300.76282 -72.925305) (xy 300.763178 -72.916288)
			(xy 300.763178 -72.849232) (xy 300.76281 -72.840216) (xy 300.756571 -72.823299) (xy 300.750986 -72.816212)
			(xy 300.750732 -72.816212) (xy 300.750732 -72.815958) (xy 300.733112 -72.795011) (xy 300.703396 -72.749043)
			(xy 300.680556 -72.699299) (xy 300.66506 -72.646802) (xy 300.657228 -72.592628) (xy 300.656752 -72.56526)
			(xy 300.65724 -72.53801) (xy 300.665001 -72.484064) (xy 300.68036 -72.431772) (xy 300.703002 -72.382197)
			(xy 300.732469 -72.336349) (xy 300.76816 -72.29516) (xy 300.809349 -72.259469) (xy 300.855197 -72.230002)
			(xy 300.904772 -72.20736) (xy 300.957064 -72.192001) (xy 301.01101 -72.18424) (xy 301.03826 -72.183752)
			(xy 301.06563 -72.184229) (xy 301.119809 -72.192042) (xy 301.172313 -72.207528) (xy 301.22206 -72.230368)
			(xy 301.268027 -72.260091) (xy 301.288958 -72.277732) (xy 301.289212 -72.277986) (xy 301.296292 -72.283582)
			(xy 301.313214 -72.289824) (xy 301.322232 -72.290178) (xy 301.389288 -72.290178) (xy 301.398305 -72.28982)
			(xy 301.415222 -72.283574) (xy 301.422308 -72.277986) (xy 301.422308 -72.277732) (xy 301.422562 -72.277732)
			(xy 301.443502 -72.260102) (xy 301.489472 -72.230388) (xy 301.539217 -72.20755) (xy 301.591717 -72.192057)
			(xy 301.645891 -72.184227) (xy 301.67326 -72.183752) (xy 301.699576 -72.184163) (xy 301.751708 -72.191407)
			(xy 301.802352 -72.205736) (xy 301.850551 -72.226879) (xy 301.895393 -72.254436) (xy 301.93603 -72.287885)
			(xy 301.954184 -72.306942) (xy 301.961717 -72.31433) (xy 301.980988 -72.322864) (xy 301.991522 -72.323452)
			(xy 302.066198 -72.323452) (xy 302.076751 -72.32295) (xy 302.096047 -72.314397) (xy 302.103536 -72.306942)
			(xy 302.12167 -72.287865) (xy 302.162305 -72.254412) (xy 302.207151 -72.226857) (xy 302.255356 -72.205723)
			(xy 302.306006 -72.19141) (xy 302.358143 -72.184189) (xy 302.38446 -72.183752) (xy 302.411708 -72.184315)
			(xy 302.465651 -72.192065) (xy 302.517942 -72.207413) (xy 302.567516 -72.230047) (xy 302.613365 -72.259505)
			(xy 302.654555 -72.295189) (xy 302.690247 -72.336371) (xy 302.719715 -72.382213) (xy 302.742359 -72.431783)
			(xy 302.757718 -72.48407) (xy 302.765479 -72.538012) (xy 302.765968 -72.56526) (xy 302.765486 -72.59263)
			(xy 302.757673 -72.646808) (xy 302.742188 -72.699312) (xy 302.71935 -72.749059) (xy 302.689628 -72.795026)
			(xy 302.671988 -72.815958) (xy 302.671734 -72.816212) (xy 302.666128 -72.823285) (xy 302.659895 -72.840213)
			(xy 302.659542 -72.849232) (xy 302.659542 -72.916288) (xy 302.659896 -72.925305) (xy 302.666145 -72.942223)
			(xy 302.671734 -72.949308) (xy 302.671988 -72.949308) (xy 302.671988 -72.949562) (xy 302.689621 -72.970499)
			(xy 302.719334 -73.01647) (xy 302.742171 -73.066217) (xy 302.757664 -73.118716) (xy 302.765493 -73.172891)
			(xy 302.765968 -73.20026) (xy 302.765507 -73.227514) (xy 302.757755 -73.281467) (xy 302.742402 -73.333767)
			(xy 302.719761 -73.38335) (xy 302.690294 -73.429205) (xy 302.654599 -73.470399) (xy 302.613405 -73.506094)
			(xy 302.56755 -73.535561) (xy 302.517967 -73.558202) (xy 302.465667 -73.573555) (xy 302.411714 -73.581307)
			(xy 302.38446 -73.581768) (xy 302.358145 -73.581337) (xy 302.306014 -73.574097) (xy 302.25537 -73.559771)
			(xy 302.207171 -73.538632) (xy 302.162329 -73.511079) (xy 302.121691 -73.477633) (xy 302.103536 -73.458578)
			(xy 302.096006 -73.451187) (xy 302.076732 -73.442657) (xy 302.066198 -73.442068) (xy 301.991522 -73.442068)
			(xy 301.980973 -73.442605) (xy 301.961679 -73.451136) (xy 301.954184 -73.458578) (xy 301.936025 -73.47763)
			(xy 301.895396 -73.511088) (xy 301.850557 -73.538648) (xy 301.802357 -73.559788) (xy 301.75171 -73.574105)
			(xy 301.699576 -73.58133) (xy 301.67326 -73.581768) (xy 301.645891 -73.581275) (xy 301.591712 -73.573465)
			(xy 301.539209 -73.557982) (xy 301.489462 -73.535146) (xy 301.443494 -73.505427) (xy 301.422562 -73.487788)
			(xy 301.422308 -73.487534) (xy 301.415229 -73.481937) (xy 301.398306 -73.475698) (xy 301.389288 -73.475342)
			(xy 301.322232 -73.475342) (xy 301.313216 -73.475705) (xy 301.296298 -73.481948) (xy 301.289212 -73.487534)
			(xy 301.289212 -73.487788) (xy 301.288958 -73.487788) (xy 301.268013 -73.505411) (xy 301.222044 -73.535126)
			(xy 301.1723 -73.557965) (xy 301.119802 -73.57346) (xy 301.065628 -73.581292) (xy 301.03826 -73.581768)
			(xy 301.011006 -73.581359) (xy 300.957053 -73.573596) (xy 300.904755 -73.558234) (xy 300.855175 -73.535585)
			(xy 300.809323 -73.506111) (xy 300.768132 -73.470412) (xy 300.732441 -73.429213) (xy 300.702976 -73.383355)
			(xy 300.680338 -73.33377) (xy 300.664987 -73.281468) (xy 300.657235 -73.227514) (xy 300.656752 -73.20026)
			(xy 282.554256 -73.20026) (xy 282.555997 -73.212377) (xy 282.556458 -73.23963) (xy 282.55602 -73.267001)
			(xy 282.548197 -73.321182) (xy 282.532702 -73.373686) (xy 282.509854 -73.423432) (xy 282.480122 -73.469398)
			(xy 282.462478 -73.490328) (xy 282.462224 -73.490582) (xy 282.45663 -73.497663) (xy 282.45039 -73.514584)
			(xy 282.450032 -73.523602) (xy 282.450032 -73.590658) (xy 282.450402 -73.599674) (xy 282.45664 -73.616591)
			(xy 282.462224 -73.623678) (xy 282.462478 -73.623678) (xy 282.462478 -73.623932) (xy 282.480095 -73.644882)
			(xy 282.509811 -73.690849) (xy 282.532652 -73.740592) (xy 282.548148 -73.793089) (xy 282.555981 -73.847262)
			(xy 282.55606 -73.85177) (xy 303.075846 -73.85177) (xy 303.079917 -73.796148) (xy 303.092043 -73.741711)
			(xy 303.111966 -73.68962) (xy 303.139262 -73.640985) (xy 303.173348 -73.596842) (xy 303.213497 -73.558133)
			(xy 303.258855 -73.525682) (xy 303.308455 -73.500181) (xy 303.361239 -73.482174) (xy 303.416082 -73.472044)
			(xy 303.471816 -73.470007) (xy 303.527253 -73.476107) (xy 303.58121 -73.490213) (xy 303.632539 -73.512025)
			(xy 303.680145 -73.541079) (xy 303.723013 -73.576754) (xy 303.76023 -73.618291) (xy 303.791003 -73.664804)
			(xy 303.814675 -73.715301) (xy 303.830743 -73.768708) (xy 303.838863 -73.823884) (xy 303.839372 -73.85177)
			(xy 304.091846 -73.85177) (xy 304.095917 -73.796148) (xy 304.108043 -73.741711) (xy 304.127966 -73.68962)
			(xy 304.155262 -73.640985) (xy 304.189348 -73.596842) (xy 304.229497 -73.558133) (xy 304.274855 -73.525682)
			(xy 304.324455 -73.500181) (xy 304.377239 -73.482174) (xy 304.432082 -73.472044) (xy 304.487816 -73.470007)
			(xy 304.543253 -73.476107) (xy 304.59721 -73.490213) (xy 304.648539 -73.512025) (xy 304.696145 -73.541079)
			(xy 304.739013 -73.576754) (xy 304.77623 -73.618291) (xy 304.807003 -73.664804) (xy 304.830675 -73.715301)
			(xy 304.846743 -73.768708) (xy 304.854863 -73.823884) (xy 304.855372 -73.85177) (xy 305.107846 -73.85177)
			(xy 305.111917 -73.796148) (xy 305.124043 -73.741711) (xy 305.143966 -73.68962) (xy 305.171262 -73.640985)
			(xy 305.205348 -73.596842) (xy 305.245497 -73.558133) (xy 305.290855 -73.525682) (xy 305.340455 -73.500181)
			(xy 305.393239 -73.482174) (xy 305.448082 -73.472044) (xy 305.503816 -73.470007) (xy 305.559253 -73.476107)
			(xy 305.61321 -73.490213) (xy 305.664539 -73.512025) (xy 305.712145 -73.541079) (xy 305.755013 -73.576754)
			(xy 305.79223 -73.618291) (xy 305.823003 -73.664804) (xy 305.846675 -73.715301) (xy 305.862743 -73.768708)
			(xy 305.870863 -73.823884) (xy 305.871372 -73.85177) (xy 305.870863 -73.879656) (xy 305.862743 -73.934832)
			(xy 305.846675 -73.988239) (xy 305.823003 -74.038736) (xy 305.79223 -74.085249) (xy 305.755013 -74.126786)
			(xy 305.712145 -74.162461) (xy 305.664539 -74.191515) (xy 305.61321 -74.213327) (xy 305.559253 -74.227433)
			(xy 305.503816 -74.233533) (xy 305.448082 -74.231496) (xy 305.393239 -74.221366) (xy 305.340455 -74.203359)
			(xy 305.290855 -74.177858) (xy 305.245497 -74.145407) (xy 305.205348 -74.106698) (xy 305.171262 -74.062555)
			(xy 305.143966 -74.01392) (xy 305.124043 -73.961829) (xy 305.111917 -73.907392) (xy 305.107846 -73.85177)
			(xy 304.855372 -73.85177) (xy 304.854863 -73.879656) (xy 304.846743 -73.934832) (xy 304.830675 -73.988239)
			(xy 304.807003 -74.038736) (xy 304.77623 -74.085249) (xy 304.739013 -74.126786) (xy 304.696145 -74.162461)
			(xy 304.648539 -74.191515) (xy 304.59721 -74.213327) (xy 304.543253 -74.227433) (xy 304.487816 -74.233533)
			(xy 304.432082 -74.231496) (xy 304.377239 -74.221366) (xy 304.324455 -74.203359) (xy 304.274855 -74.177858)
			(xy 304.229497 -74.145407) (xy 304.189348 -74.106698) (xy 304.155262 -74.062555) (xy 304.127966 -74.01392)
			(xy 304.108043 -73.961829) (xy 304.095917 -73.907392) (xy 304.091846 -73.85177) (xy 303.839372 -73.85177)
			(xy 303.838863 -73.879656) (xy 303.830743 -73.934832) (xy 303.814675 -73.988239) (xy 303.791003 -74.038736)
			(xy 303.76023 -74.085249) (xy 303.723013 -74.126786) (xy 303.680145 -74.162461) (xy 303.632539 -74.191515)
			(xy 303.58121 -74.213327) (xy 303.527253 -74.227433) (xy 303.471816 -74.233533) (xy 303.416082 -74.231496)
			(xy 303.361239 -74.221366) (xy 303.308455 -74.203359) (xy 303.258855 -74.177858) (xy 303.213497 -74.145407)
			(xy 303.173348 -74.106698) (xy 303.139262 -74.062555) (xy 303.111966 -74.01392) (xy 303.092043 -73.961829)
			(xy 303.079917 -73.907392) (xy 303.075846 -73.85177) (xy 282.55606 -73.85177) (xy 282.556458 -73.87463)
			(xy 282.556024 -73.900945) (xy 282.548784 -73.953076) (xy 282.534459 -74.00372) (xy 282.513321 -74.051919)
			(xy 282.485768 -74.096761) (xy 282.452323 -74.137399) (xy 282.433268 -74.155554) (xy 282.425851 -74.163063)
			(xy 282.417333 -74.182352) (xy 282.416758 -74.192892) (xy 282.416758 -74.267568) (xy 282.417303 -74.278116)
			(xy 282.425828 -74.29741) (xy 282.433268 -74.304906) (xy 282.452313 -74.323072) (xy 282.485773 -74.363699)
			(xy 282.513334 -74.408537) (xy 282.534474 -74.456735) (xy 282.548793 -74.507381) (xy 282.556019 -74.559514)
			(xy 282.556458 -74.58583) (xy 282.556073 -74.613086) (xy 282.550553 -74.651454) (xy 298.621639 -74.651454)
			(xy 298.621639 -74.596946) (xy 298.629396 -74.542992) (xy 298.644753 -74.490692) (xy 298.667397 -74.441109)
			(xy 298.696867 -74.395254) (xy 298.732562 -74.354059) (xy 298.773757 -74.318364) (xy 298.819613 -74.288895)
			(xy 298.869196 -74.266252) (xy 298.921496 -74.250895) (xy 298.97545 -74.243139) (xy 299.002704 -74.242676)
			(xy 299.030075 -74.243121) (xy 299.084256 -74.250941) (xy 299.13676 -74.266434) (xy 299.186507 -74.289281)
			(xy 299.232472 -74.319012) (xy 299.253402 -74.336656) (xy 299.253656 -74.33691) (xy 299.26075 -74.342485)
			(xy 299.277661 -74.348739) (xy 299.286676 -74.349102) (xy 299.353732 -74.349102) (xy 299.36275 -74.34876)
			(xy 299.379667 -74.342502) (xy 299.386752 -74.33691) (xy 299.386752 -74.336656) (xy 299.387006 -74.336656)
			(xy 299.407919 -74.318993) (xy 299.453898 -74.289286) (xy 299.50365 -74.266456) (xy 299.556155 -74.25097)
			(xy 299.610334 -74.243147) (xy 299.637704 -74.242676) (xy 299.664954 -74.243195) (xy 299.718899 -74.250951)
			(xy 299.771191 -74.266306) (xy 299.820765 -74.288946) (xy 299.866613 -74.318411) (xy 299.907801 -74.354101)
			(xy 299.943491 -74.39529) (xy 299.972956 -74.441138) (xy 299.995595 -74.490713) (xy 300.01095 -74.543005)
			(xy 300.017107 -74.58583) (xy 307.15839 -74.58583) (xy 307.158814 -74.559515) (xy 307.166058 -74.507384)
			(xy 307.180386 -74.456741) (xy 307.201527 -74.408542) (xy 307.22908 -74.3637) (xy 307.262525 -74.323062)
			(xy 307.28158 -74.304906) (xy 307.288978 -74.297381) (xy 307.297505 -74.278104) (xy 307.29809 -74.267568)
			(xy 307.29809 -74.192892) (xy 307.297581 -74.18234) (xy 307.289032 -74.163045) (xy 307.28158 -74.155554)
			(xy 307.262505 -74.137418) (xy 307.229051 -74.096783) (xy 307.201495 -74.051939) (xy 307.18036 -74.003734)
			(xy 307.166046 -73.953084) (xy 307.158826 -73.900947) (xy 307.15839 -73.87463) (xy 307.158876 -73.847261)
			(xy 307.166689 -73.793082) (xy 307.182174 -73.74058) (xy 307.205011 -73.690832) (xy 307.234731 -73.644865)
			(xy 307.25237 -73.623932) (xy 307.252624 -73.623678) (xy 307.258229 -73.616604) (xy 307.264464 -73.599677)
			(xy 307.264816 -73.590658) (xy 307.264816 -73.523602) (xy 307.264454 -73.514586) (xy 307.25821 -73.497669)
			(xy 307.252624 -73.490582) (xy 307.25237 -73.490582) (xy 307.25237 -73.490328) (xy 307.234726 -73.4694)
			(xy 307.205016 -73.423426) (xy 307.182181 -73.373677) (xy 307.166691 -73.321176) (xy 307.158864 -73.266999)
			(xy 307.15839 -73.23963) (xy 307.158883 -73.212378) (xy 307.166636 -73.158428) (xy 307.181988 -73.106131)
			(xy 307.204627 -73.056551) (xy 307.234092 -73.010698) (xy 307.269782 -72.969505) (xy 307.310972 -72.933811)
			(xy 307.356823 -72.904342) (xy 307.406401 -72.881699) (xy 307.458697 -72.866343) (xy 307.512646 -72.858585)
			(xy 307.539898 -72.858122) (xy 307.567268 -72.858584) (xy 307.621448 -72.866402) (xy 307.673951 -72.881892)
			(xy 307.723698 -72.904734) (xy 307.769665 -72.93446) (xy 307.790596 -72.952102) (xy 307.79085 -72.952356)
			(xy 307.797942 -72.957934) (xy 307.814855 -72.964185) (xy 307.82387 -72.964548) (xy 307.890926 -72.964548)
			(xy 307.899946 -72.964215) (xy 307.916863 -72.957952) (xy 307.923946 -72.952356) (xy 307.923946 -72.952102)
			(xy 307.9242 -72.952102) (xy 307.945121 -72.93445) (xy 307.991097 -72.90474) (xy 308.040847 -72.881906)
			(xy 308.09335 -72.866418) (xy 308.147528 -72.858594) (xy 308.174898 -72.858122) (xy 308.202152 -72.858557)
			(xy 308.256106 -72.866315) (xy 308.308406 -72.881672) (xy 308.357988 -72.904317) (xy 308.403843 -72.933787)
			(xy 308.445036 -72.969484) (xy 308.48073 -73.01068) (xy 308.510197 -73.056537) (xy 308.532838 -73.10612)
			(xy 308.548191 -73.158422) (xy 308.554204 -73.20026) (xy 326.6567 -73.20026) (xy 326.657201 -73.172891)
			(xy 326.665011 -73.118713) (xy 326.680491 -73.066211) (xy 326.703325 -73.016463) (xy 326.733042 -72.970495)
			(xy 326.75068 -72.949562) (xy 326.750934 -72.949308) (xy 326.756527 -72.942226) (xy 326.762769 -72.925306)
			(xy 326.763126 -72.916288) (xy 326.763126 -72.849232) (xy 326.762748 -72.840217) (xy 326.756514 -72.823301)
			(xy 326.750934 -72.816212) (xy 326.75068 -72.816212) (xy 326.75068 -72.815958) (xy 326.733052 -72.795017)
			(xy 326.703339 -72.749047) (xy 326.680501 -72.699301) (xy 326.665007 -72.646803) (xy 326.657176 -72.592629)
			(xy 326.6567 -72.56526) (xy 326.657141 -72.538007) (xy 326.664903 -72.484058) (xy 326.680263 -72.431762)
			(xy 326.70291 -72.382184) (xy 326.732381 -72.336333) (xy 326.768077 -72.295143) (xy 326.809272 -72.259452)
			(xy 326.855126 -72.229987) (xy 326.904707 -72.207347) (xy 326.957005 -72.191993) (xy 327.010955 -72.184237)
			(xy 327.038208 -72.183752) (xy 327.065579 -72.184201) (xy 327.119759 -72.192021) (xy 327.172263 -72.207513)
			(xy 327.22201 -72.230359) (xy 327.267975 -72.260088) (xy 327.288906 -72.277732) (xy 327.28916 -72.277986)
			(xy 327.296255 -72.28356) (xy 327.313165 -72.289815) (xy 327.32218 -72.290178) (xy 327.389236 -72.290178)
			(xy 327.398255 -72.289843) (xy 327.415172 -72.283581) (xy 327.422256 -72.277986) (xy 327.422256 -72.277732)
			(xy 327.42251 -72.277732) (xy 327.443432 -72.26008) (xy 327.489407 -72.230369) (xy 327.539157 -72.207535)
			(xy 327.59166 -72.192047) (xy 327.645838 -72.184223) (xy 327.673208 -72.183752) (xy 327.699523 -72.184197)
			(xy 327.751653 -72.191434) (xy 327.802297 -72.205757) (xy 327.850496 -72.226893) (xy 327.895339 -72.254444)
			(xy 327.935977 -72.287888) (xy 327.954132 -72.306942) (xy 327.961648 -72.314351) (xy 327.980932 -72.322873)
			(xy 327.99147 -72.323452) (xy 328.066146 -72.323452) (xy 328.076696 -72.322921) (xy 328.095992 -72.314389)
			(xy 328.103484 -72.306942) (xy 328.121643 -72.28789) (xy 328.162273 -72.254435) (xy 328.207113 -72.226877)
			(xy 328.255313 -72.205738) (xy 328.305959 -72.191419) (xy 328.358092 -72.184192) (xy 328.384408 -72.183752)
			(xy 328.411658 -72.18427) (xy 328.465602 -72.192027) (xy 328.517894 -72.207381) (xy 328.567468 -72.23002)
			(xy 328.613317 -72.259483) (xy 328.654506 -72.295171) (xy 328.690197 -72.336358) (xy 328.719665 -72.382203)
			(xy 328.742308 -72.431776) (xy 328.757666 -72.484067) (xy 328.765427 -72.53801) (xy 328.765916 -72.56526)
			(xy 328.765447 -72.59263) (xy 328.757633 -72.64681) (xy 328.742146 -72.699314) (xy 328.719304 -72.749061)
			(xy 328.689578 -72.795027) (xy 328.671936 -72.815958) (xy 328.671682 -72.816212) (xy 328.666082 -72.823289)
			(xy 328.659844 -72.840213) (xy 328.65949 -72.849232) (xy 328.65949 -72.916288) (xy 328.659855 -72.925304)
			(xy 328.666097 -72.942221) (xy 328.671682 -72.949308) (xy 328.671936 -72.949308) (xy 328.671936 -72.949562)
			(xy 328.689576 -72.970493) (xy 328.719287 -73.016467) (xy 328.742122 -73.066214) (xy 328.757613 -73.118715)
			(xy 328.765441 -73.172891) (xy 328.765916 -73.20026) (xy 328.765408 -73.227512) (xy 328.757656 -73.28146)
			(xy 328.742306 -73.333757) (xy 328.719668 -73.383336) (xy 328.690205 -73.429189) (xy 328.654516 -73.470382)
			(xy 328.613328 -73.506076) (xy 328.567479 -73.535545) (xy 328.517902 -73.558189) (xy 328.465607 -73.573546)
			(xy 328.411659 -73.581304) (xy 328.384408 -73.581768) (xy 328.358094 -73.581305) (xy 328.305965 -73.574071)
			(xy 328.255321 -73.559752) (xy 328.207122 -73.538618) (xy 328.162279 -73.511071) (xy 328.12164 -73.477631)
			(xy 328.103484 -73.458578) (xy 328.095973 -73.451164) (xy 328.076685 -73.442647) (xy 328.066146 -73.442068)
			(xy 327.99147 -73.442068) (xy 327.980924 -73.442631) (xy 327.961629 -73.451143) (xy 327.954132 -73.458578)
			(xy 327.935998 -73.477655) (xy 327.895364 -73.511111) (xy 327.85052 -73.538668) (xy 327.802314 -73.559803)
			(xy 327.751663 -73.574115) (xy 327.699525 -73.581333) (xy 327.673208 -73.581768) (xy 327.645838 -73.581305)
			(xy 327.591658 -73.573488) (xy 327.539155 -73.557998) (xy 327.489408 -73.535156) (xy 327.443441 -73.50543)
			(xy 327.42251 -73.487788) (xy 327.422256 -73.487534) (xy 327.415163 -73.481957) (xy 327.398251 -73.475706)
			(xy 327.389236 -73.475342) (xy 327.32218 -73.475342) (xy 327.313161 -73.47568) (xy 327.296244 -73.48194)
			(xy 327.28916 -73.487534) (xy 327.28916 -73.487788) (xy 327.288906 -73.487788) (xy 327.267981 -73.505436)
			(xy 327.222006 -73.535147) (xy 327.172257 -73.557981) (xy 327.119755 -73.57347) (xy 327.065578 -73.581296)
			(xy 327.038208 -73.581768) (xy 327.010954 -73.581337) (xy 326.956999 -73.57358) (xy 326.904698 -73.558223)
			(xy 326.855116 -73.535579) (xy 326.809261 -73.506108) (xy 326.768067 -73.470411) (xy 326.732373 -73.429214)
			(xy 326.702906 -73.383356) (xy 326.680266 -73.333772) (xy 326.664913 -73.281469) (xy 326.657161 -73.227515)
			(xy 326.6567 -73.20026) (xy 308.554204 -73.20026) (xy 308.555945 -73.212376) (xy 308.556406 -73.23963)
			(xy 308.555956 -73.267001) (xy 308.548134 -73.321181) (xy 308.532641 -73.373684) (xy 308.509796 -73.42343)
			(xy 308.480068 -73.469397) (xy 308.462426 -73.490328) (xy 308.462172 -73.490582) (xy 308.456584 -73.497667)
			(xy 308.450339 -73.514585) (xy 308.44998 -73.523602) (xy 308.44998 -73.590658) (xy 308.450361 -73.599672)
			(xy 308.456592 -73.616589) (xy 308.462172 -73.623678) (xy 308.462426 -73.623678) (xy 308.462426 -73.623932)
			(xy 308.480051 -73.644876) (xy 308.509764 -73.690846) (xy 308.532602 -73.74059) (xy 308.548097 -73.793088)
			(xy 308.555929 -73.847262) (xy 308.556008 -73.85177) (xy 329.075794 -73.85177) (xy 329.079865 -73.796148)
			(xy 329.091991 -73.741711) (xy 329.111914 -73.68962) (xy 329.13921 -73.640985) (xy 329.173296 -73.596842)
			(xy 329.213445 -73.558133) (xy 329.258803 -73.525682) (xy 329.308403 -73.500181) (xy 329.361187 -73.482174)
			(xy 329.41603 -73.472044) (xy 329.471764 -73.470007) (xy 329.527201 -73.476107) (xy 329.581158 -73.490213)
			(xy 329.632487 -73.512025) (xy 329.680093 -73.541079) (xy 329.722961 -73.576754) (xy 329.760178 -73.618291)
			(xy 329.790951 -73.664804) (xy 329.814623 -73.715301) (xy 329.830691 -73.768708) (xy 329.838811 -73.823884)
			(xy 329.83932 -73.85177) (xy 330.091794 -73.85177) (xy 330.095865 -73.796148) (xy 330.107991 -73.741711)
			(xy 330.127914 -73.68962) (xy 330.15521 -73.640985) (xy 330.189296 -73.596842) (xy 330.229445 -73.558133)
			(xy 330.274803 -73.525682) (xy 330.324403 -73.500181) (xy 330.377187 -73.482174) (xy 330.43203 -73.472044)
			(xy 330.487764 -73.470007) (xy 330.543201 -73.476107) (xy 330.597158 -73.490213) (xy 330.648487 -73.512025)
			(xy 330.696093 -73.541079) (xy 330.738961 -73.576754) (xy 330.776178 -73.618291) (xy 330.806951 -73.664804)
			(xy 330.830623 -73.715301) (xy 330.846691 -73.768708) (xy 330.854811 -73.823884) (xy 330.85532 -73.85177)
			(xy 331.107794 -73.85177) (xy 331.111865 -73.796148) (xy 331.123991 -73.741711) (xy 331.143914 -73.68962)
			(xy 331.17121 -73.640985) (xy 331.205296 -73.596842) (xy 331.245445 -73.558133) (xy 331.290803 -73.525682)
			(xy 331.340403 -73.500181) (xy 331.393187 -73.482174) (xy 331.44803 -73.472044) (xy 331.503764 -73.470007)
			(xy 331.559201 -73.476107) (xy 331.613158 -73.490213) (xy 331.664487 -73.512025) (xy 331.712093 -73.541079)
			(xy 331.754961 -73.576754) (xy 331.792178 -73.618291) (xy 331.822951 -73.664804) (xy 331.846623 -73.715301)
			(xy 331.862691 -73.768708) (xy 331.870811 -73.823884) (xy 331.87132 -73.85177) (xy 331.870811 -73.879656)
			(xy 331.862691 -73.934832) (xy 331.846623 -73.988239) (xy 331.822951 -74.038736) (xy 331.792178 -74.085249)
			(xy 331.754961 -74.126786) (xy 331.712093 -74.162461) (xy 331.664487 -74.191515) (xy 331.613158 -74.213327)
			(xy 331.559201 -74.227433) (xy 331.503764 -74.233533) (xy 331.44803 -74.231496) (xy 331.393187 -74.221366)
			(xy 331.340403 -74.203359) (xy 331.290803 -74.177858) (xy 331.245445 -74.145407) (xy 331.205296 -74.106698)
			(xy 331.17121 -74.062555) (xy 331.143914 -74.01392) (xy 331.123991 -73.961829) (xy 331.111865 -73.907392)
			(xy 331.107794 -73.85177) (xy 330.85532 -73.85177) (xy 330.854811 -73.879656) (xy 330.846691 -73.934832)
			(xy 330.830623 -73.988239) (xy 330.806951 -74.038736) (xy 330.776178 -74.085249) (xy 330.738961 -74.126786)
			(xy 330.696093 -74.162461) (xy 330.648487 -74.191515) (xy 330.597158 -74.213327) (xy 330.543201 -74.227433)
			(xy 330.487764 -74.233533) (xy 330.43203 -74.231496) (xy 330.377187 -74.221366) (xy 330.324403 -74.203359)
			(xy 330.274803 -74.177858) (xy 330.229445 -74.145407) (xy 330.189296 -74.106698) (xy 330.15521 -74.062555)
			(xy 330.127914 -74.01392) (xy 330.107991 -73.961829) (xy 330.095865 -73.907392) (xy 330.091794 -73.85177)
			(xy 329.83932 -73.85177) (xy 329.838811 -73.879656) (xy 329.830691 -73.934832) (xy 329.814623 -73.988239)
			(xy 329.790951 -74.038736) (xy 329.760178 -74.085249) (xy 329.722961 -74.126786) (xy 329.680093 -74.162461)
			(xy 329.632487 -74.191515) (xy 329.581158 -74.213327) (xy 329.527201 -74.227433) (xy 329.471764 -74.233533)
			(xy 329.41603 -74.231496) (xy 329.361187 -74.221366) (xy 329.308403 -74.203359) (xy 329.258803 -74.177858)
			(xy 329.213445 -74.145407) (xy 329.173296 -74.106698) (xy 329.13921 -74.062555) (xy 329.111914 -74.01392)
			(xy 329.091991 -73.961829) (xy 329.079865 -73.907392) (xy 329.075794 -73.85177) (xy 308.556008 -73.85177)
			(xy 308.556406 -73.87463) (xy 308.555957 -73.900945) (xy 308.548718 -73.953074) (xy 308.534395 -74.003717)
			(xy 308.513259 -74.051916) (xy 308.48571 -74.096759) (xy 308.452269 -74.137398) (xy 308.433216 -74.155554)
			(xy 308.425791 -74.163056) (xy 308.417279 -74.182351) (xy 308.416706 -74.192892) (xy 308.416706 -74.267568)
			(xy 308.417237 -74.278118) (xy 308.425771 -74.297413) (xy 308.433216 -74.304906) (xy 308.452271 -74.323063)
			(xy 308.485727 -74.363692) (xy 308.513286 -74.408533) (xy 308.534424 -74.456733) (xy 308.548742 -74.50738)
			(xy 308.555967 -74.559514) (xy 308.556406 -74.58583) (xy 308.55595 -74.613082) (xy 308.55043 -74.65145)
			(xy 324.621662 -74.65145) (xy 324.621662 -74.59695) (xy 324.629417 -74.543004) (xy 324.644771 -74.490711)
			(xy 324.667409 -74.441135) (xy 324.696872 -74.395285) (xy 324.73256 -74.354094) (xy 324.773746 -74.318401)
			(xy 324.819593 -74.288932) (xy 324.869166 -74.266287) (xy 324.921457 -74.250927) (xy 324.975402 -74.243165)
			(xy 325.002652 -74.242676) (xy 325.030022 -74.243152) (xy 325.084202 -74.250964) (xy 325.136705 -74.26645)
			(xy 325.186452 -74.28929) (xy 325.232419 -74.319014) (xy 325.25335 -74.336656) (xy 325.253604 -74.33691)
			(xy 325.260684 -74.342505) (xy 325.277606 -74.348747) (xy 325.286624 -74.349102) (xy 325.35368 -74.349102)
			(xy 325.362696 -74.348735) (xy 325.379613 -74.342494) (xy 325.3867 -74.33691) (xy 325.3867 -74.336656)
			(xy 325.386954 -74.336656) (xy 325.407887 -74.319018) (xy 325.45386 -74.289307) (xy 325.503607 -74.266472)
			(xy 325.556108 -74.25098) (xy 325.610283 -74.243151) (xy 325.637652 -74.242676) (xy 325.664906 -74.243168)
			(xy 325.71886 -74.250919) (xy 325.771161 -74.26627) (xy 325.820745 -74.288909) (xy 325.866603 -74.318375)
			(xy 325.907799 -74.354067) (xy 325.943497 -74.395259) (xy 325.972968 -74.441113) (xy 325.995613 -74.490694)
			(xy 326.010971 -74.542993) (xy 326.018729 -74.596946) (xy 326.018729 -74.651454) (xy 326.010971 -74.705407)
			(xy 325.995613 -74.757706) (xy 325.972968 -74.807287) (xy 325.943497 -74.853141) (xy 325.907799 -74.894333)
			(xy 325.866603 -74.930025) (xy 325.820745 -74.959491) (xy 325.771161 -74.98213) (xy 325.71886 -74.997481)
			(xy 325.664906 -75.005232) (xy 325.637652 -75.005692) (xy 325.610283 -75.005197) (xy 325.556105 -74.997387)
			(xy 325.503602 -74.981904) (xy 325.453855 -74.959069) (xy 325.407887 -74.92935) (xy 325.386954 -74.911712)
			(xy 325.3867 -74.911458) (xy 325.379621 -74.90586) (xy 325.362698 -74.899621) (xy 325.35368 -74.899266)
			(xy 325.286624 -74.899266) (xy 325.277609 -74.899642) (xy 325.260693 -74.905877) (xy 325.253604 -74.911458)
			(xy 325.253604 -74.911712) (xy 325.25335 -74.911712) (xy 325.232411 -74.929343) (xy 325.18644 -74.959056)
			(xy 325.136694 -74.981893) (xy 325.084195 -74.997386) (xy 325.030021 -75.005217) (xy 325.002652 -75.005692)
			(xy 324.975402 -75.005235) (xy 324.921457 -74.997473) (xy 324.869166 -74.982113) (xy 324.819593 -74.959468)
			(xy 324.773746 -74.929999) (xy 324.73256 -74.894306) (xy 324.696872 -74.853115) (xy 324.667409 -74.807265)
			(xy 324.644771 -74.757689) (xy 324.629417 -74.705396) (xy 324.621662 -74.65145) (xy 308.55043 -74.65145)
			(xy 308.548189 -74.667031) (xy 308.53283 -74.719326) (xy 308.510186 -74.768904) (xy 308.480716 -74.814754)
			(xy 308.445021 -74.855944) (xy 308.403829 -74.891635) (xy 308.357976 -74.921101) (xy 308.308396 -74.943742)
			(xy 308.2561 -74.959096) (xy 308.20215 -74.966852) (xy 308.174898 -74.967338) (xy 308.147527 -74.966888)
			(xy 308.093347 -74.959069) (xy 308.040843 -74.943577) (xy 307.991096 -74.920731) (xy 307.945131 -74.891002)
			(xy 307.9242 -74.873358) (xy 307.923946 -74.873104) (xy 307.91685 -74.867531) (xy 307.899941 -74.861276)
			(xy 307.890926 -74.860912) (xy 307.82387 -74.860912) (xy 307.814851 -74.861252) (xy 307.797934 -74.867511)
			(xy 307.79085 -74.873104) (xy 307.79085 -74.873358) (xy 307.790596 -74.873358) (xy 307.769671 -74.891006)
			(xy 307.723697 -74.920718) (xy 307.673948 -74.943553) (xy 307.621445 -74.959042) (xy 307.567268 -74.966866)
			(xy 307.539898 -74.967338) (xy 307.512648 -74.966824) (xy 307.458703 -74.959068) (xy 307.406411 -74.943714)
			(xy 307.356835 -74.921075) (xy 307.310986 -74.891611) (xy 307.269797 -74.855923) (xy 307.234105 -74.814736)
			(xy 307.204638 -74.768889) (xy 307.181995 -74.719316) (xy 307.166638 -74.667024) (xy 307.158878 -74.61308)
			(xy 307.15839 -74.58583) (xy 300.017107 -74.58583) (xy 300.018706 -74.59695) (xy 300.018706 -74.65145)
			(xy 300.01095 -74.705395) (xy 299.995595 -74.757687) (xy 299.972956 -74.807262) (xy 299.943491 -74.85311)
			(xy 299.907801 -74.894299) (xy 299.866613 -74.929989) (xy 299.820765 -74.959454) (xy 299.771191 -74.982094)
			(xy 299.718899 -74.997449) (xy 299.664954 -75.005205) (xy 299.637704 -75.005692) (xy 299.610334 -75.005226)
			(xy 299.556155 -74.997408) (xy 299.503651 -74.981919) (xy 299.453905 -74.959078) (xy 299.407938 -74.929353)
			(xy 299.387006 -74.911712) (xy 299.386752 -74.911458) (xy 299.379658 -74.905882) (xy 299.362747 -74.89963)
			(xy 299.353732 -74.899266) (xy 299.286676 -74.899266) (xy 299.277659 -74.899619) (xy 299.260742 -74.90587)
			(xy 299.253656 -74.911458) (xy 299.253656 -74.911712) (xy 299.253402 -74.911712) (xy 299.232482 -74.929365)
			(xy 299.186505 -74.959075) (xy 299.136755 -74.981908) (xy 299.084252 -74.997395) (xy 299.030074 -75.00522)
			(xy 299.002704 -75.005692) (xy 298.97545 -75.005261) (xy 298.921496 -74.997505) (xy 298.869196 -74.982148)
			(xy 298.819613 -74.959505) (xy 298.773757 -74.930036) (xy 298.732562 -74.894341) (xy 298.696867 -74.853146)
			(xy 298.667397 -74.807291) (xy 298.644753 -74.757708) (xy 298.629396 -74.705408) (xy 298.621639 -74.651454)
			(xy 282.550553 -74.651454) (xy 282.548311 -74.667042) (xy 282.532948 -74.719345) (xy 282.510298 -74.768928)
			(xy 282.480823 -74.814784) (xy 282.445121 -74.855977) (xy 282.40392 -74.891671) (xy 282.358058 -74.921137)
			(xy 282.30847 -74.943776) (xy 282.256164 -74.959128) (xy 282.202206 -74.966879) (xy 282.17495 -74.967338)
			(xy 282.14758 -74.966858) (xy 282.093401 -74.959046) (xy 282.040897 -74.943561) (xy 281.99115 -74.920722)
			(xy 281.945183 -74.890999) (xy 281.924252 -74.873358) (xy 281.923998 -74.873104) (xy 281.916916 -74.867511)
			(xy 281.899996 -74.861268) (xy 281.890978 -74.860912) (xy 281.823922 -74.860912) (xy 281.814906 -74.861277)
			(xy 281.797989 -74.867519) (xy 281.790902 -74.873104) (xy 281.790902 -74.873358) (xy 281.790648 -74.873358)
			(xy 281.769703 -74.890982) (xy 281.723735 -74.920697) (xy 281.67399 -74.943537) (xy 281.621492 -74.959031)
			(xy 281.567318 -74.966863) (xy 281.53995 -74.967338) (xy 281.5127 -74.966798) (xy 281.458753 -74.959049)
			(xy 281.406459 -74.943701) (xy 281.356881 -74.921066) (xy 281.311029 -74.891606) (xy 281.269836 -74.85592)
			(xy 281.234142 -74.814735) (xy 281.204672 -74.76889) (xy 281.182027 -74.719317) (xy 281.166668 -74.667025)
			(xy 281.158907 -74.61308) (xy 281.158442 -74.58583) (xy 274.017231 -74.58583) (xy 274.018829 -74.596946)
			(xy 274.018829 -74.651454) (xy 274.011071 -74.705406) (xy 273.995713 -74.757705) (xy 273.973068 -74.807286)
			(xy 273.943598 -74.85314) (xy 273.907901 -74.894332) (xy 273.866704 -74.930024) (xy 273.820848 -74.95949)
			(xy 273.771264 -74.982129) (xy 273.718963 -74.99748) (xy 273.66501 -75.005232) (xy 273.637756 -75.005692)
			(xy 273.610387 -75.005195) (xy 273.556209 -74.997385) (xy 273.503706 -74.981903) (xy 273.453959 -74.959068)
			(xy 273.407991 -74.92935) (xy 273.387058 -74.911712) (xy 273.386804 -74.911458) (xy 273.379724 -74.905862)
			(xy 273.362802 -74.899622) (xy 273.353784 -74.899266) (xy 273.286728 -74.899266) (xy 273.277713 -74.899644)
			(xy 273.260797 -74.905878) (xy 273.253708 -74.911458) (xy 273.253708 -74.911712) (xy 273.253454 -74.911712)
			(xy 273.232514 -74.929341) (xy 273.186543 -74.959054) (xy 273.136798 -74.981892) (xy 273.084299 -74.997385)
			(xy 273.030125 -75.005216) (xy 273.002756 -75.005692) (xy 272.975506 -75.005235) (xy 272.92156 -74.997473)
			(xy 272.869269 -74.982114) (xy 272.819695 -74.959469) (xy 272.773848 -74.93) (xy 272.732661 -74.894307)
			(xy 272.696973 -74.853117) (xy 272.66751 -74.807266) (xy 272.644871 -74.75769) (xy 272.629517 -74.705397)
			(xy 272.621762 -74.65145) (xy 256.550531 -74.65145) (xy 256.54829 -74.66703) (xy 256.532931 -74.719326)
			(xy 256.510286 -74.768903) (xy 256.480817 -74.814753) (xy 256.445123 -74.855943) (xy 256.40393 -74.891634)
			(xy 256.358078 -74.9211) (xy 256.308499 -74.943741) (xy 256.256203 -74.959096) (xy 256.202254 -74.966852)
			(xy 256.175002 -74.967338) (xy 256.147631 -74.966886) (xy 256.093451 -74.959067) (xy 256.040947 -74.943576)
			(xy 255.9912 -74.92073) (xy 255.945235 -74.891002) (xy 255.924304 -74.873358) (xy 255.92405 -74.873104)
			(xy 255.916953 -74.867533) (xy 255.900044 -74.861277) (xy 255.89103 -74.860912) (xy 255.823974 -74.860912)
			(xy 255.814956 -74.861254) (xy 255.798039 -74.867512) (xy 255.790954 -74.873104) (xy 255.790954 -74.873358)
			(xy 255.7907 -74.873358) (xy 255.769773 -74.891004) (xy 255.7238 -74.920716) (xy 255.674051 -74.943552)
			(xy 255.621549 -74.959041) (xy 255.567372 -74.966866) (xy 255.540002 -74.967338) (xy 255.512752 -74.96682)
			(xy 255.458807 -74.959065) (xy 255.406515 -74.943712) (xy 255.35694 -74.921073) (xy 255.311091 -74.89161)
			(xy 255.269901 -74.855922) (xy 255.23421 -74.814735) (xy 255.204742 -74.768889) (xy 255.1821 -74.719315)
			(xy 255.166742 -74.667024) (xy 255.158982 -74.61308) (xy 255.158494 -74.58583) (xy 253.111508 -74.58583)
			(xy 253.111508 -76.091288) (xy 253.111981 -76.101159) (xy 253.119443 -76.119439) (xy 253.125986 -76.126848)
			(xy 253.631192 -76.632054) (xy 253.6317 -76.632562) (xy 253.639084 -76.639136) (xy 253.657383 -76.646568)
			(xy 253.66726 -76.64704) (xy 254.780034 -76.64704) (xy 254.78882 -76.646665) (xy 254.805352 -76.640704)
			(xy 254.818889 -76.629498) (xy 254.823722 -76.622148) (xy 254.824484 -76.621132) (xy 254.866648 -76.540614)
			(xy 254.86979 -76.534223) (xy 254.872752 -76.520299) (xy 254.87249 -76.513182) (xy 254.871982 -76.505816)
			(xy 254.86741 -76.492862) (xy 254.861822 -76.484226) (xy 254.861568 -76.483718) (xy 254.846096 -76.459974)
			(xy 254.821583 -76.408879) (xy 254.804891 -76.354722) (xy 254.796388 -76.298692) (xy 254.795782 -76.270358)
			(xy 254.795782 -76.270104) (xy 254.796268 -76.242853) (xy 254.804024 -76.188905) (xy 254.819379 -76.13661)
			(xy 254.842021 -76.087033) (xy 254.871487 -76.041183) (xy 254.907178 -75.999992) (xy 254.948369 -75.964301)
			(xy 254.994219 -75.934835) (xy 255.043796 -75.912193) (xy 255.096091 -75.896838) (xy 255.150039 -75.889082)
			(xy 255.204541 -75.889082) (xy 255.258489 -75.896838) (xy 255.310784 -75.912193) (xy 255.360361 -75.934835)
			(xy 255.406211 -75.964301) (xy 255.447402 -75.999992) (xy 255.483093 -76.041183) (xy 255.512559 -76.087033)
			(xy 255.535201 -76.13661) (xy 255.550556 -76.188905) (xy 255.558312 -76.242853) (xy 255.558798 -76.270104)
			(xy 255.558798 -76.270358) (xy 255.558223 -76.298694) (xy 255.549721 -76.354726) (xy 255.533016 -76.408882)
			(xy 255.508478 -76.459968) (xy 255.493012 -76.483718) (xy 255.492758 -76.484226) (xy 255.48717 -76.492862)
			(xy 255.485392 -76.498196) (xy 255.48209 -76.515976) (xy 255.48209 -76.529692) (xy 255.529334 -76.619862)
			(xy 255.533983 -76.627843) (xy 255.547806 -76.640073) (xy 255.565064 -76.646613) (xy 255.574292 -76.64704)
			(xy 255.796034 -76.64704) (xy 255.80482 -76.646665) (xy 255.821352 -76.640704) (xy 255.834889 -76.629498)
			(xy 255.839722 -76.622148) (xy 255.840484 -76.621132) (xy 255.882648 -76.540614) (xy 255.88579 -76.534223)
			(xy 255.888752 -76.520299) (xy 255.88849 -76.513182) (xy 255.887982 -76.505816) (xy 255.88341 -76.492862)
			(xy 255.877822 -76.484226) (xy 255.877568 -76.483718) (xy 255.862096 -76.459974) (xy 255.837583 -76.408879)
			(xy 255.820891 -76.354722) (xy 255.812388 -76.298692) (xy 255.811782 -76.270358) (xy 255.811782 -76.270104)
			(xy 255.812268 -76.242853) (xy 255.820024 -76.188905) (xy 255.835379 -76.13661) (xy 255.858021 -76.087033)
			(xy 255.887487 -76.041183) (xy 255.923178 -75.999992) (xy 255.964369 -75.964301) (xy 256.010219 -75.934835)
			(xy 256.059796 -75.912193) (xy 256.112091 -75.896838) (xy 256.166039 -75.889082) (xy 256.220541 -75.889082)
			(xy 256.243662 -75.892406) (xy 262.02894 -75.892406) (xy 262.029351 -75.866468) (xy 262.03638 -75.815071)
			(xy 262.050309 -75.7651) (xy 262.070881 -75.717478) (xy 262.097717 -75.673083) (xy 262.130321 -75.632734)
			(xy 262.168093 -75.597175) (xy 262.18896 -75.581764) (xy 262.196275 -75.576006) (xy 262.206569 -75.560516)
			(xy 262.209026 -75.551538) (xy 262.215884 -75.521312) (xy 262.217659 -75.512039) (xy 262.214901 -75.493371)
			(xy 262.21055 -75.48499) (xy 262.19625 -75.459017) (xy 262.173741 -75.404164) (xy 262.158516 -75.34686)
			(xy 262.150832 -75.288068) (xy 262.150352 -75.258422) (xy 262.150828 -75.228436) (xy 262.158653 -75.168978)
			(xy 262.174173 -75.111049) (xy 262.197121 -75.055642) (xy 262.227106 -75.003705) (xy 262.263614 -74.956125)
			(xy 262.306019 -74.913719) (xy 262.353598 -74.87721) (xy 262.405535 -74.847225) (xy 262.460941 -74.824275)
			(xy 262.51887 -74.808755) (xy 262.578328 -74.800928) (xy 262.608314 -74.80046) (xy 263.471914 -74.80046)
			(xy 263.501901 -74.800894) (xy 263.561361 -74.808724) (xy 263.619291 -74.824248) (xy 263.674699 -74.847201)
			(xy 263.726637 -74.87719) (xy 263.774216 -74.913702) (xy 263.816622 -74.956111) (xy 263.85313 -75.003693)
			(xy 263.883115 -75.055633) (xy 263.906063 -75.111043) (xy 263.921583 -75.168974) (xy 263.929408 -75.228435)
			(xy 263.929876 -75.258422) (xy 263.929402 -75.288099) (xy 263.921731 -75.346955) (xy 263.906507 -75.404324)
			(xy 263.883987 -75.45924) (xy 263.869678 -75.485244) (xy 263.8654 -75.493581) (xy 263.862646 -75.512099)
			(xy 263.864344 -75.521312) (xy 263.870948 -75.551792) (xy 263.873346 -75.560795) (xy 263.88366 -75.576295)
			(xy 263.891014 -75.582018) (xy 263.911827 -75.597456) (xy 263.94954 -75.632993) (xy 263.982092 -75.67331)
			(xy 264.008884 -75.717664) (xy 264.029423 -75.765238) (xy 264.043328 -75.815156) (xy 264.050346 -75.866497)
			(xy 264.05078 -75.892406) (xy 264.05035 -75.91966) (xy 264.042592 -75.973614) (xy 264.027233 -76.025914)
			(xy 264.004588 -76.075496) (xy 263.975117 -76.12135) (xy 263.93942 -76.162544) (xy 263.898223 -76.198237)
			(xy 263.852366 -76.227705) (xy 263.802782 -76.250345) (xy 263.750481 -76.265699) (xy 263.719829 -76.270104)
			(xy 264.157966 -76.270104) (xy 264.162037 -76.214482) (xy 264.174163 -76.160045) (xy 264.194086 -76.107954)
			(xy 264.221382 -76.059319) (xy 264.255468 -76.015176) (xy 264.295617 -75.976467) (xy 264.340975 -75.944016)
			(xy 264.390575 -75.918515) (xy 264.443359 -75.900508) (xy 264.498202 -75.890378) (xy 264.553936 -75.888341)
			(xy 264.609373 -75.894441) (xy 264.66333 -75.908547) (xy 264.714659 -75.930359) (xy 264.762265 -75.959413)
			(xy 264.805133 -75.995088) (xy 264.84235 -76.036625) (xy 264.873123 -76.083138) (xy 264.896795 -76.133635)
			(xy 264.912863 -76.187042) (xy 264.920983 -76.242218) (xy 264.921492 -76.270104) (xy 264.920983 -76.29799)
			(xy 264.912863 -76.353166) (xy 264.896795 -76.406573) (xy 264.873123 -76.45707) (xy 264.84235 -76.503583)
			(xy 264.805133 -76.54512) (xy 264.762265 -76.580795) (xy 264.714659 -76.609849) (xy 264.66333 -76.631661)
			(xy 264.609373 -76.645767) (xy 264.553936 -76.651867) (xy 264.498202 -76.64983) (xy 264.443359 -76.6397)
			(xy 264.390575 -76.621693) (xy 264.340975 -76.596192) (xy 264.295617 -76.563741) (xy 264.255468 -76.525032)
			(xy 264.221382 -76.480889) (xy 264.194086 -76.432254) (xy 264.174163 -76.380163) (xy 264.162037 -76.325726)
			(xy 264.157966 -76.270104) (xy 263.719829 -76.270104) (xy 263.696526 -76.273453) (xy 263.669272 -76.273914)
			(xy 263.642262 -76.273409) (xy 263.588782 -76.265799) (xy 263.53691 -76.25072) (xy 263.487684 -76.228474)
			(xy 263.442089 -76.199506) (xy 263.401036 -76.164396) (xy 263.365347 -76.123845) (xy 263.335735 -76.078665)
			(xy 263.312793 -76.02976) (xy 263.29698 -75.978107) (xy 263.288611 -75.92474) (xy 263.287764 -75.89774)
			(xy 263.287764 -75.892914) (xy 263.287883 -75.877994) (xy 263.290173 -75.848241) (xy 263.292336 -75.833478)
			(xy 263.294114 -75.822556) (xy 263.288018 -75.80122) (xy 263.230614 -75.73391) (xy 263.223014 -75.725951)
			(xy 263.203 -75.716861) (xy 263.192006 -75.716384) (xy 262.887714 -75.716384) (xy 262.876727 -75.716902)
			(xy 262.856714 -75.725969) (xy 262.849106 -75.73391) (xy 262.791702 -75.80122) (xy 262.785606 -75.822556)
			(xy 262.787384 -75.833478) (xy 262.789546 -75.848241) (xy 262.791832 -75.877994) (xy 262.791956 -75.892914)
			(xy 262.791956 -75.89774) (xy 262.791122 -75.92474) (xy 262.782742 -75.978106) (xy 262.766921 -76.029756)
			(xy 262.743974 -76.07866) (xy 262.71436 -76.123838) (xy 262.678671 -76.164389) (xy 262.63762 -76.199501)
			(xy 262.592027 -76.228474) (xy 262.542805 -76.250728) (xy 262.490936 -76.265818) (xy 262.437458 -76.273442)
			(xy 262.410448 -76.273914) (xy 262.383197 -76.2734) (xy 262.329248 -76.26565) (xy 262.276951 -76.2503)
			(xy 262.227372 -76.227664) (xy 262.181519 -76.198201) (xy 262.140326 -76.162513) (xy 262.104631 -76.121325)
			(xy 262.075162 -76.075476) (xy 262.052519 -76.025899) (xy 262.037162 -75.973605) (xy 262.029404 -75.919657)
			(xy 262.02894 -75.892406) (xy 256.243662 -75.892406) (xy 256.274489 -75.896838) (xy 256.326784 -75.912193)
			(xy 256.376361 -75.934835) (xy 256.422211 -75.964301) (xy 256.463402 -75.999992) (xy 256.499093 -76.041183)
			(xy 256.528559 -76.087033) (xy 256.551201 -76.13661) (xy 256.566556 -76.188905) (xy 256.574312 -76.242853)
			(xy 256.574798 -76.270104) (xy 256.574798 -76.270358) (xy 256.574223 -76.298694) (xy 256.565721 -76.354726)
			(xy 256.549016 -76.408882) (xy 256.524478 -76.459968) (xy 256.509012 -76.483718) (xy 256.508758 -76.484226)
			(xy 256.50317 -76.492862) (xy 256.501392 -76.498196) (xy 256.49809 -76.515976) (xy 256.49809 -76.529692)
			(xy 256.545334 -76.619862) (xy 256.549983 -76.627843) (xy 256.563806 -76.640073) (xy 256.581064 -76.646613)
			(xy 256.590292 -76.64704) (xy 260.770624 -76.64704) (xy 260.802596 -76.647467) (xy 260.866156 -76.654466)
			(xy 260.928565 -76.668397) (xy 260.989067 -76.689092) (xy 261.046933 -76.716302) (xy 261.101464 -76.749699)
			(xy 261.126986 -76.76896) (xy 261.13359 -76.77404) (xy 261.155942 -76.781914) (xy 261.160061 -76.783303)
			(xy 261.168615 -76.784836) (xy 261.17296 -76.784962) (xy 261.673848 -76.784962) (xy 261.683913 -76.785396)
			(xy 261.702499 -76.793129) (xy 261.709916 -76.799948) (xy 262.756396 -77.846428) (xy 262.756904 -77.846936)
			(xy 262.764287 -77.853512) (xy 262.782586 -77.860947) (xy 262.792464 -77.861414) (xy 297.707558 -77.861414)
			(xy 297.717084 -77.861025) (xy 297.734822 -77.854076) (xy 297.748793 -77.841125) (xy 297.753278 -77.832712)
			(xy 297.792902 -77.75067) (xy 297.792902 -77.750162) (xy 297.799252 -77.737716) (xy 297.796204 -77.707998)
			(xy 297.786806 -77.69606) (xy 297.770916 -77.675638) (xy 297.74421 -77.631317) (xy 297.723743 -77.583792)
			(xy 297.70989 -77.533936) (xy 297.702908 -77.482665) (xy 297.702478 -77.456792) (xy 297.702964 -77.429541)
			(xy 297.71072 -77.375593) (xy 297.726075 -77.323298) (xy 297.748717 -77.273721) (xy 297.778183 -77.227871)
			(xy 297.813874 -77.18668) (xy 297.855065 -77.150989) (xy 297.900915 -77.121523) (xy 297.950492 -77.098881)
			(xy 298.002787 -77.083526) (xy 298.056735 -77.07577) (xy 298.111237 -77.07577) (xy 298.165185 -77.083526)
			(xy 298.21748 -77.098881) (xy 298.267057 -77.121523) (xy 298.312907 -77.150989) (xy 298.354098 -77.18668)
			(xy 298.367675 -77.202349) (xy 314.084984 -77.202349) (xy 314.084984 -77.147851) (xy 314.092739 -77.093906)
			(xy 314.108093 -77.041615) (xy 314.130731 -76.99204) (xy 314.160194 -76.946192) (xy 314.195882 -76.905003)
			(xy 314.237068 -76.869312) (xy 314.282914 -76.839846) (xy 314.332487 -76.817203) (xy 314.384777 -76.801846)
			(xy 314.438721 -76.794086) (xy 314.46597 -76.793598) (xy 314.493677 -76.794111) (xy 314.548509 -76.802112)
			(xy 314.601606 -76.817964) (xy 314.65185 -76.841333) (xy 314.698183 -76.871728) (xy 314.73963 -76.908508)
			(xy 314.775318 -76.950899) (xy 314.790328 -76.974192) (xy 314.798159 -76.986053) (xy 314.819208 -77.005138)
			(xy 314.844706 -77.017673) (xy 314.872674 -77.022685) (xy 314.900939 -77.019785) (xy 314.927305 -77.009197)
			(xy 314.949726 -76.991745) (xy 314.958476 -76.980542) (xy 314.976589 -76.95684) (xy 315.018951 -76.914843)
			(xy 315.067332 -76.87995) (xy 315.120553 -76.853011) (xy 315.177318 -76.834682) (xy 315.236244 -76.82541)
			(xy 315.26607 -76.82484) (xy 315.293328 -76.825205) (xy 315.347289 -76.832959) (xy 315.399597 -76.848315)
			(xy 315.449187 -76.870958) (xy 315.49505 -76.900429) (xy 315.518371 -76.920636) (xy 320.335897 -76.920636)
			(xy 320.335899 -76.866137) (xy 320.343657 -76.812193) (xy 320.359013 -76.759902) (xy 320.381654 -76.710328)
			(xy 320.41112 -76.664481) (xy 320.446811 -76.623295) (xy 320.488 -76.587606) (xy 320.533849 -76.558143)
			(xy 320.583424 -76.535505) (xy 320.635716 -76.520152) (xy 320.68966 -76.512398) (xy 320.71691 -76.511912)
			(xy 320.731896 -76.511912) (xy 320.75374 -76.50099) (xy 320.816732 -76.413868) (xy 320.820542 -76.389738)
			(xy 320.816478 -76.378054) (xy 320.80723 -76.348622) (xy 320.797279 -76.28774) (xy 320.796666 -76.256896)
			(xy 320.796666 -76.256642) (xy 320.797152 -76.229391) (xy 320.804908 -76.175443) (xy 320.820263 -76.123148)
			(xy 320.842905 -76.073571) (xy 320.872371 -76.027721) (xy 320.908062 -75.98653) (xy 320.949253 -75.950839)
			(xy 320.995103 -75.921373) (xy 321.04468 -75.898731) (xy 321.096975 -75.883376) (xy 321.150923 -75.87562)
			(xy 321.205425 -75.87562) (xy 321.259373 -75.883376) (xy 321.311668 -75.898731) (xy 321.361245 -75.921373)
			(xy 321.407095 -75.950839) (xy 321.448286 -75.98653) (xy 321.483977 -76.027721) (xy 321.513443 -76.073571)
			(xy 321.536085 -76.123148) (xy 321.55144 -76.175443) (xy 321.559196 -76.229391) (xy 321.559682 -76.256642)
			(xy 321.558666 -76.283566) (xy 321.558578 -76.29601) (xy 321.568687 -76.318709) (xy 321.57797 -76.327)
			(xy 321.654424 -76.38669) (xy 321.679062 -76.391262) (xy 321.691254 -76.387198) (xy 321.719577 -76.378663)
			(xy 321.778011 -76.369482) (xy 321.807586 -76.36891) (xy 321.808348 -76.36891) (xy 321.835595 -76.36943)
			(xy 321.889533 -76.377191) (xy 321.941817 -76.39255) (xy 321.991384 -76.415193) (xy 322.037224 -76.444659)
			(xy 322.078404 -76.480349) (xy 322.114085 -76.521536) (xy 322.143543 -76.567381) (xy 322.166176 -76.616952)
			(xy 322.181524 -76.66924) (xy 322.189276 -76.723179) (xy 322.189272 -76.777673) (xy 322.181513 -76.831611)
			(xy 322.166158 -76.883896) (xy 322.143518 -76.933464) (xy 322.114054 -76.979306) (xy 322.078367 -77.020488)
			(xy 322.037182 -77.056172) (xy 321.991338 -77.085632) (xy 321.941768 -77.108268) (xy 321.889482 -77.12362)
			(xy 321.835543 -77.131374) (xy 321.781049 -77.131374) (xy 321.72711 -77.123618) (xy 321.674824 -77.108265)
			(xy 321.625255 -77.085628) (xy 321.579412 -77.056167) (xy 321.538228 -77.020482) (xy 321.502541 -76.9793)
			(xy 321.473078 -76.933457) (xy 321.450439 -76.883889) (xy 321.435085 -76.831603) (xy 321.427327 -76.777665)
			(xy 321.42684 -76.750418) (xy 321.427856 -76.723494) (xy 321.427899 -76.711054) (xy 321.417821 -76.688356)
			(xy 321.408552 -76.68006) (xy 321.332098 -76.62037) (xy 321.30746 -76.615798) (xy 321.295268 -76.619862)
			(xy 321.266758 -76.628436) (xy 321.20794 -76.637621) (xy 321.178174 -76.63815) (xy 321.163188 -76.63815)
			(xy 321.141344 -76.649072) (xy 321.078352 -76.736194) (xy 321.074542 -76.760324) (xy 321.078606 -76.772008)
			(xy 321.087844 -76.801442) (xy 321.097802 -76.862322) (xy 321.098418 -76.893166) (xy 321.098418 -76.89342)
			(xy 321.0979 -76.92067) (xy 321.090142 -76.974614) (xy 321.074785 -77.026905) (xy 321.052142 -77.076478)
			(xy 321.022676 -77.122324) (xy 320.986984 -77.16351) (xy 320.945795 -77.199198) (xy 320.899946 -77.22866)
			(xy 320.85037 -77.251297) (xy 320.798078 -77.266649) (xy 320.744133 -77.274403) (xy 320.689634 -77.274401)
			(xy 320.63569 -77.266642) (xy 320.583398 -77.251286) (xy 320.533825 -77.228644) (xy 320.487979 -77.199178)
			(xy 320.446792 -77.163486) (xy 320.411104 -77.122297) (xy 320.381642 -77.076448) (xy 320.359004 -77.026873)
			(xy 320.343651 -76.974581) (xy 320.335897 -76.920636) (xy 315.518371 -76.920636) (xy 315.536251 -76.936128)
			(xy 315.571953 -76.977326) (xy 315.601427 -77.023187) (xy 315.624075 -77.072775) (xy 315.639434 -77.125082)
			(xy 315.647193 -77.179042) (xy 315.647193 -77.233558) (xy 315.639434 -77.287518) (xy 315.624075 -77.339825)
			(xy 315.601427 -77.389413) (xy 315.571953 -77.435274) (xy 315.536251 -77.476472) (xy 315.49505 -77.512171)
			(xy 315.449187 -77.541642) (xy 315.399597 -77.564285) (xy 315.347289 -77.579641) (xy 315.293328 -77.587395)
			(xy 315.26607 -77.587856) (xy 315.238363 -77.587364) (xy 315.183531 -77.579356) (xy 315.130434 -77.563499)
			(xy 315.080191 -77.540125) (xy 315.033859 -77.509728) (xy 314.992412 -77.472947) (xy 314.956723 -77.430555)
			(xy 314.941712 -77.407262) (xy 314.933831 -77.395436) (xy 314.912796 -77.376343) (xy 314.887308 -77.3638)
			(xy 314.859347 -77.35878) (xy 314.831088 -77.361675) (xy 314.804726 -77.37226) (xy 314.78231 -77.38971)
			(xy 314.773564 -77.400912) (xy 314.755442 -77.424607) (xy 314.71308 -77.466601) (xy 314.664701 -77.501493)
			(xy 314.611481 -77.528433) (xy 314.554718 -77.546765) (xy 314.495795 -77.556041) (xy 314.46597 -77.556614)
			(xy 314.438721 -77.556114) (xy 314.384777 -77.548354) (xy 314.332487 -77.532997) (xy 314.282914 -77.510354)
			(xy 314.237068 -77.480888) (xy 314.195882 -77.445197) (xy 314.160194 -77.404008) (xy 314.130731 -77.35816)
			(xy 314.108093 -77.308585) (xy 314.092739 -77.256294) (xy 314.084984 -77.202349) (xy 298.367675 -77.202349)
			(xy 298.389789 -77.227871) (xy 298.419255 -77.273721) (xy 298.441897 -77.323298) (xy 298.457252 -77.375593)
			(xy 298.465008 -77.429541) (xy 298.465494 -77.456792) (xy 298.465494 -77.457046) (xy 298.465066 -77.482918)
			(xy 298.458079 -77.534189) (xy 298.444226 -77.584045) (xy 298.423761 -77.631571) (xy 298.39706 -77.675895)
			(xy 298.381166 -77.696314) (xy 298.376594 -77.701902) (xy 298.37126 -77.714348) (xy 298.370244 -77.72146)
			(xy 298.36969 -77.726631) (xy 298.370452 -77.737003) (xy 298.371768 -77.742034) (xy 298.373038 -77.74686)
			(xy 298.414694 -77.832712) (xy 298.41571 -77.834744) (xy 298.41571 -77.834998) (xy 298.420372 -77.842794)
			(xy 298.434076 -77.854699) (xy 298.451083 -77.861043) (xy 298.46016 -77.861414) (xy 298.493434 -77.861414)
			(xy 298.503974 -77.860899) (xy 298.523284 -77.852445) (xy 298.537561 -77.836936) (xy 298.54144 -77.827124)
			(xy 298.544397 -77.798906) (xy 298.557583 -77.743724) (xy 298.578785 -77.691099) (xy 298.607536 -77.642188)
			(xy 298.643204 -77.598066) (xy 298.685004 -77.559704) (xy 298.732017 -77.527945) (xy 298.78321 -77.503487)
			(xy 298.837457 -77.486868) (xy 298.893565 -77.478453) (xy 298.921932 -77.477874) (xy 298.94826 -77.47831)
			(xy 299.000418 -77.485535) (xy 299.05109 -77.499856) (xy 299.099313 -77.521002) (xy 299.144174 -77.548573)
			(xy 299.164756 -77.564996) (xy 299.165772 -77.56525) (xy 299.24502 -77.550772) (xy 299.252511 -77.549141)
			(xy 299.266085 -77.542032) (xy 299.27169 -77.536802) (xy 299.276262 -77.53223) (xy 299.28185 -77.525626)
			(xy 299.299634 -77.501184) (xy 299.34012 -77.456299) (xy 299.38567 -77.41656) (xy 299.435632 -77.382536)
			(xy 299.489295 -77.354712) (xy 299.545892 -77.333484) (xy 299.604616 -77.319156) (xy 299.66463 -77.311932)
			(xy 299.694854 -77.311504) (xy 299.726541 -77.312) (xy 299.789419 -77.319926) (xy 299.850813 -77.335646)
			(xy 299.909762 -77.358914) (xy 299.965341 -77.389366) (xy 300.01668 -77.426524) (xy 300.062973 -77.469805)
			(xy 300.103496 -77.518532) (xy 300.137612 -77.571941) (xy 300.164787 -77.629193) (xy 300.184596 -77.689393)
			(xy 300.196727 -77.751596) (xy 300.199298 -77.783182) (xy 300.199806 -77.79258) (xy 300.21276 -77.82052)
			(xy 300.21784 -77.82814) (xy 300.236128 -77.846428) (xy 300.236636 -77.846936) (xy 300.244016 -77.853523)
			(xy 300.262315 -77.860982) (xy 300.272196 -77.861414) (xy 312.825384 -77.861414) (xy 312.835447 -77.861853)
			(xy 312.854028 -77.86959) (xy 312.861452 -77.8764) (xy 314.017914 -79.032862) (xy 314.02476 -79.04026)
			(xy 314.032485 -79.058859) (xy 314.0329 -79.06893) (xy 314.0329 -80.393032) (xy 314.034424 -80.404462)
			(xy 314.035186 -80.407256) (xy 314.040455 -80.429051) (xy 314.046436 -80.47349) (xy 314.047124 -80.495902)
			(xy 314.047378 -80.505808) (xy 314.054744 -80.523588) (xy 314.06211 -80.530954) (xy 314.070958 -80.538863)
			(xy 314.093472 -80.546271) (xy 314.10529 -80.545178) (xy 314.158376 -80.492092) (xy 314.166185 -80.465586)
			(xy 314.188385 -80.414986) (xy 314.217646 -80.368115) (xy 314.253358 -80.325951) (xy 314.294775 -80.289374)
			(xy 314.341031 -80.259149) (xy 314.391161 -80.235908) (xy 314.444117 -80.220134) (xy 314.498794 -80.212158)
			(xy 314.526422 -80.211676) (xy 314.553673 -80.212163) (xy 314.607619 -80.219922) (xy 314.659912 -80.235279)
			(xy 314.709487 -80.257921) (xy 314.755336 -80.287388) (xy 314.796525 -80.323079) (xy 314.832216 -80.364269)
			(xy 314.861682 -80.410118) (xy 314.884323 -80.459694) (xy 314.899679 -80.511987) (xy 314.907437 -80.565933)
			(xy 314.90793 -80.593184) (xy 314.907442 -80.620813) (xy 314.899477 -80.675494) (xy 314.883711 -80.728455)
			(xy 314.860473 -80.778589) (xy 314.83025 -80.824849) (xy 314.795028 -80.864732) (xy 320.080368 -80.864732)
			(xy 320.080371 -80.810228) (xy 320.08813 -80.756279) (xy 320.103489 -80.703983) (xy 320.126134 -80.654406)
			(xy 320.155604 -80.608556) (xy 320.191299 -80.567366) (xy 320.232492 -80.531676) (xy 320.278346 -80.502212)
			(xy 320.327926 -80.479573) (xy 320.380224 -80.464221) (xy 320.434174 -80.456467) (xy 320.488678 -80.456471)
			(xy 320.542627 -80.464232) (xy 320.594922 -80.479591) (xy 320.6445 -80.502237) (xy 320.690349 -80.531707)
			(xy 320.731538 -80.567403) (xy 320.767228 -80.608597) (xy 320.796691 -80.654451) (xy 320.819329 -80.704032)
			(xy 320.834681 -80.75633) (xy 320.842433 -80.81028) (xy 320.842894 -80.837532) (xy 320.842761 -80.852838)
			(xy 320.840343 -80.883355) (xy 320.838068 -80.898492) (xy 320.836036 -80.911446) (xy 320.844672 -80.936084)
			(xy 320.919602 -81.001616) (xy 320.926278 -81.006994) (xy 320.942186 -81.013357) (xy 320.959302 -81.014151)
			(xy 320.967608 -81.01203) (xy 320.967862 -81.01203) (xy 320.994834 -81.004332) (xy 321.050308 -80.99605)
			(xy 321.078352 -80.99552) (xy 321.105605 -80.996) (xy 321.159557 -81.003751) (xy 321.211856 -81.019103)
			(xy 321.261438 -81.041742) (xy 321.307293 -81.071207) (xy 321.348486 -81.106899) (xy 321.384181 -81.148091)
			(xy 321.413649 -81.193945) (xy 321.43629 -81.243525) (xy 321.451645 -81.295824) (xy 321.459399 -81.349775)
			(xy 321.45986 -81.377028) (xy 321.45986 -81.377282) (xy 321.459719 -81.391625) (xy 321.457556 -81.42023)
			(xy 321.455542 -81.434432) (xy 321.45351 -81.447894) (xy 321.462908 -81.472532) (xy 321.541394 -81.53654)
			(xy 321.54834 -81.541779) (xy 321.564707 -81.547649) (xy 321.582095 -81.547717) (xy 321.590416 -81.545176)
			(xy 321.590924 -81.545176) (xy 321.622251 -81.534548) (xy 321.687392 -81.523061) (xy 321.720464 -81.522316)
			(xy 321.74772 -81.522716) (xy 321.801677 -81.530469) (xy 321.853981 -81.545822) (xy 321.903569 -81.568462)
			(xy 321.949429 -81.597929) (xy 321.990629 -81.633623) (xy 321.997846 -81.64195) (xy 328.401932 -81.64195)
			(xy 328.406003 -81.586328) (xy 328.418129 -81.531891) (xy 328.438052 -81.4798) (xy 328.465348 -81.431165)
			(xy 328.499434 -81.387022) (xy 328.539583 -81.348313) (xy 328.584941 -81.315862) (xy 328.634541 -81.290361)
			(xy 328.687325 -81.272354) (xy 328.742168 -81.262224) (xy 328.797902 -81.260187) (xy 328.853339 -81.266287)
			(xy 328.907296 -81.280393) (xy 328.958625 -81.302205) (xy 329.006231 -81.331259) (xy 329.049099 -81.366934)
			(xy 329.086316 -81.408471) (xy 329.117089 -81.454984) (xy 329.140761 -81.505481) (xy 329.156829 -81.558888)
			(xy 329.164949 -81.614064) (xy 329.165458 -81.64195) (xy 329.164949 -81.669836) (xy 329.156829 -81.725012)
			(xy 329.140761 -81.778419) (xy 329.117089 -81.828916) (xy 329.086316 -81.875429) (xy 329.049099 -81.916966)
			(xy 329.006231 -81.952641) (xy 328.958625 -81.981695) (xy 328.907296 -82.003507) (xy 328.853339 -82.017613)
			(xy 328.797902 -82.023713) (xy 328.742168 -82.021676) (xy 328.687325 -82.011546) (xy 328.634541 -81.993539)
			(xy 328.584941 -81.968038) (xy 328.539583 -81.935587) (xy 328.499434 -81.896878) (xy 328.465348 -81.852735)
			(xy 328.438052 -81.8041) (xy 328.418129 -81.752009) (xy 328.406003 -81.697572) (xy 328.401932 -81.64195)
			(xy 321.997846 -81.64195) (xy 322.02633 -81.674816) (xy 322.055805 -81.720672) (xy 322.078454 -81.770255)
			(xy 322.093816 -81.822557) (xy 322.101579 -81.876512) (xy 322.101583 -81.931024) (xy 322.09383 -81.984981)
			(xy 322.078477 -82.037285) (xy 322.055836 -82.086872) (xy 322.026369 -82.132732) (xy 321.990675 -82.173932)
			(xy 321.94948 -82.209633) (xy 321.903625 -82.239107) (xy 321.854041 -82.261756) (xy 321.801739 -82.277117)
			(xy 321.747784 -82.284879) (xy 321.693272 -82.284883) (xy 321.639315 -82.277129) (xy 321.587011 -82.261775)
			(xy 321.537424 -82.239134) (xy 321.491564 -82.209666) (xy 321.450365 -82.173972) (xy 321.414665 -82.132777)
			(xy 321.385191 -82.086921) (xy 321.362543 -82.037338) (xy 321.347182 -81.985036) (xy 321.339421 -81.93108)
			(xy 321.338956 -81.903824) (xy 321.338956 -81.90357) (xy 321.339103 -81.889227) (xy 321.341262 -81.860622)
			(xy 321.343274 -81.84642) (xy 321.345306 -81.832958) (xy 321.335908 -81.80832) (xy 321.257422 -81.744312)
			(xy 321.250471 -81.739081) (xy 321.234106 -81.733213) (xy 321.216721 -81.733139) (xy 321.2084 -81.735676)
			(xy 321.207892 -81.735676) (xy 321.176564 -81.746298) (xy 321.111424 -81.75779) (xy 321.078352 -81.758536)
			(xy 321.051101 -81.758067) (xy 320.997154 -81.750305) (xy 320.944861 -81.734945) (xy 320.895285 -81.7123)
			(xy 320.849436 -81.682831) (xy 320.808247 -81.647138) (xy 320.772557 -81.605948) (xy 320.74309 -81.560097)
			(xy 320.720448 -81.510521) (xy 320.705091 -81.458226) (xy 320.697332 -81.404279) (xy 320.696844 -81.377028)
			(xy 320.696985 -81.361722) (xy 320.699397 -81.331205) (xy 320.70167 -81.316068) (xy 320.703702 -81.303114)
			(xy 320.695066 -81.278476) (xy 320.620136 -81.212944) (xy 320.613445 -81.207588) (xy 320.597544 -81.201222)
			(xy 320.580435 -81.200416) (xy 320.57213 -81.20253) (xy 320.571876 -81.20253) (xy 320.544902 -81.210219)
			(xy 320.489429 -81.218507) (xy 320.461386 -81.21904) (xy 320.434134 -81.21853) (xy 320.380185 -81.210771)
			(xy 320.327889 -81.195413) (xy 320.278311 -81.172769) (xy 320.23246 -81.1433) (xy 320.19127 -81.107606)
			(xy 320.15558 -81.066412) (xy 320.126114 -81.020559) (xy 320.103475 -80.970979) (xy 320.088122 -80.918682)
			(xy 320.080368 -80.864732) (xy 314.795028 -80.864732) (xy 314.793672 -80.866268) (xy 314.751505 -80.90198)
			(xy 314.704629 -80.93124) (xy 314.654025 -80.953434) (xy 314.627514 -80.96123) (xy 314.23102 -81.357724)
			(xy 314.0329 -81.357724) (xy 314.0329 -82.342245) (xy 319.386028 -82.342245) (xy 319.386028 -82.287755)
			(xy 319.393782 -82.233818) (xy 319.409133 -82.181535) (xy 319.431767 -82.131967) (xy 319.461225 -82.086125)
			(xy 319.496906 -82.044942) (xy 319.538085 -82.009255) (xy 319.583923 -81.979791) (xy 319.633488 -81.95715)
			(xy 319.68577 -81.941793) (xy 319.739705 -81.934032) (xy 319.76695 -81.933542) (xy 319.793554 -81.93401)
			(xy 319.846247 -81.941386) (xy 319.897403 -81.956016) (xy 319.946028 -81.977615) (xy 319.991179 -82.005764)
			(xy 320.031978 -82.039916) (xy 320.067633 -82.079408) (xy 320.082926 -82.101182) (xy 320.09126 -82.112662)
			(xy 320.113004 -82.130866) (xy 320.138917 -82.142384) (xy 320.167 -82.146324) (xy 320.195083 -82.142384)
			(xy 320.220996 -82.130866) (xy 320.24274 -82.112662) (xy 320.251074 -82.101182) (xy 320.266386 -82.079424)
			(xy 320.302048 -82.039943) (xy 320.342848 -82.005798) (xy 320.387995 -81.97765) (xy 320.436614 -81.956045)
			(xy 320.487762 -81.941403) (xy 320.540449 -81.934007) (xy 320.56705 -81.933542) (xy 320.594309 -81.933902)
			(xy 320.648272 -81.941654) (xy 320.700583 -81.957007) (xy 320.750176 -81.97965) (xy 320.796041 -82.009121)
			(xy 320.837246 -82.044819) (xy 320.872949 -82.086018) (xy 320.902426 -82.13188) (xy 320.925075 -82.18147)
			(xy 320.940436 -82.233779) (xy 320.948195 -82.287741) (xy 320.948195 -82.342259) (xy 320.940436 -82.396221)
			(xy 320.925075 -82.44853) (xy 320.902426 -82.49812) (xy 320.872949 -82.543982) (xy 320.837246 -82.585181)
			(xy 320.796041 -82.620879) (xy 320.750176 -82.65035) (xy 320.700583 -82.672992) (xy 320.648272 -82.688346)
			(xy 320.594309 -82.696098) (xy 320.56705 -82.696558) (xy 320.540446 -82.69609) (xy 320.487753 -82.688714)
			(xy 320.436597 -82.674084) (xy 320.387972 -82.652485) (xy 320.342821 -82.624336) (xy 320.302022 -82.590184)
			(xy 320.266367 -82.550692) (xy 320.251074 -82.528918) (xy 320.24274 -82.517438) (xy 320.220996 -82.499234)
			(xy 320.195083 -82.487716) (xy 320.167 -82.483776) (xy 320.138917 -82.487716) (xy 320.113004 -82.499234)
			(xy 320.09126 -82.517438) (xy 320.082926 -82.528918) (xy 320.067614 -82.550676) (xy 320.031952 -82.590157)
			(xy 319.991152 -82.624302) (xy 319.946005 -82.65245) (xy 319.897386 -82.674055) (xy 319.846238 -82.688697)
			(xy 319.793551 -82.696093) (xy 319.76695 -82.696558) (xy 319.739705 -82.695968) (xy 319.68577 -82.688207)
			(xy 319.633488 -82.67285) (xy 319.583923 -82.650209) (xy 319.538085 -82.620745) (xy 319.496906 -82.585058)
			(xy 319.461225 -82.543875) (xy 319.431767 -82.498033) (xy 319.409133 -82.448465) (xy 319.393782 -82.396182)
			(xy 319.386028 -82.342245) (xy 314.0329 -82.342245) (xy 314.0329 -83.847251) (xy 319.531978 -83.847251)
			(xy 319.531978 -83.792749) (xy 319.539734 -83.738801) (xy 319.555089 -83.686506) (xy 319.577731 -83.636929)
			(xy 319.607197 -83.591079) (xy 319.642888 -83.549888) (xy 319.684079 -83.514197) (xy 319.729929 -83.484731)
			(xy 319.779506 -83.462089) (xy 319.831801 -83.446734) (xy 319.885749 -83.438978) (xy 319.913 -83.438492)
			(xy 319.94055 -83.438975) (xy 319.995079 -83.446889) (xy 320.047902 -83.462568) (xy 320.097918 -83.485685)
			(xy 320.144088 -83.515758) (xy 320.18545 -83.552162) (xy 320.197216 -83.566) (xy 330.199492 -83.566)
			(xy 330.199991 -83.539569) (xy 330.207301 -83.487215) (xy 330.221769 -83.436371) (xy 330.243117 -83.388012)
			(xy 330.270935 -83.343062) (xy 330.304693 -83.302382) (xy 330.343742 -83.266752) (xy 330.387336 -83.236853)
			(xy 330.43464 -83.213258) (xy 330.484749 -83.196418) (xy 330.510642 -83.191096) (xy 330.52063 -83.188739)
			(xy 330.537668 -83.177329) (xy 330.543662 -83.168998) (xy 330.583794 -83.107276) (xy 330.589025 -83.098375)
			(xy 330.592562 -83.078053) (xy 330.590652 -83.067906) (xy 330.590652 -83.067652) (xy 330.585903 -83.046185)
			(xy 330.580813 -83.002514) (xy 330.580492 -82.98053) (xy 330.580492 -82.979768) (xy 330.580978 -82.952517)
			(xy 330.588734 -82.898569) (xy 330.604089 -82.846274) (xy 330.626731 -82.796697) (xy 330.656197 -82.750847)
			(xy 330.691888 -82.709656) (xy 330.733079 -82.673965) (xy 330.778929 -82.644499) (xy 330.828506 -82.621857)
			(xy 330.880801 -82.606502) (xy 330.934749 -82.598746) (xy 330.989251 -82.598746) (xy 331.043199 -82.606502)
			(xy 331.095494 -82.621857) (xy 331.145071 -82.644499) (xy 331.190921 -82.673965) (xy 331.232112 -82.709656)
			(xy 331.267803 -82.750847) (xy 331.297269 -82.796697) (xy 331.319911 -82.846274) (xy 331.335266 -82.898569)
			(xy 331.343022 -82.952517) (xy 331.343508 -82.979768) (xy 331.343071 -83.006201) (xy 331.335752 -83.058557)
			(xy 331.321275 -83.109402) (xy 331.29992 -83.157763) (xy 331.272094 -83.202712) (xy 331.23833 -83.243391)
			(xy 331.199274 -83.279021) (xy 331.155675 -83.308918) (xy 331.108366 -83.332512) (xy 331.058253 -83.34935)
			(xy 331.032358 -83.354672) (xy 331.022374 -83.357041) (xy 331.005335 -83.368443) (xy 330.999338 -83.37677)
			(xy 330.959206 -83.438492) (xy 330.953992 -83.447402) (xy 330.950445 -83.467717) (xy 330.952348 -83.477862)
			(xy 330.952348 -83.478116) (xy 330.957138 -83.499769) (xy 330.962231 -83.543825) (xy 330.962508 -83.566)
			(xy 330.961492 -83.59394) (xy 330.96073 -83.603084) (xy 330.96581 -83.620864) (xy 331.017118 -83.68919)
			(xy 331.032358 -83.698842) (xy 331.041248 -83.700874) (xy 331.041756 -83.700874) (xy 331.06986 -83.707396)
			(xy 331.123815 -83.727825) (xy 331.174081 -83.756143) (xy 331.219511 -83.791705) (xy 331.25907 -83.833701)
			(xy 331.291856 -83.881172) (xy 331.317123 -83.933039) (xy 331.334295 -83.988117) (xy 331.342979 -84.045153)
			(xy 331.343508 -84.074) (xy 331.343022 -84.101251) (xy 331.335266 -84.155199) (xy 331.319911 -84.207494)
			(xy 331.297269 -84.257071) (xy 331.267803 -84.302921) (xy 331.232112 -84.344112) (xy 331.190921 -84.379803)
			(xy 331.145071 -84.409269) (xy 331.095494 -84.431911) (xy 331.043199 -84.447266) (xy 330.989251 -84.455022)
			(xy 330.934749 -84.455022) (xy 330.880801 -84.447266) (xy 330.828506 -84.431911) (xy 330.778929 -84.409269)
			(xy 330.733079 -84.379803) (xy 330.691888 -84.344112) (xy 330.656197 -84.302921) (xy 330.626731 -84.257071)
			(xy 330.604089 -84.207494) (xy 330.588734 -84.155199) (xy 330.580978 -84.101251) (xy 330.580492 -84.074)
			(xy 330.580492 -84.073746) (xy 330.581508 -84.04606) (xy 330.58227 -84.036916) (xy 330.57719 -84.019136)
			(xy 330.525882 -83.95081) (xy 330.510642 -83.941158) (xy 330.501752 -83.939126) (xy 330.501244 -83.939126)
			(xy 330.47314 -83.932604) (xy 330.419185 -83.912175) (xy 330.368919 -83.883857) (xy 330.323489 -83.848295)
			(xy 330.28393 -83.806299) (xy 330.251144 -83.758828) (xy 330.225877 -83.706961) (xy 330.208705 -83.651883)
			(xy 330.200021 -83.594847) (xy 330.199492 -83.566) (xy 320.197216 -83.566) (xy 320.221142 -83.594139)
			(xy 320.250423 -83.640816) (xy 320.261996 -83.665822) (xy 320.266822 -83.676998) (xy 320.285618 -83.691984)
			(xy 320.389504 -83.714844) (xy 320.413126 -83.708748) (xy 320.42227 -83.70062) (xy 320.443315 -83.682697)
			(xy 320.489561 -83.652418) (xy 320.539694 -83.629135) (xy 320.592665 -83.613337) (xy 320.647362 -83.605354)
			(xy 320.675 -83.604862) (xy 320.70225 -83.605378) (xy 320.756195 -83.613133) (xy 320.808487 -83.628487)
			(xy 320.858063 -83.651126) (xy 320.903912 -83.680589) (xy 320.945101 -83.716278) (xy 320.980793 -83.757464)
			(xy 321.01026 -83.803311) (xy 321.032902 -83.852885) (xy 321.04826 -83.905176) (xy 321.05602 -83.95912)
			(xy 321.056508 -83.98637) (xy 327.111612 -83.98637) (xy 327.115683 -83.930748) (xy 327.127809 -83.876311)
			(xy 327.147732 -83.82422) (xy 327.175028 -83.775585) (xy 327.209114 -83.731442) (xy 327.249263 -83.692733)
			(xy 327.294621 -83.660282) (xy 327.344221 -83.634781) (xy 327.397005 -83.616774) (xy 327.451848 -83.606644)
			(xy 327.507582 -83.604607) (xy 327.563019 -83.610707) (xy 327.616976 -83.624813) (xy 327.668305 -83.646625)
			(xy 327.715911 -83.675679) (xy 327.758779 -83.711354) (xy 327.795996 -83.752891) (xy 327.826769 -83.799404)
			(xy 327.850441 -83.849901) (xy 327.866509 -83.903308) (xy 327.874629 -83.958484) (xy 327.875138 -83.98637)
			(xy 327.874629 -84.014256) (xy 327.866509 -84.069432) (xy 327.850441 -84.122839) (xy 327.826769 -84.173336)
			(xy 327.795996 -84.219849) (xy 327.758779 -84.261386) (xy 327.715911 -84.297061) (xy 327.668305 -84.326115)
			(xy 327.616976 -84.347927) (xy 327.563019 -84.362033) (xy 327.507582 -84.368133) (xy 327.451848 -84.366096)
			(xy 327.397005 -84.355966) (xy 327.344221 -84.337959) (xy 327.294621 -84.312458) (xy 327.249263 -84.280007)
			(xy 327.209114 -84.241298) (xy 327.175028 -84.197155) (xy 327.147732 -84.14852) (xy 327.127809 -84.096429)
			(xy 327.115683 -84.041992) (xy 327.111612 -83.98637) (xy 321.056508 -83.98637) (xy 321.056508 -83.986624)
			(xy 321.055772 -84.020366) (xy 321.043891 -84.086798) (xy 321.032886 -84.118704) (xy 321.028568 -84.130134)
			(xy 321.031362 -84.154264) (xy 321.08394 -84.23275) (xy 321.09118 -84.242452) (xy 321.11227 -84.25426)
			(xy 321.124326 -84.255356) (xy 321.12458 -84.255356) (xy 321.151162 -84.256776) (xy 321.203571 -84.266103)
			(xy 321.254174 -84.282625) (xy 321.301989 -84.306021) (xy 321.346087 -84.335838) (xy 321.385611 -84.371495)
			(xy 321.419795 -84.412301) (xy 321.447975 -84.457463) (xy 321.469602 -84.506104) (xy 321.484257 -84.557279)
			(xy 321.491656 -84.609994) (xy 321.492118 -84.63661) (xy 321.491716 -84.663047) (xy 321.484389 -84.715411)
			(xy 321.469904 -84.766263) (xy 321.448539 -84.814628) (xy 321.420702 -84.859582) (xy 321.386927 -84.900263)
			(xy 321.34786 -84.935892) (xy 321.304249 -84.965788) (xy 321.28079 -84.977986) (xy 321.271144 -84.983317)
			(xy 321.257325 -85.000459) (xy 321.25412 -85.011006) (xy 321.234077 -85.09) (xy 327.913492 -85.09)
			(xy 327.914042 -85.060925) (xy 327.922854 -85.003447) (xy 327.940289 -84.947973) (xy 327.965943 -84.895788)
			(xy 327.999221 -84.848103) (xy 328.039352 -84.806021) (xy 328.085406 -84.770519) (xy 328.110596 -84.75599)
			(xy 328.12304 -84.748591) (xy 328.143486 -84.728114) (xy 328.157359 -84.702719) (xy 328.163544 -84.674451)
			(xy 328.161543 -84.645583) (xy 328.151517 -84.618438) (xy 328.134273 -84.5952) (xy 328.123042 -84.586064)
			(xy 328.100012 -84.567928) (xy 328.059277 -84.525777) (xy 328.025475 -84.477887) (xy 327.999401 -84.425388)
			(xy 327.981671 -84.369516) (xy 327.972701 -84.311589) (xy 327.972166 -84.28228) (xy 327.972652 -84.255029)
			(xy 327.980408 -84.201081) (xy 327.995763 -84.148786) (xy 328.018405 -84.099209) (xy 328.047871 -84.053359)
			(xy 328.083562 -84.012168) (xy 328.124753 -83.976477) (xy 328.170603 -83.947011) (xy 328.22018 -83.924369)
			(xy 328.272475 -83.909014) (xy 328.326423 -83.901258) (xy 328.380925 -83.901258) (xy 328.434873 -83.909014)
			(xy 328.487168 -83.924369) (xy 328.536745 -83.947011) (xy 328.582595 -83.976477) (xy 328.623786 -84.012168)
			(xy 328.659477 -84.053359) (xy 328.688943 -84.099209) (xy 328.711585 -84.148786) (xy 328.72694 -84.201081)
			(xy 328.734696 -84.255029) (xy 328.735182 -84.28228) (xy 328.734658 -84.311355) (xy 328.725836 -84.368833)
			(xy 328.708394 -84.424306) (xy 328.682735 -84.476489) (xy 328.649454 -84.524174) (xy 328.609322 -84.566256)
			(xy 328.563268 -84.60176) (xy 328.538078 -84.61629) (xy 328.525652 -84.623715) (xy 328.505212 -84.644189)
			(xy 328.491342 -84.669578) (xy 328.485156 -84.69784) (xy 328.487153 -84.726701) (xy 328.497172 -84.753842)
			(xy 328.514407 -84.777078) (xy 328.525632 -84.786216) (xy 328.548668 -84.804344) (xy 328.589399 -84.846499)
			(xy 328.623198 -84.894391) (xy 328.64927 -84.946892) (xy 328.667 -85.002764) (xy 328.675971 -85.060691)
			(xy 328.676508 -85.09) (xy 328.676022 -85.117251) (xy 328.668266 -85.171199) (xy 328.652911 -85.223494)
			(xy 328.630269 -85.273071) (xy 328.600803 -85.318921) (xy 328.565112 -85.360112) (xy 328.523921 -85.395803)
			(xy 328.478071 -85.425269) (xy 328.428494 -85.447911) (xy 328.376199 -85.463266) (xy 328.322251 -85.471022)
			(xy 328.267749 -85.471022) (xy 328.213801 -85.463266) (xy 328.161506 -85.447911) (xy 328.111929 -85.425269)
			(xy 328.066079 -85.395803) (xy 328.024888 -85.360112) (xy 327.989197 -85.318921) (xy 327.959731 -85.273071)
			(xy 327.937089 -85.223494) (xy 327.921734 -85.171199) (xy 327.913978 -85.117251) (xy 327.913492 -85.09)
			(xy 321.234077 -85.09) (xy 321.23253 -85.096096) (xy 321.23634 -85.117686) (xy 321.24269 -85.12683)
			(xy 321.258704 -85.150885) (xy 321.284044 -85.20282) (xy 321.301266 -85.25798) (xy 321.309976 -85.315107)
			(xy 321.310508 -85.344) (xy 321.310022 -85.371251) (xy 321.302266 -85.425199) (xy 321.286911 -85.477494)
			(xy 321.264269 -85.527071) (xy 321.234803 -85.572921) (xy 321.199112 -85.614112) (xy 321.157921 -85.649803)
			(xy 321.112071 -85.679269) (xy 321.062494 -85.701911) (xy 321.010199 -85.717266) (xy 320.956251 -85.725022)
			(xy 320.901749 -85.725022) (xy 320.847801 -85.717266) (xy 320.795506 -85.701911) (xy 320.745929 -85.679269)
			(xy 320.700079 -85.649803) (xy 320.658888 -85.614112) (xy 320.623197 -85.572921) (xy 320.593731 -85.527071)
			(xy 320.571089 -85.477494) (xy 320.555734 -85.425199) (xy 320.547978 -85.371251) (xy 320.547492 -85.344)
			(xy 320.547952 -85.317566) (xy 320.555276 -85.265206) (xy 320.569755 -85.214358) (xy 320.591113 -85.165995)
			(xy 320.618942 -85.121042) (xy 320.652708 -85.08036) (xy 320.691765 -85.044727) (xy 320.735365 -85.014825)
			(xy 320.75882 -85.002624) (xy 320.768445 -84.997262) (xy 320.782278 -84.980143) (xy 320.78549 -84.969604)
			(xy 320.80708 -84.884514) (xy 320.80327 -84.862924) (xy 320.79692 -84.85378) (xy 320.780912 -84.829721)
			(xy 320.75557 -84.777788) (xy 320.738347 -84.722629) (xy 320.729635 -84.665503) (xy 320.729102 -84.63661)
			(xy 320.729102 -84.636356) (xy 320.729832 -84.602613) (xy 320.741717 -84.536182) (xy 320.752724 -84.504276)
			(xy 320.757042 -84.492846) (xy 320.754248 -84.468716) (xy 320.70167 -84.39023) (xy 320.694407 -84.380547)
			(xy 320.673335 -84.368725) (xy 320.661284 -84.367624) (xy 320.66103 -84.367624) (xy 320.634391 -84.366164)
			(xy 320.581868 -84.356814) (xy 320.53116 -84.340237) (xy 320.483257 -84.316755) (xy 320.439093 -84.286828)
			(xy 320.39953 -84.251038) (xy 320.365341 -84.210085) (xy 320.337192 -84.164767) (xy 320.326004 -84.140548)
			(xy 320.321178 -84.129372) (xy 320.302382 -84.114386) (xy 320.198496 -84.091526) (xy 320.174874 -84.097622)
			(xy 320.16573 -84.10575) (xy 320.144694 -84.123684) (xy 320.098445 -84.153959) (xy 320.048309 -84.177239)
			(xy 319.995336 -84.193035) (xy 319.940639 -84.201016) (xy 319.913 -84.201508) (xy 319.885749 -84.201022)
			(xy 319.831801 -84.193266) (xy 319.779506 -84.177911) (xy 319.729929 -84.155269) (xy 319.684079 -84.125803)
			(xy 319.642888 -84.090112) (xy 319.607197 -84.048921) (xy 319.577731 -84.003071) (xy 319.555089 -83.953494)
			(xy 319.539734 -83.901199) (xy 319.531978 -83.847251) (xy 314.0329 -83.847251) (xy 314.0329 -84.488782)
			(xy 314.033372 -84.498654) (xy 314.040831 -84.516936) (xy 314.047378 -84.524342) (xy 314.232036 -84.709)
			(xy 318.895982 -84.709) (xy 318.900053 -84.653378) (xy 318.912179 -84.598941) (xy 318.932102 -84.54685)
			(xy 318.959398 -84.498215) (xy 318.993484 -84.454072) (xy 319.033633 -84.415363) (xy 319.078991 -84.382912)
			(xy 319.128591 -84.357411) (xy 319.181375 -84.339404) (xy 319.236218 -84.329274) (xy 319.291952 -84.327237)
			(xy 319.347389 -84.333337) (xy 319.401346 -84.347443) (xy 319.452675 -84.369255) (xy 319.500281 -84.398309)
			(xy 319.543149 -84.433984) (xy 319.580366 -84.475521) (xy 319.611139 -84.522034) (xy 319.634811 -84.572531)
			(xy 319.650879 -84.625938) (xy 319.658999 -84.681114) (xy 319.659508 -84.709) (xy 319.658999 -84.736886)
			(xy 319.650879 -84.792062) (xy 319.634811 -84.845469) (xy 319.611139 -84.895966) (xy 319.580366 -84.942479)
			(xy 319.543149 -84.984016) (xy 319.500281 -85.019691) (xy 319.452675 -85.048745) (xy 319.401346 -85.070557)
			(xy 319.347389 -85.084663) (xy 319.291952 -85.090763) (xy 319.236218 -85.088726) (xy 319.181375 -85.078596)
			(xy 319.128591 -85.060589) (xy 319.078991 -85.035088) (xy 319.033633 -85.002637) (xy 318.993484 -84.963928)
			(xy 318.959398 -84.919785) (xy 318.932102 -84.87115) (xy 318.912179 -84.819059) (xy 318.900053 -84.764622)
			(xy 318.895982 -84.709) (xy 314.232036 -84.709) (xy 316.010036 -86.487) (xy 318.642492 -86.487) (xy 318.64296 -86.45963)
			(xy 318.650778 -86.405451) (xy 318.666266 -86.352948) (xy 318.689108 -86.303201) (xy 318.718831 -86.257234)
			(xy 318.736472 -86.236302) (xy 318.736726 -86.236048) (xy 318.742302 -86.228954) (xy 318.748554 -86.212043)
			(xy 318.748918 -86.203028) (xy 318.748918 -86.135972) (xy 318.748571 -86.126954) (xy 318.742316 -86.110037)
			(xy 318.736726 -86.102952) (xy 318.736472 -86.102952) (xy 318.736472 -86.102698) (xy 318.718814 -86.081781)
			(xy 318.689106 -86.035804) (xy 318.666274 -85.986052) (xy 318.650787 -85.933548) (xy 318.642964 -85.87937)
			(xy 318.642492 -85.852) (xy 318.642978 -85.824749) (xy 318.650734 -85.770801) (xy 318.666089 -85.718506)
			(xy 318.688731 -85.668929) (xy 318.718197 -85.623079) (xy 318.753888 -85.581888) (xy 318.795079 -85.546197)
			(xy 318.840929 -85.516731) (xy 318.890506 -85.494089) (xy 318.942801 -85.478734) (xy 318.996749 -85.470978)
			(xy 319.051251 -85.470978) (xy 319.105199 -85.478734) (xy 319.157494 -85.494089) (xy 319.207071 -85.516731)
			(xy 319.252921 -85.546197) (xy 319.294112 -85.581888) (xy 319.329803 -85.623079) (xy 319.359269 -85.668929)
			(xy 319.381911 -85.718506) (xy 319.397266 -85.770801) (xy 319.405022 -85.824749) (xy 319.405508 -85.852)
			(xy 319.40504 -85.87937) (xy 319.397222 -85.933549) (xy 319.381734 -85.986052) (xy 319.358892 -86.035799)
			(xy 319.329169 -86.081766) (xy 319.311528 -86.102698) (xy 319.311274 -86.102952) (xy 319.305698 -86.110046)
			(xy 319.299446 -86.126957) (xy 319.299082 -86.135972) (xy 319.299082 -86.203028) (xy 319.299429 -86.212046)
			(xy 319.305684 -86.228963) (xy 319.311274 -86.236048) (xy 319.311528 -86.236048) (xy 319.311528 -86.236302)
			(xy 319.329186 -86.257219) (xy 319.358894 -86.303196) (xy 319.381726 -86.352948) (xy 319.397213 -86.405452)
			(xy 319.405036 -86.45963) (xy 319.405508 -86.487) (xy 319.405022 -86.514251) (xy 319.401965 -86.535514)
			(xy 319.655696 -86.535514) (xy 319.659767 -86.479892) (xy 319.671893 -86.425455) (xy 319.691816 -86.373364)
			(xy 319.719112 -86.324729) (xy 319.753198 -86.280586) (xy 319.793347 -86.241877) (xy 319.838705 -86.209426)
			(xy 319.888305 -86.183925) (xy 319.941089 -86.165918) (xy 319.995932 -86.155788) (xy 320.051666 -86.153751)
			(xy 320.107103 -86.159851) (xy 320.16106 -86.173957) (xy 320.212389 -86.195769) (xy 320.259995 -86.224823)
			(xy 320.268295 -86.23173) (xy 325.625458 -86.23173) (xy 325.629529 -86.176108) (xy 325.641655 -86.121671)
			(xy 325.661578 -86.06958) (xy 325.688874 -86.020945) (xy 325.72296 -85.976802) (xy 325.763109 -85.938093)
			(xy 325.808467 -85.905642) (xy 325.858067 -85.880141) (xy 325.910851 -85.862134) (xy 325.965694 -85.852004)
			(xy 326.021428 -85.849967) (xy 326.076865 -85.856067) (xy 326.130822 -85.870173) (xy 326.182151 -85.891985)
			(xy 326.229757 -85.921039) (xy 326.272625 -85.956714) (xy 326.309842 -85.998251) (xy 326.340615 -86.044764)
			(xy 326.364287 -86.095261) (xy 326.380355 -86.148668) (xy 326.388475 -86.203844) (xy 326.388984 -86.23173)
			(xy 326.388475 -86.259616) (xy 326.383937 -86.290449) (xy 329.920604 -86.290449) (xy 329.920604 -86.235951)
			(xy 329.92836 -86.182007) (xy 329.943714 -86.129716) (xy 329.966354 -86.080142) (xy 329.995818 -86.034295)
			(xy 330.031507 -85.993107) (xy 330.072695 -85.957418) (xy 330.118542 -85.927954) (xy 330.168116 -85.905314)
			(xy 330.220407 -85.88996) (xy 330.274351 -85.882204) (xy 330.3016 -85.881718) (xy 330.327509 -85.882125)
			(xy 330.378849 -85.889162) (xy 330.428764 -85.90308) (xy 330.476338 -85.923622) (xy 330.520695 -85.950411)
			(xy 330.56102 -85.982955) (xy 330.596573 -86.020655) (xy 330.611988 -86.041484) (xy 330.617797 -86.048828)
			(xy 330.633426 -86.059115) (xy 330.642468 -86.06155) (xy 330.67244 -86.068408) (xy 330.681735 -86.070112)
			(xy 330.7004 -86.067224) (xy 330.708762 -86.06282) (xy 330.734719 -86.048577) (xy 330.789527 -86.02618)
			(xy 330.846762 -86.011023) (xy 330.905472 -86.003361) (xy 330.935076 -86.002876) (xy 330.935584 -86.002876)
			(xy 330.965551 -86.003397) (xy 331.024971 -86.011218) (xy 331.082863 -86.026728) (xy 331.138235 -86.049661)
			(xy 331.19014 -86.079626) (xy 331.237689 -86.116109) (xy 331.28007 -86.158487) (xy 331.316556 -86.206034)
			(xy 331.346525 -86.257936) (xy 331.347349 -86.259924) (xy 333.146144 -86.259924) (xy 333.150215 -86.204302)
			(xy 333.162341 -86.149865) (xy 333.182264 -86.097774) (xy 333.20956 -86.049139) (xy 333.243646 -86.004996)
			(xy 333.283795 -85.966287) (xy 333.329153 -85.933836) (xy 333.378753 -85.908335) (xy 333.431537 -85.890328)
			(xy 333.48638 -85.880198) (xy 333.542114 -85.878161) (xy 333.597551 -85.884261) (xy 333.651508 -85.898367)
			(xy 333.702837 -85.920179) (xy 333.750443 -85.949233) (xy 333.793311 -85.984908) (xy 333.830528 -86.026445)
			(xy 333.861301 -86.072958) (xy 333.884973 -86.123455) (xy 333.901041 -86.176862) (xy 333.909161 -86.232038)
			(xy 333.90967 -86.259924) (xy 333.909161 -86.28781) (xy 333.901041 -86.342986) (xy 333.884973 -86.396393)
			(xy 333.861301 -86.44689) (xy 333.830528 -86.493403) (xy 333.793311 -86.53494) (xy 333.750443 -86.570615)
			(xy 333.702837 -86.599669) (xy 333.651508 -86.621481) (xy 333.597551 -86.635587) (xy 333.542114 -86.641687)
			(xy 333.48638 -86.63965) (xy 333.431537 -86.62952) (xy 333.378753 -86.611513) (xy 333.329153 -86.586012)
			(xy 333.283795 -86.553561) (xy 333.243646 -86.514852) (xy 333.20956 -86.470709) (xy 333.182264 -86.422074)
			(xy 333.162341 -86.369983) (xy 333.150215 -86.315546) (xy 333.146144 -86.259924) (xy 331.347349 -86.259924)
			(xy 331.369462 -86.313307) (xy 331.384976 -86.371197) (xy 331.392801 -86.430617) (xy 331.393292 -86.460584)
			(xy 331.393292 -87.324184) (xy 331.392824 -87.354153) (xy 331.385002 -87.413579) (xy 331.36949 -87.471476)
			(xy 331.346554 -87.526852) (xy 331.316585 -87.578761) (xy 331.280097 -87.626314) (xy 331.237714 -87.668697)
			(xy 331.190161 -87.705185) (xy 331.138252 -87.735154) (xy 331.082876 -87.75809) (xy 331.024979 -87.773602)
			(xy 330.965553 -87.781424) (xy 330.935584 -87.781892) (xy 330.934822 -87.781892) (xy 330.90529 -87.781402)
			(xy 330.846721 -87.773775) (xy 330.789618 -87.758683) (xy 330.734928 -87.736377) (xy 330.709016 -87.722202)
			(xy 330.700622 -87.717892) (xy 330.681993 -87.715017) (xy 330.672694 -87.716614) (xy 330.642722 -87.723472)
			(xy 330.63364 -87.725822) (xy 330.617976 -87.736115) (xy 330.612242 -87.743538) (xy 330.596837 -87.764409)
			(xy 330.561273 -87.802173) (xy 330.520921 -87.83477) (xy 330.476524 -87.8616) (xy 330.428902 -87.882168)
			(xy 330.378933 -87.896095) (xy 330.327537 -87.903122) (xy 330.3016 -87.903558) (xy 330.274352 -87.902972)
			(xy 330.220412 -87.895216) (xy 330.168124 -87.879863) (xy 330.118553 -87.857225) (xy 330.072709 -87.827763)
			(xy 330.031524 -87.792076) (xy 329.995837 -87.750891) (xy 329.966375 -87.705047) (xy 329.943737 -87.655476)
			(xy 329.928384 -87.603188) (xy 329.920628 -87.549248) (xy 329.920628 -87.494752) (xy 329.928384 -87.440812)
			(xy 329.943737 -87.388524) (xy 329.966375 -87.338953) (xy 329.995837 -87.293109) (xy 330.031524 -87.251924)
			(xy 330.072709 -87.216237) (xy 330.118553 -87.186775) (xy 330.168124 -87.164137) (xy 330.220412 -87.148784)
			(xy 330.274352 -87.141028) (xy 330.3016 -87.140542) (xy 330.316393 -87.140675) (xy 330.345891 -87.142966)
			(xy 330.360528 -87.145114) (xy 330.371502 -87.146245) (xy 330.392694 -87.14018) (xy 330.401422 -87.13343)
			(xy 330.460096 -87.083392) (xy 330.46812 -87.075821) (xy 330.477338 -87.055803) (xy 330.477876 -87.044784)
			(xy 330.477876 -86.740492) (xy 330.47735 -86.729471) (xy 330.468123 -86.709455) (xy 330.460096 -86.701884)
			(xy 330.401422 -86.651846) (xy 330.392709 -86.645061) (xy 330.371507 -86.63899) (xy 330.360528 -86.640162)
			(xy 330.345891 -86.642306) (xy 330.316393 -86.644592) (xy 330.3016 -86.644734) (xy 330.274351 -86.644196)
			(xy 330.220407 -86.63644) (xy 330.168116 -86.621086) (xy 330.118542 -86.598446) (xy 330.072695 -86.568982)
			(xy 330.031507 -86.533293) (xy 329.995818 -86.492105) (xy 329.966354 -86.446258) (xy 329.943714 -86.396684)
			(xy 329.92836 -86.344393) (xy 329.920604 -86.290449) (xy 326.383937 -86.290449) (xy 326.380355 -86.314792)
			(xy 326.364287 -86.368199) (xy 326.340615 -86.418696) (xy 326.309842 -86.465209) (xy 326.272625 -86.506746)
			(xy 326.229757 -86.542421) (xy 326.182151 -86.571475) (xy 326.130822 -86.593287) (xy 326.076865 -86.607393)
			(xy 326.021428 -86.613493) (xy 325.965694 -86.611456) (xy 325.910851 -86.601326) (xy 325.858067 -86.583319)
			(xy 325.808467 -86.557818) (xy 325.763109 -86.525367) (xy 325.72296 -86.486658) (xy 325.688874 -86.442515)
			(xy 325.661578 -86.39388) (xy 325.641655 -86.341789) (xy 325.629529 -86.287352) (xy 325.625458 -86.23173)
			(xy 320.268295 -86.23173) (xy 320.302863 -86.260498) (xy 320.34008 -86.302035) (xy 320.370853 -86.348548)
			(xy 320.394525 -86.399045) (xy 320.410593 -86.452452) (xy 320.418713 -86.507628) (xy 320.419222 -86.535514)
			(xy 320.418713 -86.5634) (xy 320.410593 -86.618576) (xy 320.394525 -86.671983) (xy 320.370853 -86.72248)
			(xy 320.34008 -86.768993) (xy 320.302863 -86.81053) (xy 320.259995 -86.846205) (xy 320.212389 -86.875259)
			(xy 320.16106 -86.897071) (xy 320.107103 -86.911177) (xy 320.051666 -86.917277) (xy 319.995932 -86.91524)
			(xy 319.941089 -86.90511) (xy 319.888305 -86.887103) (xy 319.838705 -86.861602) (xy 319.793347 -86.829151)
			(xy 319.753198 -86.790442) (xy 319.719112 -86.746299) (xy 319.691816 -86.697664) (xy 319.671893 -86.645573)
			(xy 319.659767 -86.591136) (xy 319.655696 -86.535514) (xy 319.401965 -86.535514) (xy 319.397266 -86.568199)
			(xy 319.381911 -86.620494) (xy 319.359269 -86.670071) (xy 319.329803 -86.715921) (xy 319.294112 -86.757112)
			(xy 319.252921 -86.792803) (xy 319.207071 -86.822269) (xy 319.157494 -86.844911) (xy 319.105199 -86.860266)
			(xy 319.051251 -86.868022) (xy 318.996749 -86.868022) (xy 318.942801 -86.860266) (xy 318.890506 -86.844911)
			(xy 318.840929 -86.822269) (xy 318.795079 -86.792803) (xy 318.753888 -86.757112) (xy 318.718197 -86.715921)
			(xy 318.688731 -86.670071) (xy 318.666089 -86.620494) (xy 318.650734 -86.568199) (xy 318.642978 -86.514251)
			(xy 318.642492 -86.487) (xy 316.010036 -86.487) (xy 317.942722 -88.419686) (xy 331.85303 -88.419686)
			(xy 331.857101 -88.364064) (xy 331.869227 -88.309627) (xy 331.88915 -88.257536) (xy 331.916446 -88.208901)
			(xy 331.950532 -88.164758) (xy 331.990681 -88.126049) (xy 332.036039 -88.093598) (xy 332.085639 -88.068097)
			(xy 332.138423 -88.05009) (xy 332.193266 -88.03996) (xy 332.249 -88.037923) (xy 332.304437 -88.044023)
			(xy 332.358394 -88.058129) (xy 332.409723 -88.079941) (xy 332.457329 -88.108995) (xy 332.500197 -88.14467)
			(xy 332.537414 -88.186207) (xy 332.568187 -88.23272) (xy 332.591859 -88.283217) (xy 332.607927 -88.336624)
			(xy 332.616047 -88.3918) (xy 332.616556 -88.419686) (xy 332.616047 -88.447572) (xy 332.607927 -88.502748)
			(xy 332.591859 -88.556155) (xy 332.568187 -88.606652) (xy 332.537414 -88.653165) (xy 332.500197 -88.694702)
			(xy 332.457329 -88.730377) (xy 332.409723 -88.759431) (xy 332.358394 -88.781243) (xy 332.304437 -88.795349)
			(xy 332.249 -88.801449) (xy 332.193266 -88.799412) (xy 332.138423 -88.789282) (xy 332.085639 -88.771275)
			(xy 332.036039 -88.745774) (xy 331.990681 -88.713323) (xy 331.950532 -88.674614) (xy 331.916446 -88.630471)
			(xy 331.88915 -88.581836) (xy 331.869227 -88.529745) (xy 331.857101 -88.475308) (xy 331.85303 -88.419686)
			(xy 317.942722 -88.419686) (xy 318.377316 -88.85428) (xy 328.314302 -88.85428) (xy 328.318373 -88.798658)
			(xy 328.330499 -88.744221) (xy 328.350422 -88.69213) (xy 328.377718 -88.643495) (xy 328.411804 -88.599352)
			(xy 328.451953 -88.560643) (xy 328.497311 -88.528192) (xy 328.546911 -88.502691) (xy 328.599695 -88.484684)
			(xy 328.654538 -88.474554) (xy 328.710272 -88.472517) (xy 328.765709 -88.478617) (xy 328.819666 -88.492723)
			(xy 328.870995 -88.514535) (xy 328.918601 -88.543589) (xy 328.961469 -88.579264) (xy 328.998686 -88.620801)
			(xy 329.029459 -88.667314) (xy 329.053131 -88.717811) (xy 329.069199 -88.771218) (xy 329.077319 -88.826394)
			(xy 329.077828 -88.85428) (xy 329.077319 -88.882166) (xy 329.069199 -88.937342) (xy 329.053131 -88.990749)
			(xy 329.029459 -89.041246) (xy 328.998686 -89.087759) (xy 328.961469 -89.129296) (xy 328.918601 -89.164971)
			(xy 328.870995 -89.194025) (xy 328.819666 -89.215837) (xy 328.765709 -89.229943) (xy 328.710272 -89.236043)
			(xy 328.654538 -89.234006) (xy 328.599695 -89.223876) (xy 328.546911 -89.205869) (xy 328.497311 -89.180368)
			(xy 328.451953 -89.147917) (xy 328.411804 -89.109208) (xy 328.377718 -89.065065) (xy 328.350422 -89.01643)
			(xy 328.330499 -88.964339) (xy 328.318373 -88.909902) (xy 328.314302 -88.85428) (xy 318.377316 -88.85428)
			(xy 318.792352 -89.269316) (xy 329.807568 -89.269316) (xy 329.811639 -89.213694) (xy 329.823765 -89.159257)
			(xy 329.843688 -89.107166) (xy 329.870984 -89.058531) (xy 329.90507 -89.014388) (xy 329.945219 -88.975679)
			(xy 329.990577 -88.943228) (xy 330.040177 -88.917727) (xy 330.092961 -88.89972) (xy 330.147804 -88.88959)
			(xy 330.203538 -88.887553) (xy 330.258975 -88.893653) (xy 330.312932 -88.907759) (xy 330.364261 -88.929571)
			(xy 330.411867 -88.958625) (xy 330.454735 -88.9943) (xy 330.491952 -89.035837) (xy 330.522725 -89.08235)
			(xy 330.546397 -89.132847) (xy 330.562465 -89.186254) (xy 330.570585 -89.24143) (xy 330.571094 -89.269316)
			(xy 330.570585 -89.297202) (xy 330.562465 -89.352378) (xy 330.546397 -89.405785) (xy 330.522725 -89.456282)
			(xy 330.491952 -89.502795) (xy 330.454735 -89.544332) (xy 330.411867 -89.580007) (xy 330.364261 -89.609061)
			(xy 330.312932 -89.630873) (xy 330.258975 -89.644979) (xy 330.203538 -89.651079) (xy 330.147804 -89.649042)
			(xy 330.092961 -89.638912) (xy 330.040177 -89.620905) (xy 329.990577 -89.595404) (xy 329.945219 -89.562953)
			(xy 329.90507 -89.524244) (xy 329.870984 -89.480101) (xy 329.843688 -89.431466) (xy 329.823765 -89.379375)
			(xy 329.811639 -89.324938) (xy 329.807568 -89.269316) (xy 318.792352 -89.269316) (xy 319.184274 -89.661238)
			(xy 319.184782 -89.661746) (xy 319.192164 -89.668324) (xy 319.210464 -89.675765) (xy 319.220342 -89.676224)
			(xy 326.60463 -89.676224) (xy 326.614697 -89.676653) (xy 326.633292 -89.684378) (xy 326.640698 -89.69121)
			(xy 327.615804 -90.666316) (xy 329.807568 -90.666316) (xy 329.811639 -90.610694) (xy 329.823765 -90.556257)
			(xy 329.843688 -90.504166) (xy 329.870984 -90.455531) (xy 329.90507 -90.411388) (xy 329.945219 -90.372679)
			(xy 329.990577 -90.340228) (xy 330.040177 -90.314727) (xy 330.092961 -90.29672) (xy 330.147804 -90.28659)
			(xy 330.203538 -90.284553) (xy 330.258975 -90.290653) (xy 330.312932 -90.304759) (xy 330.364261 -90.326571)
			(xy 330.411867 -90.355625) (xy 330.454735 -90.3913) (xy 330.491952 -90.432837) (xy 330.522725 -90.47935)
			(xy 330.546397 -90.529847) (xy 330.562465 -90.583254) (xy 330.570585 -90.63843) (xy 330.571094 -90.666316)
			(xy 330.570585 -90.694202) (xy 330.562465 -90.749378) (xy 330.546397 -90.802785) (xy 330.522725 -90.853282)
			(xy 330.491952 -90.899795) (xy 330.454735 -90.941332) (xy 330.411867 -90.977007) (xy 330.364261 -91.006061)
			(xy 330.312932 -91.027873) (xy 330.258975 -91.041979) (xy 330.203538 -91.048079) (xy 330.147804 -91.046042)
			(xy 330.092961 -91.035912) (xy 330.040177 -91.017905) (xy 329.990577 -90.992404) (xy 329.945219 -90.959953)
			(xy 329.90507 -90.921244) (xy 329.870984 -90.877101) (xy 329.843688 -90.828466) (xy 329.823765 -90.776375)
			(xy 329.811639 -90.721938) (xy 329.807568 -90.666316) (xy 327.615804 -90.666316) (xy 329.232768 -92.28328)
			(xy 329.239605 -92.290681) (xy 329.247316 -92.30928) (xy 329.247754 -92.319348) (xy 329.247754 -93.648784)
			(xy 329.248194 -93.658846) (xy 329.255936 -93.677423) (xy 329.26274 -93.684852) (xy 329.590146 -94.012258)
			(xy 329.598266 -94.019635) (xy 329.618804 -94.027284) (xy 329.62977 -94.02699) (xy 329.7174 -94.02064)
			(xy 329.736704 -94.009972) (xy 329.743308 -94.001082) (xy 329.761442 -93.977532) (xy 329.803776 -93.935812)
			(xy 329.852061 -93.901154) (xy 329.905132 -93.874394) (xy 329.961708 -93.856178) (xy 330.020422 -93.846946)
			(xy 330.05014 -93.846396) (xy 330.077389 -93.846885) (xy 330.131332 -93.854646) (xy 330.183622 -93.870004)
			(xy 330.233194 -93.892648) (xy 330.279039 -93.922115) (xy 330.320224 -93.957807) (xy 330.355911 -93.998996)
			(xy 330.385373 -94.044845) (xy 330.408011 -94.094419) (xy 330.423364 -94.146711) (xy 330.431119 -94.200655)
			(xy 330.431648 -94.227904) (xy 330.431648 -94.228158) (xy 330.431334 -94.244922) (xy 330.620114 -94.244922)
			(xy 330.624185 -94.1893) (xy 330.636311 -94.134863) (xy 330.656234 -94.082772) (xy 330.68353 -94.034137)
			(xy 330.717616 -93.989994) (xy 330.757765 -93.951285) (xy 330.803123 -93.918834) (xy 330.852723 -93.893333)
			(xy 330.905507 -93.875326) (xy 330.96035 -93.865196) (xy 331.016084 -93.863159) (xy 331.071521 -93.869259)
			(xy 331.125478 -93.883365) (xy 331.176807 -93.905177) (xy 331.224413 -93.934231) (xy 331.267281 -93.969906)
			(xy 331.304498 -94.011443) (xy 331.335271 -94.057956) (xy 331.358943 -94.108453) (xy 331.375011 -94.16186)
			(xy 331.383131 -94.217036) (xy 331.383469 -94.235551) (xy 331.955101 -94.235551) (xy 331.955101 -94.181049)
			(xy 331.962858 -94.127101) (xy 331.978215 -94.074806) (xy 332.000857 -94.025229) (xy 332.030325 -93.97938)
			(xy 332.066019 -93.938191) (xy 332.107212 -93.902501) (xy 332.153064 -93.873038) (xy 332.202643 -93.850401)
			(xy 332.25494 -93.83505) (xy 332.308889 -93.827298) (xy 332.33614 -93.826838) (xy 332.362303 -93.827297)
			(xy 332.414139 -93.834448) (xy 332.464513 -93.84861) (xy 332.512481 -93.869518) (xy 332.557145 -93.89678)
			(xy 332.597668 -93.929886) (xy 332.615794 -93.948758) (xy 332.623414 -93.95714) (xy 332.64348 -93.965268)
			(xy 332.74254 -93.96222) (xy 332.762352 -93.952314) (xy 332.76921 -93.943678) (xy 332.787409 -93.921946)
			(xy 332.829165 -93.883613) (xy 332.876134 -93.851881) (xy 332.927282 -93.82745) (xy 332.981482 -93.810856)
			(xy 333.03754 -93.802465) (xy 333.065882 -93.801946) (xy 333.093132 -93.8025) (xy 333.147079 -93.810254)
			(xy 333.199372 -93.825607) (xy 333.248949 -93.848245) (xy 333.294799 -93.877709) (xy 333.335989 -93.913399)
			(xy 333.37168 -93.954587) (xy 333.401146 -94.000435) (xy 333.423787 -94.050011) (xy 333.439142 -94.102304)
			(xy 333.446899 -94.15625) (xy 333.446899 -94.21075) (xy 333.443738 -94.23273) (xy 335.127344 -94.23273)
			(xy 335.131415 -94.177108) (xy 335.143541 -94.122671) (xy 335.163464 -94.07058) (xy 335.19076 -94.021945)
			(xy 335.224846 -93.977802) (xy 335.264995 -93.939093) (xy 335.310353 -93.906642) (xy 335.359953 -93.881141)
			(xy 335.412737 -93.863134) (xy 335.46758 -93.853004) (xy 335.523314 -93.850967) (xy 335.578751 -93.857067)
			(xy 335.632708 -93.871173) (xy 335.684037 -93.892985) (xy 335.731643 -93.922039) (xy 335.774511 -93.957714)
			(xy 335.811728 -93.999251) (xy 335.842501 -94.045764) (xy 335.866173 -94.096261) (xy 335.882241 -94.149668)
			(xy 335.890361 -94.204844) (xy 335.89087 -94.23273) (xy 335.890361 -94.260616) (xy 335.882241 -94.315792)
			(xy 335.866173 -94.369199) (xy 335.842501 -94.419696) (xy 335.811728 -94.466209) (xy 335.774511 -94.507746)
			(xy 335.731643 -94.543421) (xy 335.684037 -94.572475) (xy 335.632708 -94.594287) (xy 335.578751 -94.608393)
			(xy 335.523314 -94.614493) (xy 335.46758 -94.612456) (xy 335.412737 -94.602326) (xy 335.359953 -94.584319)
			(xy 335.310353 -94.558818) (xy 335.264995 -94.526367) (xy 335.224846 -94.487658) (xy 335.19076 -94.443515)
			(xy 335.163464 -94.39488) (xy 335.143541 -94.342789) (xy 335.131415 -94.288352) (xy 335.127344 -94.23273)
			(xy 333.443738 -94.23273) (xy 333.439142 -94.264696) (xy 333.423787 -94.316989) (xy 333.401146 -94.366565)
			(xy 333.37168 -94.412413) (xy 333.335989 -94.453601) (xy 333.294799 -94.489291) (xy 333.248949 -94.518755)
			(xy 333.199372 -94.541393) (xy 333.147079 -94.556746) (xy 333.093132 -94.5645) (xy 333.065882 -94.564962)
			(xy 333.039717 -94.564555) (xy 332.987879 -94.557394) (xy 332.937504 -94.543221) (xy 332.889536 -94.522304)
			(xy 332.844873 -94.495032) (xy 332.804353 -94.461918) (xy 332.786228 -94.443042) (xy 332.778608 -94.43466)
			(xy 332.758542 -94.426532) (xy 332.659482 -94.42958) (xy 332.63967 -94.439486) (xy 332.632812 -94.448122)
			(xy 332.614601 -94.469844) (xy 332.572847 -94.508177) (xy 332.525881 -94.53991) (xy 332.474736 -94.564344)
			(xy 332.420538 -94.58094) (xy 332.364481 -94.589333) (xy 332.33614 -94.589854) (xy 332.308889 -94.589302)
			(xy 332.25494 -94.58155) (xy 332.202643 -94.566199) (xy 332.153064 -94.543562) (xy 332.107212 -94.514099)
			(xy 332.066019 -94.478409) (xy 332.030325 -94.43722) (xy 332.000857 -94.391371) (xy 331.978215 -94.341794)
			(xy 331.962858 -94.289499) (xy 331.955101 -94.235551) (xy 331.383469 -94.235551) (xy 331.38364 -94.244922)
			(xy 331.383131 -94.272808) (xy 331.375011 -94.327984) (xy 331.358943 -94.381391) (xy 331.335271 -94.431888)
			(xy 331.304498 -94.478401) (xy 331.267281 -94.519938) (xy 331.224413 -94.555613) (xy 331.176807 -94.584667)
			(xy 331.125478 -94.606479) (xy 331.071521 -94.620585) (xy 331.016084 -94.626685) (xy 330.96035 -94.624648)
			(xy 330.905507 -94.614518) (xy 330.852723 -94.596511) (xy 330.803123 -94.57101) (xy 330.757765 -94.538559)
			(xy 330.717616 -94.49985) (xy 330.68353 -94.455707) (xy 330.656234 -94.407072) (xy 330.636311 -94.354981)
			(xy 330.624185 -94.300544) (xy 330.620114 -94.244922) (xy 330.431334 -94.244922) (xy 330.431092 -94.257831)
			(xy 330.421909 -94.31646) (xy 330.403743 -94.372956) (xy 330.377034 -94.42595) (xy 330.342428 -94.47416)
			(xy 330.300763 -94.516419) (xy 330.277216 -94.534482) (xy 330.268072 -94.541086) (xy 330.257404 -94.560644)
			(xy 330.251054 -94.648274) (xy 330.250761 -94.659242) (xy 330.258401 -94.679784) (xy 330.265786 -94.687898)
			(xy 330.334112 -94.756224) (xy 330.341508 -94.763077) (xy 330.360106 -94.770819) (xy 330.37018 -94.77121)
			(xy 331.886306 -94.77121) (xy 331.900022 -94.773242) (xy 331.903324 -94.774258) (xy 331.923898 -94.78264)
			(xy 331.928469 -94.784356) (xy 331.938065 -94.786157) (xy 331.942948 -94.786196) (xy 333.203042 -94.786196)
			(xy 333.213109 -94.786627) (xy 333.231703 -94.794352) (xy 333.23911 -94.801182) (xy 333.25689 -94.818962)
			(xy 333.262478 -94.823788) (xy 333.443072 -94.823788) (xy 333.455518 -94.836234) (xy 333.481963 -94.839983)
			(xy 333.533188 -94.855095) (xy 333.581218 -94.878453) (xy 333.624736 -94.909414) (xy 333.643986 -94.927928)
			(xy 333.825596 -95.109792) (xy 333.832994 -95.11664) (xy 333.851592 -95.124377) (xy 333.861664 -95.124778)
		)
		(stroke
			(width 0)
			(type solid)
		)
		(fill yes)
		(layer "In9.Cu")
		(net "P3V3")
	)
	(gr_poly
		(pts
			(xy 122.304048 -61.571632) (xy 122.31366 -61.571224) (xy 122.331551 -61.564187) (xy 122.338846 -61.557916)
			(xy 122.3391 -61.557662) (xy 122.391932 -61.506862) (xy 122.40006 -61.489082) (xy 122.400314 -61.478922)
			(xy 122.401899 -61.45013) (xy 122.412664 -61.393481) (xy 122.431836 -61.339099) (xy 122.458976 -61.288223)
			(xy 122.493467 -61.242013) (xy 122.513598 -61.221366) (xy 122.531614 -61.203502) (xy 122.57155 -61.17221)
			(xy 122.615282 -61.146489) (xy 122.662038 -61.126791) (xy 122.710992 -61.113465) (xy 122.76128 -61.106746)
			(xy 122.786648 -61.106304) (xy 122.81368 -61.106777) (xy 122.867202 -61.114415) (xy 122.919111 -61.129531)
			(xy 122.968366 -61.151821) (xy 123.013982 -61.180841) (xy 123.055046 -61.216009) (xy 123.090734 -61.256621)
			(xy 123.120333 -61.301863) (xy 123.143251 -61.35083) (xy 123.159027 -61.402541) (xy 123.167346 -61.455962)
			(xy 123.168156 -61.482986) (xy 123.16841 -61.493146) (xy 123.176284 -61.511688) (xy 123.223782 -61.557408)
			(xy 123.224544 -61.55817) (xy 123.231806 -61.564346) (xy 123.249561 -61.571249) (xy 123.259088 -61.571632)
			(xy 126.876302 -61.571632) (xy 126.879589 -61.569984) (xy 126.885709 -61.565906) (xy 126.888494 -61.563504)
			(xy 126.981966 -61.470032) (xy 126.98222 -61.470032) (xy 127.099568 -61.35243) (xy 127.239522 -61.212476)
			(xy 127.516636 -60.935362) (xy 127.523448 -60.928018) (xy 127.531176 -60.909555) (xy 127.531622 -60.899548)
			(xy 127.531622 -38.905688) (xy 127.53086 -38.897052) (xy 127.52832 -38.883082) (xy 127.519938 -38.868096)
			(xy 127.513334 -38.862254) (xy 127.481861 -38.83407) (xy 127.423559 -38.772918) (xy 127.37098 -38.706779)
			(xy 127.32455 -38.636189) (xy 127.284643 -38.561716) (xy 127.251581 -38.483963) (xy 127.22563 -38.403555)
			(xy 127.207001 -38.321143) (xy 127.195843 -38.237392) (xy 127.192247 -38.152978) (xy 127.196242 -38.068581)
			(xy 127.207795 -37.984883) (xy 127.226814 -37.902561) (xy 127.253144 -37.822277) (xy 127.286574 -37.74468)
			(xy 127.326832 -37.670397) (xy 127.373596 -37.600027) (xy 127.426486 -37.534138) (xy 127.455422 -37.503354)
			(xy 127.455676 -37.5031) (xy 127.456184 -37.502592) (xy 127.488188 -37.470334) (xy 127.514604 -37.446204)
			(xy 127.522226 -37.438639) (xy 127.531029 -37.41908) (xy 127.531622 -37.408358) (xy 127.531622 -31.238444)
			(xy 127.531736 -31.233488) (xy 127.533645 -31.223763) (xy 127.535432 -31.21914) (xy 127.544322 -31.198058)
			(xy 127.544322 -29.841698) (xy 127.544052 -29.833762) (xy 127.539256 -29.818636) (xy 127.534924 -29.81198)
			(xy 127.518112 -29.787563) (xy 127.491448 -29.734619) (xy 127.473303 -29.678186) (xy 127.464112 -29.619623)
			(xy 127.46355 -29.589984) (xy 127.464134 -29.560347) (xy 127.473339 -29.501791) (xy 127.491481 -29.44536)
			(xy 127.518122 -29.392409) (xy 127.534924 -29.367988) (xy 127.539282 -29.361346) (xy 127.544071 -29.34621)
			(xy 127.544322 -29.33827) (xy 127.544322 -28.112974) (xy 127.544442 -28.108426) (xy 127.546096 -28.099479)
			(xy 127.547624 -28.095194) (xy 127.549389 -28.090051) (xy 127.550921 -28.07929) (xy 127.550672 -28.073858)
			(xy 127.54864 -28.044394) (xy 127.547931 -28.037137) (xy 127.542888 -28.023463) (xy 127.538734 -28.01747)
			(xy 127.521053 -27.992658) (xy 127.492975 -27.938592) (xy 127.473853 -27.880749) (xy 127.464173 -27.820601)
			(xy 127.46355 -27.79014) (xy 127.464033 -27.762886) (xy 127.471785 -27.708931) (xy 127.487136 -27.65663)
			(xy 127.509774 -27.607045) (xy 127.539239 -27.561186) (xy 127.57493 -27.519988) (xy 127.61612 -27.484288)
			(xy 127.661973 -27.454814) (xy 127.711553 -27.432165) (xy 127.763851 -27.416802) (xy 127.817804 -27.409039)
			(xy 127.845058 -27.408632) (xy 127.870604 -27.409045) (xy 127.92124 -27.415867) (xy 127.970513 -27.429382)
			(xy 128.017543 -27.449348) (xy 128.06149 -27.475408) (xy 128.081786 -27.490928) (xy 128.097026 -27.50312)
			(xy 128.13538 -27.500834) (xy 128.288542 -27.347672) (xy 128.295939 -27.340824) (xy 128.314538 -27.333094)
			(xy 128.32461 -27.332686) (xy 128.471168 -27.332686) (xy 128.475486 -27.331924) (xy 128.495806 -27.32913)
			(xy 128.49606 -27.32913) (xy 128.527556 -27.327352) (xy 132.57276 -27.327352) (xy 132.582783 -27.326939)
			(xy 132.601305 -27.319274) (xy 132.615479 -27.305099) (xy 132.62314 -27.286575) (xy 132.62356 -27.276552)
			(xy 132.62356 -26.478992) (xy 132.623696 -26.463769) (xy 132.625728 -26.433391) (xy 132.627624 -26.418286)
			(xy 132.627624 -26.418032) (xy 132.629402 -26.407618) (xy 132.629402 -26.407364) (xy 132.631688 -26.39441)
			(xy 132.634482 -26.379424) (xy 132.623306 -26.352246) (xy 132.602986 -26.338022) (xy 132.597188 -26.334105)
			(xy 132.584039 -26.329341) (xy 132.577078 -26.328624) (xy 132.563108 -26.327862) (xy 132.550408 -26.334212)
			(xy 132.550154 -26.334466) (xy 132.523049 -26.347747) (xy 132.46569 -26.366533) (xy 132.406088 -26.376053)
			(xy 132.37591 -26.37663) (xy 132.348658 -26.376145) (xy 132.294708 -26.36839) (xy 132.242411 -26.353036)
			(xy 132.192831 -26.330395) (xy 132.146977 -26.30093) (xy 132.105784 -26.265238) (xy 132.070089 -26.224048)
			(xy 132.04062 -26.178197) (xy 132.017976 -26.12862) (xy 132.002617 -26.076324) (xy 131.994857 -26.022374)
			(xy 131.994402 -25.995122) (xy 131.994978 -25.96489) (xy 132.004515 -25.905182) (xy 132.023353 -25.847727)
			(xy 132.05102 -25.793963) (xy 132.086823 -25.745239) (xy 132.10794 -25.723596) (xy 132.126017 -25.705671)
			(xy 132.166098 -25.674285) (xy 132.209998 -25.648508) (xy 132.256936 -25.628798) (xy 132.306078 -25.615506)
			(xy 132.356551 -25.608869) (xy 132.382006 -25.608534) (xy 132.387086 -25.608534) (xy 132.415712 -25.609504)
			(xy 132.472201 -25.618965) (xy 132.526641 -25.636763) (xy 132.577811 -25.662497) (xy 132.62456 -25.695588)
			(xy 132.665838 -25.735295) (xy 132.700719 -25.780724) (xy 132.728419 -25.830856) (xy 132.728863 -25.832054)
			(xy 134.28802 -25.832054) (xy 134.292091 -25.776432) (xy 134.304217 -25.721995) (xy 134.32414 -25.669904)
			(xy 134.351436 -25.621269) (xy 134.385522 -25.577126) (xy 134.425671 -25.538417) (xy 134.471029 -25.505966)
			(xy 134.520629 -25.480465) (xy 134.573413 -25.462458) (xy 134.628256 -25.452328) (xy 134.68399 -25.450291)
			(xy 134.739427 -25.456391) (xy 134.793384 -25.470497) (xy 134.844713 -25.492309) (xy 134.892319 -25.521363)
			(xy 134.935187 -25.557038) (xy 134.936721 -25.55875) (xy 138.74242 -25.55875) (xy 138.742906 -25.531499)
			(xy 138.750662 -25.477551) (xy 138.766017 -25.425256) (xy 138.788659 -25.375679) (xy 138.818125 -25.329829)
			(xy 138.853816 -25.288638) (xy 138.895007 -25.252947) (xy 138.940857 -25.223481) (xy 138.990434 -25.200839)
			(xy 139.042729 -25.185484) (xy 139.096677 -25.177728) (xy 139.151179 -25.177728) (xy 139.205127 -25.185484)
			(xy 139.257422 -25.200839) (xy 139.306999 -25.223481) (xy 139.352849 -25.252947) (xy 139.39404 -25.288638)
			(xy 139.429731 -25.329829) (xy 139.459197 -25.375679) (xy 139.481839 -25.425256) (xy 139.497194 -25.477551)
			(xy 139.50495 -25.531499) (xy 139.505436 -25.55875) (xy 139.50488 -25.589013) (xy 139.495328 -25.648779)
			(xy 139.476455 -25.706286) (xy 139.448736 -25.760091) (xy 139.431268 -25.78481) (xy 139.422989 -25.796956)
			(xy 139.41304 -25.824599) (xy 139.411372 -25.853932) (xy 139.418125 -25.882524) (xy 139.432739 -25.908011)
			(xy 139.454005 -25.928283) (xy 139.480162 -25.941661) (xy 139.494514 -25.94483) (xy 139.520409 -25.950164)
			(xy 139.570532 -25.966982) (xy 139.617851 -25.990562) (xy 139.661459 -26.020452) (xy 139.700521 -26.056079)
			(xy 139.734287 -26.096761) (xy 139.76211 -26.141716) (xy 139.783457 -26.190084) (xy 139.797918 -26.240937)
			(xy 139.805216 -26.2933) (xy 139.805664 -26.319734) (xy 140.942058 -26.319734) (xy 140.946129 -26.264112)
			(xy 140.958255 -26.209675) (xy 140.978178 -26.157584) (xy 141.005474 -26.108949) (xy 141.03956 -26.064806)
			(xy 141.079709 -26.026097) (xy 141.125067 -25.993646) (xy 141.174667 -25.968145) (xy 141.227451 -25.950138)
			(xy 141.282294 -25.940008) (xy 141.338028 -25.937971) (xy 141.393465 -25.944071) (xy 141.447422 -25.958177)
			(xy 141.498751 -25.979989) (xy 141.546357 -26.009043) (xy 141.589225 -26.044718) (xy 141.626442 -26.086255)
			(xy 141.657215 -26.132768) (xy 141.680887 -26.183265) (xy 141.696955 -26.236672) (xy 141.705075 -26.291848)
			(xy 141.705584 -26.319734) (xy 141.705075 -26.34762) (xy 141.696955 -26.402796) (xy 141.680887 -26.456203)
			(xy 141.657215 -26.5067) (xy 141.626442 -26.553213) (xy 141.589225 -26.59475) (xy 141.546357 -26.630425)
			(xy 141.498751 -26.659479) (xy 141.447422 -26.681291) (xy 141.393465 -26.695397) (xy 141.338028 -26.701497)
			(xy 141.282294 -26.69946) (xy 141.227451 -26.68933) (xy 141.174667 -26.671323) (xy 141.125067 -26.645822)
			(xy 141.079709 -26.613371) (xy 141.03956 -26.574662) (xy 141.005474 -26.530519) (xy 140.978178 -26.481884)
			(xy 140.958255 -26.429793) (xy 140.946129 -26.375356) (xy 140.942058 -26.319734) (xy 139.805664 -26.319734)
			(xy 139.805178 -26.346985) (xy 139.797422 -26.400933) (xy 139.782067 -26.453228) (xy 139.759425 -26.502805)
			(xy 139.729959 -26.548655) (xy 139.694268 -26.589846) (xy 139.653077 -26.625537) (xy 139.607227 -26.655003)
			(xy 139.55765 -26.677645) (xy 139.505355 -26.693) (xy 139.451407 -26.700756) (xy 139.396905 -26.700756)
			(xy 139.342957 -26.693) (xy 139.290662 -26.677645) (xy 139.241085 -26.655003) (xy 139.195235 -26.625537)
			(xy 139.154044 -26.589846) (xy 139.118353 -26.548655) (xy 139.088887 -26.502805) (xy 139.066245 -26.453228)
			(xy 139.05089 -26.400933) (xy 139.043134 -26.346985) (xy 139.042648 -26.319734) (xy 139.043199 -26.289471)
			(xy 139.052753 -26.229705) (xy 139.071627 -26.172197) (xy 139.099348 -26.118393) (xy 139.116816 -26.093674)
			(xy 139.125125 -26.081546) (xy 139.135074 -26.053897) (xy 139.13674 -26.024558) (xy 139.129982 -25.99596)
			(xy 139.115362 -25.97047) (xy 139.09409 -25.950198) (xy 139.067926 -25.936821) (xy 139.05357 -25.933654)
			(xy 139.027669 -25.928347) (xy 138.977545 -25.911526) (xy 138.930226 -25.887943) (xy 138.886617 -25.858049)
			(xy 138.847555 -25.822419) (xy 138.81379 -25.781735) (xy 138.785968 -25.736776) (xy 138.764623 -25.688406)
			(xy 138.750163 -25.63755) (xy 138.742867 -25.585185) (xy 138.74242 -25.55875) (xy 134.936721 -25.55875)
			(xy 134.972404 -25.598575) (xy 135.003177 -25.645088) (xy 135.026849 -25.695585) (xy 135.042917 -25.748992)
			(xy 135.051037 -25.804168) (xy 135.051546 -25.832054) (xy 135.051037 -25.85994) (xy 135.042917 -25.915116)
			(xy 135.026849 -25.968523) (xy 135.003177 -26.01902) (xy 134.972404 -26.065533) (xy 134.935187 -26.10707)
			(xy 134.892319 -26.142745) (xy 134.844713 -26.171799) (xy 134.793384 -26.193611) (xy 134.739427 -26.207717)
			(xy 134.68399 -26.213817) (xy 134.628256 -26.21178) (xy 134.573413 -26.20165) (xy 134.520629 -26.183643)
			(xy 134.471029 -26.158142) (xy 134.425671 -26.125691) (xy 134.385522 -26.086982) (xy 134.351436 -26.042839)
			(xy 134.32414 -25.994204) (xy 134.304217 -25.942113) (xy 134.292091 -25.887676) (xy 134.28802 -25.832054)
			(xy 132.728863 -25.832054) (xy 132.748316 -25.884565) (xy 132.759963 -25.940644) (xy 132.76199 -25.969214)
			(xy 132.76199 -25.969468) (xy 132.762752 -25.981914) (xy 132.768848 -25.992328) (xy 132.772116 -25.99757)
			(xy 132.780729 -26.006422) (xy 132.785866 -26.009854) (xy 132.856224 -26.053796) (xy 132.861409 -26.056879)
			(xy 132.872837 -26.060731) (xy 132.87883 -26.061416) (xy 132.891784 -26.062432) (xy 132.921355 -26.049578)
			(xy 132.983206 -26.031365) (xy 133.047001 -26.022007) (xy 133.079236 -26.021284) (xy 133.081522 -26.021284)
			(xy 133.111506 -26.021755) (xy 133.17096 -26.029585) (xy 133.228883 -26.045109) (xy 133.284284 -26.068061)
			(xy 133.336215 -26.098048) (xy 133.383788 -26.134557) (xy 133.426188 -26.176963) (xy 133.46269 -26.224542)
			(xy 133.492669 -26.276477) (xy 133.515613 -26.331882) (xy 133.523381 -26.360882) (xy 136.20572 -26.360882)
			(xy 136.209791 -26.30526) (xy 136.221917 -26.250823) (xy 136.24184 -26.198732) (xy 136.269136 -26.150097)
			(xy 136.303222 -26.105954) (xy 136.343371 -26.067245) (xy 136.388729 -26.034794) (xy 136.438329 -26.009293)
			(xy 136.491113 -25.991286) (xy 136.545956 -25.981156) (xy 136.60169 -25.979119) (xy 136.657127 -25.985219)
			(xy 136.711084 -25.999325) (xy 136.762413 -26.021137) (xy 136.810019 -26.050191) (xy 136.852887 -26.085866)
			(xy 136.890104 -26.127403) (xy 136.920877 -26.173916) (xy 136.944549 -26.224413) (xy 136.960617 -26.27782)
			(xy 136.968737 -26.332996) (xy 136.969246 -26.360882) (xy 136.968737 -26.388768) (xy 136.960617 -26.443944)
			(xy 136.944549 -26.497351) (xy 136.920877 -26.547848) (xy 136.890104 -26.594361) (xy 136.852887 -26.635898)
			(xy 136.810019 -26.671573) (xy 136.762413 -26.700627) (xy 136.711084 -26.722439) (xy 136.657127 -26.736545)
			(xy 136.60169 -26.742645) (xy 136.545956 -26.740608) (xy 136.491113 -26.730478) (xy 136.438329 -26.712471)
			(xy 136.388729 -26.68697) (xy 136.343371 -26.654519) (xy 136.303222 -26.61581) (xy 136.269136 -26.571667)
			(xy 136.24184 -26.523032) (xy 136.221917 -26.470941) (xy 136.209791 -26.416504) (xy 136.20572 -26.360882)
			(xy 133.523381 -26.360882) (xy 133.531128 -26.389807) (xy 133.53895 -26.449262) (xy 133.539484 -26.479246)
			(xy 133.539484 -27.276806) (xy 133.53987 -27.286793) (xy 133.547472 -27.305262) (xy 133.561585 -27.319393)
			(xy 133.580043 -27.327017) (xy 133.59003 -27.327352) (xy 142.795752 -27.327352) (xy 142.805627 -27.326887)
			(xy 142.823922 -27.319441) (xy 142.831312 -27.312874) (xy 142.831566 -27.31262) (xy 143.190722 -26.953464)
			(xy 143.197571 -26.946067) (xy 143.205305 -26.927468) (xy 143.205708 -26.917396) (xy 143.205708 -25.071578)
			(xy 143.205161 -25.060977) (xy 143.196631 -25.041564) (xy 143.189198 -25.033986) (xy 143.125698 -24.976074)
			(xy 143.105378 -24.969216) (xy 143.09471 -24.970232) (xy 143.058896 -24.97201) (xy 143.031645 -24.971524)
			(xy 142.977697 -24.963767) (xy 142.925403 -24.948412) (xy 142.875826 -24.92577) (xy 142.829976 -24.896304)
			(xy 142.788786 -24.860612) (xy 142.753095 -24.819422) (xy 142.723629 -24.773572) (xy 142.700988 -24.723995)
			(xy 142.685633 -24.671701) (xy 142.677876 -24.617753) (xy 142.677388 -24.590502) (xy 142.677915 -24.561667)
			(xy 142.686588 -24.504652) (xy 142.69466 -24.476964) (xy 142.69847 -24.464772) (xy 142.693898 -24.440134)
			(xy 142.625318 -24.354536) (xy 142.602458 -24.344376) (xy 142.589758 -24.345392) (xy 142.559532 -24.346662)
			(xy 142.532284 -24.346178) (xy 142.478343 -24.338427) (xy 142.426054 -24.323079) (xy 142.376481 -24.300445)
			(xy 142.330634 -24.270986) (xy 142.289446 -24.235303) (xy 142.253755 -24.194121) (xy 142.224288 -24.14828)
			(xy 142.201645 -24.098711) (xy 142.186287 -24.046424) (xy 142.178527 -23.992484) (xy 142.178522 -23.937989)
			(xy 142.186272 -23.884047) (xy 142.20162 -23.831758) (xy 142.224253 -23.782185) (xy 142.253711 -23.736337)
			(xy 142.289394 -23.695149) (xy 142.330575 -23.659458) (xy 142.376416 -23.629991) (xy 142.425985 -23.607347)
			(xy 142.478271 -23.591988) (xy 142.532211 -23.584227) (xy 142.586706 -23.584221) (xy 142.640648 -23.591971)
			(xy 142.692938 -23.607318) (xy 142.742511 -23.629951) (xy 142.788359 -23.659408) (xy 142.829548 -23.69509)
			(xy 142.865239 -23.736271) (xy 142.894707 -23.782112) (xy 142.917351 -23.83168) (xy 142.932711 -23.883967)
			(xy 142.940473 -23.937906) (xy 142.94104 -23.965154) (xy 142.940509 -23.993989) (xy 142.931829 -24.051001)
			(xy 142.923768 -24.078692) (xy 142.919958 -24.090884) (xy 142.92453 -24.115522) (xy 142.99311 -24.20112)
			(xy 143.01597 -24.21128) (xy 143.02867 -24.210264) (xy 143.058896 -24.208994) (xy 143.09471 -24.210772)
			(xy 143.105378 -24.211788) (xy 143.125698 -24.20493) (xy 143.189198 -24.147018) (xy 143.19675 -24.139523)
			(xy 143.205302 -24.120058) (xy 143.205708 -24.109426) (xy 143.205708 -24.081994) (xy 143.202914 -24.073866)
			(xy 143.192751 -24.043102) (xy 143.18176 -23.979257) (xy 143.18107 -23.946866) (xy 143.181774 -23.914475)
			(xy 143.192751 -23.850629) (xy 143.202914 -23.819866) (xy 143.205708 -23.811738) (xy 143.205708 -22.239224)
			(xy 143.188944 -22.214078) (xy 143.174466 -22.207982) (xy 143.148727 -22.196751) (xy 143.100585 -22.167838)
			(xy 143.057203 -22.13218) (xy 143.019517 -22.090547) (xy 142.988342 -22.043839) (xy 142.964351 -21.993065)
			(xy 142.948064 -21.939322) (xy 142.939832 -21.883772) (xy 142.939833 -21.827616) (xy 142.948067 -21.772066)
			(xy 142.964356 -21.718324) (xy 142.988348 -21.667551) (xy 143.019524 -21.620843) (xy 143.057212 -21.579211)
			(xy 143.100595 -21.543555) (xy 143.148738 -21.514644) (xy 143.174466 -21.503386) (xy 143.188944 -21.49729)
			(xy 143.205708 -21.472144) (xy 143.205708 -15.834106) (xy 143.205235 -15.824138) (xy 143.197667 -15.805694)
			(xy 143.190976 -15.798292) (xy 143.13408 -15.740634) (xy 143.116046 -15.73276) (xy 143.105886 -15.73276)
			(xy 143.08017 -15.731907) (xy 143.029305 -15.724141) (xy 142.979944 -15.709615) (xy 142.932981 -15.68859)
			(xy 142.889267 -15.661449) (xy 142.849594 -15.628683) (xy 142.83182 -15.610078) (xy 142.8242 -15.60195)
			(xy 142.804134 -15.593568) (xy 142.705582 -15.596108) (xy 142.686024 -15.605506) (xy 142.678912 -15.614142)
			(xy 142.660702 -15.635294) (xy 142.619156 -15.672563) (xy 142.572625 -15.703385) (xy 142.522102 -15.727101)
			(xy 142.468663 -15.743205) (xy 142.413448 -15.751355) (xy 142.385542 -15.75181) (xy 142.358287 -15.75135)
			(xy 142.304331 -15.743597) (xy 142.252028 -15.728245) (xy 142.202442 -15.705605) (xy 142.156584 -15.676138)
			(xy 142.115386 -15.640444) (xy 142.079688 -15.59925) (xy 142.050215 -15.553394) (xy 142.02757 -15.503811)
			(xy 142.012212 -15.45151) (xy 142.004453 -15.397555) (xy 142.004453 -15.343045) (xy 142.012212 -15.28909)
			(xy 142.02757 -15.236789) (xy 142.050215 -15.187206) (xy 142.079688 -15.14135) (xy 142.115386 -15.100156)
			(xy 142.156584 -15.064462) (xy 142.202442 -15.034995) (xy 142.252028 -15.012355) (xy 142.304331 -14.997003)
			(xy 142.358287 -14.98925) (xy 142.385542 -14.988794) (xy 142.411777 -14.989234) (xy 142.463752 -14.996436)
			(xy 142.514247 -15.010699) (xy 142.562309 -15.031752) (xy 142.607029 -15.059198) (xy 142.647563 -15.092518)
			(xy 142.665704 -15.111476) (xy 142.673324 -15.119604) (xy 142.69339 -15.127986) (xy 142.791942 -15.125446)
			(xy 142.8115 -15.116048) (xy 142.818612 -15.107412) (xy 142.836491 -15.086647) (xy 142.877185 -15.049952)
			(xy 142.922705 -15.019448) (xy 142.972117 -14.995763) (xy 143.024406 -14.979383) (xy 143.0785 -14.970643)
			(xy 143.105886 -14.969744) (xy 143.116046 -14.969744) (xy 143.13408 -14.96187) (xy 143.190976 -14.904212)
			(xy 143.197665 -14.896804) (xy 143.205255 -14.878368) (xy 143.205708 -14.868398) (xy 143.205708 -13.72108)
			(xy 143.198088 -13.702284) (xy 143.190722 -13.695172) (xy 142.885414 -13.389864) (xy 142.878014 -13.383024)
			(xy 142.859415 -13.375311) (xy 142.849346 -13.374878) (xy 138.132566 -13.374878) (xy 138.11377 -13.382498)
			(xy 138.106658 -13.389864) (xy 137.39622 -14.100302) (xy 142.143224 -14.100302) (xy 142.147295 -14.04468)
			(xy 142.159421 -13.990243) (xy 142.179344 -13.938152) (xy 142.20664 -13.889517) (xy 142.240726 -13.845374)
			(xy 142.280875 -13.806665) (xy 142.326233 -13.774214) (xy 142.375833 -13.748713) (xy 142.428617 -13.730706)
			(xy 142.48346 -13.720576) (xy 142.539194 -13.718539) (xy 142.594631 -13.724639) (xy 142.648588 -13.738745)
			(xy 142.699917 -13.760557) (xy 142.747523 -13.789611) (xy 142.790391 -13.825286) (xy 142.827608 -13.866823)
			(xy 142.858381 -13.913336) (xy 142.882053 -13.963833) (xy 142.898121 -14.01724) (xy 142.906241 -14.072416)
			(xy 142.90675 -14.100302) (xy 142.906241 -14.128188) (xy 142.898121 -14.183364) (xy 142.882053 -14.236771)
			(xy 142.858381 -14.287268) (xy 142.827608 -14.333781) (xy 142.790391 -14.375318) (xy 142.747523 -14.410993)
			(xy 142.699917 -14.440047) (xy 142.648588 -14.461859) (xy 142.594631 -14.475965) (xy 142.539194 -14.482065)
			(xy 142.48346 -14.480028) (xy 142.428617 -14.469898) (xy 142.375833 -14.451891) (xy 142.326233 -14.42639)
			(xy 142.280875 -14.393939) (xy 142.240726 -14.35523) (xy 142.20664 -14.311087) (xy 142.179344 -14.262452)
			(xy 142.159421 -14.210361) (xy 142.147295 -14.155924) (xy 142.143224 -14.100302) (xy 137.39622 -14.100302)
			(xy 136.800844 -14.695678) (xy 136.795626 -14.700578) (xy 136.783117 -14.707524) (xy 136.776206 -14.709394)
			(xy 136.766554 -14.71168) (xy 136.75106 -14.722348) (xy 136.701022 -14.796262) (xy 136.694599 -14.807025)
			(xy 136.692056 -14.831931) (xy 136.696196 -14.84376) (xy 136.721676 -14.907684) (xy 136.765332 -15.038202)
			(xy 136.800483 -15.171263) (xy 136.826982 -15.306313) (xy 136.844719 -15.44279) (xy 136.853622 -15.580127)
			(xy 136.854184 -15.64894) (xy 136.854184 -15.649956) (xy 136.853688 -15.71498) (xy 136.845766 -15.844785)
			(xy 136.829954 -15.973868) (xy 136.806311 -16.101748) (xy 136.774925 -16.227951) (xy 136.735913 -16.352009)
			(xy 136.689418 -16.47346) (xy 136.635615 -16.591856) (xy 136.574702 -16.706755) (xy 136.506905 -16.817732)
			(xy 136.432476 -16.924375) (xy 136.351692 -17.026287) (xy 136.264852 -17.123092) (xy 136.21893 -17.16913)
			(xy 136.173047 -17.214029) (xy 136.076682 -17.298867) (xy 135.975392 -17.377758) (xy 135.869541 -17.450417)
			(xy 135.759514 -17.516582) (xy 135.645709 -17.576012) (xy 135.528537 -17.628494) (xy 135.408422 -17.673837)
			(xy 135.285798 -17.711877) (xy 135.161109 -17.742476) (xy 135.034806 -17.765525) (xy 134.907346 -17.780939)
			(xy 134.77919 -17.788663) (xy 134.714996 -17.789144) (xy 134.650524 -17.788657) (xy 134.521817 -17.780872)
			(xy 134.393814 -17.765329) (xy 134.266983 -17.742086) (xy 134.141786 -17.711228) (xy 134.018682 -17.672868)
			(xy 133.898118 -17.627144) (xy 133.780534 -17.574225) (xy 133.666361 -17.514302) (xy 133.556013 -17.447596)
			(xy 133.449895 -17.374348) (xy 133.348392 -17.294827) (xy 133.251876 -17.209323) (xy 133.160699 -17.118147)
			(xy 133.075193 -17.021632) (xy 132.995671 -16.920131) (xy 132.922422 -16.814014) (xy 132.855713 -16.703667)
			(xy 132.795789 -16.589495) (xy 132.742868 -16.471912) (xy 132.697143 -16.351349) (xy 132.65878 -16.228244)
			(xy 132.62792 -16.103049) (xy 132.604676 -15.976218) (xy 132.589131 -15.848215) (xy 132.581344 -15.719508)
			(xy 132.580888 -15.655036) (xy 132.581424 -15.58632) (xy 132.590247 -15.449173) (xy 132.60788 -15.312877)
			(xy 132.634248 -15.177999) (xy 132.669243 -15.045098) (xy 132.712719 -14.914725) (xy 132.738114 -14.850872)
			(xy 132.738368 -14.850618) (xy 132.740146 -14.846046) (xy 132.740908 -14.841728) (xy 132.742594 -14.831661)
			(xy 132.738781 -14.811627) (xy 132.733542 -14.802866) (xy 132.686298 -14.733016) (xy 132.678768 -14.722998)
			(xy 132.656652 -14.711275) (xy 132.644134 -14.710664) (xy 130.829558 -14.710664) (xy 130.820189 -14.711041)
			(xy 130.802677 -14.717694) (xy 130.788733 -14.730202) (xy 130.784092 -14.73835) (xy 130.746754 -14.81201)
			(xy 130.743735 -14.818432) (xy 130.741034 -14.832356) (xy 130.74142 -14.839442) (xy 130.74269 -14.853412)
			(xy 130.751072 -14.865096) (xy 130.751326 -14.86535) (xy 130.775946 -14.899837) (xy 130.819579 -14.972482)
			(xy 130.856501 -15.048757) (xy 130.886411 -15.128045) (xy 130.909067 -15.209702) (xy 130.924285 -15.293066)
			(xy 130.931941 -15.377461) (xy 130.932428 -15.419832) (xy 130.932428 -15.425674) (xy 130.931585 -15.471623)
			(xy 130.922046 -15.563035) (xy 130.903633 -15.653079) (xy 130.876522 -15.740897) (xy 130.840972 -15.825651)
			(xy 130.819652 -15.866364) (xy 130.819652 -15.866618) (xy 130.814327 -15.877971) (xy 130.814324 -15.903018)
			(xy 130.819652 -15.91437) (xy 130.861562 -15.992602) (xy 130.882898 -16.006572) (xy 130.895852 -16.007588)
			(xy 130.94006 -16.011808) (xy 131.027506 -16.027336) (xy 131.113156 -16.050825) (xy 131.196289 -16.082078)
			(xy 131.276201 -16.120831) (xy 131.352218 -16.166757) (xy 131.423698 -16.219467) (xy 131.490037 -16.278516)
			(xy 131.550676 -16.343407) (xy 131.605101 -16.41359) (xy 131.652854 -16.488473) (xy 131.69353 -16.567423)
			(xy 131.726787 -16.649775) (xy 131.752343 -16.734831) (xy 131.769983 -16.821875) (xy 131.779558 -16.91017)
			(xy 131.780986 -16.998972) (xy 131.774257 -17.08753) (xy 131.759426 -17.175096) (xy 131.736619 -17.26093)
			(xy 131.706028 -17.344309) (xy 131.667912 -17.424527) (xy 131.622593 -17.500907) (xy 131.570454 -17.572805)
			(xy 131.511934 -17.639612) (xy 131.480052 -17.670526) (xy 131.479544 -17.671034) (xy 131.479036 -17.671542)
			(xy 131.446902 -17.701731) (xy 131.37801 -17.756766) (xy 131.304387 -17.805292) (xy 131.226648 -17.846904)
			(xy 131.145439 -17.881256) (xy 131.061436 -17.908062) (xy 130.97534 -17.927098) (xy 130.887866 -17.938207)
			(xy 130.799745 -17.941295) (xy 130.711708 -17.936337) (xy 130.62449 -17.923374) (xy 130.538817 -17.902514)
			(xy 130.455403 -17.873932) (xy 130.374941 -17.837864) (xy 130.298102 -17.794611) (xy 130.225526 -17.744534)
			(xy 130.157818 -17.688049) (xy 130.09554 -17.625627) (xy 130.039213 -17.557787) (xy 129.989304 -17.485096)
			(xy 129.94623 -17.408157) (xy 129.910348 -17.327612) (xy 129.881959 -17.244131) (xy 129.861298 -17.15841)
			(xy 129.848538 -17.071162) (xy 129.843784 -16.983114) (xy 129.847077 -16.895) (xy 129.858388 -16.807553)
			(xy 129.877624 -16.721501) (xy 129.904625 -16.63756) (xy 129.939165 -16.556431) (xy 129.959608 -16.517366)
			(xy 129.961132 -16.514826) (xy 129.963164 -16.509746) (xy 129.965147 -16.504453) (xy 129.966935 -16.493296)
			(xy 129.96672 -16.487648) (xy 129.965958 -16.475202) (xy 129.914904 -16.390112) (xy 129.907792 -16.378428)
			(xy 129.884932 -16.36522) (xy 128.13284 -16.36522) (xy 128.089401 -16.364735) (xy 128.002892 -16.356722)
			(xy 127.917492 -16.340761) (xy 127.833929 -16.316988) (xy 127.752916 -16.285606) (xy 127.675145 -16.246882)
			(xy 127.601278 -16.201147) (xy 127.531947 -16.148792) (xy 127.467742 -16.090262) (xy 127.409212 -16.026058)
			(xy 127.356856 -15.956727) (xy 127.311121 -15.882861) (xy 127.272397 -15.805089) (xy 127.241014 -15.724077)
			(xy 127.21724 -15.640514) (xy 127.201279 -15.555114) (xy 127.193265 -15.468605) (xy 127.192786 -15.425166)
			(xy 127.192786 -15.424658) (xy 127.193286 -15.382487) (xy 127.200895 -15.29849) (xy 127.215993 -15.21551)
			(xy 127.23846 -15.134216) (xy 127.268116 -15.055259) (xy 127.304721 -14.979275) (xy 127.347982 -14.906874)
			(xy 127.372364 -14.872462) (xy 127.372618 -14.872208) (xy 127.373126 -14.8717) (xy 127.378066 -14.863973)
			(xy 127.382634 -14.846225) (xy 127.380681 -14.828003) (xy 127.376936 -14.81963) (xy 127.336042 -14.738858)
			(xy 127.330962 -14.730476) (xy 127.327627 -14.726389) (xy 127.319556 -14.719602) (xy 127.31496 -14.717014)
			(xy 127.314452 -14.71676) (xy 127.308823 -14.713935) (xy 127.296617 -14.710848) (xy 127.290322 -14.710664)
			(xy 117.959378 -14.710664) (xy 117.940582 -14.718284) (xy 117.93347 -14.72565) (xy 117.53088 -15.12824)
			(xy 117.524031 -15.135637) (xy 117.516299 -15.154236) (xy 117.515894 -15.164308) (xy 117.515894 -18.44421)
			(xy 138.376404 -18.44421) (xy 138.380475 -18.388588) (xy 138.392601 -18.334151) (xy 138.412524 -18.28206)
			(xy 138.43982 -18.233425) (xy 138.473906 -18.189282) (xy 138.514055 -18.150573) (xy 138.559413 -18.118122)
			(xy 138.609013 -18.092621) (xy 138.661797 -18.074614) (xy 138.71664 -18.064484) (xy 138.772374 -18.062447)
			(xy 138.827811 -18.068547) (xy 138.881768 -18.082653) (xy 138.933097 -18.104465) (xy 138.980703 -18.133519)
			(xy 139.023571 -18.169194) (xy 139.060788 -18.210731) (xy 139.091561 -18.257244) (xy 139.115233 -18.307741)
			(xy 139.131301 -18.361148) (xy 139.139421 -18.416324) (xy 139.13993 -18.44421) (xy 139.139421 -18.472096)
			(xy 139.131301 -18.527272) (xy 139.115233 -18.580679) (xy 139.091561 -18.631176) (xy 139.060788 -18.677689)
			(xy 139.023571 -18.719226) (xy 138.980703 -18.754901) (xy 138.933097 -18.783955) (xy 138.881768 -18.805767)
			(xy 138.827811 -18.819873) (xy 138.772374 -18.825973) (xy 138.71664 -18.823936) (xy 138.661797 -18.813806)
			(xy 138.609013 -18.795799) (xy 138.559413 -18.770298) (xy 138.514055 -18.737847) (xy 138.473906 -18.699138)
			(xy 138.43982 -18.654995) (xy 138.412524 -18.60636) (xy 138.392601 -18.554269) (xy 138.380475 -18.499832)
			(xy 138.376404 -18.44421) (xy 117.515894 -18.44421) (xy 117.515894 -20.72513) (xy 121.28044 -20.72513)
			(xy 121.28441 -20.594996) (xy 121.296306 -20.465346) (xy 121.316085 -20.336663) (xy 121.343671 -20.209424)
			(xy 121.378964 -20.084105) (xy 121.42183 -19.961169) (xy 121.472112 -19.841076) (xy 121.529621 -19.724272)
			(xy 121.594145 -19.61119) (xy 121.665442 -19.502253) (xy 121.743247 -19.397865) (xy 121.827272 -19.298414)
			(xy 121.917204 -19.204271) (xy 122.012708 -19.115786) (xy 122.113428 -19.033287) (xy 122.21899 -18.957082)
			(xy 122.329002 -18.887455) (xy 122.443054 -18.824664) (xy 122.560722 -18.768942) (xy 122.681568 -18.720498)
			(xy 122.805143 -18.679511) (xy 122.930986 -18.646134) (xy 123.058631 -18.620491) (xy 123.187601 -18.602677)
			(xy 123.317417 -18.592759) (xy 123.447596 -18.590774) (xy 123.577655 -18.596728) (xy 123.707108 -18.610601)
			(xy 123.835475 -18.632339) (xy 123.962278 -18.661863) (xy 124.087045 -18.699062) (xy 124.209312 -18.743798)
			(xy 124.328625 -18.795906) (xy 124.444538 -18.855189) (xy 124.556623 -18.92143) (xy 124.66446 -18.99438)
			(xy 124.767649 -19.073768) (xy 124.865807 -19.1593) (xy 124.958568 -19.250657) (xy 125.045587 -19.347499)
			(xy 125.12654 -19.449466) (xy 125.201126 -19.556178) (xy 125.269067 -19.667239) (xy 125.330112 -19.782235)
			(xy 125.384033 -19.900739) (xy 125.430628 -20.02231) (xy 125.469726 -20.146495) (xy 125.50118 -20.272833)
			(xy 125.524874 -20.400854) (xy 125.540718 -20.53008) (xy 125.548656 -20.660033) (xy 125.549152 -20.72513)
			(xy 125.548656 -20.790227) (xy 125.540718 -20.92018) (xy 125.524874 -21.049406) (xy 125.50118 -21.177427)
			(xy 125.469726 -21.303765) (xy 125.430628 -21.42795) (xy 125.384033 -21.549521) (xy 125.330112 -21.668025)
			(xy 125.292788 -21.738336) (xy 127.51689 -21.738336) (xy 127.517377 -21.709596) (xy 127.526009 -21.652767)
			(xy 127.543068 -21.597876) (xy 127.568168 -21.546165) (xy 127.60074 -21.498804) (xy 127.620014 -21.477478)
			(xy 127.626618 -21.470366) (xy 127.63373 -21.45284) (xy 127.63373 -21.363432) (xy 127.626618 -21.345906)
			(xy 127.620014 -21.338794) (xy 127.600779 -21.317436) (xy 127.568214 -21.270079) (xy 127.543121 -21.218372)
			(xy 127.526069 -21.163486) (xy 127.517443 -21.106663) (xy 127.517439 -21.049189) (xy 127.526057 -20.992365)
			(xy 127.543102 -20.937477) (xy 127.568187 -20.885767) (xy 127.600746 -20.838405) (xy 127.620014 -20.817078)
			(xy 127.626618 -20.809966) (xy 127.63373 -20.79244) (xy 127.63373 -20.703032) (xy 127.626618 -20.685506)
			(xy 127.620014 -20.678394) (xy 127.600779 -20.657036) (xy 127.568214 -20.609679) (xy 127.543121 -20.557972)
			(xy 127.526069 -20.503086) (xy 127.517443 -20.446263) (xy 127.517439 -20.388789) (xy 127.526057 -20.331965)
			(xy 127.543102 -20.277077) (xy 127.568187 -20.225367) (xy 127.600746 -20.178005) (xy 127.620014 -20.156678)
			(xy 127.626618 -20.149566) (xy 127.63373 -20.13204) (xy 127.63373 -20.042632) (xy 127.626618 -20.025106)
			(xy 127.620014 -20.017994) (xy 127.600779 -19.996636) (xy 127.568214 -19.949279) (xy 127.543121 -19.897572)
			(xy 127.526069 -19.842686) (xy 127.517443 -19.785863) (xy 127.517439 -19.728389) (xy 127.526057 -19.671565)
			(xy 127.543102 -19.616677) (xy 127.568187 -19.564967) (xy 127.600746 -19.517605) (xy 127.620014 -19.496278)
			(xy 127.626618 -19.489166) (xy 127.63373 -19.47164) (xy 127.63373 -19.382232) (xy 127.626618 -19.364706)
			(xy 127.620014 -19.357594) (xy 127.600756 -19.336256) (xy 127.568189 -19.288896) (xy 127.543095 -19.237188)
			(xy 127.526041 -19.182299) (xy 127.517414 -19.125474) (xy 127.51689 -19.096736) (xy 127.517376 -19.069485)
			(xy 127.525132 -19.015537) (xy 127.540487 -18.963242) (xy 127.563129 -18.913665) (xy 127.592595 -18.867815)
			(xy 127.628286 -18.826624) (xy 127.669477 -18.790933) (xy 127.715327 -18.761467) (xy 127.764904 -18.738825)
			(xy 127.817199 -18.72347) (xy 127.871147 -18.715714) (xy 127.925649 -18.715714) (xy 127.979597 -18.72347)
			(xy 128.031892 -18.738825) (xy 128.081469 -18.761467) (xy 128.127319 -18.790933) (xy 128.16851 -18.826624)
			(xy 128.204201 -18.867815) (xy 128.233667 -18.913665) (xy 128.256309 -18.963242) (xy 128.271664 -19.015537)
			(xy 128.27942 -19.069485) (xy 128.279906 -19.096736) (xy 128.279403 -19.125476) (xy 128.270775 -19.182304)
			(xy 128.25372 -19.237195) (xy 128.228624 -19.288906) (xy 128.196055 -19.336268) (xy 128.176782 -19.357594)
			(xy 128.170178 -19.364706) (xy 128.163066 -19.382232) (xy 128.163066 -19.47164) (xy 128.170178 -19.489166)
			(xy 128.176782 -19.496278) (xy 128.196088 -19.517574) (xy 128.228652 -19.564942) (xy 128.253741 -19.616659)
			(xy 128.270788 -19.671554) (xy 128.279407 -19.728386) (xy 128.279403 -19.785867) (xy 128.270776 -19.842697)
			(xy 128.253722 -19.89759) (xy 128.228625 -19.949304) (xy 128.196055 -19.996667) (xy 128.176782 -20.017994)
			(xy 128.170178 -20.025106) (xy 128.163066 -20.042632) (xy 128.163066 -20.13204) (xy 128.170178 -20.149566)
			(xy 128.176782 -20.156678) (xy 128.196088 -20.177974) (xy 128.228652 -20.225342) (xy 128.253741 -20.277059)
			(xy 128.270788 -20.331954) (xy 128.279407 -20.388786) (xy 128.279403 -20.446267) (xy 128.270776 -20.503097)
			(xy 128.253722 -20.55799) (xy 128.228625 -20.609704) (xy 128.196055 -20.657067) (xy 128.176782 -20.678394)
			(xy 128.170178 -20.685506) (xy 128.163066 -20.703032) (xy 128.163066 -20.79244) (xy 128.170178 -20.809966)
			(xy 128.176782 -20.817078) (xy 128.196088 -20.838374) (xy 128.228652 -20.885742) (xy 128.253741 -20.937459)
			(xy 128.270788 -20.992354) (xy 128.279407 -21.049186) (xy 128.279403 -21.106667) (xy 128.270776 -21.163497)
			(xy 128.253722 -21.21839) (xy 128.228625 -21.270104) (xy 128.196055 -21.317467) (xy 128.176782 -21.338794)
			(xy 128.170178 -21.345906) (xy 128.163066 -21.363432) (xy 128.163066 -21.45284) (xy 128.170178 -21.470366)
			(xy 128.176782 -21.477478) (xy 128.196073 -21.498787) (xy 128.228636 -21.546155) (xy 128.253724 -21.597871)
			(xy 128.266502 -21.639022) (xy 132.17398 -21.639022) (xy 132.174522 -21.610284) (xy 132.183141 -21.553458)
			(xy 132.200187 -21.498567) (xy 132.225275 -21.446855) (xy 132.257835 -21.399492) (xy 132.277104 -21.378164)
			(xy 132.283708 -21.371052) (xy 132.29082 -21.353526) (xy 132.29082 -21.264118) (xy 132.283708 -21.246592)
			(xy 132.277104 -21.23948) (xy 132.257856 -21.218134) (xy 132.225292 -21.170774) (xy 132.2002 -21.119065)
			(xy 132.183149 -21.064178) (xy 132.174525 -21.007354) (xy 132.174523 -20.949879) (xy 132.183142 -20.893054)
			(xy 132.200188 -20.838165) (xy 132.225275 -20.786454) (xy 132.257836 -20.739091) (xy 132.277104 -20.717764)
			(xy 132.283708 -20.710652) (xy 132.29082 -20.693126) (xy 132.29082 -20.603718) (xy 132.283708 -20.586192)
			(xy 132.277104 -20.57908) (xy 132.257856 -20.557734) (xy 132.225292 -20.510374) (xy 132.2002 -20.458665)
			(xy 132.183149 -20.403778) (xy 132.174525 -20.346954) (xy 132.174523 -20.289479) (xy 132.183142 -20.232654)
			(xy 132.200188 -20.177765) (xy 132.225275 -20.126054) (xy 132.257836 -20.078691) (xy 132.277104 -20.057364)
			(xy 132.283708 -20.050252) (xy 132.29082 -20.032726) (xy 132.29082 -19.943318) (xy 132.283708 -19.925792)
			(xy 132.277104 -19.91868) (xy 132.257856 -19.897334) (xy 132.225292 -19.849974) (xy 132.2002 -19.798265)
			(xy 132.183149 -19.743378) (xy 132.174525 -19.686554) (xy 132.174523 -19.629079) (xy 132.183142 -19.572254)
			(xy 132.200188 -19.517365) (xy 132.225275 -19.465654) (xy 132.257836 -19.418291) (xy 132.277104 -19.396964)
			(xy 132.283708 -19.389852) (xy 132.29082 -19.372326) (xy 132.29082 -19.282918) (xy 132.283708 -19.265392)
			(xy 132.277104 -19.25828) (xy 132.257855 -19.236934) (xy 132.225283 -19.189578) (xy 132.200186 -19.137872)
			(xy 132.18313 -19.082985) (xy 132.174503 -19.02616) (xy 132.17398 -18.997422) (xy 132.174466 -18.970171)
			(xy 132.182222 -18.916223) (xy 132.197577 -18.863928) (xy 132.220219 -18.814351) (xy 132.249685 -18.768501)
			(xy 132.285376 -18.72731) (xy 132.326567 -18.691619) (xy 132.372417 -18.662153) (xy 132.421994 -18.639511)
			(xy 132.474289 -18.624156) (xy 132.528237 -18.6164) (xy 132.582739 -18.6164) (xy 132.636687 -18.624156)
			(xy 132.688982 -18.639511) (xy 132.738559 -18.662153) (xy 132.784409 -18.691619) (xy 132.8256 -18.72731)
			(xy 132.861291 -18.768501) (xy 132.890757 -18.814351) (xy 132.913399 -18.863928) (xy 132.928754 -18.916223)
			(xy 132.93651 -18.970171) (xy 132.936996 -18.997422) (xy 132.936487 -19.026161) (xy 132.927861 -19.082989)
			(xy 132.910807 -19.13788) (xy 132.885713 -19.189592) (xy 132.853144 -19.236954) (xy 132.833872 -19.25828)
			(xy 132.827268 -19.265392) (xy 132.820156 -19.282918) (xy 132.820156 -19.366857) (xy 137.679315 -19.366857)
			(xy 137.679315 -19.312343) (xy 137.687074 -19.258384) (xy 137.702433 -19.206078) (xy 137.72508 -19.15649)
			(xy 137.754554 -19.110631) (xy 137.790254 -19.069433) (xy 137.831455 -19.033736) (xy 137.877317 -19.004265)
			(xy 137.926906 -18.981622) (xy 137.979213 -18.966267) (xy 138.033173 -18.958513) (xy 138.06043 -18.958052)
			(xy 138.087202 -18.958505) (xy 138.140217 -18.966006) (xy 138.191663 -18.980844) (xy 138.240531 -19.002727)
			(xy 138.28586 -19.031226) (xy 138.326761 -19.06578) (xy 138.362431 -19.105712) (xy 138.377676 -19.127724)
			(xy 138.383772 -19.136614) (xy 138.401298 -19.148044) (xy 138.495786 -19.163284) (xy 138.516106 -19.158204)
			(xy 138.524488 -19.1516) (xy 138.544642 -19.136484) (xy 138.588163 -19.11111) (xy 138.634649 -19.091693)
			(xy 138.683288 -19.078572) (xy 138.733233 -19.071975) (xy 138.758422 -19.07159) (xy 138.785672 -19.072081)
			(xy 138.839617 -19.07984) (xy 138.891909 -19.095197) (xy 138.941483 -19.11784) (xy 138.987331 -19.147306)
			(xy 139.028518 -19.182998) (xy 139.064207 -19.224187) (xy 139.093671 -19.270036) (xy 139.11631 -19.319612)
			(xy 139.131664 -19.371904) (xy 139.13942 -19.42585) (xy 139.13942 -19.48035) (xy 139.131664 -19.534296)
			(xy 139.11631 -19.586588) (xy 139.093671 -19.636164) (xy 139.064207 -19.682013) (xy 139.028518 -19.723202)
			(xy 138.987331 -19.758894) (xy 138.941483 -19.78836) (xy 138.891909 -19.811003) (xy 138.839617 -19.82636)
			(xy 138.785672 -19.834119) (xy 138.758422 -19.834606) (xy 138.731651 -19.834132) (xy 138.678636 -19.826637)
			(xy 138.627189 -19.811804) (xy 138.578321 -19.789925) (xy 138.532991 -19.761429) (xy 138.49209 -19.726877)
			(xy 138.45642 -19.686946) (xy 138.441176 -19.664934) (xy 138.43508 -19.656044) (xy 138.417554 -19.644614)
			(xy 138.323066 -19.629374) (xy 138.302746 -19.634454) (xy 138.294364 -19.641058) (xy 138.274222 -19.65619)
			(xy 138.230698 -19.681563) (xy 138.184209 -19.700977) (xy 138.135567 -19.714094) (xy 138.08562 -19.720686)
			(xy 138.06043 -19.721068) (xy 138.033173 -19.720687) (xy 137.979213 -19.712933) (xy 137.926906 -19.697578)
			(xy 137.877317 -19.674935) (xy 137.831455 -19.645464) (xy 137.790254 -19.609767) (xy 137.754554 -19.568569)
			(xy 137.72508 -19.52271) (xy 137.702433 -19.473122) (xy 137.687074 -19.420816) (xy 137.679315 -19.366857)
			(xy 132.820156 -19.366857) (xy 132.820156 -19.372326) (xy 132.827268 -19.389852) (xy 132.833872 -19.396964)
			(xy 132.853165 -19.418272) (xy 132.88573 -19.465637) (xy 132.91082 -19.517352) (xy 132.927869 -19.572246)
			(xy 132.93649 -19.629076) (xy 132.936487 -19.686556) (xy 132.927862 -19.743385) (xy 132.910808 -19.798278)
			(xy 132.885713 -19.84999) (xy 132.853145 -19.897353) (xy 132.833872 -19.91868) (xy 132.827268 -19.925792)
			(xy 132.820156 -19.943318) (xy 132.820156 -20.032726) (xy 132.827268 -20.050252) (xy 132.833872 -20.057364)
			(xy 132.853165 -20.078672) (xy 132.88573 -20.126037) (xy 132.91082 -20.177752) (xy 132.927869 -20.232646)
			(xy 132.93649 -20.289476) (xy 132.936487 -20.346956) (xy 132.935181 -20.35556) (xy 137.678412 -20.35556)
			(xy 137.682483 -20.299938) (xy 137.694609 -20.245501) (xy 137.714532 -20.19341) (xy 137.741828 -20.144775)
			(xy 137.775914 -20.100632) (xy 137.816063 -20.061923) (xy 137.861421 -20.029472) (xy 137.911021 -20.003971)
			(xy 137.963805 -19.985964) (xy 138.018648 -19.975834) (xy 138.074382 -19.973797) (xy 138.129819 -19.979897)
			(xy 138.183776 -19.994003) (xy 138.235105 -20.015815) (xy 138.282711 -20.044869) (xy 138.325579 -20.080544)
			(xy 138.362796 -20.122081) (xy 138.393569 -20.168594) (xy 138.417241 -20.219091) (xy 138.433309 -20.272498)
			(xy 138.441429 -20.327674) (xy 138.441938 -20.35556) (xy 138.441429 -20.383446) (xy 138.433309 -20.438622)
			(xy 138.417241 -20.492029) (xy 138.393569 -20.542526) (xy 138.362796 -20.589039) (xy 138.325579 -20.630576)
			(xy 138.282711 -20.666251) (xy 138.235105 -20.695305) (xy 138.183776 -20.717117) (xy 138.129819 -20.731223)
			(xy 138.074382 -20.737323) (xy 138.018648 -20.735286) (xy 137.963805 -20.725156) (xy 137.911021 -20.707149)
			(xy 137.861421 -20.681648) (xy 137.816063 -20.649197) (xy 137.775914 -20.610488) (xy 137.741828 -20.566345)
			(xy 137.714532 -20.51771) (xy 137.694609 -20.465619) (xy 137.682483 -20.411182) (xy 137.678412 -20.35556)
			(xy 132.935181 -20.35556) (xy 132.927862 -20.403785) (xy 132.910808 -20.458678) (xy 132.885713 -20.51039)
			(xy 132.853145 -20.557753) (xy 132.833872 -20.57908) (xy 132.827268 -20.586192) (xy 132.820156 -20.603718)
			(xy 132.820156 -20.693126) (xy 132.827268 -20.710652) (xy 132.833872 -20.717764) (xy 132.853165 -20.739072)
			(xy 132.88573 -20.786437) (xy 132.91082 -20.838152) (xy 132.927869 -20.893046) (xy 132.93649 -20.949876)
			(xy 132.936487 -21.007356) (xy 132.927862 -21.064185) (xy 132.910808 -21.119078) (xy 132.885713 -21.17079)
			(xy 132.853145 -21.218153) (xy 132.833872 -21.23948) (xy 132.827268 -21.246592) (xy 132.820156 -21.264118)
			(xy 132.820156 -21.353526) (xy 132.827268 -21.371052) (xy 132.82774 -21.37156) (xy 137.678412 -21.37156)
			(xy 137.682483 -21.315938) (xy 137.694609 -21.261501) (xy 137.714532 -21.20941) (xy 137.741828 -21.160775)
			(xy 137.775914 -21.116632) (xy 137.816063 -21.077923) (xy 137.861421 -21.045472) (xy 137.911021 -21.019971)
			(xy 137.963805 -21.001964) (xy 138.018648 -20.991834) (xy 138.074382 -20.989797) (xy 138.129819 -20.995897)
			(xy 138.183776 -21.010003) (xy 138.235105 -21.031815) (xy 138.282711 -21.060869) (xy 138.325579 -21.096544)
			(xy 138.362796 -21.138081) (xy 138.393569 -21.184594) (xy 138.417241 -21.235091) (xy 138.433309 -21.288498)
			(xy 138.441429 -21.343674) (xy 138.441938 -21.37156) (xy 138.441429 -21.399446) (xy 138.433309 -21.454622)
			(xy 138.417241 -21.508029) (xy 138.393569 -21.558526) (xy 138.362796 -21.605039) (xy 138.325579 -21.646576)
			(xy 138.282711 -21.682251) (xy 138.235105 -21.711305) (xy 138.183776 -21.733117) (xy 138.129819 -21.747223)
			(xy 138.074382 -21.753323) (xy 138.018648 -21.751286) (xy 137.963805 -21.741156) (xy 137.911021 -21.723149)
			(xy 137.861421 -21.697648) (xy 137.816063 -21.665197) (xy 137.775914 -21.626488) (xy 137.741828 -21.582345)
			(xy 137.714532 -21.53371) (xy 137.694609 -21.481619) (xy 137.682483 -21.427182) (xy 137.678412 -21.37156)
			(xy 132.82774 -21.37156) (xy 132.833872 -21.378164) (xy 132.853155 -21.399481) (xy 132.885719 -21.446846)
			(xy 132.910809 -21.49856) (xy 132.927857 -21.553453) (xy 132.936477 -21.610282) (xy 132.936996 -21.639022)
			(xy 132.93651 -21.666273) (xy 132.928754 -21.720221) (xy 132.913399 -21.772516) (xy 132.911957 -21.775674)
			(xy 142.036036 -21.775674) (xy 142.040107 -21.720052) (xy 142.052233 -21.665615) (xy 142.072156 -21.613524)
			(xy 142.099452 -21.564889) (xy 142.133538 -21.520746) (xy 142.173687 -21.482037) (xy 142.219045 -21.449586)
			(xy 142.268645 -21.424085) (xy 142.321429 -21.406078) (xy 142.376272 -21.395948) (xy 142.432006 -21.393911)
			(xy 142.487443 -21.400011) (xy 142.5414 -21.414117) (xy 142.592729 -21.435929) (xy 142.640335 -21.464983)
			(xy 142.683203 -21.500658) (xy 142.72042 -21.542195) (xy 142.751193 -21.588708) (xy 142.774865 -21.639205)
			(xy 142.790933 -21.692612) (xy 142.799053 -21.747788) (xy 142.799562 -21.775674) (xy 142.799053 -21.80356)
			(xy 142.790933 -21.858736) (xy 142.774865 -21.912143) (xy 142.751193 -21.96264) (xy 142.72042 -22.009153)
			(xy 142.683203 -22.05069) (xy 142.640335 -22.086365) (xy 142.592729 -22.115419) (xy 142.5414 -22.137231)
			(xy 142.487443 -22.151337) (xy 142.432006 -22.157437) (xy 142.376272 -22.1554) (xy 142.321429 -22.14527)
			(xy 142.268645 -22.127263) (xy 142.219045 -22.101762) (xy 142.173687 -22.069311) (xy 142.133538 -22.030602)
			(xy 142.099452 -21.986459) (xy 142.072156 -21.937824) (xy 142.052233 -21.885733) (xy 142.040107 -21.831296)
			(xy 142.036036 -21.775674) (xy 132.911957 -21.775674) (xy 132.890757 -21.822093) (xy 132.861291 -21.867943)
			(xy 132.8256 -21.909134) (xy 132.784409 -21.944825) (xy 132.738559 -21.974291) (xy 132.688982 -21.996933)
			(xy 132.636687 -22.012288) (xy 132.582739 -22.020044) (xy 132.528237 -22.020044) (xy 132.474289 -22.012288)
			(xy 132.421994 -21.996933) (xy 132.372417 -21.974291) (xy 132.326567 -21.944825) (xy 132.285376 -21.909134)
			(xy 132.249685 -21.867943) (xy 132.220219 -21.822093) (xy 132.197577 -21.772516) (xy 132.182222 -21.720221)
			(xy 132.174466 -21.666273) (xy 132.17398 -21.639022) (xy 128.266502 -21.639022) (xy 128.27077 -21.652765)
			(xy 128.279388 -21.709596) (xy 128.279906 -21.738336) (xy 128.27942 -21.765587) (xy 128.271664 -21.819535)
			(xy 128.256309 -21.87183) (xy 128.233667 -21.921407) (xy 128.204201 -21.967257) (xy 128.16851 -22.008448)
			(xy 128.127319 -22.044139) (xy 128.081469 -22.073605) (xy 128.031892 -22.096247) (xy 127.979597 -22.111602)
			(xy 127.925649 -22.119358) (xy 127.871147 -22.119358) (xy 127.817199 -22.111602) (xy 127.764904 -22.096247)
			(xy 127.715327 -22.073605) (xy 127.669477 -22.044139) (xy 127.628286 -22.008448) (xy 127.592595 -21.967257)
			(xy 127.563129 -21.921407) (xy 127.540487 -21.87183) (xy 127.525132 -21.819535) (xy 127.517376 -21.765587)
			(xy 127.51689 -21.738336) (xy 125.292788 -21.738336) (xy 125.269067 -21.783021) (xy 125.201126 -21.894082)
			(xy 125.12654 -22.000794) (xy 125.045587 -22.102761) (xy 124.958568 -22.199603) (xy 124.865807 -22.29096)
			(xy 124.767649 -22.376492) (xy 124.66446 -22.45588) (xy 124.556623 -22.52883) (xy 124.444538 -22.595071)
			(xy 124.328625 -22.654354) (xy 124.209312 -22.706462) (xy 124.087045 -22.751198) (xy 123.962278 -22.788397)
			(xy 123.835475 -22.817921) (xy 123.707108 -22.839659) (xy 123.577655 -22.853532) (xy 123.447596 -22.859486)
			(xy 123.317417 -22.857501) (xy 123.187601 -22.847583) (xy 123.058631 -22.829769) (xy 122.930986 -22.804126)
			(xy 122.805143 -22.770749) (xy 122.681568 -22.729762) (xy 122.560722 -22.681318) (xy 122.443054 -22.625596)
			(xy 122.329002 -22.562805) (xy 122.21899 -22.493178) (xy 122.113428 -22.416973) (xy 122.012708 -22.334474)
			(xy 121.917204 -22.245989) (xy 121.827272 -22.151846) (xy 121.743247 -22.052395) (xy 121.665442 -21.948007)
			(xy 121.594145 -21.83907) (xy 121.529621 -21.725988) (xy 121.472112 -21.609184) (xy 121.42183 -21.489091)
			(xy 121.378964 -21.366155) (xy 121.343671 -21.240836) (xy 121.316085 -21.113597) (xy 121.296306 -20.984914)
			(xy 121.28441 -20.855264) (xy 121.28044 -20.72513) (xy 117.515894 -20.72513) (xy 117.515894 -23.0251)
			(xy 127.462532 -23.0251) (xy 127.466603 -22.969478) (xy 127.478729 -22.915041) (xy 127.498652 -22.86295)
			(xy 127.525948 -22.814315) (xy 127.560034 -22.770172) (xy 127.600183 -22.731463) (xy 127.645541 -22.699012)
			(xy 127.695141 -22.673511) (xy 127.747925 -22.655504) (xy 127.802768 -22.645374) (xy 127.858502 -22.643337)
			(xy 127.913939 -22.649437) (xy 127.967896 -22.663543) (xy 128.019225 -22.685355) (xy 128.066831 -22.714409)
			(xy 128.109699 -22.750084) (xy 128.146916 -22.791621) (xy 128.177689 -22.838134) (xy 128.201361 -22.888631)
			(xy 128.217429 -22.942038) (xy 128.225549 -22.997214) (xy 128.226058 -23.0251) (xy 128.225549 -23.052986)
			(xy 128.217429 -23.108162) (xy 128.201361 -23.161569) (xy 128.177689 -23.212066) (xy 128.146916 -23.258579)
			(xy 128.109699 -23.300116) (xy 128.066831 -23.335791) (xy 128.019225 -23.364845) (xy 127.967896 -23.386657)
			(xy 127.913939 -23.400763) (xy 127.858502 -23.406863) (xy 127.802768 -23.404826) (xy 127.747925 -23.394696)
			(xy 127.695141 -23.376689) (xy 127.645541 -23.351188) (xy 127.600183 -23.318737) (xy 127.560034 -23.280028)
			(xy 127.525948 -23.235885) (xy 127.498652 -23.18725) (xy 127.478729 -23.135159) (xy 127.466603 -23.080722)
			(xy 127.462532 -23.0251) (xy 117.515894 -23.0251) (xy 117.515894 -23.610823) (xy 128.166122 -23.610823)
			(xy 128.166126 -23.556328) (xy 128.173885 -23.502388) (xy 128.189241 -23.450102) (xy 128.211882 -23.400533)
			(xy 128.241346 -23.35469) (xy 128.277035 -23.313508) (xy 128.318221 -23.277823) (xy 128.364067 -23.248363)
			(xy 128.413638 -23.225727) (xy 128.465926 -23.210376) (xy 128.519867 -23.202623) (xy 128.547114 -23.202138)
			(xy 128.571143 -23.202511) (xy 128.618821 -23.208551) (xy 128.665362 -23.220533) (xy 128.68783 -23.229062)
			(xy 128.700985 -23.233838) (xy 128.728811 -23.236741) (xy 128.756381 -23.231988) (xy 128.78163 -23.219938)
			(xy 128.802665 -23.201492) (xy 128.817909 -23.178032) (xy 128.826221 -23.151318) (xy 128.826977 -23.123352)
			(xy 128.823974 -23.109682) (xy 128.818524 -23.086699) (xy 128.812662 -23.039828) (xy 128.81229 -23.01621)
			(xy 128.812744 -22.988956) (xy 128.8205 -22.935003) (xy 128.835855 -22.882703) (xy 128.858497 -22.833121)
			(xy 128.887965 -22.787266) (xy 128.923659 -22.746071) (xy 128.964853 -22.710375) (xy 129.010707 -22.680905)
			(xy 129.060288 -22.658261) (xy 129.112588 -22.642903) (xy 129.16654 -22.635145) (xy 129.221048 -22.635144)
			(xy 129.275001 -22.642901) (xy 129.3273 -22.658257) (xy 129.376883 -22.680899) (xy 129.422738 -22.710368)
			(xy 129.463932 -22.746062) (xy 129.499627 -22.787256) (xy 129.529097 -22.83311) (xy 129.55174 -22.882692)
			(xy 129.567097 -22.934992) (xy 129.574855 -22.988944) (xy 129.574855 -23.043452) (xy 129.567098 -23.097405)
			(xy 129.551742 -23.149704) (xy 129.529099 -23.199286) (xy 129.49963 -23.245141) (xy 129.463935 -23.286335)
			(xy 129.422741 -23.32203) (xy 129.376886 -23.351499) (xy 129.327304 -23.374142) (xy 129.275005 -23.389498)
			(xy 129.221052 -23.397255) (xy 129.193798 -23.397718) (xy 129.169769 -23.397338) (xy 129.122092 -23.3913)
			(xy 129.07555 -23.379321) (xy 129.053082 -23.370794) (xy 129.039908 -23.366083) (xy 129.012093 -23.363182)
			(xy 128.984534 -23.367931) (xy 128.959295 -23.379973) (xy 128.938266 -23.398408) (xy 128.923022 -23.421854)
			(xy 128.914707 -23.448554) (xy 128.913942 -23.476509) (xy 128.916938 -23.490174) (xy 128.922399 -23.513155)
			(xy 128.928254 -23.560028) (xy 128.928622 -23.583646) (xy 128.928494 -23.589996) (xy 132.184646 -23.589996)
			(xy 132.188717 -23.534374) (xy 132.200843 -23.479937) (xy 132.220766 -23.427846) (xy 132.248062 -23.379211)
			(xy 132.282148 -23.335068) (xy 132.322297 -23.296359) (xy 132.367655 -23.263908) (xy 132.417255 -23.238407)
			(xy 132.470039 -23.2204) (xy 132.524882 -23.21027) (xy 132.580616 -23.208233) (xy 132.636053 -23.214333)
			(xy 132.69001 -23.228439) (xy 132.741339 -23.250251) (xy 132.788945 -23.279305) (xy 132.831813 -23.31498)
			(xy 132.868167 -23.355554) (xy 141.430756 -23.355554) (xy 141.431243 -23.328744) (xy 141.43875 -23.275651)
			(xy 141.453622 -23.224134) (xy 141.475567 -23.17521) (xy 141.504152 -23.129843) (xy 141.538811 -23.08893)
			(xy 141.578862 -23.053278) (xy 141.600936 -23.038054) (xy 141.612475 -23.029765) (xy 141.630872 -23.008134)
			(xy 141.642605 -22.982274) (xy 141.646767 -22.954184) (xy 141.643036 -22.926033) (xy 141.631702 -22.899996)
			(xy 141.613638 -22.878085) (xy 141.602206 -22.869652) (xy 141.580765 -22.854278) (xy 141.541851 -22.818655)
			(xy 141.508216 -22.77801) (xy 141.480503 -22.733119) (xy 141.45924 -22.684837) (xy 141.444833 -22.634085)
			(xy 141.437556 -22.581832) (xy 141.437106 -22.555454) (xy 141.437592 -22.528203) (xy 141.445348 -22.474255)
			(xy 141.460703 -22.42196) (xy 141.483345 -22.372383) (xy 141.512811 -22.326533) (xy 141.548502 -22.285342)
			(xy 141.589693 -22.249651) (xy 141.635543 -22.220185) (xy 141.68512 -22.197543) (xy 141.737415 -22.182188)
			(xy 141.791363 -22.174432) (xy 141.845865 -22.174432) (xy 141.899813 -22.182188) (xy 141.952108 -22.197543)
			(xy 142.001685 -22.220185) (xy 142.047535 -22.249651) (xy 142.088726 -22.285342) (xy 142.124417 -22.326533)
			(xy 142.153883 -22.372383) (xy 142.176525 -22.42196) (xy 142.19188 -22.474255) (xy 142.199636 -22.528203)
			(xy 142.200122 -22.555454) (xy 142.19965 -22.582265) (xy 142.192142 -22.635359) (xy 142.177268 -22.686877)
			(xy 142.15532 -22.735801) (xy 142.126733 -22.781168) (xy 142.092071 -22.82208) (xy 142.052017 -22.857731)
			(xy 142.029942 -22.872954) (xy 142.018388 -22.881229) (xy 141.999977 -22.902859) (xy 141.988235 -22.928723)
			(xy 141.984071 -22.956821) (xy 141.987806 -22.984979) (xy 141.999152 -23.011019) (xy 142.017231 -23.032928)
			(xy 142.028672 -23.041356) (xy 142.050134 -23.056701) (xy 142.089044 -23.092331) (xy 142.122675 -23.132982)
			(xy 142.150384 -23.177879) (xy 142.171643 -23.226165) (xy 142.186048 -23.27692) (xy 142.193323 -23.329175)
			(xy 142.193772 -23.355554) (xy 142.193286 -23.382805) (xy 142.18553 -23.436753) (xy 142.170175 -23.489048)
			(xy 142.147533 -23.538625) (xy 142.118067 -23.584475) (xy 142.082376 -23.625666) (xy 142.041185 -23.661357)
			(xy 141.995335 -23.690823) (xy 141.945758 -23.713465) (xy 141.893463 -23.72882) (xy 141.839515 -23.736576)
			(xy 141.785013 -23.736576) (xy 141.731065 -23.72882) (xy 141.67877 -23.713465) (xy 141.629193 -23.690823)
			(xy 141.583343 -23.661357) (xy 141.542152 -23.625666) (xy 141.506461 -23.584475) (xy 141.476995 -23.538625)
			(xy 141.454353 -23.489048) (xy 141.438998 -23.436753) (xy 141.431242 -23.382805) (xy 141.430756 -23.355554)
			(xy 132.868167 -23.355554) (xy 132.86903 -23.356517) (xy 132.899803 -23.40303) (xy 132.923475 -23.453527)
			(xy 132.939543 -23.506934) (xy 132.947663 -23.56211) (xy 132.948172 -23.589996) (xy 132.947663 -23.617882)
			(xy 132.939543 -23.673058) (xy 132.923475 -23.726465) (xy 132.899803 -23.776962) (xy 132.86903 -23.823475)
			(xy 132.831813 -23.865012) (xy 132.813421 -23.880318) (xy 133.340854 -23.880318) (xy 133.344925 -23.824696)
			(xy 133.357051 -23.770259) (xy 133.376974 -23.718168) (xy 133.40427 -23.669533) (xy 133.438356 -23.62539)
			(xy 133.478505 -23.586681) (xy 133.523863 -23.55423) (xy 133.573463 -23.528729) (xy 133.626247 -23.510722)
			(xy 133.68109 -23.500592) (xy 133.736824 -23.498555) (xy 133.792261 -23.504655) (xy 133.846218 -23.518761)
			(xy 133.897547 -23.540573) (xy 133.945153 -23.569627) (xy 133.988021 -23.605302) (xy 134.025238 -23.646839)
			(xy 134.056011 -23.693352) (xy 134.079683 -23.743849) (xy 134.095751 -23.797256) (xy 134.103871 -23.852432)
			(xy 134.10438 -23.880318) (xy 134.356854 -23.880318) (xy 134.360925 -23.824696) (xy 134.373051 -23.770259)
			(xy 134.392974 -23.718168) (xy 134.42027 -23.669533) (xy 134.454356 -23.62539) (xy 134.494505 -23.586681)
			(xy 134.539863 -23.55423) (xy 134.589463 -23.528729) (xy 134.642247 -23.510722) (xy 134.69709 -23.500592)
			(xy 134.752824 -23.498555) (xy 134.808261 -23.504655) (xy 134.862218 -23.518761) (xy 134.913547 -23.540573)
			(xy 134.961153 -23.569627) (xy 135.004021 -23.605302) (xy 135.041238 -23.646839) (xy 135.072011 -23.693352)
			(xy 135.095683 -23.743849) (xy 135.111751 -23.797256) (xy 135.119871 -23.852432) (xy 135.12038 -23.880318)
			(xy 135.372854 -23.880318) (xy 135.376925 -23.824696) (xy 135.389051 -23.770259) (xy 135.408974 -23.718168)
			(xy 135.43627 -23.669533) (xy 135.470356 -23.62539) (xy 135.510505 -23.586681) (xy 135.555863 -23.55423)
			(xy 135.605463 -23.528729) (xy 135.658247 -23.510722) (xy 135.71309 -23.500592) (xy 135.768824 -23.498555)
			(xy 135.824261 -23.504655) (xy 135.878218 -23.518761) (xy 135.929547 -23.540573) (xy 135.977153 -23.569627)
			(xy 136.020021 -23.605302) (xy 136.057238 -23.646839) (xy 136.088011 -23.693352) (xy 136.111683 -23.743849)
			(xy 136.127751 -23.797256) (xy 136.135871 -23.852432) (xy 136.13638 -23.880318) (xy 136.39114 -23.880318)
			(xy 136.395211 -23.824696) (xy 136.407337 -23.770259) (xy 136.42726 -23.718168) (xy 136.454556 -23.669533)
			(xy 136.488642 -23.62539) (xy 136.528791 -23.586681) (xy 136.574149 -23.55423) (xy 136.623749 -23.528729)
			(xy 136.676533 -23.510722) (xy 136.731376 -23.500592) (xy 136.78711 -23.498555) (xy 136.842547 -23.504655)
			(xy 136.896504 -23.518761) (xy 136.947833 -23.540573) (xy 136.995439 -23.569627) (xy 137.038307 -23.605302)
			(xy 137.075524 -23.646839) (xy 137.106297 -23.693352) (xy 137.129969 -23.743849) (xy 137.146037 -23.797256)
			(xy 137.154157 -23.852432) (xy 137.154666 -23.880318) (xy 137.154157 -23.908204) (xy 137.146037 -23.96338)
			(xy 137.129969 -24.016787) (xy 137.106297 -24.067284) (xy 137.075524 -24.113797) (xy 137.038307 -24.155334)
			(xy 136.995439 -24.191009) (xy 136.947833 -24.220063) (xy 136.896504 -24.241875) (xy 136.842547 -24.255981)
			(xy 136.78711 -24.262081) (xy 136.731376 -24.260044) (xy 136.676533 -24.249914) (xy 136.623749 -24.231907)
			(xy 136.574149 -24.206406) (xy 136.528791 -24.173955) (xy 136.488642 -24.135246) (xy 136.454556 -24.091103)
			(xy 136.42726 -24.042468) (xy 136.407337 -23.990377) (xy 136.395211 -23.93594) (xy 136.39114 -23.880318)
			(xy 136.13638 -23.880318) (xy 136.135871 -23.908204) (xy 136.127751 -23.96338) (xy 136.111683 -24.016787)
			(xy 136.088011 -24.067284) (xy 136.057238 -24.113797) (xy 136.020021 -24.155334) (xy 135.977153 -24.191009)
			(xy 135.929547 -24.220063) (xy 135.878218 -24.241875) (xy 135.824261 -24.255981) (xy 135.768824 -24.262081)
			(xy 135.71309 -24.260044) (xy 135.658247 -24.249914) (xy 135.605463 -24.231907) (xy 135.555863 -24.206406)
			(xy 135.510505 -24.173955) (xy 135.470356 -24.135246) (xy 135.43627 -24.091103) (xy 135.408974 -24.042468)
			(xy 135.389051 -23.990377) (xy 135.376925 -23.93594) (xy 135.372854 -23.880318) (xy 135.12038 -23.880318)
			(xy 135.119871 -23.908204) (xy 135.111751 -23.96338) (xy 135.095683 -24.016787) (xy 135.072011 -24.067284)
			(xy 135.041238 -24.113797) (xy 135.004021 -24.155334) (xy 134.961153 -24.191009) (xy 134.913547 -24.220063)
			(xy 134.862218 -24.241875) (xy 134.808261 -24.255981) (xy 134.752824 -24.262081) (xy 134.69709 -24.260044)
			(xy 134.642247 -24.249914) (xy 134.589463 -24.231907) (xy 134.539863 -24.206406) (xy 134.494505 -24.173955)
			(xy 134.454356 -24.135246) (xy 134.42027 -24.091103) (xy 134.392974 -24.042468) (xy 134.373051 -23.990377)
			(xy 134.360925 -23.93594) (xy 134.356854 -23.880318) (xy 134.10438 -23.880318) (xy 134.103871 -23.908204)
			(xy 134.095751 -23.96338) (xy 134.079683 -24.016787) (xy 134.056011 -24.067284) (xy 134.025238 -24.113797)
			(xy 133.988021 -24.155334) (xy 133.945153 -24.191009) (xy 133.897547 -24.220063) (xy 133.846218 -24.241875)
			(xy 133.792261 -24.255981) (xy 133.736824 -24.262081) (xy 133.68109 -24.260044) (xy 133.626247 -24.249914)
			(xy 133.573463 -24.231907) (xy 133.523863 -24.206406) (xy 133.478505 -24.173955) (xy 133.438356 -24.135246)
			(xy 133.40427 -24.091103) (xy 133.376974 -24.042468) (xy 133.357051 -23.990377) (xy 133.344925 -23.93594)
			(xy 133.340854 -23.880318) (xy 132.813421 -23.880318) (xy 132.788945 -23.900687) (xy 132.741339 -23.929741)
			(xy 132.69001 -23.951553) (xy 132.636053 -23.965659) (xy 132.580616 -23.971759) (xy 132.524882 -23.969722)
			(xy 132.470039 -23.959592) (xy 132.417255 -23.941585) (xy 132.367655 -23.916084) (xy 132.322297 -23.883633)
			(xy 132.282148 -23.844924) (xy 132.248062 -23.800781) (xy 132.220766 -23.752146) (xy 132.200843 -23.700055)
			(xy 132.188717 -23.645618) (xy 132.184646 -23.589996) (xy 128.928494 -23.589996) (xy 128.928073 -23.610893)
			(xy 128.920311 -23.664833) (xy 128.904952 -23.717118) (xy 128.882308 -23.766686) (xy 128.852841 -23.812527)
			(xy 128.81715 -23.853708) (xy 128.775962 -23.88939) (xy 128.730115 -23.918847) (xy 128.680542 -23.94148)
			(xy 128.628253 -23.956828) (xy 128.574312 -23.964578) (xy 128.519817 -23.964573) (xy 128.465878 -23.956813)
			(xy 128.413592 -23.941455) (xy 128.364023 -23.918813) (xy 128.318182 -23.889347) (xy 128.277 -23.853657)
			(xy 128.241317 -23.81247) (xy 128.211858 -23.766624) (xy 128.189224 -23.717052) (xy 128.173874 -23.664764)
			(xy 128.166122 -23.610823) (xy 117.515894 -23.610823) (xy 117.515894 -24.158194) (xy 123.550932 -24.158194)
			(xy 123.555003 -24.102572) (xy 123.567129 -24.048135) (xy 123.587052 -23.996044) (xy 123.614348 -23.947409)
			(xy 123.648434 -23.903266) (xy 123.688583 -23.864557) (xy 123.733941 -23.832106) (xy 123.783541 -23.806605)
			(xy 123.836325 -23.788598) (xy 123.891168 -23.778468) (xy 123.946902 -23.776431) (xy 124.002339 -23.782531)
			(xy 124.056296 -23.796637) (xy 124.107625 -23.818449) (xy 124.155231 -23.847503) (xy 124.198099 -23.883178)
			(xy 124.235316 -23.924715) (xy 124.266089 -23.971228) (xy 124.289761 -24.021725) (xy 124.305829 -24.075132)
			(xy 124.313949 -24.130308) (xy 124.314458 -24.158194) (xy 124.313949 -24.18608) (xy 124.31338 -24.189944)
			(xy 127.399032 -24.189944) (xy 127.403103 -24.134322) (xy 127.415229 -24.079885) (xy 127.435152 -24.027794)
			(xy 127.462448 -23.979159) (xy 127.496534 -23.935016) (xy 127.536683 -23.896307) (xy 127.582041 -23.863856)
			(xy 127.631641 -23.838355) (xy 127.684425 -23.820348) (xy 127.739268 -23.810218) (xy 127.795002 -23.808181)
			(xy 127.850439 -23.814281) (xy 127.904396 -23.828387) (xy 127.955725 -23.850199) (xy 128.003331 -23.879253)
			(xy 128.046199 -23.914928) (xy 128.083416 -23.956465) (xy 128.114189 -24.002978) (xy 128.137861 -24.053475)
			(xy 128.153929 -24.106882) (xy 128.162049 -24.162058) (xy 128.162558 -24.189944) (xy 129.922014 -24.189944)
			(xy 129.926085 -24.134322) (xy 129.938211 -24.079885) (xy 129.958134 -24.027794) (xy 129.98543 -23.979159)
			(xy 130.019516 -23.935016) (xy 130.059665 -23.896307) (xy 130.105023 -23.863856) (xy 130.154623 -23.838355)
			(xy 130.207407 -23.820348) (xy 130.26225 -23.810218) (xy 130.317984 -23.808181) (xy 130.373421 -23.814281)
			(xy 130.427378 -23.828387) (xy 130.478707 -23.850199) (xy 130.526313 -23.879253) (xy 130.569181 -23.914928)
			(xy 130.606398 -23.956465) (xy 130.637171 -24.002978) (xy 130.660843 -24.053475) (xy 130.676911 -24.106882)
			(xy 130.685031 -24.162058) (xy 130.68554 -24.189944) (xy 130.685031 -24.21783) (xy 130.676911 -24.273006)
			(xy 130.660843 -24.326413) (xy 130.637171 -24.37691) (xy 130.606398 -24.423423) (xy 130.569181 -24.46496)
			(xy 130.526313 -24.500635) (xy 130.478707 -24.529689) (xy 130.427378 -24.551501) (xy 130.373421 -24.565607)
			(xy 130.317984 -24.571707) (xy 130.26225 -24.56967) (xy 130.207407 -24.55954) (xy 130.154623 -24.541533)
			(xy 130.105023 -24.516032) (xy 130.059665 -24.483581) (xy 130.019516 -24.444872) (xy 129.98543 -24.400729)
			(xy 129.958134 -24.352094) (xy 129.938211 -24.300003) (xy 129.926085 -24.245566) (xy 129.922014 -24.189944)
			(xy 128.162558 -24.189944) (xy 128.162049 -24.21783) (xy 128.153929 -24.273006) (xy 128.137861 -24.326413)
			(xy 128.114189 -24.37691) (xy 128.083416 -24.423423) (xy 128.046199 -24.46496) (xy 128.003331 -24.500635)
			(xy 127.955725 -24.529689) (xy 127.904396 -24.551501) (xy 127.850439 -24.565607) (xy 127.795002 -24.571707)
			(xy 127.739268 -24.56967) (xy 127.684425 -24.55954) (xy 127.631641 -24.541533) (xy 127.582041 -24.516032)
			(xy 127.536683 -24.483581) (xy 127.496534 -24.444872) (xy 127.462448 -24.400729) (xy 127.435152 -24.352094)
			(xy 127.415229 -24.300003) (xy 127.403103 -24.245566) (xy 127.399032 -24.189944) (xy 124.31338 -24.189944)
			(xy 124.305829 -24.241256) (xy 124.289761 -24.294663) (xy 124.266089 -24.34516) (xy 124.235316 -24.391673)
			(xy 124.198099 -24.43321) (xy 124.155231 -24.468885) (xy 124.107625 -24.497939) (xy 124.056296 -24.519751)
			(xy 124.002339 -24.533857) (xy 123.946902 -24.539957) (xy 123.891168 -24.53792) (xy 123.836325 -24.52779)
			(xy 123.783541 -24.509783) (xy 123.733941 -24.484282) (xy 123.688583 -24.451831) (xy 123.648434 -24.413122)
			(xy 123.614348 -24.368979) (xy 123.587052 -24.320344) (xy 123.567129 -24.268253) (xy 123.555003 -24.213816)
			(xy 123.550932 -24.158194) (xy 117.515894 -24.158194) (xy 117.515894 -24.307292) (xy 117.515652 -24.314242)
			(xy 117.511912 -24.327632) (xy 117.508528 -24.333708) (xy 117.508274 -24.333962) (xy 117.504718 -24.340058)
			(xy 117.50294 -24.346408) (xy 117.500908 -24.360378) (xy 117.500908 -24.807418) (xy 124.720348 -24.807418)
			(xy 124.724419 -24.751796) (xy 124.736545 -24.697359) (xy 124.756468 -24.645268) (xy 124.783764 -24.596633)
			(xy 124.81785 -24.55249) (xy 124.857999 -24.513781) (xy 124.903357 -24.48133) (xy 124.952957 -24.455829)
			(xy 125.005741 -24.437822) (xy 125.060584 -24.427692) (xy 125.116318 -24.425655) (xy 125.171755 -24.431755)
			(xy 125.225712 -24.445861) (xy 125.277041 -24.467673) (xy 125.324647 -24.496727) (xy 125.367515 -24.532402)
			(xy 125.404732 -24.573939) (xy 125.435505 -24.620452) (xy 125.459177 -24.670949) (xy 125.475245 -24.724356)
			(xy 125.480292 -24.75865) (xy 136.968736 -24.75865) (xy 136.972807 -24.703028) (xy 136.984933 -24.648591)
			(xy 137.004856 -24.5965) (xy 137.032152 -24.547865) (xy 137.066238 -24.503722) (xy 137.106387 -24.465013)
			(xy 137.151745 -24.432562) (xy 137.201345 -24.407061) (xy 137.254129 -24.389054) (xy 137.308972 -24.378924)
			(xy 137.364706 -24.376887) (xy 137.420143 -24.382987) (xy 137.4741 -24.397093) (xy 137.525429 -24.418905)
			(xy 137.573035 -24.447959) (xy 137.615903 -24.483634) (xy 137.65312 -24.525171) (xy 137.683893 -24.571684)
			(xy 137.707565 -24.622181) (xy 137.723633 -24.675588) (xy 137.731753 -24.730764) (xy 137.732262 -24.75865)
			(xy 137.731753 -24.786536) (xy 137.723633 -24.841712) (xy 137.707565 -24.895119) (xy 137.683893 -24.945616)
			(xy 137.65312 -24.992129) (xy 137.615903 -25.033666) (xy 137.573035 -25.069341) (xy 137.525429 -25.098395)
			(xy 137.4741 -25.120207) (xy 137.420143 -25.134313) (xy 137.364706 -25.140413) (xy 137.308972 -25.138376)
			(xy 137.254129 -25.128246) (xy 137.201345 -25.110239) (xy 137.151745 -25.084738) (xy 137.106387 -25.052287)
			(xy 137.066238 -25.013578) (xy 137.032152 -24.969435) (xy 137.004856 -24.9208) (xy 136.984933 -24.868709)
			(xy 136.972807 -24.814272) (xy 136.968736 -24.75865) (xy 125.480292 -24.75865) (xy 125.483365 -24.779532)
			(xy 125.483874 -24.807418) (xy 125.483365 -24.835304) (xy 125.475245 -24.89048) (xy 125.459177 -24.943887)
			(xy 125.435505 -24.994384) (xy 125.404732 -25.040897) (xy 125.367515 -25.082434) (xy 125.324647 -25.118109)
			(xy 125.277041 -25.147163) (xy 125.225712 -25.168975) (xy 125.171755 -25.183081) (xy 125.116318 -25.189181)
			(xy 125.060584 -25.187144) (xy 125.005741 -25.177014) (xy 124.952957 -25.159007) (xy 124.903357 -25.133506)
			(xy 124.857999 -25.101055) (xy 124.81785 -25.062346) (xy 124.783764 -25.018203) (xy 124.756468 -24.969568)
			(xy 124.736545 -24.917477) (xy 124.724419 -24.86304) (xy 124.720348 -24.807418) (xy 117.500908 -24.807418)
			(xy 117.500908 -25.390094) (xy 129.909824 -25.390094) (xy 129.91031 -25.362843) (xy 129.918066 -25.308895)
			(xy 129.933421 -25.2566) (xy 129.956063 -25.207023) (xy 129.985529 -25.161173) (xy 130.02122 -25.119982)
			(xy 130.062411 -25.084291) (xy 130.108261 -25.054825) (xy 130.157838 -25.032183) (xy 130.210133 -25.016828)
			(xy 130.264081 -25.009072) (xy 130.318583 -25.009072) (xy 130.372531 -25.016828) (xy 130.424826 -25.032183)
			(xy 130.474403 -25.054825) (xy 130.520253 -25.084291) (xy 130.561444 -25.119982) (xy 130.597135 -25.161173)
			(xy 130.626601 -25.207023) (xy 130.649243 -25.2566) (xy 130.664598 -25.308895) (xy 130.672354 -25.362843)
			(xy 130.67284 -25.390094) (xy 130.672273 -25.419114) (xy 130.663482 -25.476485) (xy 130.646104 -25.531862)
			(xy 130.620538 -25.583967) (xy 130.587374 -25.6316) (xy 130.547379 -25.673659) (xy 130.524758 -25.691846)
			(xy 130.514218 -25.700619) (xy 130.497783 -25.722555) (xy 130.487781 -25.748074) (xy 130.484936 -25.775336)
			(xy 130.489451 -25.802371) (xy 130.501002 -25.827228) (xy 130.518754 -25.848112) (xy 130.529838 -25.856184)
			(xy 130.551485 -25.871494) (xy 130.59074 -25.907135) (xy 130.624681 -25.947868) (xy 130.652653 -25.99291)
			(xy 130.674119 -26.041391) (xy 130.688663 -26.092378) (xy 130.696006 -26.144888) (xy 130.696462 -26.171398)
			(xy 130.695976 -26.198649) (xy 130.68822 -26.252597) (xy 130.672865 -26.304892) (xy 130.650223 -26.354469)
			(xy 130.620757 -26.400319) (xy 130.585066 -26.44151) (xy 130.543875 -26.477201) (xy 130.498025 -26.506667)
			(xy 130.448448 -26.529309) (xy 130.396153 -26.544664) (xy 130.342205 -26.55242) (xy 130.287703 -26.55242)
			(xy 130.233755 -26.544664) (xy 130.18146 -26.529309) (xy 130.131883 -26.506667) (xy 130.086033 -26.477201)
			(xy 130.044842 -26.44151) (xy 130.009151 -26.400319) (xy 129.979685 -26.354469) (xy 129.957043 -26.304892)
			(xy 129.941688 -26.252597) (xy 129.933932 -26.198649) (xy 129.933446 -26.171398) (xy 129.934013 -26.142378)
			(xy 129.942804 -26.085008) (xy 129.960183 -26.029631) (xy 129.985749 -25.977525) (xy 130.018913 -25.929893)
			(xy 130.058908 -25.887833) (xy 130.081528 -25.869646) (xy 130.092078 -25.860884) (xy 130.108516 -25.838946)
			(xy 130.118518 -25.813424) (xy 130.121363 -25.786159) (xy 130.116845 -25.759122) (xy 130.105291 -25.734263)
			(xy 130.087535 -25.713379) (xy 130.076448 -25.705308) (xy 130.054794 -25.690007) (xy 130.01554 -25.654365)
			(xy 129.9816 -25.613629) (xy 129.953628 -25.568586) (xy 129.932164 -25.520104) (xy 129.917621 -25.469116)
			(xy 129.910279 -25.416605) (xy 129.909824 -25.390094) (xy 117.500908 -25.390094) (xy 117.500908 -25.971246)
			(xy 118.05996 -25.971246) (xy 118.064031 -25.915624) (xy 118.076157 -25.861187) (xy 118.09608 -25.809096)
			(xy 118.123376 -25.760461) (xy 118.157462 -25.716318) (xy 118.197611 -25.677609) (xy 118.242969 -25.645158)
			(xy 118.292569 -25.619657) (xy 118.345353 -25.60165) (xy 118.400196 -25.59152) (xy 118.45593 -25.589483)
			(xy 118.511367 -25.595583) (xy 118.565324 -25.609689) (xy 118.616653 -25.631501) (xy 118.664259 -25.660555)
			(xy 118.707127 -25.69623) (xy 118.744344 -25.737767) (xy 118.775117 -25.78428) (xy 118.798789 -25.834777)
			(xy 118.814857 -25.888184) (xy 118.822977 -25.94336) (xy 118.823486 -25.971246) (xy 119.07596 -25.971246)
			(xy 119.080031 -25.915624) (xy 119.092157 -25.861187) (xy 119.11208 -25.809096) (xy 119.139376 -25.760461)
			(xy 119.173462 -25.716318) (xy 119.213611 -25.677609) (xy 119.258969 -25.645158) (xy 119.308569 -25.619657)
			(xy 119.361353 -25.60165) (xy 119.416196 -25.59152) (xy 119.47193 -25.589483) (xy 119.527367 -25.595583)
			(xy 119.581324 -25.609689) (xy 119.632653 -25.631501) (xy 119.680259 -25.660555) (xy 119.723127 -25.69623)
			(xy 119.760344 -25.737767) (xy 119.791117 -25.78428) (xy 119.814789 -25.834777) (xy 119.830857 -25.888184)
			(xy 119.838977 -25.94336) (xy 119.839486 -25.971246) (xy 120.09196 -25.971246) (xy 120.096031 -25.915624)
			(xy 120.108157 -25.861187) (xy 120.12808 -25.809096) (xy 120.155376 -25.760461) (xy 120.189462 -25.716318)
			(xy 120.229611 -25.677609) (xy 120.274969 -25.645158) (xy 120.324569 -25.619657) (xy 120.377353 -25.60165)
			(xy 120.432196 -25.59152) (xy 120.48793 -25.589483) (xy 120.543367 -25.595583) (xy 120.597324 -25.609689)
			(xy 120.648653 -25.631501) (xy 120.696259 -25.660555) (xy 120.739127 -25.69623) (xy 120.776344 -25.737767)
			(xy 120.807117 -25.78428) (xy 120.830789 -25.834777) (xy 120.846857 -25.888184) (xy 120.854977 -25.94336)
			(xy 120.855486 -25.971246) (xy 120.854977 -25.999132) (xy 120.849885 -26.03373) (xy 121.368056 -26.03373)
			(xy 121.372127 -25.978108) (xy 121.384253 -25.923671) (xy 121.404176 -25.87158) (xy 121.431472 -25.822945)
			(xy 121.465558 -25.778802) (xy 121.505707 -25.740093) (xy 121.551065 -25.707642) (xy 121.600665 -25.682141)
			(xy 121.653449 -25.664134) (xy 121.708292 -25.654004) (xy 121.764026 -25.651967) (xy 121.819463 -25.658067)
			(xy 121.87342 -25.672173) (xy 121.924749 -25.693985) (xy 121.972355 -25.723039) (xy 122.015223 -25.758714)
			(xy 122.05244 -25.800251) (xy 122.083213 -25.846764) (xy 122.106885 -25.897261) (xy 122.122953 -25.950668)
			(xy 122.131073 -26.005844) (xy 122.131582 -26.03373) (xy 122.131073 -26.061616) (xy 122.122953 -26.116792)
			(xy 122.106885 -26.170199) (xy 122.083213 -26.220696) (xy 122.052979 -26.266394) (xy 124.620782 -26.266394)
			(xy 124.621272 -26.239143) (xy 124.629029 -26.185196) (xy 124.644385 -26.132902) (xy 124.667026 -26.083325)
			(xy 124.696492 -26.037475) (xy 124.732183 -25.996286) (xy 124.773372 -25.960594) (xy 124.819222 -25.931128)
			(xy 124.868798 -25.908486) (xy 124.921092 -25.89313) (xy 124.975039 -25.885372) (xy 125.00229 -25.884886)
			(xy 125.031615 -25.885419) (xy 125.089573 -25.8944) (xy 125.145472 -25.912152) (xy 125.197992 -25.938256)
			(xy 125.222254 -25.954736) (xy 125.232668 -25.961848) (xy 125.257052 -25.96515) (xy 125.359414 -25.927304)
			(xy 125.376178 -25.908762) (xy 125.379226 -25.89657) (xy 125.386579 -25.869487) (xy 125.408138 -25.817675)
			(xy 125.437058 -25.769582) (xy 125.472712 -25.726246) (xy 125.514333 -25.688604) (xy 125.561021 -25.657467)
			(xy 125.611768 -25.633508) (xy 125.665477 -25.617245) (xy 125.720991 -25.609028) (xy 125.74905 -25.608534)
			(xy 125.776308 -25.60891) (xy 125.830271 -25.616662) (xy 125.88258 -25.632015) (xy 125.932172 -25.654657)
			(xy 125.978037 -25.684127) (xy 126.01924 -25.719825) (xy 126.054943 -25.761023) (xy 126.084419 -25.806884)
			(xy 126.107068 -25.856473) (xy 126.122428 -25.908781) (xy 126.130187 -25.962742) (xy 126.130187 -25.990042)
			(xy 127.399032 -25.990042) (xy 127.403103 -25.93442) (xy 127.415229 -25.879983) (xy 127.435152 -25.827892)
			(xy 127.462448 -25.779257) (xy 127.496534 -25.735114) (xy 127.536683 -25.696405) (xy 127.582041 -25.663954)
			(xy 127.631641 -25.638453) (xy 127.684425 -25.620446) (xy 127.739268 -25.610316) (xy 127.795002 -25.608279)
			(xy 127.850439 -25.614379) (xy 127.904396 -25.628485) (xy 127.955725 -25.650297) (xy 128.003331 -25.679351)
			(xy 128.046199 -25.715026) (xy 128.083416 -25.756563) (xy 128.114189 -25.803076) (xy 128.137861 -25.853573)
			(xy 128.153929 -25.90698) (xy 128.162049 -25.962156) (xy 128.162558 -25.990042) (xy 128.162049 -26.017928)
			(xy 128.153929 -26.073104) (xy 128.137861 -26.126511) (xy 128.114189 -26.177008) (xy 128.083416 -26.223521)
			(xy 128.046199 -26.265058) (xy 128.003331 -26.300733) (xy 127.955725 -26.329787) (xy 127.904396 -26.351599)
			(xy 127.850439 -26.365705) (xy 127.795002 -26.371805) (xy 127.739268 -26.369768) (xy 127.684425 -26.359638)
			(xy 127.631641 -26.341631) (xy 127.582041 -26.31613) (xy 127.536683 -26.283679) (xy 127.496534 -26.24497)
			(xy 127.462448 -26.200827) (xy 127.435152 -26.152192) (xy 127.415229 -26.100101) (xy 127.403103 -26.045664)
			(xy 127.399032 -25.990042) (xy 126.130187 -25.990042) (xy 126.130187 -26.017258) (xy 126.122428 -26.071219)
			(xy 126.107068 -26.123527) (xy 126.084419 -26.173116) (xy 126.054943 -26.218977) (xy 126.01924 -26.260175)
			(xy 125.978037 -26.295873) (xy 125.932172 -26.325343) (xy 125.88258 -26.347985) (xy 125.830271 -26.363338)
			(xy 125.776308 -26.37109) (xy 125.74905 -26.37155) (xy 125.719726 -26.37099) (xy 125.66177 -26.362016)
			(xy 125.605871 -26.344272) (xy 125.553349 -26.318176) (xy 125.529086 -26.3017) (xy 125.518672 -26.294588)
			(xy 125.494288 -26.291286) (xy 125.391926 -26.329132) (xy 125.375162 -26.347674) (xy 125.372114 -26.359866)
			(xy 125.365345 -26.384902) (xy 125.345927 -26.432993) (xy 125.320167 -26.478007) (xy 125.288542 -26.519112)
			(xy 125.251635 -26.55555) (xy 125.231144 -26.571448) (xy 125.220984 -26.579322) (xy 125.210316 -26.601928)
			(xy 125.215904 -26.711656) (xy 125.228858 -26.733246) (xy 125.23978 -26.73985) (xy 125.263512 -26.754762)
			(xy 125.306748 -26.790426) (xy 125.344301 -26.832032) (xy 125.375362 -26.878684) (xy 125.399262 -26.92938)
			(xy 125.415488 -26.983027) (xy 125.423689 -27.038471) (xy 125.424184 -27.066494) (xy 125.423698 -27.093745)
			(xy 125.415942 -27.147693) (xy 125.400587 -27.199988) (xy 125.377945 -27.249565) (xy 125.348479 -27.295415)
			(xy 125.312788 -27.336606) (xy 125.271597 -27.372297) (xy 125.225747 -27.401763) (xy 125.17617 -27.424405)
			(xy 125.123875 -27.43976) (xy 125.069927 -27.447516) (xy 125.015425 -27.447516) (xy 124.961477 -27.43976)
			(xy 124.909182 -27.424405) (xy 124.859605 -27.401763) (xy 124.813755 -27.372297) (xy 124.772564 -27.336606)
			(xy 124.736873 -27.295415) (xy 124.707407 -27.249565) (xy 124.684765 -27.199988) (xy 124.66941 -27.147693)
			(xy 124.661654 -27.093745) (xy 124.661168 -27.066494) (xy 124.661724 -27.037007) (xy 124.67082 -26.978737)
			(xy 124.688778 -26.922562) (xy 124.71517 -26.869822) (xy 124.749368 -26.821774) (xy 124.790555 -26.779564)
			(xy 124.813822 -26.76144) (xy 124.823982 -26.753566) (xy 124.83465 -26.73096) (xy 124.829062 -26.621232)
			(xy 124.816108 -26.599642) (xy 124.805186 -26.593038) (xy 124.781441 -26.578146) (xy 124.738206 -26.542478)
			(xy 124.700656 -26.500868) (xy 124.669597 -26.454212) (xy 124.645699 -26.403513) (xy 124.629475 -26.349864)
			(xy 124.621276 -26.294418) (xy 124.620782 -26.266394) (xy 122.052979 -26.266394) (xy 122.05244 -26.267209)
			(xy 122.015223 -26.308746) (xy 121.972355 -26.344421) (xy 121.924749 -26.373475) (xy 121.87342 -26.395287)
			(xy 121.819463 -26.409393) (xy 121.764026 -26.415493) (xy 121.708292 -26.413456) (xy 121.653449 -26.403326)
			(xy 121.600665 -26.385319) (xy 121.551065 -26.359818) (xy 121.505707 -26.327367) (xy 121.465558 -26.288658)
			(xy 121.431472 -26.244515) (xy 121.404176 -26.19588) (xy 121.384253 -26.143789) (xy 121.372127 -26.089352)
			(xy 121.368056 -26.03373) (xy 120.849885 -26.03373) (xy 120.846857 -26.054308) (xy 120.830789 -26.107715)
			(xy 120.807117 -26.158212) (xy 120.776344 -26.204725) (xy 120.739127 -26.246262) (xy 120.696259 -26.281937)
			(xy 120.648653 -26.310991) (xy 120.597324 -26.332803) (xy 120.543367 -26.346909) (xy 120.48793 -26.353009)
			(xy 120.432196 -26.350972) (xy 120.377353 -26.340842) (xy 120.324569 -26.322835) (xy 120.274969 -26.297334)
			(xy 120.229611 -26.264883) (xy 120.189462 -26.226174) (xy 120.155376 -26.182031) (xy 120.12808 -26.133396)
			(xy 120.108157 -26.081305) (xy 120.096031 -26.026868) (xy 120.09196 -25.971246) (xy 119.839486 -25.971246)
			(xy 119.838977 -25.999132) (xy 119.830857 -26.054308) (xy 119.814789 -26.107715) (xy 119.791117 -26.158212)
			(xy 119.760344 -26.204725) (xy 119.723127 -26.246262) (xy 119.680259 -26.281937) (xy 119.632653 -26.310991)
			(xy 119.581324 -26.332803) (xy 119.527367 -26.346909) (xy 119.47193 -26.353009) (xy 119.416196 -26.350972)
			(xy 119.361353 -26.340842) (xy 119.308569 -26.322835) (xy 119.258969 -26.297334) (xy 119.213611 -26.264883)
			(xy 119.173462 -26.226174) (xy 119.139376 -26.182031) (xy 119.11208 -26.133396) (xy 119.092157 -26.081305)
			(xy 119.080031 -26.026868) (xy 119.07596 -25.971246) (xy 118.823486 -25.971246) (xy 118.822977 -25.999132)
			(xy 118.814857 -26.054308) (xy 118.798789 -26.107715) (xy 118.775117 -26.158212) (xy 118.744344 -26.204725)
			(xy 118.707127 -26.246262) (xy 118.664259 -26.281937) (xy 118.616653 -26.310991) (xy 118.565324 -26.332803)
			(xy 118.511367 -26.346909) (xy 118.45593 -26.353009) (xy 118.400196 -26.350972) (xy 118.345353 -26.340842)
			(xy 118.292569 -26.322835) (xy 118.242969 -26.297334) (xy 118.197611 -26.264883) (xy 118.157462 -26.226174)
			(xy 118.123376 -26.182031) (xy 118.09608 -26.133396) (xy 118.076157 -26.081305) (xy 118.064031 -26.026868)
			(xy 118.05996 -25.971246) (xy 117.500908 -25.971246) (xy 117.500908 -27.66949) (xy 117.516402 -27.694382)
			(xy 117.529864 -27.700732) (xy 117.556628 -27.714216) (xy 117.605954 -27.748248) (xy 117.615099 -27.756952)
			(xy 120.859266 -27.756952) (xy 120.859266 -27.702448) (xy 120.867022 -27.648499) (xy 120.882378 -27.596203)
			(xy 120.905019 -27.546624) (xy 120.934486 -27.500773) (xy 120.970178 -27.459581) (xy 121.01137 -27.423889)
			(xy 121.057221 -27.394421) (xy 121.106799 -27.371779) (xy 121.159095 -27.356423) (xy 121.213044 -27.348666)
			(xy 121.240296 -27.34818) (xy 121.254381 -27.348285) (xy 121.282477 -27.350316) (xy 121.29643 -27.352244)
			(xy 121.310146 -27.354276) (xy 121.336054 -27.343862) (xy 121.406412 -27.249882) (xy 121.40946 -27.221942)
			(xy 121.403618 -27.209242) (xy 121.39258 -27.184111) (xy 121.376974 -27.131489) (xy 121.369066 -27.077173)
			(xy 121.368566 -27.04973) (xy 121.369052 -27.022479) (xy 121.376808 -26.968531) (xy 121.392163 -26.916236)
			(xy 121.414805 -26.866659) (xy 121.444271 -26.820809) (xy 121.479962 -26.779618) (xy 121.521153 -26.743927)
			(xy 121.567003 -26.714461) (xy 121.61658 -26.691819) (xy 121.668875 -26.676464) (xy 121.722823 -26.668708)
			(xy 121.777325 -26.668708) (xy 121.831273 -26.676464) (xy 121.883568 -26.691819) (xy 121.933145 -26.714461)
			(xy 121.978995 -26.743927) (xy 122.020186 -26.779618) (xy 122.055877 -26.820809) (xy 122.085343 -26.866659)
			(xy 122.107985 -26.916236) (xy 122.12334 -26.968531) (xy 122.131096 -27.022479) (xy 122.131582 -27.04973)
			(xy 122.130963 -27.081146) (xy 122.1207 -27.143133) (xy 122.100424 -27.202603) (xy 122.086116 -27.230578)
			(xy 122.080782 -27.24023) (xy 122.079258 -27.262074) (xy 122.113548 -27.354022) (xy 122.128788 -27.369516)
			(xy 122.138948 -27.37358) (xy 122.165603 -27.38432) (xy 122.215569 -27.412705) (xy 122.26071 -27.448266)
			(xy 122.300003 -27.490199) (xy 122.332559 -27.537553) (xy 122.35764 -27.589256) (xy 122.374679 -27.644138)
			(xy 122.383289 -27.700955) (xy 122.383804 -27.729688) (xy 122.383333 -27.756941) (xy 122.375578 -27.810892)
			(xy 122.360223 -27.86319) (xy 122.337582 -27.91277) (xy 122.308115 -27.958623) (xy 122.272422 -27.999816)
			(xy 122.23123 -28.03551) (xy 122.185377 -28.064978) (xy 122.135797 -28.087621) (xy 122.083499 -28.102976)
			(xy 122.029549 -28.110733) (xy 122.002296 -28.111196) (xy 121.973379 -28.110682) (xy 121.916207 -28.101952)
			(xy 121.861009 -28.084693) (xy 121.809047 -28.059301) (xy 121.761513 -28.026357) (xy 121.719496 -27.986616)
			(xy 121.701306 -27.96413) (xy 121.693749 -27.955364) (xy 121.672986 -27.945186) (xy 121.661428 -27.944572)
			(xy 121.581164 -27.944572) (xy 121.569597 -27.945154) (xy 121.548824 -27.955338) (xy 121.541286 -27.96413)
			(xy 121.52311 -27.986626) (xy 121.481087 -28.026359) (xy 121.433548 -28.059296) (xy 121.381584 -28.084682)
			(xy 121.326384 -28.101936) (xy 121.269213 -28.110662) (xy 121.240296 -28.111196) (xy 121.213044 -28.110734)
			(xy 121.159095 -28.102977) (xy 121.106799 -28.087621) (xy 121.057221 -28.064979) (xy 121.01137 -28.035511)
			(xy 120.970178 -27.999819) (xy 120.934486 -27.958627) (xy 120.905019 -27.912776) (xy 120.882378 -27.863197)
			(xy 120.867022 -27.810901) (xy 120.859266 -27.756952) (xy 117.615099 -27.756952) (xy 117.649363 -27.789563)
			(xy 117.66804 -27.813) (xy 117.670326 -27.815794) (xy 117.676168 -27.821636) (xy 117.682127 -27.827145)
			(xy 117.696632 -27.834408) (xy 117.704616 -27.83586) (xy 117.773196 -27.84602) (xy 117.783283 -27.847099)
			(xy 117.802927 -27.842105) (xy 117.811296 -27.836368) (xy 117.81155 -27.836114) (xy 117.831599 -27.821287)
			(xy 117.874814 -27.796407) (xy 117.920902 -27.777368) (xy 117.969077 -27.764494) (xy 118.018519 -27.758006)
			(xy 118.043452 -27.757628) (xy 118.051326 -27.757628) (xy 118.078799 -27.758679) (xy 118.133033 -27.767698)
			(xy 118.18541 -27.784408) (xy 118.234847 -27.808462) (xy 118.28032 -27.839362) (xy 118.320887 -27.87647)
			(xy 118.355708 -27.919015) (xy 118.37035 -27.942286) (xy 118.373144 -27.947112) (xy 118.377462 -27.951684)
			(xy 118.38813 -27.960066) (xy 118.40845 -27.972004) (xy 118.416578 -27.975814) (xy 118.42877 -27.978608)
			(xy 118.434104 -27.978862) (xy 118.500652 -27.978862) (xy 118.509545 -27.97853) (xy 118.52626 -27.972449)
			(xy 118.539878 -27.961009) (xy 118.544594 -27.953462) (xy 118.557251 -27.932331) (xy 118.58719 -27.893218)
			(xy 118.604284 -27.875484) (xy 118.607586 -27.871928) (xy 118.60784 -27.871674) (xy 118.629521 -27.850459)
			(xy 118.678357 -27.814483) (xy 118.73227 -27.786686) (xy 118.789901 -27.767769) (xy 118.849799 -27.758208)
			(xy 118.880128 -27.757628) (xy 118.889272 -27.757628) (xy 118.916094 -27.758724) (xy 118.969052 -27.767514)
			(xy 119.020253 -27.783643) (xy 119.068687 -27.806793) (xy 119.113395 -27.836506) (xy 119.153496 -27.872195)
			(xy 119.188195 -27.913154) (xy 119.216808 -27.958575) (xy 119.238769 -28.007559) (xy 119.253644 -28.059139)
			(xy 119.261139 -28.112295) (xy 119.261636 -28.139136) (xy 119.76811 -28.139136) (xy 119.772181 -28.083514)
			(xy 119.784307 -28.029077) (xy 119.80423 -27.976986) (xy 119.831526 -27.928351) (xy 119.865612 -27.884208)
			(xy 119.905761 -27.845499) (xy 119.951119 -27.813048) (xy 120.000719 -27.787547) (xy 120.053503 -27.76954)
			(xy 120.108346 -27.75941) (xy 120.16408 -27.757373) (xy 120.219517 -27.763473) (xy 120.273474 -27.777579)
			(xy 120.324803 -27.799391) (xy 120.372409 -27.828445) (xy 120.415277 -27.86412) (xy 120.452494 -27.905657)
			(xy 120.483267 -27.95217) (xy 120.506939 -28.002667) (xy 120.523007 -28.056074) (xy 120.531127 -28.11125)
			(xy 120.531636 -28.139136) (xy 120.531127 -28.167022) (xy 120.523007 -28.222198) (xy 120.506939 -28.275605)
			(xy 120.483267 -28.326102) (xy 120.452494 -28.372615) (xy 120.415277 -28.414152) (xy 120.372409 -28.449827)
			(xy 120.324803 -28.478881) (xy 120.273474 -28.500693) (xy 120.219517 -28.514799) (xy 120.16408 -28.520899)
			(xy 120.108346 -28.518862) (xy 120.053503 -28.508732) (xy 120.000719 -28.490725) (xy 119.951119 -28.465224)
			(xy 119.905761 -28.432773) (xy 119.865612 -28.394064) (xy 119.831526 -28.349921) (xy 119.80423 -28.301286)
			(xy 119.784307 -28.249195) (xy 119.772181 -28.194758) (xy 119.76811 -28.139136) (xy 119.261636 -28.139136)
			(xy 119.261217 -28.164504) (xy 119.254488 -28.214791) (xy 119.241154 -28.263743) (xy 119.221449 -28.310496)
			(xy 119.195722 -28.354224) (xy 119.164426 -28.394158) (xy 119.146574 -28.412186) (xy 119.124926 -28.433295)
			(xy 119.076197 -28.469087) (xy 119.022434 -28.496747) (xy 118.964982 -28.515583) (xy 118.905278 -28.525125)
			(xy 118.875048 -28.525724) (xy 118.846495 -28.525187) (xy 118.790027 -28.516672) (xy 118.735458 -28.49984)
			(xy 118.684005 -28.475066) (xy 118.636817 -28.442903) (xy 118.594947 -28.40407) (xy 118.55933 -28.359432)
			(xy 118.544594 -28.33497) (xy 118.539815 -28.327476) (xy 118.526211 -28.316057) (xy 118.509531 -28.309956)
			(xy 118.500652 -28.30957) (xy 118.4148 -28.30957) (xy 118.406011 -28.30994) (xy 118.389472 -28.315894)
			(xy 118.375927 -28.327099) (xy 118.371112 -28.334462) (xy 118.358166 -28.355422) (xy 118.327718 -28.394151)
			(xy 118.310406 -28.411678) (xy 118.309898 -28.412186) (xy 118.288251 -28.433296) (xy 118.239523 -28.469091)
			(xy 118.18576 -28.496755) (xy 118.128307 -28.515595) (xy 118.068603 -28.52514) (xy 118.038372 -28.525724)
			(xy 118.009215 -28.52517) (xy 117.95158 -28.516294) (xy 117.895967 -28.498753) (xy 117.84367 -28.472955)
			(xy 117.795906 -28.439502) (xy 117.753787 -28.399171) (xy 117.735604 -28.376372) (xy 117.733572 -28.373578)
			(xy 117.72773 -28.367736) (xy 117.721797 -28.362298) (xy 117.707436 -28.355053) (xy 117.699536 -28.353512)
			(xy 117.629178 -28.343098) (xy 117.624218 -28.342485) (xy 117.614237 -28.342994) (xy 117.609366 -28.344114)
			(xy 117.599968 -28.3464) (xy 117.59184 -28.352242) (xy 117.584474 -28.357576) (xy 117.579902 -28.360878)
			(xy 117.56771 -28.373832) (xy 117.560598 -28.383738) (xy 117.552216 -28.399486) (xy 117.549283 -28.405151)
			(xy 117.546072 -28.417494) (xy 117.545866 -28.42387) (xy 117.545866 -28.428442) (xy 117.546103 -28.434813)
			(xy 117.549325 -28.447143) (xy 117.552216 -28.452826) (xy 117.559582 -28.466288) (xy 117.568218 -28.475686)
			(xy 117.573806 -28.479242) (xy 117.596302 -28.493924) (xy 117.637322 -28.52861) (xy 117.673069 -28.568708)
			(xy 117.702838 -28.613425) (xy 117.726038 -28.661875) (xy 117.742212 -28.713102) (xy 117.751038 -28.766091)
			(xy 117.752114 -28.792932) (xy 117.752114 -28.800552) (xy 117.752114 -28.802076) (xy 117.751705 -28.827556)
			(xy 117.744953 -28.878065) (xy 117.731539 -28.927226) (xy 117.711701 -28.974165) (xy 117.685792 -29.018046)
			(xy 117.654274 -29.058088) (xy 117.63629 -29.076142) (xy 117.635528 -29.07665) (xy 117.612089 -29.099268)
			(xy 117.558963 -29.136945) (xy 117.529864 -29.15158) (xy 117.516402 -29.15793) (xy 117.500908 -29.182568)
			(xy 117.500908 -29.217874) (xy 117.501345 -29.227938) (xy 117.509079 -29.246522) (xy 117.515894 -29.253942)
			(xy 117.530118 -29.268166) (xy 117.537738 -29.271976) (xy 117.561488 -29.284072) (xy 117.605679 -29.313868)
			(xy 117.645295 -29.349523) (xy 117.679563 -29.390344) (xy 117.707817 -29.435537) (xy 117.729508 -29.484221)
			(xy 117.744213 -29.53545) (xy 117.751647 -29.588227) (xy 117.752114 -29.614876) (xy 117.751701 -29.640215)
			(xy 117.744995 -29.690448) (xy 117.731697 -29.739351) (xy 117.712042 -29.786062) (xy 117.686375 -29.829761)
			(xy 117.655149 -29.869676) (xy 117.637306 -29.887672) (xy 117.636798 -29.88818) (xy 117.628067 -29.896892)
			(xy 117.609638 -29.913289) (xy 117.599968 -29.920946) (xy 117.591137 -29.928536) (xy 117.580947 -29.949446)
			(xy 117.58041 -29.961078) (xy 117.58041 -30.031944) (xy 117.58095 -30.043772) (xy 117.591399 -30.064986)
			(xy 117.600476 -30.072584) (xy 117.623669 -30.09077) (xy 117.664694 -30.133081) (xy 117.698722 -30.181201)
			(xy 117.724941 -30.233982) (xy 117.742728 -30.290169) (xy 117.751659 -30.348423) (xy 117.752114 -30.377892)
			(xy 117.752114 -30.380686) (xy 117.751252 -30.410916) (xy 117.741152 -30.47054) (xy 117.721772 -30.527824)
			(xy 117.693599 -30.581333) (xy 117.657338 -30.629728) (xy 117.636036 -30.651196) (xy 117.635274 -30.651704)
			(xy 117.611883 -30.674242) (xy 117.558885 -30.711789) (xy 117.529864 -30.72638) (xy 117.516402 -30.73273)
			(xy 117.500908 -30.757368) (xy 117.500908 -31.141416) (xy 117.501296 -31.150339) (xy 117.507393 -31.16711)
			(xy 117.512846 -31.174182) (xy 117.518942 -31.181294) (xy 117.534436 -31.18993) (xy 117.543326 -31.191454)
			(xy 117.569729 -31.196298) (xy 117.62093 -31.212424) (xy 117.669364 -31.235569) (xy 117.714074 -31.265277)
			(xy 117.754177 -31.300961) (xy 117.788879 -31.341916) (xy 117.817496 -31.387332) (xy 117.839462 -31.436312)
			(xy 117.854343 -31.487888) (xy 117.861845 -31.541042) (xy 117.86235 -31.567882) (xy 117.861765 -31.598222)
			(xy 117.852161 -31.658138) (xy 117.833193 -31.715777) (xy 117.83139 -31.719266) (xy 118.385588 -31.719266)
			(xy 118.389659 -31.663644) (xy 118.401785 -31.609207) (xy 118.421708 -31.557116) (xy 118.449004 -31.508481)
			(xy 118.48309 -31.464338) (xy 118.523239 -31.425629) (xy 118.568597 -31.393178) (xy 118.618197 -31.367677)
			(xy 118.670981 -31.34967) (xy 118.725824 -31.33954) (xy 118.781558 -31.337503) (xy 118.836995 -31.343603)
			(xy 118.890952 -31.357709) (xy 118.942281 -31.379521) (xy 118.989887 -31.408575) (xy 119.032755 -31.44425)
			(xy 119.069972 -31.485787) (xy 119.100745 -31.5323) (xy 119.124417 -31.582797) (xy 119.140485 -31.636204)
			(xy 119.144635 -31.664402) (xy 119.661176 -31.664402) (xy 119.665247 -31.60878) (xy 119.677373 -31.554343)
			(xy 119.697296 -31.502252) (xy 119.724592 -31.453617) (xy 119.758678 -31.409474) (xy 119.798827 -31.370765)
			(xy 119.844185 -31.338314) (xy 119.893785 -31.312813) (xy 119.946569 -31.294806) (xy 120.001412 -31.284676)
			(xy 120.057146 -31.282639) (xy 120.112583 -31.288739) (xy 120.16654 -31.302845) (xy 120.217869 -31.324657)
			(xy 120.265475 -31.353711) (xy 120.308343 -31.389386) (xy 120.34556 -31.430923) (xy 120.376333 -31.477436)
			(xy 120.400005 -31.527933) (xy 120.416073 -31.58134) (xy 120.424193 -31.636516) (xy 120.424702 -31.664402)
			(xy 120.424193 -31.692288) (xy 120.416073 -31.747464) (xy 120.407133 -31.777178) (xy 120.92635 -31.777178)
			(xy 120.930421 -31.721556) (xy 120.942547 -31.667119) (xy 120.96247 -31.615028) (xy 120.989766 -31.566393)
			(xy 121.023852 -31.52225) (xy 121.064001 -31.483541) (xy 121.109359 -31.45109) (xy 121.158959 -31.425589)
			(xy 121.211743 -31.407582) (xy 121.266586 -31.397452) (xy 121.32232 -31.395415) (xy 121.377757 -31.401515)
			(xy 121.431714 -31.415621) (xy 121.483043 -31.437433) (xy 121.530649 -31.466487) (xy 121.573517 -31.502162)
			(xy 121.610734 -31.543699) (xy 121.641507 -31.590212) (xy 121.665179 -31.640709) (xy 121.681247 -31.694116)
			(xy 121.689367 -31.749292) (xy 121.689876 -31.777178) (xy 121.689367 -31.805064) (xy 121.681247 -31.86024)
			(xy 121.665179 -31.913647) (xy 121.641507 -31.964144) (xy 121.610734 -32.010657) (xy 121.573517 -32.052194)
			(xy 121.530649 -32.087869) (xy 121.483043 -32.116923) (xy 121.431714 -32.138735) (xy 121.377757 -32.152841)
			(xy 121.32232 -32.158941) (xy 121.266586 -32.156904) (xy 121.211743 -32.146774) (xy 121.158959 -32.128767)
			(xy 121.109359 -32.103266) (xy 121.064001 -32.070815) (xy 121.023852 -32.032106) (xy 120.989766 -31.987963)
			(xy 120.96247 -31.939328) (xy 120.942547 -31.887237) (xy 120.930421 -31.8328) (xy 120.92635 -31.777178)
			(xy 120.407133 -31.777178) (xy 120.400005 -31.800871) (xy 120.376333 -31.851368) (xy 120.34556 -31.897881)
			(xy 120.308343 -31.939418) (xy 120.265475 -31.975093) (xy 120.217869 -32.004147) (xy 120.16654 -32.025959)
			(xy 120.112583 -32.040065) (xy 120.057146 -32.046165) (xy 120.001412 -32.044128) (xy 119.946569 -32.033998)
			(xy 119.893785 -32.015991) (xy 119.844185 -31.99049) (xy 119.798827 -31.958039) (xy 119.758678 -31.91933)
			(xy 119.724592 -31.875187) (xy 119.697296 -31.826552) (xy 119.677373 -31.774461) (xy 119.665247 -31.720024)
			(xy 119.661176 -31.664402) (xy 119.144635 -31.664402) (xy 119.148605 -31.69138) (xy 119.149114 -31.719266)
			(xy 119.148605 -31.747152) (xy 119.140485 -31.802328) (xy 119.124417 -31.855735) (xy 119.100745 -31.906232)
			(xy 119.069972 -31.952745) (xy 119.032755 -31.994282) (xy 118.989887 -32.029957) (xy 118.942281 -32.059011)
			(xy 118.890952 -32.080823) (xy 118.836995 -32.094929) (xy 118.781558 -32.101029) (xy 118.725824 -32.098992)
			(xy 118.670981 -32.088862) (xy 118.618197 -32.070855) (xy 118.568597 -32.045354) (xy 118.523239 -32.012903)
			(xy 118.48309 -31.974194) (xy 118.449004 -31.930051) (xy 118.421708 -31.881416) (xy 118.401785 -31.829325)
			(xy 118.389659 -31.774888) (xy 118.385588 -31.719266) (xy 117.83139 -31.719266) (xy 117.805338 -31.769687)
			(xy 117.7693 -31.818506) (xy 117.74805 -31.84017) (xy 117.747288 -31.840932) (xy 117.726288 -31.861465)
			(xy 117.679135 -31.896477) (xy 117.627173 -31.923848) (xy 117.571631 -31.942934) (xy 117.542818 -31.948628)
			(xy 117.542564 -31.948628) (xy 117.533914 -31.950585) (xy 117.518607 -31.959512) (xy 117.507271 -31.973131)
			(xy 117.501271 -31.989805) (xy 117.500908 -31.998666) (xy 117.500908 -33.512506) (xy 117.501389 -33.522403)
			(xy 117.508895 -33.54072) (xy 117.522757 -33.554851) (xy 117.531642 -33.559242) (xy 117.631718 -33.602168)
			(xy 117.661944 -33.596326) (xy 117.672866 -33.585658) (xy 117.694408 -33.565269) (xy 117.742627 -33.530734)
			(xy 117.795609 -33.504074) (xy 117.852077 -33.485932) (xy 117.910673 -33.476745) (xy 117.940328 -33.476184)
			(xy 117.953066 -33.476263) (xy 117.978487 -33.477919) (xy 117.991128 -33.479486) (xy 118.018173 -33.48359)
			(xy 118.070792 -33.498536) (xy 118.120737 -33.520846) (xy 118.166982 -33.550063) (xy 118.208579 -33.585586)
			(xy 118.244674 -33.626687) (xy 118.274527 -33.672524) (xy 118.297526 -33.722155) (xy 118.305834 -33.748218)
			(xy 118.308628 -33.757362) (xy 118.320312 -33.772348) (xy 118.38559 -33.81121) (xy 118.393972 -33.812734)
			(xy 118.416533 -33.8075) (xy 118.462508 -33.801894) (xy 118.485666 -33.801558) (xy 118.51292 -33.802041)
			(xy 118.566873 -33.809794) (xy 118.619174 -33.825146) (xy 118.668757 -33.847784) (xy 118.684177 -33.857692)
			(xy 119.59031 -33.857692) (xy 119.594381 -33.80207) (xy 119.606507 -33.747633) (xy 119.62643 -33.695542)
			(xy 119.653726 -33.646907) (xy 119.687812 -33.602764) (xy 119.727961 -33.564055) (xy 119.773319 -33.531604)
			(xy 119.822919 -33.506103) (xy 119.875703 -33.488096) (xy 119.930546 -33.477966) (xy 119.98628 -33.475929)
			(xy 120.041717 -33.482029) (xy 120.095674 -33.496135) (xy 120.147003 -33.517947) (xy 120.194609 -33.547001)
			(xy 120.237477 -33.582676) (xy 120.274694 -33.624213) (xy 120.305467 -33.670726) (xy 120.329139 -33.721223)
			(xy 120.345207 -33.77463) (xy 120.353327 -33.829806) (xy 120.353836 -33.857692) (xy 120.353327 -33.885578)
			(xy 120.345207 -33.940754) (xy 120.329139 -33.994161) (xy 120.305467 -34.044658) (xy 120.274694 -34.091171)
			(xy 120.237477 -34.132708) (xy 120.194609 -34.168383) (xy 120.147003 -34.197437) (xy 120.095674 -34.219249)
			(xy 120.041717 -34.233355) (xy 119.98628 -34.239455) (xy 119.930546 -34.237418) (xy 119.875703 -34.227288)
			(xy 119.822919 -34.209281) (xy 119.773319 -34.18378) (xy 119.727961 -34.151329) (xy 119.687812 -34.11262)
			(xy 119.653726 -34.068477) (xy 119.62643 -34.019842) (xy 119.606507 -33.967751) (xy 119.594381 -33.913314)
			(xy 119.59031 -33.857692) (xy 118.684177 -33.857692) (xy 118.714614 -33.877249) (xy 118.755812 -33.91294)
			(xy 118.79151 -33.954131) (xy 118.820983 -33.999983) (xy 118.843631 -34.049562) (xy 118.858992 -34.101861)
			(xy 118.866754 -34.155812) (xy 118.867174 -34.183066) (xy 118.86676 -34.208436) (xy 118.86004 -34.258728)
			(xy 118.846713 -34.307687) (xy 118.827016 -34.354447) (xy 118.801295 -34.398184) (xy 118.770005 -34.438127)
			(xy 118.752112 -34.456116) (xy 118.730464 -34.477226) (xy 118.681736 -34.51302) (xy 118.627973 -34.540683)
			(xy 118.570521 -34.559524) (xy 118.510817 -34.56907) (xy 118.480586 -34.569654) (xy 118.453991 -34.569193)
			(xy 118.401316 -34.561807) (xy 118.350177 -34.54718) (xy 118.301563 -34.525595) (xy 118.256417 -34.497471)
			(xy 118.215612 -34.463352) (xy 118.179939 -34.423898) (xy 118.150088 -34.379874) (xy 118.126638 -34.332132)
			(xy 118.117874 -34.307018) (xy 118.117874 -34.306764) (xy 118.114826 -34.297874) (xy 118.109492 -34.291016)
			(xy 118.106526 -34.287412) (xy 118.099498 -34.28127) (xy 118.095522 -34.278824) (xy 118.030244 -34.239708)
			(xy 118.012464 -34.236406) (xy 118.00332 -34.238184) (xy 117.98651 -34.241026) (xy 117.95255 -34.244076)
			(xy 117.935502 -34.24428) (xy 117.935248 -34.24428) (xy 117.906238 -34.243736) (xy 117.848885 -34.234954)
			(xy 117.79352 -34.217598) (xy 117.741417 -34.192069) (xy 117.693775 -34.158954) (xy 117.672358 -34.139378)
			(xy 117.667024 -34.134298) (xy 117.653816 -34.127694) (xy 117.64645 -34.12617) (xy 117.638992 -34.125045)
			(xy 117.624013 -34.126731) (xy 117.616986 -34.129472) (xy 117.531642 -34.166302) (xy 117.517418 -34.172398)
			(xy 117.500908 -34.197544) (xy 117.500908 -35.264852) (xy 120.002552 -35.264852) (xy 120.006623 -35.20923)
			(xy 120.018749 -35.154793) (xy 120.038672 -35.102702) (xy 120.065968 -35.054067) (xy 120.100054 -35.009924)
			(xy 120.140203 -34.971215) (xy 120.185561 -34.938764) (xy 120.235161 -34.913263) (xy 120.287945 -34.895256)
			(xy 120.342788 -34.885126) (xy 120.398522 -34.883089) (xy 120.453959 -34.889189) (xy 120.507916 -34.903295)
			(xy 120.559245 -34.925107) (xy 120.606851 -34.954161) (xy 120.649719 -34.989836) (xy 120.674552 -35.017551)
			(xy 122.320056 -35.017551) (xy 122.320056 -34.963049) (xy 122.327811 -34.909103) (xy 122.343165 -34.856809)
			(xy 122.365804 -34.807232) (xy 122.395267 -34.761382) (xy 122.430955 -34.720191) (xy 122.472142 -34.684497)
			(xy 122.517989 -34.655028) (xy 122.567562 -34.632382) (xy 122.619854 -34.617022) (xy 122.6738 -34.609259)
			(xy 122.70105 -34.60877) (xy 122.718162 -34.608963) (xy 122.752249 -34.612014) (xy 122.769122 -34.614866)
			(xy 122.780387 -34.616267) (xy 122.802271 -34.610335) (xy 122.811286 -34.603436) (xy 122.83567 -34.582354)
			(xy 122.844059 -34.574429) (xy 122.853182 -34.553255) (xy 122.853196 -34.541714) (xy 122.852688 -34.52241)
			(xy 122.852688 -33.65881) (xy 122.853196 -33.638744) (xy 122.853038 -33.627234) (xy 122.843927 -33.606126)
			(xy 122.83567 -33.598104) (xy 122.811286 -33.577022) (xy 122.802296 -33.570074) (xy 122.780393 -33.564145)
			(xy 122.769122 -33.565592) (xy 122.752251 -33.56846) (xy 122.718163 -33.571514) (xy 122.70105 -33.571688)
			(xy 122.6738 -33.571239) (xy 122.619855 -33.563476) (xy 122.567563 -33.548116) (xy 122.517989 -33.525471)
			(xy 122.472143 -33.496001) (xy 122.430957 -33.460308) (xy 122.395269 -33.419117) (xy 122.365805 -33.373267)
			(xy 122.343167 -33.32369) (xy 122.327813 -33.271397) (xy 122.320058 -33.21745) (xy 122.320058 -33.16295)
			(xy 122.327813 -33.109003) (xy 122.343167 -33.05671) (xy 122.365805 -33.007133) (xy 122.395269 -32.961283)
			(xy 122.430957 -32.920092) (xy 122.472143 -32.884399) (xy 122.517989 -32.854929) (xy 122.567563 -32.832284)
			(xy 122.619855 -32.816924) (xy 122.6738 -32.809161) (xy 122.70105 -32.808672) (xy 122.72806 -32.809074)
			(xy 122.78154 -32.816687) (xy 122.833411 -32.831768) (xy 122.882636 -32.854016) (xy 122.928231 -32.882985)
			(xy 122.969283 -32.918097) (xy 123.004972 -32.958648) (xy 123.034583 -33.003829) (xy 123.057525 -33.052734)
			(xy 123.073338 -33.104387) (xy 123.077986 -33.130998) (xy 123.07951 -33.141666) (xy 123.09094 -33.159446)
			(xy 123.171204 -33.212786) (xy 123.191778 -33.216596) (xy 123.202446 -33.214056) (xy 123.229078 -33.207929)
			(xy 123.283326 -33.201306) (xy 123.31065 -33.200848) (xy 123.337975 -33.201301) (xy 123.392223 -33.207924)
			(xy 123.418854 -33.214056) (xy 123.429522 -33.216596) (xy 123.450096 -33.212786) (xy 123.53036 -33.159446)
			(xy 123.54179 -33.141666) (xy 123.543314 -33.130998) (xy 123.547967 -33.104393) (xy 123.563798 -33.052755)
			(xy 123.586752 -33.003864) (xy 123.61637 -32.958699) (xy 123.65206 -32.918161) (xy 123.693109 -32.88306)
			(xy 123.738697 -32.854097) (xy 123.787914 -32.83185) (xy 123.839775 -32.816766) (xy 123.893245 -32.809144)
			(xy 123.92025 -32.808672) (xy 123.94762 -32.80915) (xy 124.001799 -32.816962) (xy 124.054303 -32.832447)
			(xy 124.10405 -32.855287) (xy 124.150017 -32.885011) (xy 124.170948 -32.902652) (xy 124.17806 -32.908748)
			(xy 124.195078 -32.915098) (xy 124.280422 -32.915098) (xy 124.29744 -32.908748) (xy 124.304552 -32.902652)
			(xy 124.325498 -32.88503) (xy 124.371466 -32.855314) (xy 124.42121 -32.832474) (xy 124.473708 -32.816979)
			(xy 124.527882 -32.809147) (xy 124.55525 -32.808672) (xy 124.572362 -32.808865) (xy 124.606449 -32.811916)
			(xy 124.623322 -32.814768) (xy 124.634587 -32.816169) (xy 124.656471 -32.810237) (xy 124.665486 -32.803338)
			(xy 124.68987 -32.782256) (xy 124.698258 -32.77433) (xy 124.707382 -32.753157) (xy 124.707396 -32.741616)
			(xy 124.706888 -32.722312) (xy 124.706888 -31.858712) (xy 124.707396 -31.838646) (xy 124.707237 -31.827136)
			(xy 124.698127 -31.806028) (xy 124.68987 -31.798006) (xy 124.665486 -31.776924) (xy 124.656496 -31.769976)
			(xy 124.634592 -31.764047) (xy 124.623322 -31.765494) (xy 124.606451 -31.768362) (xy 124.572363 -31.771416)
			(xy 124.55525 -31.77159) (xy 124.527881 -31.771097) (xy 124.473703 -31.763286) (xy 124.4212 -31.747803)
			(xy 124.371452 -31.724968) (xy 124.325485 -31.695249) (xy 124.304552 -31.67761) (xy 124.29744 -31.671514)
			(xy 124.280676 -31.665164) (xy 124.195078 -31.665164) (xy 124.17806 -31.671514) (xy 124.171202 -31.677864)
			(xy 124.150267 -31.695541) (xy 124.104247 -31.725279) (xy 124.054443 -31.748122) (xy 124.001882 -31.763601)
			(xy 123.947647 -31.771395) (xy 123.92025 -31.771844) (xy 123.893271 -31.77142) (xy 123.83985 -31.763832)
			(xy 123.788033 -31.748786) (xy 123.738856 -31.726584) (xy 123.693301 -31.697668) (xy 123.652278 -31.662617)
			(xy 123.616609 -31.622132) (xy 123.587005 -31.577021) (xy 123.564059 -31.528186) (xy 123.548229 -31.476603)
			(xy 123.543568 -31.450026) (xy 123.54179 -31.439358) (xy 123.53036 -31.421832) (xy 123.450096 -31.368238)
			(xy 123.429522 -31.364682) (xy 123.419108 -31.367222) (xy 123.392405 -31.373291) (xy 123.338031 -31.379788)
			(xy 123.31065 -31.380176) (xy 123.283268 -31.379806) (xy 123.228892 -31.373308) (xy 123.202192 -31.367222)
			(xy 123.191778 -31.364682) (xy 123.171204 -31.368238) (xy 123.09094 -31.421832) (xy 123.07951 -31.439358)
			(xy 123.077732 -31.450026) (xy 123.073077 -31.476599) (xy 123.057219 -31.528165) (xy 123.034255 -31.576981)
			(xy 123.004641 -31.622075) (xy 122.968969 -31.662547) (xy 122.927951 -31.697588) (xy 122.882404 -31.726501)
			(xy 122.833238 -31.748708) (xy 122.781433 -31.763765) (xy 122.728024 -31.771374) (xy 122.70105 -31.771844)
			(xy 122.673804 -31.771282) (xy 122.619867 -31.763521) (xy 122.567583 -31.748163) (xy 122.518017 -31.725521)
			(xy 122.472177 -31.696056) (xy 122.430997 -31.660368) (xy 122.395314 -31.619183) (xy 122.365855 -31.573339)
			(xy 122.34322 -31.52377) (xy 122.327869 -31.471485) (xy 122.320114 -31.417546) (xy 122.320114 -31.363054)
			(xy 122.327869 -31.309115) (xy 122.34322 -31.25683) (xy 122.365855 -31.207261) (xy 122.395314 -31.161417)
			(xy 122.430996 -31.120232) (xy 122.472177 -31.084544) (xy 122.518017 -31.055079) (xy 122.567583 -31.032437)
			(xy 122.619867 -31.017079) (xy 122.673804 -31.009318) (xy 122.70105 -31.008828) (xy 122.718162 -31.009021)
			(xy 122.752249 -31.012072) (xy 122.769122 -31.014924) (xy 122.780387 -31.016335) (xy 122.802272 -31.010398)
			(xy 122.811286 -31.003494) (xy 122.83567 -30.982412) (xy 122.844032 -30.974463) (xy 122.85317 -30.953308)
			(xy 122.853196 -30.941772) (xy 122.852688 -30.922468) (xy 122.852688 -30.058868) (xy 122.853196 -30.038802)
			(xy 122.853004 -30.027294) (xy 122.843917 -30.006187) (xy 122.83567 -29.998162) (xy 122.811286 -29.97708)
			(xy 122.802299 -29.970128) (xy 122.780393 -29.964203) (xy 122.769122 -29.96565) (xy 122.752251 -29.968519)
			(xy 122.718163 -29.971572) (xy 122.70105 -29.971746) (xy 122.673804 -29.97118) (xy 122.619867 -29.963419)
			(xy 122.567583 -29.948061) (xy 122.518018 -29.925419) (xy 122.472178 -29.895955) (xy 122.430998 -29.860267)
			(xy 122.395315 -29.819082) (xy 122.365857 -29.773239) (xy 122.343222 -29.72367) (xy 122.32787 -29.671384)
			(xy 122.320116 -29.617446) (xy 122.320116 -29.562954) (xy 122.32787 -29.509016) (xy 122.343222 -29.45673)
			(xy 122.365857 -29.407161) (xy 122.395315 -29.361318) (xy 122.430998 -29.320133) (xy 122.472178 -29.284445)
			(xy 122.518018 -29.254981) (xy 122.567583 -29.232339) (xy 122.619867 -29.216981) (xy 122.673804 -29.20922)
			(xy 122.70105 -29.20873) (xy 122.728058 -29.209167) (xy 122.781535 -29.216779) (xy 122.833404 -29.231859)
			(xy 122.882627 -29.254103) (xy 122.92822 -29.283069) (xy 122.969271 -29.318176) (xy 123.00496 -29.358723)
			(xy 123.034573 -29.403898) (xy 123.057518 -29.452799) (xy 123.073336 -29.504447) (xy 123.077986 -29.531056)
			(xy 123.07951 -29.541724) (xy 123.09094 -29.559504) (xy 123.171204 -29.612844) (xy 123.191778 -29.616654)
			(xy 123.202446 -29.614114) (xy 123.229084 -29.608046) (xy 123.283332 -29.601556) (xy 123.31065 -29.60116)
			(xy 123.337968 -29.601549) (xy 123.392217 -29.608042) (xy 123.418854 -29.614114) (xy 123.429522 -29.616654)
			(xy 123.450096 -29.612844) (xy 123.53036 -29.559504) (xy 123.54179 -29.541724) (xy 123.543314 -29.531056)
			(xy 123.548011 -29.504459) (xy 123.563835 -29.452821) (xy 123.586782 -29.40393) (xy 123.616394 -29.358764)
			(xy 123.652079 -29.318224) (xy 123.693123 -29.283122) (xy 123.738707 -29.254157) (xy 123.78792 -29.23191)
			(xy 123.839779 -29.216824) (xy 123.893246 -29.209202) (xy 123.92025 -29.20873) (xy 123.94762 -29.209218)
			(xy 124.001798 -29.217029) (xy 124.054301 -29.232513) (xy 124.104048 -29.25535) (xy 124.150016 -29.285071)
			(xy 124.170948 -29.30271) (xy 124.17806 -29.308806) (xy 124.195078 -29.315156) (xy 124.280422 -29.315156)
			(xy 124.29744 -29.308806) (xy 124.304552 -29.30271) (xy 124.325493 -29.285082) (xy 124.371463 -29.255368)
			(xy 124.421208 -29.23253) (xy 124.473707 -29.217036) (xy 124.527881 -29.209205) (xy 124.55525 -29.20873)
			(xy 124.572362 -29.208923) (xy 124.606449 -29.211974) (xy 124.623322 -29.214826) (xy 124.634587 -29.216236)
			(xy 124.656472 -29.210299) (xy 124.665486 -29.203396) (xy 124.68987 -29.182314) (xy 124.698231 -29.174364)
			(xy 124.70737 -29.153209) (xy 124.707396 -29.141674) (xy 124.706888 -29.12237) (xy 124.706888 -28.25877)
			(xy 124.707396 -28.238704) (xy 124.707203 -28.227196) (xy 124.698117 -28.206089) (xy 124.68987 -28.198064)
			(xy 124.665486 -28.176982) (xy 124.656499 -28.17003) (xy 124.634593 -28.164105) (xy 124.623322 -28.165552)
			(xy 124.606451 -28.168421) (xy 124.572363 -28.171474) (xy 124.55525 -28.171648) (xy 124.528004 -28.171078)
			(xy 124.474067 -28.163317) (xy 124.421784 -28.147959) (xy 124.372219 -28.125318) (xy 124.326379 -28.095853)
			(xy 124.285199 -28.060165) (xy 124.249517 -28.018981) (xy 124.220058 -27.973138) (xy 124.197423 -27.923569)
			(xy 124.182072 -27.871284) (xy 124.174318 -27.817346) (xy 124.174318 -27.762854) (xy 124.182072 -27.708916)
			(xy 124.197423 -27.656631) (xy 124.220058 -27.607062) (xy 124.249517 -27.561219) (xy 124.285199 -27.520035)
			(xy 124.326379 -27.484347) (xy 124.372218 -27.454882) (xy 124.421784 -27.432241) (xy 124.474067 -27.416883)
			(xy 124.528004 -27.409122) (xy 124.55525 -27.408632) (xy 124.582258 -27.409067) (xy 124.635735 -27.41668)
			(xy 124.687604 -27.431759) (xy 124.736827 -27.454004) (xy 124.78242 -27.48297) (xy 124.823472 -27.518077)
			(xy 124.859161 -27.558624) (xy 124.888774 -27.6038) (xy 124.911718 -27.652701) (xy 124.927536 -27.704349)
			(xy 124.932186 -27.730958) (xy 124.93371 -27.741626) (xy 124.94514 -27.759406) (xy 125.025404 -27.812746)
			(xy 125.045978 -27.816556) (xy 125.056646 -27.814016) (xy 125.083278 -27.807888) (xy 125.137526 -27.801266)
			(xy 125.16485 -27.800808) (xy 125.187028 -27.801102) (xy 125.231174 -27.805429) (xy 125.252988 -27.809444)
			(xy 125.263402 -27.811476) (xy 125.283214 -27.807412) (xy 125.360176 -27.754072) (xy 125.371098 -27.737054)
			(xy 125.372876 -27.72664) (xy 125.377752 -27.700297) (xy 125.393969 -27.649236) (xy 125.417171 -27.600947)
			(xy 125.446901 -27.556379) (xy 125.482574 -27.516409) (xy 125.523489 -27.481824) (xy 125.56884 -27.453303)
			(xy 125.617736 -27.431409) (xy 125.669215 -27.416571) (xy 125.722263 -27.409082) (xy 125.74905 -27.408632)
			(xy 125.776308 -27.409012) (xy 125.83027 -27.416764) (xy 125.88258 -27.432117) (xy 125.932171 -27.454759)
			(xy 125.978035 -27.484229) (xy 126.019238 -27.519926) (xy 126.054941 -27.561124) (xy 126.084417 -27.606985)
			(xy 126.107066 -27.656574) (xy 126.122426 -27.708881) (xy 126.130185 -27.762842) (xy 126.130185 -27.817358)
			(xy 126.122426 -27.871319) (xy 126.107066 -27.923626) (xy 126.084417 -27.973215) (xy 126.054941 -28.019076)
			(xy 126.019238 -28.060274) (xy 125.978035 -28.095971) (xy 125.932171 -28.125441) (xy 125.88258 -28.148083)
			(xy 125.83027 -28.163436) (xy 125.776308 -28.171188) (xy 125.74905 -28.171648) (xy 125.737528 -28.171556)
			(xy 125.714525 -28.170156) (xy 125.703076 -28.168854) (xy 125.692162 -28.168134) (xy 125.671367 -28.174833)
			(xy 125.662944 -28.181808) (xy 125.639068 -28.203398) (xy 125.631214 -28.21125) (xy 125.622527 -28.231664)
			(xy 125.622304 -28.242768) (xy 125.622812 -28.25877) (xy 125.622812 -29.12237) (xy 125.622558 -29.137356)
			(xy 125.622686 -29.148442) (xy 125.631253 -29.168862) (xy 125.639068 -29.176726) (xy 125.662944 -29.198316)
			(xy 125.671351 -29.205318) (xy 125.692159 -29.212018) (xy 125.703076 -29.21127) (xy 125.714524 -29.209954)
			(xy 125.737527 -29.208559) (xy 125.74905 -29.208476) (xy 125.776304 -29.208968) (xy 125.830258 -29.216719)
			(xy 125.88256 -29.23207) (xy 125.932144 -29.254709) (xy 125.978002 -29.284174) (xy 126.019199 -29.319866)
			(xy 126.054896 -29.361058) (xy 126.084367 -29.406912) (xy 126.107013 -29.456493) (xy 126.122371 -29.508793)
			(xy 126.130129 -29.562746) (xy 126.130129 -29.617254) (xy 126.122371 -29.671207) (xy 126.107013 -29.723507)
			(xy 126.084367 -29.773088) (xy 126.054896 -29.818942) (xy 126.019199 -29.860134) (xy 125.978002 -29.895826)
			(xy 125.932144 -29.925291) (xy 125.88256 -29.94793) (xy 125.830258 -29.963281) (xy 125.776304 -29.971032)
			(xy 125.74905 -29.971492) (xy 125.722304 -29.970976) (xy 125.669338 -29.96349) (xy 125.617936 -29.948684)
			(xy 125.569103 -29.926848) (xy 125.523796 -29.898411) (xy 125.482901 -29.863929) (xy 125.447219 -29.824076)
			(xy 125.417449 -29.779633) (xy 125.394173 -29.73147) (xy 125.377847 -29.68053) (xy 125.372876 -29.654246)
			(xy 125.371098 -29.643832) (xy 125.36043 -29.626814) (xy 125.283214 -29.573728) (xy 125.263402 -29.569664)
			(xy 125.253242 -29.571696) (xy 125.231369 -29.575747) (xy 125.187093 -29.580071) (xy 125.16485 -29.580332)
			(xy 125.137462 -29.579883) (xy 125.083086 -29.573265) (xy 125.056392 -29.567124) (xy 125.045978 -29.564584)
			(xy 125.025404 -29.56814) (xy 124.94514 -29.621734) (xy 124.93371 -29.63926) (xy 124.931932 -29.649928)
			(xy 124.927278 -29.676501) (xy 124.911421 -29.728067) (xy 124.888456 -29.776883) (xy 124.858842 -29.821977)
			(xy 124.82317 -29.862449) (xy 124.782151 -29.897491) (xy 124.736604 -29.926403) (xy 124.687438 -29.94861)
			(xy 124.635634 -29.963667) (xy 124.582224 -29.971276) (xy 124.55525 -29.971746) (xy 124.52788 -29.971264)
			(xy 124.473701 -29.963452) (xy 124.421198 -29.947967) (xy 124.371451 -29.925129) (xy 124.325484 -29.895406)
			(xy 124.304552 -29.877766) (xy 124.29744 -29.87167) (xy 124.280422 -29.86532) (xy 124.195078 -29.86532)
			(xy 124.17806 -29.87167) (xy 124.170948 -29.877766) (xy 124.150004 -29.895391) (xy 124.104035 -29.925106)
			(xy 124.054291 -29.947945) (xy 124.001792 -29.963439) (xy 123.947618 -29.971271) (xy 123.92025 -29.971746)
			(xy 123.903138 -29.971553) (xy 123.869051 -29.968502) (xy 123.852178 -29.96565) (xy 123.840913 -29.964245)
			(xy 123.819029 -29.970179) (xy 123.810014 -29.97708) (xy 123.78563 -29.998162) (xy 123.777233 -30.00608)
			(xy 123.768114 -30.027259) (xy 123.768104 -30.038802) (xy 123.768612 -30.058868) (xy 123.768612 -30.922468)
			(xy 123.768104 -30.941772) (xy 123.768252 -30.953283) (xy 123.77737 -30.974391) (xy 123.78563 -30.982412)
			(xy 123.810014 -31.003494) (xy 123.819003 -31.010444) (xy 123.840907 -31.016371) (xy 123.852178 -31.014924)
			(xy 123.869049 -31.012055) (xy 123.903137 -31.009002) (xy 123.92025 -31.008828) (xy 123.94762 -31.009317)
			(xy 124.001798 -31.017128) (xy 124.054301 -31.032611) (xy 124.104048 -31.055448) (xy 124.150016 -31.085169)
			(xy 124.170948 -31.102808) (xy 124.17806 -31.108904) (xy 124.194824 -31.115254) (xy 124.280422 -31.115254)
			(xy 124.29744 -31.108904) (xy 124.304298 -31.102554) (xy 124.325235 -31.084879) (xy 124.371255 -31.055141)
			(xy 124.421058 -31.032297) (xy 124.473618 -31.016818) (xy 124.527853 -31.009023) (xy 124.55525 -31.008574)
			(xy 124.58226 -31.008974) (xy 124.63574 -31.016587) (xy 124.687612 -31.031669) (xy 124.736837 -31.053917)
			(xy 124.782432 -31.082886) (xy 124.823484 -31.117998) (xy 124.859172 -31.158549) (xy 124.888783 -31.20373)
			(xy 124.911725 -31.252636) (xy 124.927538 -31.304289) (xy 124.932186 -31.3309) (xy 124.93371 -31.341568)
			(xy 124.94514 -31.359348) (xy 125.025404 -31.412688) (xy 125.045978 -31.416498) (xy 125.056646 -31.413958)
			(xy 125.083284 -31.407891) (xy 125.137532 -31.4014) (xy 125.16485 -31.401004) (xy 125.187023 -31.401225)
			(xy 125.23117 -31.405428) (xy 125.252988 -31.409386) (xy 125.263402 -31.411418) (xy 125.283214 -31.407354)
			(xy 125.360176 -31.354014) (xy 125.371098 -31.336996) (xy 125.372876 -31.326582) (xy 125.377708 -31.30023)
			(xy 125.393933 -31.24917) (xy 125.417141 -31.200881) (xy 125.446877 -31.156314) (xy 125.482556 -31.116345)
			(xy 125.523475 -31.081761) (xy 125.568831 -31.053242) (xy 125.61773 -31.031349) (xy 125.669211 -31.016512)
			(xy 125.722262 -31.009023) (xy 125.74905 -31.008574) (xy 125.776304 -31.00907) (xy 125.830258 -31.016821)
			(xy 125.882559 -31.032172) (xy 125.932143 -31.05481) (xy 125.978 -31.084276) (xy 126.019197 -31.119968)
			(xy 126.054894 -31.16116) (xy 126.084366 -31.207013) (xy 126.107011 -31.256594) (xy 126.122369 -31.308893)
			(xy 126.130127 -31.362846) (xy 126.130127 -31.417354) (xy 126.122369 -31.471307) (xy 126.107011 -31.523606)
			(xy 126.084366 -31.573187) (xy 126.054894 -31.61904) (xy 126.019197 -31.660232) (xy 125.978 -31.695924)
			(xy 125.932143 -31.72539) (xy 125.882559 -31.748028) (xy 125.830258 -31.763379) (xy 125.776304 -31.77113)
			(xy 125.74905 -31.77159) (xy 125.737528 -31.771495) (xy 125.714525 -31.770096) (xy 125.703076 -31.768796)
			(xy 125.692162 -31.768066) (xy 125.671365 -31.77477) (xy 125.662944 -31.78175) (xy 125.639068 -31.80334)
			(xy 125.631241 -31.811215) (xy 125.622539 -31.831612) (xy 125.622304 -31.84271) (xy 125.622812 -31.858712)
			(xy 125.622812 -32.722312) (xy 125.622304 -32.737552) (xy 125.622485 -32.748665) (xy 125.631183 -32.769089)
			(xy 125.639068 -32.776922) (xy 125.662944 -32.798512) (xy 125.671351 -32.805513) (xy 125.692159 -32.812214)
			(xy 125.703076 -32.811466) (xy 125.714524 -32.81015) (xy 125.737527 -32.808755) (xy 125.74905 -32.808672)
			(xy 125.776304 -32.809172) (xy 125.830257 -32.816923) (xy 125.882558 -32.832274) (xy 125.932142 -32.854912)
			(xy 125.977999 -32.884377) (xy 126.019196 -32.920069) (xy 126.054893 -32.961261) (xy 126.084364 -33.007114)
			(xy 126.107009 -33.056695) (xy 126.122367 -33.108994) (xy 126.130125 -33.162946) (xy 126.130125 -33.217454)
			(xy 126.122367 -33.271406) (xy 126.107009 -33.323705) (xy 126.084364 -33.373286) (xy 126.054893 -33.419139)
			(xy 126.019196 -33.460331) (xy 125.977999 -33.496023) (xy 125.932142 -33.525488) (xy 125.882558 -33.548126)
			(xy 125.830257 -33.563477) (xy 125.776304 -33.571228) (xy 125.74905 -33.571688) (xy 125.722284 -33.571271)
			(xy 125.669274 -33.563807) (xy 125.617829 -33.549003) (xy 125.568959 -33.527151) (xy 125.523625 -33.498681)
			(xy 125.482718 -33.464151) (xy 125.44704 -33.424241) (xy 125.417294 -33.379734) (xy 125.394064 -33.331504)
			(xy 125.377805 -33.2805) (xy 125.372876 -33.254188) (xy 125.371098 -33.243774) (xy 125.36043 -33.226756)
			(xy 125.283214 -33.17367) (xy 125.263402 -33.169606) (xy 125.253242 -33.171638) (xy 125.231363 -33.175621)
			(xy 125.187088 -33.179819) (xy 125.16485 -33.18002) (xy 125.137468 -33.179652) (xy 125.083092 -33.173153)
			(xy 125.056392 -33.167066) (xy 125.045978 -33.164526) (xy 125.025404 -33.168082) (xy 124.94514 -33.221676)
			(xy 124.93371 -33.239202) (xy 124.931932 -33.24987) (xy 124.927234 -33.276435) (xy 124.911384 -33.328)
			(xy 124.888426 -33.376818) (xy 124.858818 -33.421913) (xy 124.823152 -33.462385) (xy 124.782137 -33.497429)
			(xy 124.736594 -33.526343) (xy 124.687432 -33.54855) (xy 124.63563 -33.563609) (xy 124.582223 -33.571218)
			(xy 124.55525 -33.571688) (xy 124.527881 -33.571196) (xy 124.473703 -33.563385) (xy 124.4212 -33.547902)
			(xy 124.371452 -33.525066) (xy 124.325484 -33.495347) (xy 124.304552 -33.477708) (xy 124.29744 -33.471612)
			(xy 124.280422 -33.465262) (xy 124.195078 -33.465262) (xy 124.17806 -33.471612) (xy 124.170948 -33.477708)
			(xy 124.15001 -33.495339) (xy 124.104038 -33.525052) (xy 124.054293 -33.547889) (xy 124.001793 -33.563382)
			(xy 123.947619 -33.571213) (xy 123.92025 -33.571688) (xy 123.903138 -33.571495) (xy 123.869051 -33.568444)
			(xy 123.852178 -33.565592) (xy 123.840913 -33.564177) (xy 123.819027 -33.570116) (xy 123.810014 -33.577022)
			(xy 123.78563 -33.598104) (xy 123.777261 -33.606047) (xy 123.768127 -33.627207) (xy 123.768104 -33.638744)
			(xy 123.768612 -33.65881) (xy 123.768612 -34.52241) (xy 123.768104 -34.541714) (xy 123.768286 -34.553222)
			(xy 123.77738 -34.57433) (xy 123.78563 -34.582354) (xy 123.810014 -34.603436) (xy 123.819007 -34.610381)
			(xy 123.840908 -34.616314) (xy 123.852178 -34.614866) (xy 123.869049 -34.611997) (xy 123.903137 -34.608944)
			(xy 123.92025 -34.60877) (xy 123.947504 -34.609274) (xy 124.001457 -34.617025) (xy 124.053758 -34.632375)
			(xy 124.103341 -34.655014) (xy 124.149198 -34.684479) (xy 124.190394 -34.72017) (xy 124.226091 -34.761362)
			(xy 124.255562 -34.807215) (xy 124.278207 -34.856795) (xy 124.293565 -34.909094) (xy 124.301323 -34.963046)
			(xy 124.301323 -34.990024) (xy 125.367032 -34.990024) (xy 125.371103 -34.934402) (xy 125.383229 -34.879965)
			(xy 125.403152 -34.827874) (xy 125.430448 -34.779239) (xy 125.464534 -34.735096) (xy 125.504683 -34.696387)
			(xy 125.550041 -34.663936) (xy 125.599641 -34.638435) (xy 125.652425 -34.620428) (xy 125.707268 -34.610298)
			(xy 125.763002 -34.608261) (xy 125.818439 -34.614361) (xy 125.872396 -34.628467) (xy 125.923725 -34.650279)
			(xy 125.971331 -34.679333) (xy 126.014199 -34.715008) (xy 126.051416 -34.756545) (xy 126.082189 -34.803058)
			(xy 126.105861 -34.853555) (xy 126.121929 -34.906962) (xy 126.130049 -34.962138) (xy 126.130558 -34.990024)
			(xy 126.130049 -35.01791) (xy 126.121929 -35.073086) (xy 126.105861 -35.126493) (xy 126.082189 -35.17699)
			(xy 126.051416 -35.223503) (xy 126.014199 -35.26504) (xy 125.971331 -35.300715) (xy 125.923725 -35.329769)
			(xy 125.872396 -35.351581) (xy 125.818439 -35.365687) (xy 125.763002 -35.371787) (xy 125.707268 -35.36975)
			(xy 125.652425 -35.35962) (xy 125.599641 -35.341613) (xy 125.550041 -35.316112) (xy 125.504683 -35.283661)
			(xy 125.464534 -35.244952) (xy 125.430448 -35.200809) (xy 125.403152 -35.152174) (xy 125.383229 -35.100083)
			(xy 125.371103 -35.045646) (xy 125.367032 -34.990024) (xy 124.301323 -34.990024) (xy 124.301323 -35.017554)
			(xy 124.293565 -35.071506) (xy 124.278207 -35.123805) (xy 124.255562 -35.173385) (xy 124.226091 -35.219238)
			(xy 124.190394 -35.26043) (xy 124.149198 -35.296121) (xy 124.103341 -35.325586) (xy 124.053758 -35.348225)
			(xy 124.001457 -35.363575) (xy 123.947504 -35.371326) (xy 123.92025 -35.371786) (xy 123.893273 -35.371327)
			(xy 123.839855 -35.36374) (xy 123.788041 -35.348696) (xy 123.738865 -35.326496) (xy 123.693312 -35.297585)
			(xy 123.65229 -35.262538) (xy 123.61662 -35.222057) (xy 123.587015 -35.176951) (xy 123.564066 -35.128121)
			(xy 123.548231 -35.076543) (xy 123.543568 -35.049968) (xy 123.54179 -35.0393) (xy 123.53036 -35.021774)
			(xy 123.450096 -34.96818) (xy 123.429522 -34.964624) (xy 123.419108 -34.967164) (xy 123.392415 -34.97331)
			(xy 123.338038 -34.979928) (xy 123.31065 -34.980372) (xy 123.283262 -34.979922) (xy 123.228886 -34.973305)
			(xy 123.202192 -34.967164) (xy 123.191778 -34.964624) (xy 123.171204 -34.96818) (xy 123.09094 -35.021774)
			(xy 123.07951 -35.0393) (xy 123.077732 -35.049968) (xy 123.073109 -35.076547) (xy 123.057246 -35.128113)
			(xy 123.034276 -35.176929) (xy 123.004658 -35.222022) (xy 122.968982 -35.262493) (xy 122.927961 -35.297533)
			(xy 122.882411 -35.326445) (xy 122.833243 -35.348651) (xy 122.781436 -35.363708) (xy 122.728025 -35.371316)
			(xy 122.70105 -35.371786) (xy 122.6738 -35.371341) (xy 122.619854 -35.363578) (xy 122.567562 -35.348218)
			(xy 122.517989 -35.325572) (xy 122.472142 -35.296103) (xy 122.430955 -35.260409) (xy 122.395267 -35.219218)
			(xy 122.365804 -35.173368) (xy 122.343165 -35.123791) (xy 122.327811 -35.071497) (xy 122.320056 -35.017551)
			(xy 120.674552 -35.017551) (xy 120.686936 -35.031373) (xy 120.717709 -35.077886) (xy 120.741381 -35.128383)
			(xy 120.757449 -35.18179) (xy 120.765569 -35.236966) (xy 120.766078 -35.264852) (xy 120.765569 -35.292738)
			(xy 120.757449 -35.347914) (xy 120.741381 -35.401321) (xy 120.717709 -35.451818) (xy 120.686936 -35.498331)
			(xy 120.649719 -35.539868) (xy 120.606851 -35.575543) (xy 120.559245 -35.604597) (xy 120.507916 -35.626409)
			(xy 120.453959 -35.640515) (xy 120.398522 -35.646615) (xy 120.342788 -35.644578) (xy 120.287945 -35.634448)
			(xy 120.235161 -35.616441) (xy 120.185561 -35.59094) (xy 120.140203 -35.558489) (xy 120.100054 -35.51978)
			(xy 120.065968 -35.475637) (xy 120.038672 -35.427002) (xy 120.018749 -35.374911) (xy 120.006623 -35.320474)
			(xy 120.002552 -35.264852) (xy 117.500908 -35.264852) (xy 117.500908 -37.087048) (xy 121.301002 -37.087048)
			(xy 121.301486 -37.060445) (xy 121.308862 -37.007754) (xy 121.32349 -36.956599) (xy 121.345086 -36.907974)
			(xy 121.373232 -36.862823) (xy 121.407381 -36.822023) (xy 121.44687 -36.786366) (xy 121.468642 -36.771072)
			(xy 121.478475 -36.763462) (xy 121.490164 -36.741567) (xy 121.490994 -36.729162) (xy 121.490994 -36.644834)
			(xy 121.49034 -36.632381) (xy 121.478619 -36.610404) (xy 121.468642 -36.602924) (xy 121.446875 -36.587625)
			(xy 121.407395 -36.55196) (xy 121.373252 -36.511157) (xy 121.345106 -36.466008) (xy 121.323503 -36.417387)
			(xy 121.308862 -36.366237) (xy 121.301466 -36.31355) (xy 121.301002 -36.286948) (xy 121.3015 -36.259696)
			(xy 121.309251 -36.205746) (xy 121.324601 -36.153448) (xy 121.347239 -36.103867) (xy 121.376703 -36.058013)
			(xy 121.412393 -36.01682) (xy 121.453583 -35.981125) (xy 121.499434 -35.951657) (xy 121.549012 -35.929014)
			(xy 121.601308 -35.913659) (xy 121.655258 -35.905903) (xy 121.68251 -35.90544) (xy 121.687082 -35.90544)
			(xy 121.696734 -35.905694) (xy 121.713498 -35.899344) (xy 121.77903 -35.843464) (xy 121.787666 -35.827462)
			(xy 121.788936 -35.818064) (xy 121.793232 -35.791124) (xy 121.808545 -35.738764) (xy 121.83116 -35.689119)
			(xy 121.860617 -35.643202) (xy 121.896313 -35.601949) (xy 121.937522 -35.566201) (xy 121.983402 -35.536688)
			(xy 122.033019 -35.514011) (xy 122.08536 -35.498633) (xy 122.139357 -35.490867) (xy 122.166634 -35.490404)
			(xy 122.193885 -35.490868) (xy 122.24783 -35.498629) (xy 122.300123 -35.513987) (xy 122.349697 -35.536631)
			(xy 122.395545 -35.566099) (xy 122.436732 -35.601792) (xy 122.472421 -35.642983) (xy 122.501885 -35.688833)
			(xy 122.524525 -35.738409) (xy 122.539878 -35.790703) (xy 122.547634 -35.844649) (xy 122.547634 -35.899151)
			(xy 122.539878 -35.953097) (xy 122.524525 -36.005391) (xy 122.501885 -36.054967) (xy 122.472421 -36.100817)
			(xy 122.436732 -36.142008) (xy 122.395545 -36.177701) (xy 122.349697 -36.207169) (xy 122.300123 -36.229813)
			(xy 122.24783 -36.245171) (xy 122.193885 -36.252932) (xy 122.166634 -36.25342) (xy 122.162062 -36.25342)
			(xy 122.15241 -36.253166) (xy 122.135646 -36.259516) (xy 122.070114 -36.315396) (xy 122.061478 -36.331398)
			(xy 122.060208 -36.340796) (xy 122.055987 -36.366995) (xy 122.041305 -36.417988) (xy 122.019696 -36.466453)
			(xy 121.991576 -36.511454) (xy 121.988145 -36.515548) (xy 123.114306 -36.515548) (xy 123.118377 -36.459926)
			(xy 123.130503 -36.405489) (xy 123.150426 -36.353398) (xy 123.177722 -36.304763) (xy 123.211808 -36.26062)
			(xy 123.251957 -36.221911) (xy 123.297315 -36.18946) (xy 123.346915 -36.163959) (xy 123.399699 -36.145952)
			(xy 123.454542 -36.135822) (xy 123.510276 -36.133785) (xy 123.565713 -36.139885) (xy 123.61967 -36.153991)
			(xy 123.670999 -36.175803) (xy 123.718605 -36.204857) (xy 123.761473 -36.240532) (xy 123.79869 -36.282069)
			(xy 123.829463 -36.328582) (xy 123.853135 -36.379079) (xy 123.869203 -36.432486) (xy 123.877323 -36.487662)
			(xy 123.877832 -36.515548) (xy 123.877323 -36.543434) (xy 123.869203 -36.59861) (xy 123.853135 -36.652017)
			(xy 123.829463 -36.702514) (xy 123.79869 -36.749027) (xy 123.761473 -36.790564) (xy 123.718605 -36.826239)
			(xy 123.670999 -36.855293) (xy 123.61967 -36.877105) (xy 123.565713 -36.891211) (xy 123.510276 -36.897311)
			(xy 123.454542 -36.895274) (xy 123.399699 -36.885144) (xy 123.346915 -36.867137) (xy 123.297315 -36.841636)
			(xy 123.251957 -36.809185) (xy 123.211808 -36.770476) (xy 123.177722 -36.726333) (xy 123.150426 -36.677698)
			(xy 123.130503 -36.625607) (xy 123.118377 -36.57117) (xy 123.114306 -36.515548) (xy 121.988145 -36.515548)
			(xy 121.957489 -36.552123) (xy 121.918094 -36.587673) (xy 121.896378 -36.602924) (xy 121.886449 -36.610449)
			(xy 121.874725 -36.632397) (xy 121.874026 -36.644834) (xy 121.874026 -36.729162) (xy 121.874675 -36.741616)
			(xy 121.886398 -36.763593) (xy 121.896378 -36.771072) (xy 121.918148 -36.786367) (xy 121.957626 -36.822034)
			(xy 121.991769 -36.862838) (xy 122.019914 -36.907988) (xy 122.041517 -36.956609) (xy 122.056158 -37.007759)
			(xy 122.063553 -37.060446) (xy 122.064018 -37.087048) (xy 122.063411 -37.118807) (xy 122.052925 -37.181453)
			(xy 122.032186 -37.241489) (xy 122.017536 -37.269674) (xy 122.012202 -37.27958) (xy 122.010678 -37.301678)
			(xy 122.046492 -37.394896) (xy 122.062494 -37.41039) (xy 122.073162 -37.4142) (xy 122.097687 -37.423288)
			(xy 122.144218 -37.447167) (xy 122.18705 -37.477179) (xy 122.22538 -37.512762) (xy 122.25849 -37.553248)
			(xy 122.285757 -37.597878) (xy 122.306671 -37.645815) (xy 122.320839 -37.696159) (xy 122.327996 -37.747968)
			(xy 122.328432 -37.774118) (xy 122.327946 -37.801369) (xy 122.32019 -37.855317) (xy 122.304835 -37.907612)
			(xy 122.282193 -37.957189) (xy 122.252727 -38.003039) (xy 122.217036 -38.04423) (xy 122.175845 -38.079921)
			(xy 122.129995 -38.109387) (xy 122.080418 -38.132029) (xy 122.028123 -38.147384) (xy 121.974175 -38.15514)
			(xy 121.919673 -38.15514) (xy 121.865725 -38.147384) (xy 121.81343 -38.132029) (xy 121.763853 -38.109387)
			(xy 121.718003 -38.079921) (xy 121.676812 -38.04423) (xy 121.641121 -38.003039) (xy 121.611655 -37.957189)
			(xy 121.589013 -37.907612) (xy 121.573658 -37.855317) (xy 121.565902 -37.801369) (xy 121.565416 -37.774118)
			(xy 121.566005 -37.742358) (xy 121.576498 -37.679712) (xy 121.597245 -37.619676) (xy 121.611898 -37.591492)
			(xy 121.617232 -37.581586) (xy 121.618756 -37.559488) (xy 121.582942 -37.46627) (xy 121.56694 -37.450776)
			(xy 121.556272 -37.446966) (xy 121.531721 -37.437945) (xy 121.48519 -37.414056) (xy 121.442359 -37.384034)
			(xy 121.404031 -37.348442) (xy 121.370925 -37.307947) (xy 121.343661 -37.263309) (xy 121.322752 -37.215365)
			(xy 121.308588 -37.165014) (xy 121.301436 -37.113201) (xy 121.301002 -37.087048) (xy 117.500908 -37.087048)
			(xy 117.500908 -38.315138) (xy 122.518168 -38.315138) (xy 122.522239 -38.259516) (xy 122.534365 -38.205079)
			(xy 122.554288 -38.152988) (xy 122.581584 -38.104353) (xy 122.61567 -38.06021) (xy 122.655819 -38.021501)
			(xy 122.701177 -37.98905) (xy 122.750777 -37.963549) (xy 122.803561 -37.945542) (xy 122.858404 -37.935412)
			(xy 122.914138 -37.933375) (xy 122.969575 -37.939475) (xy 123.023532 -37.953581) (xy 123.074861 -37.975393)
			(xy 123.122467 -38.004447) (xy 123.165335 -38.040122) (xy 123.202552 -38.081659) (xy 123.233325 -38.128172)
			(xy 123.256997 -38.178669) (xy 123.273065 -38.232076) (xy 123.281185 -38.287252) (xy 123.281694 -38.315138)
			(xy 123.281185 -38.343024) (xy 123.273065 -38.3982) (xy 123.256997 -38.451607) (xy 123.233325 -38.502104)
			(xy 123.202552 -38.548617) (xy 123.165335 -38.590154) (xy 123.122467 -38.625829) (xy 123.074861 -38.654883)
			(xy 123.023532 -38.676695) (xy 122.969575 -38.690801) (xy 122.914138 -38.696901) (xy 122.858404 -38.694864)
			(xy 122.803561 -38.684734) (xy 122.750777 -38.666727) (xy 122.701177 -38.641226) (xy 122.655819 -38.608775)
			(xy 122.61567 -38.570066) (xy 122.581584 -38.525923) (xy 122.554288 -38.477288) (xy 122.534365 -38.425197)
			(xy 122.522239 -38.37076) (xy 122.518168 -38.315138) (xy 117.500908 -38.315138) (xy 117.500908 -49.60195)
			(xy 118.391182 -49.60195) (xy 118.391182 -49.54745) (xy 118.398938 -49.493505) (xy 118.414291 -49.441212)
			(xy 118.436931 -49.391637) (xy 118.466395 -49.345788) (xy 118.502083 -49.304599) (xy 118.543271 -49.268908)
			(xy 118.589118 -49.239441) (xy 118.638692 -49.216799) (xy 118.690983 -49.201442) (xy 118.744928 -49.193683)
			(xy 118.772178 -49.193196) (xy 118.799548 -49.193676) (xy 118.853726 -49.201491) (xy 118.906229 -49.216976)
			(xy 118.955976 -49.239815) (xy 119.001944 -49.269536) (xy 119.022876 -49.287176) (xy 119.029988 -49.293272)
			(xy 119.047006 -49.299622) (xy 119.13235 -49.299622) (xy 119.149368 -49.293272) (xy 119.15648 -49.287176)
			(xy 119.177413 -49.269535) (xy 119.223381 -49.239811) (xy 119.273127 -49.216965) (xy 119.325629 -49.201469)
			(xy 119.379807 -49.19364) (xy 119.434549 -49.19364) (xy 119.488727 -49.201469) (xy 119.541229 -49.216965)
			(xy 119.590975 -49.239811) (xy 119.636943 -49.269535) (xy 119.657876 -49.287176) (xy 119.664988 -49.293272)
			(xy 119.682006 -49.299622) (xy 119.76735 -49.299622) (xy 119.784368 -49.293272) (xy 119.79148 -49.287176)
			(xy 119.812406 -49.269529) (xy 119.858381 -49.239819) (xy 119.90813 -49.216985) (xy 119.960632 -49.201496)
			(xy 120.014808 -49.193669) (xy 120.042178 -49.193196) (xy 120.068495 -49.193619) (xy 120.12063 -49.200845)
			(xy 120.171279 -49.215164) (xy 120.219481 -49.236304) (xy 120.264322 -49.263865) (xy 120.304953 -49.297324)
			(xy 120.323102 -49.316386) (xy 120.330623 -49.323788) (xy 120.349903 -49.332313) (xy 120.36044 -49.332896)
			(xy 120.435116 -49.332896) (xy 120.445668 -49.33239) (xy 120.464964 -49.323839) (xy 120.472454 -49.316386)
			(xy 120.49056 -49.297278) (xy 120.531187 -49.263803) (xy 120.576033 -49.236237) (xy 120.624246 -49.215103)
			(xy 120.674909 -49.200805) (xy 120.727057 -49.193613) (xy 120.753378 -49.193196) (xy 120.780632 -49.19365)
			(xy 120.834586 -49.201404) (xy 120.886887 -49.216759) (xy 120.93647 -49.2394) (xy 120.982327 -49.268868)
			(xy 121.023523 -49.304562) (xy 121.059219 -49.345756) (xy 121.088689 -49.39161) (xy 121.111334 -49.441192)
			(xy 121.126691 -49.493492) (xy 121.134449 -49.547446) (xy 121.134449 -49.601954) (xy 121.126691 -49.655908)
			(xy 121.111334 -49.708208) (xy 121.088689 -49.75779) (xy 121.059219 -49.803644) (xy 121.023523 -49.844838)
			(xy 120.982327 -49.880532) (xy 120.93647 -49.91) (xy 120.886887 -49.932641) (xy 120.834586 -49.947996)
			(xy 120.780632 -49.95575) (xy 120.753378 -49.956212) (xy 120.727062 -49.95575) (xy 120.674929 -49.948531)
			(xy 120.624281 -49.934219) (xy 120.576079 -49.913087) (xy 120.531237 -49.885533) (xy 120.490604 -49.852081)
			(xy 120.472454 -49.833022) (xy 120.464949 -49.825601) (xy 120.445656 -49.817087) (xy 120.435116 -49.816512)
			(xy 120.36044 -49.816512) (xy 120.349891 -49.817046) (xy 120.330595 -49.825577) (xy 120.323102 -49.833022)
			(xy 120.304951 -49.852086) (xy 120.264336 -49.885568) (xy 120.219499 -49.913142) (xy 120.171295 -49.934284)
			(xy 120.120639 -49.948591) (xy 120.068497 -49.955791) (xy 120.042178 -49.956212) (xy 120.014807 -49.955756)
			(xy 119.960628 -49.947935) (xy 119.908125 -49.932444) (xy 119.858378 -49.9096) (xy 119.812412 -49.879874)
			(xy 119.79148 -49.862232) (xy 119.784368 -49.856136) (xy 119.76735 -49.849786) (xy 119.682006 -49.849786)
			(xy 119.664988 -49.856136) (xy 119.657876 -49.862232) (xy 119.636943 -49.879873) (xy 119.590975 -49.909597)
			(xy 119.541229 -49.932443) (xy 119.488727 -49.947939) (xy 119.434549 -49.955768) (xy 119.379807 -49.955768)
			(xy 119.325629 -49.947939) (xy 119.273127 -49.932443) (xy 119.223381 -49.909597) (xy 119.177413 -49.879873)
			(xy 119.15648 -49.862232) (xy 119.149368 -49.856136) (xy 119.13235 -49.849786) (xy 119.047006 -49.849786)
			(xy 119.029988 -49.856136) (xy 119.022876 -49.862232) (xy 119.00193 -49.879854) (xy 118.955961 -49.909567)
			(xy 118.906217 -49.932406) (xy 118.853719 -49.947901) (xy 118.799546 -49.955735) (xy 118.772178 -49.956212)
			(xy 118.744928 -49.955717) (xy 118.690983 -49.947958) (xy 118.638692 -49.932601) (xy 118.589118 -49.909959)
			(xy 118.543271 -49.880492) (xy 118.502083 -49.844801) (xy 118.466395 -49.803612) (xy 118.436931 -49.757763)
			(xy 118.414291 -49.708188) (xy 118.398938 -49.655895) (xy 118.391182 -49.60195) (xy 117.500908 -49.60195)
			(xy 117.500908 -51.689052) (xy 118.355577 -51.689052) (xy 118.355577 -51.634548) (xy 118.363334 -51.580599)
			(xy 118.37869 -51.528302) (xy 118.401333 -51.478724) (xy 118.430801 -51.432872) (xy 118.466494 -51.391682)
			(xy 118.507687 -51.35599) (xy 118.55354 -51.326524) (xy 118.603119 -51.303884) (xy 118.655416 -51.28853)
			(xy 118.709366 -51.280776) (xy 118.736618 -51.280314) (xy 118.763989 -51.280766) (xy 118.818169 -51.288587)
			(xy 118.870672 -51.304079) (xy 118.920419 -51.326924) (xy 118.966385 -51.356651) (xy 118.987316 -51.374294)
			(xy 118.994428 -51.38039) (xy 119.011446 -51.38674) (xy 119.09679 -51.38674) (xy 119.113808 -51.38039)
			(xy 119.12092 -51.374294) (xy 119.141871 -51.356678) (xy 119.187838 -51.326963) (xy 119.237581 -51.304123)
			(xy 119.290078 -51.288626) (xy 119.34425 -51.280792) (xy 119.371618 -51.280314) (xy 119.389961 -51.280555)
			(xy 119.426474 -51.284112) (xy 119.444516 -51.287426) (xy 119.455438 -51.289458) (xy 119.476012 -51.284632)
			(xy 119.55399 -51.225704) (xy 119.564404 -51.206908) (xy 119.565166 -51.195986) (xy 119.56805 -51.167701)
			(xy 119.581089 -51.112363) (xy 119.602187 -51.059569) (xy 119.630878 -51.010486) (xy 119.666529 -50.966199)
			(xy 119.687086 -50.946558) (xy 119.694506 -50.939052) (xy 119.70302 -50.91976) (xy 119.703596 -50.90922)
			(xy 119.703596 -50.834544) (xy 119.703058 -50.823995) (xy 119.694529 -50.8047) (xy 119.687086 -50.797206)
			(xy 119.668007 -50.779071) (xy 119.634529 -50.73845) (xy 119.606959 -50.69361) (xy 119.585821 -50.645402)
			(xy 119.571516 -50.594745) (xy 119.564317 -50.542601) (xy 119.563896 -50.516282) (xy 119.564382 -50.489031)
			(xy 119.572138 -50.435083) (xy 119.587493 -50.382788) (xy 119.610135 -50.333211) (xy 119.639601 -50.287361)
			(xy 119.675292 -50.24617) (xy 119.716483 -50.210479) (xy 119.762333 -50.181013) (xy 119.81191 -50.158371)
			(xy 119.864205 -50.143016) (xy 119.918153 -50.13526) (xy 119.972655 -50.13526) (xy 120.026603 -50.143016)
			(xy 120.078898 -50.158371) (xy 120.128475 -50.181013) (xy 120.174325 -50.210479) (xy 120.215516 -50.24617)
			(xy 120.251207 -50.287361) (xy 120.280673 -50.333211) (xy 120.303315 -50.382788) (xy 120.31867 -50.435083)
			(xy 120.326426 -50.489031) (xy 120.326912 -50.516282) (xy 120.32649 -50.542599) (xy 120.319263 -50.594734)
			(xy 120.304943 -50.645383) (xy 120.283803 -50.693585) (xy 120.256243 -50.738426) (xy 120.222784 -50.779057)
			(xy 120.203722 -50.797206) (xy 120.196319 -50.804726) (xy 120.187795 -50.824007) (xy 120.187212 -50.834544)
			(xy 120.187212 -50.90922) (xy 120.187767 -50.919767) (xy 120.196284 -50.939063) (xy 120.203722 -50.946558)
			(xy 120.222766 -50.964729) (xy 120.25625 -51.00534) (xy 120.283827 -51.050172) (xy 120.304973 -51.098373)
			(xy 120.319284 -51.149025) (xy 120.326488 -51.201164) (xy 120.326912 -51.227482) (xy 120.326428 -51.254734)
			(xy 120.318674 -51.308684) (xy 120.30332 -51.360981) (xy 120.28068 -51.410561) (xy 120.251214 -51.456414)
			(xy 120.215523 -51.497607) (xy 120.174332 -51.533301) (xy 120.128481 -51.562769) (xy 120.078902 -51.585412)
			(xy 120.026606 -51.600769) (xy 119.972656 -51.608526) (xy 119.945404 -51.60899) (xy 119.927061 -51.608761)
			(xy 119.890548 -51.605195) (xy 119.872506 -51.601878) (xy 119.861584 -51.599846) (xy 119.84101 -51.604672)
			(xy 119.763032 -51.6636) (xy 119.752618 -51.682396) (xy 119.751856 -51.693318) (xy 119.74896 -51.721576)
			(xy 119.735928 -51.776861) (xy 119.714843 -51.829604) (xy 119.686172 -51.878637) (xy 119.650548 -51.922878)
			(xy 119.608758 -51.961349) (xy 119.561727 -51.993199) (xy 119.510494 -52.017724) (xy 119.456191 -52.034383)
			(xy 119.400018 -52.042807) (xy 119.371618 -52.04333) (xy 119.344247 -52.04287) (xy 119.290067 -52.035054)
			(xy 119.237563 -52.019564) (xy 119.187817 -51.99672) (xy 119.141851 -51.966993) (xy 119.12092 -51.94935)
			(xy 119.113808 -51.943254) (xy 119.09679 -51.936904) (xy 119.011446 -51.936904) (xy 118.994428 -51.943254)
			(xy 118.987316 -51.94935) (xy 118.966382 -51.966987) (xy 118.920411 -51.996701) (xy 118.870664 -52.019538)
			(xy 118.818163 -52.035029) (xy 118.763987 -52.042857) (xy 118.736618 -52.04333) (xy 118.709366 -52.042824)
			(xy 118.655416 -52.03507) (xy 118.603119 -52.019716) (xy 118.55354 -51.997076) (xy 118.507687 -51.96761)
			(xy 118.466494 -51.931918) (xy 118.430801 -51.890728) (xy 118.401333 -51.844876) (xy 118.37869 -51.795298)
			(xy 118.363334 -51.743001) (xy 118.355577 -51.689052) (xy 117.500908 -51.689052) (xy 117.500908 -52.564153)
			(xy 119.92733 -52.564153) (xy 119.92733 -52.509647) (xy 119.935087 -52.455695) (xy 119.950442 -52.403396)
			(xy 119.973084 -52.353814) (xy 120.002551 -52.30796) (xy 120.038244 -52.266765) (xy 120.079436 -52.231069)
			(xy 120.125288 -52.201598) (xy 120.174868 -52.178953) (xy 120.227165 -52.163593) (xy 120.281117 -52.155832)
			(xy 120.30837 -52.155344) (xy 120.33574 -52.155817) (xy 120.389919 -52.163631) (xy 120.442423 -52.179118)
			(xy 120.49217 -52.201959) (xy 120.538137 -52.231683) (xy 120.559068 -52.249324) (xy 120.56618 -52.25542)
			(xy 120.583198 -52.26177) (xy 120.668542 -52.26177) (xy 120.68556 -52.25542) (xy 120.692672 -52.249324)
			(xy 120.713607 -52.231688) (xy 120.759579 -52.201975) (xy 120.809325 -52.179138) (xy 120.861825 -52.163646)
			(xy 120.916001 -52.155818) (xy 120.94337 -52.155344) (xy 120.970621 -52.155901) (xy 121.024568 -52.163654)
			(xy 121.076863 -52.179005) (xy 121.126441 -52.201643) (xy 121.172292 -52.231107) (xy 121.213483 -52.266796)
			(xy 121.249175 -52.307984) (xy 121.278642 -52.353833) (xy 121.301284 -52.403409) (xy 121.31664 -52.455702)
			(xy 121.324397 -52.509649) (xy 121.324397 -52.564151) (xy 121.31664 -52.618098) (xy 121.301284 -52.670391)
			(xy 121.278642 -52.719967) (xy 121.249175 -52.765816) (xy 121.213483 -52.807004) (xy 121.172292 -52.842693)
			(xy 121.126441 -52.872157) (xy 121.076863 -52.894795) (xy 121.024568 -52.910146) (xy 120.970621 -52.917899)
			(xy 120.94337 -52.91836) (xy 120.915999 -52.917921) (xy 120.861818 -52.910098) (xy 120.809314 -52.894603)
			(xy 120.759568 -52.871755) (xy 120.713602 -52.842024) (xy 120.692672 -52.82438) (xy 120.68556 -52.818284)
			(xy 120.668542 -52.811934) (xy 120.583198 -52.811934) (xy 120.56618 -52.818284) (xy 120.559068 -52.82438)
			(xy 120.538119 -52.841998) (xy 120.492151 -52.871713) (xy 120.442408 -52.894554) (xy 120.389911 -52.91005)
			(xy 120.335738 -52.917883) (xy 120.30837 -52.91836) (xy 120.281117 -52.917968) (xy 120.227165 -52.910207)
			(xy 120.174868 -52.894847) (xy 120.125288 -52.872202) (xy 120.079436 -52.842731) (xy 120.038244 -52.807035)
			(xy 120.002551 -52.76584) (xy 119.973084 -52.719986) (xy 119.950442 -52.670404) (xy 119.935087 -52.618105)
			(xy 119.92733 -52.564153) (xy 117.500908 -52.564153) (xy 117.500908 -54.238906) (xy 124.48616 -54.238906)
			(xy 124.490231 -54.183284) (xy 124.502357 -54.128847) (xy 124.52228 -54.076756) (xy 124.549576 -54.028121)
			(xy 124.583662 -53.983978) (xy 124.623811 -53.945269) (xy 124.669169 -53.912818) (xy 124.718769 -53.887317)
			(xy 124.771553 -53.86931) (xy 124.826396 -53.85918) (xy 124.88213 -53.857143) (xy 124.937567 -53.863243)
			(xy 124.991524 -53.877349) (xy 125.042853 -53.899161) (xy 125.090459 -53.928215) (xy 125.133327 -53.96389)
			(xy 125.170544 -54.005427) (xy 125.201317 -54.05194) (xy 125.224989 -54.102437) (xy 125.241057 -54.155844)
			(xy 125.249177 -54.21102) (xy 125.249686 -54.238906) (xy 125.249177 -54.266792) (xy 125.241057 -54.321968)
			(xy 125.224989 -54.375375) (xy 125.201317 -54.425872) (xy 125.170544 -54.472385) (xy 125.133327 -54.513922)
			(xy 125.090459 -54.549597) (xy 125.042853 -54.578651) (xy 124.991524 -54.600463) (xy 124.937567 -54.614569)
			(xy 124.88213 -54.620669) (xy 124.826396 -54.618632) (xy 124.771553 -54.608502) (xy 124.718769 -54.590495)
			(xy 124.669169 -54.564994) (xy 124.623811 -54.532543) (xy 124.583662 -54.493834) (xy 124.549576 -54.449691)
			(xy 124.52228 -54.401056) (xy 124.502357 -54.348965) (xy 124.490231 -54.294528) (xy 124.48616 -54.238906)
			(xy 117.500908 -54.238906) (xy 117.500908 -54.989051) (xy 120.001268 -54.989051) (xy 120.001268 -54.934549)
			(xy 120.009024 -54.880601) (xy 120.024379 -54.828306) (xy 120.047019 -54.778729) (xy 120.076485 -54.732878)
			(xy 120.112176 -54.691687) (xy 120.153365 -54.655995) (xy 120.199215 -54.626527) (xy 120.248791 -54.603884)
			(xy 120.301085 -54.588527) (xy 120.355033 -54.580769) (xy 120.382284 -54.580282) (xy 120.410375 -54.58079)
			(xy 120.465952 -54.589014) (xy 120.51972 -54.605303) (xy 120.570518 -54.629304) (xy 120.617245 -54.660497)
			(xy 120.65889 -54.698207) (xy 120.694553 -54.741618) (xy 120.709436 -54.765448) (xy 120.71477 -54.774592)
			(xy 120.731788 -54.786784) (xy 120.825006 -54.80685) (xy 120.84558 -54.802786) (xy 120.854216 -54.79669)
			(xy 120.878273 -54.78068) (xy 120.930207 -54.75534) (xy 120.985367 -54.738117) (xy 121.042493 -54.729405)
			(xy 121.071386 -54.728872) (xy 121.098636 -54.729391) (xy 121.152581 -54.737145) (xy 121.204874 -54.752498)
			(xy 121.25445 -54.775136) (xy 121.300299 -54.804599) (xy 121.341489 -54.840287) (xy 121.377181 -54.881473)
			(xy 121.406648 -54.92732) (xy 121.42929 -54.976894) (xy 121.444647 -55.029185) (xy 121.452406 -55.08313)
			(xy 121.452894 -55.11038) (xy 121.452418 -55.13775) (xy 121.444603 -55.191929) (xy 121.429116 -55.244432)
			(xy 121.406276 -55.294179) (xy 121.376554 -55.340146) (xy 121.358914 -55.361078) (xy 121.352818 -55.36819)
			(xy 121.346468 -55.385208) (xy 121.346468 -55.470552) (xy 121.352818 -55.48757) (xy 121.358914 -55.494682)
			(xy 121.376533 -55.515631) (xy 121.406256 -55.561597) (xy 121.4291 -55.611341) (xy 121.444596 -55.66384)
			(xy 121.452426 -55.718016) (xy 121.452428 -55.772754) (xy 121.444602 -55.82693) (xy 121.42911 -55.879431)
			(xy 121.40627 -55.929176) (xy 121.376552 -55.975144) (xy 121.358914 -55.996078) (xy 121.352818 -56.00319)
			(xy 121.346468 -56.020208) (xy 121.346468 -56.105552) (xy 121.352818 -56.12257) (xy 121.358914 -56.129682)
			(xy 121.37656 -56.150608) (xy 121.406271 -56.196583) (xy 121.429105 -56.246332) (xy 121.444594 -56.298834)
			(xy 121.452421 -56.35301) (xy 121.452894 -56.38038) (xy 121.452408 -56.407631) (xy 121.444652 -56.461579)
			(xy 121.429297 -56.513874) (xy 121.406655 -56.563451) (xy 121.377189 -56.609301) (xy 121.341498 -56.650492)
			(xy 121.300307 -56.686183) (xy 121.254457 -56.715649) (xy 121.20488 -56.738291) (xy 121.152585 -56.753646)
			(xy 121.098637 -56.761402) (xy 121.044135 -56.761402) (xy 120.990187 -56.753646) (xy 120.937892 -56.738291)
			(xy 120.888315 -56.715649) (xy 120.842465 -56.686183) (xy 120.801274 -56.650492) (xy 120.765583 -56.609301)
			(xy 120.736117 -56.563451) (xy 120.713475 -56.513874) (xy 120.69812 -56.461579) (xy 120.690364 -56.407631)
			(xy 120.689878 -56.38038) (xy 120.690313 -56.353008) (xy 120.698136 -56.298827) (xy 120.713631 -56.246323)
			(xy 120.73648 -56.196577) (xy 120.766213 -56.150612) (xy 120.783858 -56.129682) (xy 120.789954 -56.12257)
			(xy 120.796304 -56.105552) (xy 120.796304 -56.020208) (xy 120.789954 -56.00319) (xy 120.783858 -55.996078)
			(xy 120.766196 -55.975162) (xy 120.73647 -55.929192) (xy 120.713624 -55.879443) (xy 120.698128 -55.826938)
			(xy 120.690301 -55.772757) (xy 120.690303 -55.718013) (xy 120.698134 -55.663832) (xy 120.713635 -55.611329)
			(xy 120.736485 -55.561582) (xy 120.766215 -55.515614) (xy 120.783858 -55.494682) (xy 120.789954 -55.48757)
			(xy 120.796304 -55.470552) (xy 120.796304 -55.385208) (xy 120.789954 -55.36819) (xy 120.783858 -55.361078)
			(xy 120.772903 -55.348285) (xy 120.753065 -55.321064) (xy 120.744234 -55.306722) (xy 120.7389 -55.297578)
			(xy 120.721882 -55.285386) (xy 120.628664 -55.26532) (xy 120.60809 -55.269384) (xy 120.599454 -55.27548)
			(xy 120.575403 -55.2915) (xy 120.523467 -55.316838) (xy 120.468305 -55.334059) (xy 120.411178 -55.342767)
			(xy 120.382284 -55.343298) (xy 120.355033 -55.342831) (xy 120.301085 -55.335073) (xy 120.248791 -55.319716)
			(xy 120.199215 -55.297073) (xy 120.153365 -55.267605) (xy 120.112176 -55.231913) (xy 120.076485 -55.190722)
			(xy 120.047019 -55.144871) (xy 120.024379 -55.095294) (xy 120.009024 -55.042999) (xy 120.001268 -54.989051)
			(xy 117.500908 -54.989051) (xy 117.500908 -55.420851) (xy 118.324868 -55.420851) (xy 118.324868 -55.366349)
			(xy 118.332624 -55.312401) (xy 118.347979 -55.260106) (xy 118.370619 -55.210529) (xy 118.400085 -55.164678)
			(xy 118.435776 -55.123487) (xy 118.476965 -55.087795) (xy 118.522815 -55.058327) (xy 118.572391 -55.035684)
			(xy 118.624685 -55.020327) (xy 118.678633 -55.012569) (xy 118.705884 -55.012082) (xy 118.732201 -55.012505)
			(xy 118.784336 -55.019732) (xy 118.834985 -55.034051) (xy 118.883186 -55.055192) (xy 118.928028 -55.082752)
			(xy 118.968658 -55.11621) (xy 118.986808 -55.135272) (xy 118.994328 -55.142675) (xy 119.013609 -55.1512)
			(xy 119.024146 -55.151782) (xy 119.098822 -55.151782) (xy 119.109369 -55.15123) (xy 119.128665 -55.142711)
			(xy 119.13616 -55.135272) (xy 119.154328 -55.116226) (xy 119.19494 -55.082742) (xy 119.239773 -55.055165)
			(xy 119.287974 -55.034021) (xy 119.338626 -55.01971) (xy 119.390766 -55.012506) (xy 119.417084 -55.012082)
			(xy 119.444337 -55.012564) (xy 119.498288 -55.020319) (xy 119.550587 -55.035673) (xy 119.600167 -55.058314)
			(xy 119.646021 -55.087781) (xy 119.687215 -55.123474) (xy 119.722909 -55.164666) (xy 119.752378 -55.210519)
			(xy 119.775021 -55.260098) (xy 119.790377 -55.312396) (xy 119.798135 -55.366347) (xy 119.798135 -55.420853)
			(xy 119.790377 -55.474804) (xy 119.775021 -55.527102) (xy 119.752378 -55.576681) (xy 119.722909 -55.622534)
			(xy 119.687215 -55.663726) (xy 119.646021 -55.699419) (xy 119.600167 -55.728886) (xy 119.550587 -55.751527)
			(xy 119.498288 -55.766881) (xy 119.444337 -55.774636) (xy 119.417084 -55.775098) (xy 119.390768 -55.774636)
			(xy 119.338635 -55.767418) (xy 119.287987 -55.753107) (xy 119.239785 -55.731974) (xy 119.194942 -55.70442)
			(xy 119.15431 -55.670968) (xy 119.13616 -55.651908) (xy 119.128654 -55.644488) (xy 119.109362 -55.635974)
			(xy 119.098822 -55.635398) (xy 119.024146 -55.635398) (xy 119.013598 -55.635939) (xy 118.994302 -55.644466)
			(xy 118.986808 -55.651908) (xy 118.968671 -55.670985) (xy 118.928051 -55.704463) (xy 118.883211 -55.732034)
			(xy 118.835004 -55.753172) (xy 118.784347 -55.767478) (xy 118.732203 -55.774677) (xy 118.705884 -55.775098)
			(xy 118.678633 -55.774631) (xy 118.624685 -55.766873) (xy 118.572391 -55.751516) (xy 118.522815 -55.728873)
			(xy 118.476965 -55.699405) (xy 118.435776 -55.663713) (xy 118.400085 -55.622522) (xy 118.370619 -55.576671)
			(xy 118.347979 -55.527094) (xy 118.332624 -55.474799) (xy 118.324868 -55.420851) (xy 117.500908 -55.420851)
			(xy 117.500908 -57.48528) (xy 120.706132 -57.48528) (xy 120.710203 -57.429658) (xy 120.722329 -57.375221)
			(xy 120.742252 -57.32313) (xy 120.769548 -57.274495) (xy 120.803634 -57.230352) (xy 120.843783 -57.191643)
			(xy 120.889141 -57.159192) (xy 120.938741 -57.133691) (xy 120.991525 -57.115684) (xy 121.046368 -57.105554)
			(xy 121.102102 -57.103517) (xy 121.157539 -57.109617) (xy 121.211496 -57.123723) (xy 121.262825 -57.145535)
			(xy 121.310431 -57.174589) (xy 121.353299 -57.210264) (xy 121.390516 -57.251801) (xy 121.421289 -57.298314)
			(xy 121.444961 -57.348811) (xy 121.461029 -57.402218) (xy 121.469149 -57.457394) (xy 121.469658 -57.48528)
			(xy 121.469149 -57.513166) (xy 121.461029 -57.568342) (xy 121.444961 -57.621749) (xy 121.421289 -57.672246)
			(xy 121.390516 -57.718759) (xy 121.353299 -57.760296) (xy 121.310431 -57.795971) (xy 121.262825 -57.825025)
			(xy 121.211496 -57.846837) (xy 121.157539 -57.860943) (xy 121.102102 -57.867043) (xy 121.046368 -57.865006)
			(xy 120.991525 -57.854876) (xy 120.938741 -57.836869) (xy 120.889141 -57.811368) (xy 120.843783 -57.778917)
			(xy 120.803634 -57.740208) (xy 120.769548 -57.696065) (xy 120.742252 -57.64743) (xy 120.722329 -57.595339)
			(xy 120.710203 -57.540902) (xy 120.706132 -57.48528) (xy 117.500908 -57.48528) (xy 117.500908 -58.076084)
			(xy 121.458226 -58.076084) (xy 121.462297 -58.020462) (xy 121.474423 -57.966025) (xy 121.494346 -57.913934)
			(xy 121.521642 -57.865299) (xy 121.555728 -57.821156) (xy 121.595877 -57.782447) (xy 121.641235 -57.749996)
			(xy 121.690835 -57.724495) (xy 121.743619 -57.706488) (xy 121.798462 -57.696358) (xy 121.854196 -57.694321)
			(xy 121.909633 -57.700421) (xy 121.96359 -57.714527) (xy 122.014919 -57.736339) (xy 122.062525 -57.765393)
			(xy 122.105393 -57.801068) (xy 122.14261 -57.842605) (xy 122.158946 -57.867296) (xy 123.742956 -57.867296)
			(xy 123.747029 -57.811637) (xy 123.759164 -57.757164) (xy 123.7791 -57.705038) (xy 123.806414 -57.65637)
			(xy 123.840522 -57.612198) (xy 123.880699 -57.573463) (xy 123.926087 -57.540991) (xy 123.975719 -57.515473)
			(xy 124.028539 -57.497454) (xy 124.083418 -57.487317) (xy 124.139189 -57.485279) (xy 124.194663 -57.491382)
			(xy 124.248656 -57.505498) (xy 124.300019 -57.527325) (xy 124.347657 -57.556398) (xy 124.390553 -57.592097)
			(xy 124.427795 -57.633661) (xy 124.458589 -57.680205) (xy 124.482277 -57.730736) (xy 124.498355 -57.784178)
			(xy 124.506481 -57.839392) (xy 124.50699 -57.867296) (xy 124.506481 -57.8952) (xy 124.498355 -57.950414)
			(xy 124.482277 -58.003856) (xy 124.458589 -58.054387) (xy 124.427795 -58.100931) (xy 124.390553 -58.142495)
			(xy 124.347657 -58.178194) (xy 124.300019 -58.207267) (xy 124.248656 -58.229094) (xy 124.194663 -58.24321)
			(xy 124.139189 -58.249313) (xy 124.083418 -58.247275) (xy 124.028539 -58.237138) (xy 123.975719 -58.219119)
			(xy 123.926087 -58.193601) (xy 123.880699 -58.161129) (xy 123.840522 -58.122394) (xy 123.806414 -58.078222)
			(xy 123.7791 -58.029554) (xy 123.759164 -57.977428) (xy 123.747029 -57.922955) (xy 123.742956 -57.867296)
			(xy 122.158946 -57.867296) (xy 122.173383 -57.889118) (xy 122.197055 -57.939615) (xy 122.213123 -57.993022)
			(xy 122.221243 -58.048198) (xy 122.221752 -58.076084) (xy 122.221243 -58.10397) (xy 122.213123 -58.159146)
			(xy 122.197055 -58.212553) (xy 122.173383 -58.26305) (xy 122.14261 -58.309563) (xy 122.105393 -58.3511)
			(xy 122.062525 -58.386775) (xy 122.014919 -58.415829) (xy 121.96359 -58.437641) (xy 121.909633 -58.451747)
			(xy 121.854196 -58.457847) (xy 121.798462 -58.45581) (xy 121.743619 -58.44568) (xy 121.690835 -58.427673)
			(xy 121.641235 -58.402172) (xy 121.595877 -58.369721) (xy 121.555728 -58.331012) (xy 121.521642 -58.286869)
			(xy 121.494346 -58.238234) (xy 121.474423 -58.186143) (xy 121.462297 -58.131706) (xy 121.458226 -58.076084)
			(xy 117.500908 -58.076084) (xy 117.500908 -58.561224) (xy 122.66244 -58.561224) (xy 122.666511 -58.505602)
			(xy 122.678637 -58.451165) (xy 122.69856 -58.399074) (xy 122.725856 -58.350439) (xy 122.759942 -58.306296)
			(xy 122.800091 -58.267587) (xy 122.845449 -58.235136) (xy 122.895049 -58.209635) (xy 122.947833 -58.191628)
			(xy 123.002676 -58.181498) (xy 123.05841 -58.179461) (xy 123.113847 -58.185561) (xy 123.167804 -58.199667)
			(xy 123.219133 -58.221479) (xy 123.266739 -58.250533) (xy 123.309607 -58.286208) (xy 123.346824 -58.327745)
			(xy 123.377597 -58.374258) (xy 123.401269 -58.424755) (xy 123.408779 -58.449718) (xy 124.90907 -58.449718)
			(xy 124.913141 -58.394096) (xy 124.925267 -58.339659) (xy 124.94519 -58.287568) (xy 124.972486 -58.238933)
			(xy 125.006572 -58.19479) (xy 125.046721 -58.156081) (xy 125.092079 -58.12363) (xy 125.141679 -58.098129)
			(xy 125.194463 -58.080122) (xy 125.249306 -58.069992) (xy 125.30504 -58.067955) (xy 125.360477 -58.074055)
			(xy 125.414434 -58.088161) (xy 125.465763 -58.109973) (xy 125.513369 -58.139027) (xy 125.556237 -58.174702)
			(xy 125.593454 -58.216239) (xy 125.624227 -58.262752) (xy 125.647899 -58.313249) (xy 125.663967 -58.366656)
			(xy 125.672087 -58.421832) (xy 125.672596 -58.449718) (xy 125.672087 -58.477604) (xy 125.663967 -58.53278)
			(xy 125.647899 -58.586187) (xy 125.624227 -58.636684) (xy 125.593454 -58.683197) (xy 125.556237 -58.724734)
			(xy 125.513369 -58.760409) (xy 125.465763 -58.789463) (xy 125.414434 -58.811275) (xy 125.360477 -58.825381)
			(xy 125.30504 -58.831481) (xy 125.249306 -58.829444) (xy 125.194463 -58.819314) (xy 125.141679 -58.801307)
			(xy 125.092079 -58.775806) (xy 125.046721 -58.743355) (xy 125.006572 -58.704646) (xy 124.972486 -58.660503)
			(xy 124.94519 -58.611868) (xy 124.925267 -58.559777) (xy 124.913141 -58.50534) (xy 124.90907 -58.449718)
			(xy 123.408779 -58.449718) (xy 123.417337 -58.478162) (xy 123.425457 -58.533338) (xy 123.425966 -58.561224)
			(xy 123.425457 -58.58911) (xy 123.417337 -58.644286) (xy 123.401269 -58.697693) (xy 123.377597 -58.74819)
			(xy 123.346824 -58.794703) (xy 123.309607 -58.83624) (xy 123.266739 -58.871915) (xy 123.219133 -58.900969)
			(xy 123.167804 -58.922781) (xy 123.113847 -58.936887) (xy 123.05841 -58.942987) (xy 123.002676 -58.94095)
			(xy 122.947833 -58.93082) (xy 122.895049 -58.912813) (xy 122.845449 -58.887312) (xy 122.800091 -58.854861)
			(xy 122.759942 -58.816152) (xy 122.725856 -58.772009) (xy 122.69856 -58.723374) (xy 122.678637 -58.671283)
			(xy 122.666511 -58.616846) (xy 122.66244 -58.561224) (xy 117.500908 -58.561224) (xy 117.500908 -59.974734)
			(xy 121.18721 -59.974734) (xy 121.187637 -59.947907) (xy 121.195158 -59.894782) (xy 121.210042 -59.843233)
			(xy 121.231996 -59.794276) (xy 121.260587 -59.748874) (xy 121.295254 -59.707922) (xy 121.335312 -59.672227)
			(xy 121.35739 -59.65698) (xy 121.368959 -59.648764) (xy 121.387369 -59.627185) (xy 121.399126 -59.601372)
			(xy 121.403321 -59.573319) (xy 121.399632 -59.545196) (xy 121.388342 -59.519175) (xy 121.370324 -59.497268)
			(xy 121.358914 -59.488832) (xy 121.337466 -59.473468) (xy 121.298551 -59.437844) (xy 121.264917 -59.397197)
			(xy 121.237204 -59.352304) (xy 121.215943 -59.30402) (xy 121.201537 -59.253267) (xy 121.194262 -59.201013)
			(xy 121.193814 -59.174634) (xy 121.1943 -59.147383) (xy 121.202056 -59.093435) (xy 121.217411 -59.04114)
			(xy 121.240053 -58.991563) (xy 121.269519 -58.945713) (xy 121.30521 -58.904522) (xy 121.346401 -58.868831)
			(xy 121.392251 -58.839365) (xy 121.441828 -58.816723) (xy 121.494123 -58.801368) (xy 121.548071 -58.793612)
			(xy 121.602573 -58.793612) (xy 121.656521 -58.801368) (xy 121.708816 -58.816723) (xy 121.758393 -58.839365)
			(xy 121.804243 -58.868831) (xy 121.845434 -58.904522) (xy 121.881125 -58.945713) (xy 121.910591 -58.991563)
			(xy 121.933233 -59.04114) (xy 121.948588 -59.093435) (xy 121.956344 -59.147383) (xy 121.95683 -59.174634)
			(xy 121.956361 -59.20146) (xy 121.948845 -59.254582) (xy 121.933967 -59.306129) (xy 121.91202 -59.355085)
			(xy 121.883435 -59.400488) (xy 121.848776 -59.441441) (xy 121.808725 -59.477139) (xy 121.78665 -59.492388)
			(xy 121.775117 -59.500647) (xy 121.756719 -59.52222) (xy 121.744968 -59.548023) (xy 121.740771 -59.576063)
			(xy 121.744452 -59.604175) (xy 121.755727 -59.63019) (xy 121.773726 -59.652097) (xy 121.785126 -59.660536)
			(xy 121.806615 -59.675845) (xy 121.845527 -59.71148) (xy 121.879157 -59.752136) (xy 121.906863 -59.797039)
			(xy 121.928119 -59.845332) (xy 121.942516 -59.896092) (xy 121.949782 -59.948352) (xy 121.950226 -59.974734)
			(xy 121.94974 -60.001985) (xy 121.941984 -60.055933) (xy 121.926629 -60.108228) (xy 121.903987 -60.157805)
			(xy 121.874521 -60.203655) (xy 121.83883 -60.244846) (xy 121.797639 -60.280537) (xy 121.751789 -60.310003)
			(xy 121.702212 -60.332645) (xy 121.649917 -60.348) (xy 121.595969 -60.355756) (xy 121.541467 -60.355756)
			(xy 121.487519 -60.348) (xy 121.435224 -60.332645) (xy 121.385647 -60.310003) (xy 121.339797 -60.280537)
			(xy 121.298606 -60.244846) (xy 121.262915 -60.203655) (xy 121.233449 -60.157805) (xy 121.210807 -60.108228)
			(xy 121.195452 -60.055933) (xy 121.187696 -60.001985) (xy 121.18721 -59.974734) (xy 117.500908 -59.974734)
			(xy 117.500908 -60.601606) (xy 120.433336 -60.601606) (xy 120.437407 -60.545984) (xy 120.449533 -60.491547)
			(xy 120.469456 -60.439456) (xy 120.496752 -60.390821) (xy 120.530838 -60.346678) (xy 120.570987 -60.307969)
			(xy 120.616345 -60.275518) (xy 120.665945 -60.250017) (xy 120.718729 -60.23201) (xy 120.773572 -60.22188)
			(xy 120.829306 -60.219843) (xy 120.884743 -60.225943) (xy 120.9387 -60.240049) (xy 120.990029 -60.261861)
			(xy 121.037635 -60.290915) (xy 121.080503 -60.32659) (xy 121.11772 -60.368127) (xy 121.148493 -60.41464)
			(xy 121.172165 -60.465137) (xy 121.188233 -60.518544) (xy 121.196353 -60.57372) (xy 121.196862 -60.601606)
			(xy 121.196398 -60.627006) (xy 122.821444 -60.627006) (xy 122.825515 -60.571384) (xy 122.837641 -60.516947)
			(xy 122.857564 -60.464856) (xy 122.88486 -60.416221) (xy 122.918946 -60.372078) (xy 122.959095 -60.333369)
			(xy 123.004453 -60.300918) (xy 123.054053 -60.275417) (xy 123.106837 -60.25741) (xy 123.16168 -60.24728)
			(xy 123.217414 -60.245243) (xy 123.272851 -60.251343) (xy 123.326808 -60.265449) (xy 123.378137 -60.287261)
			(xy 123.425743 -60.316315) (xy 123.468611 -60.35199) (xy 123.505828 -60.393527) (xy 123.536601 -60.44004)
			(xy 123.560273 -60.490537) (xy 123.576341 -60.543944) (xy 123.584461 -60.59912) (xy 123.58497 -60.627006)
			(xy 123.584854 -60.633356) (xy 124.913134 -60.633356) (xy 124.917205 -60.577734) (xy 124.929331 -60.523297)
			(xy 124.949254 -60.471206) (xy 124.97655 -60.422571) (xy 125.010636 -60.378428) (xy 125.050785 -60.339719)
			(xy 125.096143 -60.307268) (xy 125.145743 -60.281767) (xy 125.198527 -60.26376) (xy 125.25337 -60.25363)
			(xy 125.309104 -60.251593) (xy 125.364541 -60.257693) (xy 125.418498 -60.271799) (xy 125.469827 -60.293611)
			(xy 125.517433 -60.322665) (xy 125.560301 -60.35834) (xy 125.597518 -60.399877) (xy 125.628291 -60.44639)
			(xy 125.651963 -60.496887) (xy 125.668031 -60.550294) (xy 125.676151 -60.60547) (xy 125.67666 -60.633356)
			(xy 125.676151 -60.661242) (xy 125.668031 -60.716418) (xy 125.651963 -60.769825) (xy 125.628291 -60.820322)
			(xy 125.597518 -60.866835) (xy 125.560301 -60.908372) (xy 125.517433 -60.944047) (xy 125.469827 -60.973101)
			(xy 125.418498 -60.994913) (xy 125.364541 -61.009019) (xy 125.309104 -61.015119) (xy 125.25337 -61.013082)
			(xy 125.198527 -61.002952) (xy 125.145743 -60.984945) (xy 125.096143 -60.959444) (xy 125.050785 -60.926993)
			(xy 125.010636 -60.888284) (xy 124.97655 -60.844141) (xy 124.949254 -60.795506) (xy 124.929331 -60.743415)
			(xy 124.917205 -60.688978) (xy 124.913134 -60.633356) (xy 123.584854 -60.633356) (xy 123.584461 -60.654892)
			(xy 123.576341 -60.710068) (xy 123.560273 -60.763475) (xy 123.536601 -60.813972) (xy 123.505828 -60.860485)
			(xy 123.468611 -60.902022) (xy 123.425743 -60.937697) (xy 123.378137 -60.966751) (xy 123.326808 -60.988563)
			(xy 123.272851 -61.002669) (xy 123.217414 -61.008769) (xy 123.16168 -61.006732) (xy 123.106837 -60.996602)
			(xy 123.054053 -60.978595) (xy 123.004453 -60.953094) (xy 122.959095 -60.920643) (xy 122.918946 -60.881934)
			(xy 122.88486 -60.837791) (xy 122.857564 -60.789156) (xy 122.837641 -60.737065) (xy 122.825515 -60.682628)
			(xy 122.821444 -60.627006) (xy 121.196398 -60.627006) (xy 121.196353 -60.629492) (xy 121.188233 -60.684668)
			(xy 121.172165 -60.738075) (xy 121.148493 -60.788572) (xy 121.11772 -60.835085) (xy 121.080503 -60.876622)
			(xy 121.037635 -60.912297) (xy 120.990029 -60.941351) (xy 120.9387 -60.963163) (xy 120.884743 -60.977269)
			(xy 120.829306 -60.983369) (xy 120.773572 -60.981332) (xy 120.718729 -60.971202) (xy 120.665945 -60.953195)
			(xy 120.616345 -60.927694) (xy 120.570987 -60.895243) (xy 120.530838 -60.856534) (xy 120.496752 -60.812391)
			(xy 120.469456 -60.763756) (xy 120.449533 -60.711665) (xy 120.437407 -60.657228) (xy 120.433336 -60.601606)
			(xy 117.500908 -60.601606) (xy 117.500908 -61.333126) (xy 117.501336 -61.343194) (xy 117.509058 -61.361791)
			(xy 117.515894 -61.369194) (xy 117.703346 -61.556646) (xy 117.703854 -61.557154) (xy 117.711235 -61.563736)
			(xy 117.729534 -61.571186) (xy 117.739414 -61.571632)
		)
		(stroke
			(width 0)
			(type solid)
		)
		(fill yes)
		(layer "In9.Cu")
		(net "P3V3_SSD4")
	)
	(gr_poly
		(pts
			(xy 353.328224 -61.576712) (xy 353.337019 -61.575758) (xy 353.354683 -61.574745) (xy 353.36353 -61.57468)
			(xy 354.498656 -61.57468) (xy 354.506022 -61.573918) (xy 354.522024 -61.571124) (xy 354.525277 -61.569363)
			(xy 354.531273 -61.565029) (xy 354.533962 -61.562488) (xy 354.587048 -61.511434) (xy 354.590604 -61.507878)
			(xy 354.591874 -61.506862) (xy 354.592128 -61.506608) (xy 354.599748 -61.489336) (xy 354.600256 -61.478922)
			(xy 354.600256 -61.478668) (xy 354.601763 -61.450762) (xy 354.611936 -61.395811) (xy 354.630034 -61.342938)
			(xy 354.64242 -61.317886) (xy 354.65676 -61.291398) (xy 354.692487 -61.242907) (xy 354.71354 -61.221366)
			(xy 354.714048 -61.220858) (xy 354.735723 -61.199569) (xy 354.784574 -61.163452) (xy 354.838531 -61.135533)
			(xy 354.89623 -61.116519) (xy 354.956214 -61.106889) (xy 354.98659 -61.106304) (xy 355.014382 -61.106806)
			(xy 355.069379 -61.114873) (xy 355.122621 -61.130838) (xy 355.172983 -61.154363) (xy 355.219396 -61.184949)
			(xy 355.260877 -61.221948) (xy 355.296549 -61.264577) (xy 355.325654 -61.311932) (xy 355.347578 -61.363011)
			(xy 355.361854 -61.416731) (xy 355.368181 -61.471954) (xy 355.367844 -61.49975) (xy 355.370892 -61.506608)
			(xy 355.429058 -61.562488) (xy 355.431759 -61.565015) (xy 355.437753 -61.569346) (xy 355.440996 -61.571124)
			(xy 355.456998 -61.573918) (xy 355.464364 -61.57468) (xy 356.443026 -61.57468) (xy 356.477062 -61.576458)
			(xy 356.481634 -61.576712) (xy 357.340916 -61.576712) (xy 357.345488 -61.576458) (xy 357.378254 -61.57468)
			(xy 359.055162 -61.57468) (xy 359.057448 -61.574426) (xy 359.06583 -61.573156) (xy 359.077514 -61.571124)
			(xy 359.078022 -61.57087) (xy 359.725468 -60.923424) (xy 359.72827 -60.917855) (xy 359.731354 -60.905779)
			(xy 359.731564 -60.899548) (xy 359.731564 -38.904926) (xy 359.731056 -38.899084) (xy 359.730548 -38.89629)
			(xy 359.728008 -38.882574) (xy 359.7275 -38.88105) (xy 359.725962 -38.877627) (xy 359.722005 -38.871252)
			(xy 359.719626 -38.86835) (xy 359.714292 -38.863016) (xy 359.682663 -38.834754) (xy 359.624075 -38.773409)
			(xy 359.571252 -38.707035) (xy 359.524622 -38.636174) (xy 359.484565 -38.5614) (xy 359.451406 -38.483322)
			(xy 359.425415 -38.402574) (xy 359.406804 -38.319813) (xy 359.395723 -38.235712) (xy 359.392263 -38.150955)
			(xy 359.396451 -38.066231) (xy 359.408255 -37.982229) (xy 359.427577 -37.899631) (xy 359.454262 -37.81911)
			(xy 359.488091 -37.74132) (xy 359.528789 -37.666893) (xy 359.576027 -37.596435) (xy 359.629419 -37.530518)
			(xy 359.658666 -37.499798) (xy 359.68686 -37.471604) (xy 359.705402 -37.454332) (xy 359.720642 -37.44087)
			(xy 359.725479 -37.434246) (xy 359.731045 -37.418829) (xy 359.731564 -37.410644) (xy 359.731564 -31.238444)
			(xy 359.731722 -31.233617) (xy 359.733632 -31.224152) (xy 359.735374 -31.219648) (xy 359.735628 -31.21914)
			(xy 359.735882 -31.218124) (xy 359.741724 -31.20263) (xy 359.742835 -31.198979) (xy 359.744114 -31.191457)
			(xy 359.744264 -31.187644) (xy 359.744264 -29.841444) (xy 359.743965 -29.833573) (xy 359.739173 -29.818576)
			(xy 359.734866 -29.81198) (xy 359.719887 -29.790309) (xy 359.695395 -29.743667) (xy 359.677561 -29.694097)
			(xy 359.666723 -29.642542) (xy 359.663089 -29.589987) (xy 359.666727 -29.537432) (xy 359.677568 -29.485878)
			(xy 359.695406 -29.436309) (xy 359.7199 -29.389669) (xy 359.734866 -29.367988) (xy 359.739192 -29.361402)
			(xy 359.743976 -29.346398) (xy 359.744264 -29.338524) (xy 359.744264 -28.112974) (xy 359.744365 -28.108362)
			(xy 359.746027 -28.099289) (xy 359.747566 -28.09494) (xy 359.74932 -28.08986) (xy 359.750861 -28.079226)
			(xy 359.750614 -28.073858) (xy 359.748582 -28.044394) (xy 359.747867 -28.037138) (xy 359.742831 -28.023462)
			(xy 359.738676 -28.01747) (xy 359.721003 -27.992653) (xy 359.692929 -27.938584) (xy 359.673796 -27.880744)
			(xy 359.664087 -27.820601) (xy 359.663492 -27.79014) (xy 359.663953 -27.762885) (xy 359.671705 -27.70893)
			(xy 359.687058 -27.656627) (xy 359.709698 -27.607042) (xy 359.739165 -27.561184) (xy 359.774858 -27.519987)
			(xy 359.816052 -27.484289) (xy 359.861907 -27.454817) (xy 359.91149 -27.432172) (xy 359.963791 -27.416813)
			(xy 360.017745 -27.409055) (xy 360.045 -27.408632) (xy 360.070548 -27.409041) (xy 360.121186 -27.415856)
			(xy 360.170464 -27.429365) (xy 360.217499 -27.449326) (xy 360.261451 -27.475382) (xy 360.281728 -27.490928)
			(xy 360.28923 -27.496334) (xy 360.306851 -27.501886) (xy 360.325296 -27.500834) (xy 360.342171 -27.493313)
			(xy 360.349038 -27.487118) (xy 360.488484 -27.347672) (xy 360.495884 -27.340831) (xy 360.514483 -27.333116)
			(xy 360.524552 -27.332686) (xy 360.67111 -27.332686) (xy 360.675428 -27.331924) (xy 360.693716 -27.329384)
			(xy 360.694224 -27.329384) (xy 360.727498 -27.327352) (xy 364.772956 -27.327352) (xy 364.78298 -27.326939)
			(xy 364.801503 -27.319276) (xy 364.815678 -27.3051) (xy 364.82334 -27.286576) (xy 364.823756 -27.276552)
			(xy 364.823756 -26.478484) (xy 364.823988 -26.457599) (xy 364.827807 -26.416005) (xy 364.831376 -26.395426)
			(xy 364.83163 -26.393648) (xy 364.832392 -26.384758) (xy 364.832312 -26.379941) (xy 364.830519 -26.370476)
			(xy 364.828836 -26.365962) (xy 364.826042 -26.359104) (xy 364.82147 -26.353516) (xy 364.819137 -26.350647)
			(xy 364.813783 -26.345545) (xy 364.810802 -26.343356) (xy 364.802674 -26.337768) (xy 364.796116 -26.333559)
			(xy 364.781251 -26.328909) (xy 364.773464 -26.328624) (xy 364.76305 -26.330656) (xy 364.752636 -26.333958)
			(xy 364.745778 -26.336752) (xy 364.719317 -26.3493) (xy 364.663505 -26.367037) (xy 364.60564 -26.376046)
			(xy 364.57636 -26.37663) (xy 364.575852 -26.37663) (xy 364.548602 -26.376141) (xy 364.494659 -26.368379)
			(xy 364.442368 -26.35302) (xy 364.392796 -26.330376) (xy 364.34695 -26.300909) (xy 364.305764 -26.265218)
			(xy 364.270075 -26.224029) (xy 364.240611 -26.178181) (xy 364.217971 -26.128607) (xy 364.202615 -26.076316)
			(xy 364.194857 -26.022372) (xy 364.194344 -25.995122) (xy 364.19492 -25.96489) (xy 364.204458 -25.905183)
			(xy 364.223297 -25.847729) (xy 364.250967 -25.793968) (xy 364.286773 -25.745246) (xy 364.307882 -25.723596)
			(xy 364.30839 -25.723088) (xy 364.330066 -25.701799) (xy 364.378917 -25.665681) (xy 364.432873 -25.637759)
			(xy 364.490572 -25.61874) (xy 364.550556 -25.609103) (xy 364.580932 -25.608534) (xy 364.609881 -25.609073)
			(xy 364.667115 -25.617825) (xy 364.722369 -25.635124) (xy 364.774375 -25.660572) (xy 364.82194 -25.693585)
			(xy 364.863971 -25.733405) (xy 364.899503 -25.779118) (xy 364.927721 -25.829674) (xy 364.92861 -25.832054)
			(xy 366.487962 -25.832054) (xy 366.492033 -25.776432) (xy 366.504159 -25.721995) (xy 366.524082 -25.669904)
			(xy 366.551378 -25.621269) (xy 366.585464 -25.577126) (xy 366.625613 -25.538417) (xy 366.670971 -25.505966)
			(xy 366.720571 -25.480465) (xy 366.773355 -25.462458) (xy 366.828198 -25.452328) (xy 366.883932 -25.450291)
			(xy 366.939369 -25.456391) (xy 366.993326 -25.470497) (xy 367.044655 -25.492309) (xy 367.092261 -25.521363)
			(xy 367.135129 -25.557038) (xy 367.136663 -25.55875) (xy 370.942362 -25.55875) (xy 370.942848 -25.531499)
			(xy 370.950604 -25.477551) (xy 370.965959 -25.425256) (xy 370.988601 -25.375679) (xy 371.018067 -25.329829)
			(xy 371.053758 -25.288638) (xy 371.094949 -25.252947) (xy 371.140799 -25.223481) (xy 371.190376 -25.200839)
			(xy 371.242671 -25.185484) (xy 371.296619 -25.177728) (xy 371.351121 -25.177728) (xy 371.405069 -25.185484)
			(xy 371.457364 -25.200839) (xy 371.506941 -25.223481) (xy 371.552791 -25.252947) (xy 371.593982 -25.288638)
			(xy 371.629673 -25.329829) (xy 371.659139 -25.375679) (xy 371.681781 -25.425256) (xy 371.697136 -25.477551)
			(xy 371.704892 -25.531499) (xy 371.705378 -25.55875) (xy 371.704814 -25.589012) (xy 371.695263 -25.648778)
			(xy 371.676392 -25.706285) (xy 371.648676 -25.76009) (xy 371.63121 -25.78481) (xy 371.622905 -25.796942)
			(xy 371.612949 -25.82459) (xy 371.61128 -25.85393) (xy 371.618036 -25.882529) (xy 371.632656 -25.908021)
			(xy 371.653932 -25.928292) (xy 371.680099 -25.941666) (xy 371.694456 -25.94483) (xy 371.720358 -25.950133)
			(xy 371.77048 -25.966957) (xy 371.817799 -25.990541) (xy 371.861406 -26.020436) (xy 371.900467 -26.056067)
			(xy 371.934232 -26.096751) (xy 371.962054 -26.14171) (xy 371.9834 -26.19008) (xy 371.99786 -26.240934)
			(xy 372.005158 -26.293299) (xy 372.005606 -26.319734) (xy 373.142 -26.319734) (xy 373.146071 -26.264112)
			(xy 373.158197 -26.209675) (xy 373.17812 -26.157584) (xy 373.205416 -26.108949) (xy 373.239502 -26.064806)
			(xy 373.279651 -26.026097) (xy 373.325009 -25.993646) (xy 373.374609 -25.968145) (xy 373.427393 -25.950138)
			(xy 373.482236 -25.940008) (xy 373.53797 -25.937971) (xy 373.593407 -25.944071) (xy 373.647364 -25.958177)
			(xy 373.698693 -25.979989) (xy 373.746299 -26.009043) (xy 373.789167 -26.044718) (xy 373.826384 -26.086255)
			(xy 373.857157 -26.132768) (xy 373.880829 -26.183265) (xy 373.896897 -26.236672) (xy 373.905017 -26.291848)
			(xy 373.905526 -26.319734) (xy 373.905017 -26.34762) (xy 373.896897 -26.402796) (xy 373.880829 -26.456203)
			(xy 373.857157 -26.5067) (xy 373.826384 -26.553213) (xy 373.789167 -26.59475) (xy 373.746299 -26.630425)
			(xy 373.698693 -26.659479) (xy 373.647364 -26.681291) (xy 373.593407 -26.695397) (xy 373.53797 -26.701497)
			(xy 373.482236 -26.69946) (xy 373.427393 -26.68933) (xy 373.374609 -26.671323) (xy 373.325009 -26.645822)
			(xy 373.279651 -26.613371) (xy 373.239502 -26.574662) (xy 373.205416 -26.530519) (xy 373.17812 -26.481884)
			(xy 373.158197 -26.429793) (xy 373.146071 -26.375356) (xy 373.142 -26.319734) (xy 372.005606 -26.319734)
			(xy 372.00512 -26.346985) (xy 371.997364 -26.400933) (xy 371.982009 -26.453228) (xy 371.959367 -26.502805)
			(xy 371.929901 -26.548655) (xy 371.89421 -26.589846) (xy 371.853019 -26.625537) (xy 371.807169 -26.655003)
			(xy 371.757592 -26.677645) (xy 371.705297 -26.693) (xy 371.651349 -26.700756) (xy 371.596847 -26.700756)
			(xy 371.542899 -26.693) (xy 371.490604 -26.677645) (xy 371.441027 -26.655003) (xy 371.395177 -26.625537)
			(xy 371.353986 -26.589846) (xy 371.318295 -26.548655) (xy 371.288829 -26.502805) (xy 371.266187 -26.453228)
			(xy 371.250832 -26.400933) (xy 371.243076 -26.346985) (xy 371.24259 -26.319734) (xy 371.243152 -26.289472)
			(xy 371.252705 -26.229706) (xy 371.271576 -26.172199) (xy 371.299292 -26.118394) (xy 371.316758 -26.093674)
			(xy 371.325102 -26.081566) (xy 371.335061 -26.053909) (xy 371.336729 -26.024561) (xy 371.329968 -25.995954)
			(xy 371.315339 -25.970457) (xy 371.294053 -25.950185) (xy 371.267874 -25.936815) (xy 371.253512 -25.933654)
			(xy 371.227618 -25.928316) (xy 371.177494 -25.911501) (xy 371.130174 -25.887922) (xy 371.086564 -25.858033)
			(xy 371.047502 -25.822406) (xy 371.013735 -25.781725) (xy 370.985912 -25.736769) (xy 370.964566 -25.688401)
			(xy 370.950106 -25.637548) (xy 370.942809 -25.585185) (xy 370.942362 -25.55875) (xy 367.136663 -25.55875)
			(xy 367.172346 -25.598575) (xy 367.203119 -25.645088) (xy 367.226791 -25.695585) (xy 367.242859 -25.748992)
			(xy 367.250979 -25.804168) (xy 367.251488 -25.832054) (xy 367.250979 -25.85994) (xy 367.242859 -25.915116)
			(xy 367.226791 -25.968523) (xy 367.203119 -26.01902) (xy 367.172346 -26.065533) (xy 367.135129 -26.10707)
			(xy 367.092261 -26.142745) (xy 367.044655 -26.171799) (xy 366.993326 -26.193611) (xy 366.939369 -26.207717)
			(xy 366.883932 -26.213817) (xy 366.828198 -26.21178) (xy 366.773355 -26.20165) (xy 366.720571 -26.183643)
			(xy 366.670971 -26.158142) (xy 366.625613 -26.125691) (xy 366.585464 -26.086982) (xy 366.551378 -26.042839)
			(xy 366.524082 -25.994204) (xy 366.504159 -25.942113) (xy 366.492033 -25.887676) (xy 366.487962 -25.832054)
			(xy 364.92861 -25.832054) (xy 364.947978 -25.883914) (xy 364.959807 -25.940591) (xy 364.961932 -25.969468)
			(xy 364.962694 -25.982422) (xy 364.968536 -25.992328) (xy 364.970954 -25.996212) (xy 364.976963 -26.003111)
			(xy 364.980474 -26.006044) (xy 364.985554 -26.009854) (xy 365.002572 -26.020522) (xy 365.05769 -26.055066)
			(xy 365.062704 -26.05778) (xy 365.073606 -26.06111) (xy 365.07928 -26.06167) (xy 365.091472 -26.062432)
			(xy 365.100108 -26.058876) (xy 365.128861 -26.047027) (xy 365.188761 -26.030314) (xy 365.25037 -26.021844)
			(xy 365.281464 -26.021284) (xy 365.311423 -26.021771) (xy 365.370829 -26.029585) (xy 365.428707 -26.045083)
			(xy 365.484068 -26.068002) (xy 365.535966 -26.097948) (xy 365.583512 -26.13441) (xy 365.625894 -26.176764)
			(xy 365.662387 -26.224286) (xy 365.692367 -26.276164) (xy 365.715321 -26.33151) (xy 365.723206 -26.360882)
			(xy 368.405662 -26.360882) (xy 368.409733 -26.30526) (xy 368.421859 -26.250823) (xy 368.441782 -26.198732)
			(xy 368.469078 -26.150097) (xy 368.503164 -26.105954) (xy 368.543313 -26.067245) (xy 368.588671 -26.034794)
			(xy 368.638271 -26.009293) (xy 368.691055 -25.991286) (xy 368.745898 -25.981156) (xy 368.801632 -25.979119)
			(xy 368.857069 -25.985219) (xy 368.911026 -25.999325) (xy 368.962355 -26.021137) (xy 369.009961 -26.050191)
			(xy 369.052829 -26.085866) (xy 369.090046 -26.127403) (xy 369.120819 -26.173916) (xy 369.144491 -26.224413)
			(xy 369.160559 -26.27782) (xy 369.168679 -26.332996) (xy 369.169188 -26.360882) (xy 369.168679 -26.388768)
			(xy 369.160559 -26.443944) (xy 369.144491 -26.497351) (xy 369.120819 -26.547848) (xy 369.090046 -26.594361)
			(xy 369.052829 -26.635898) (xy 369.009961 -26.671573) (xy 368.962355 -26.700627) (xy 368.911026 -26.722439)
			(xy 368.857069 -26.736545) (xy 368.801632 -26.742645) (xy 368.745898 -26.740608) (xy 368.691055 -26.730478)
			(xy 368.638271 -26.712471) (xy 368.588671 -26.68697) (xy 368.543313 -26.654519) (xy 368.503164 -26.61581)
			(xy 368.469078 -26.571667) (xy 368.441782 -26.523032) (xy 368.421859 -26.470941) (xy 368.409733 -26.416504)
			(xy 368.405662 -26.360882) (xy 365.723206 -26.360882) (xy 365.730857 -26.389379) (xy 365.738709 -26.448779)
			(xy 365.739172 -26.478738) (xy 365.739172 -27.276552) (xy 365.739583 -27.286582) (xy 365.747243 -27.30512)
			(xy 365.761416 -27.319314) (xy 365.779943 -27.327002) (xy 365.789972 -27.327352) (xy 374.995694 -27.327352)
			(xy 375.005346 -27.326336) (xy 375.01259 -27.324708) (xy 375.025757 -27.317865) (xy 375.031254 -27.312874)
			(xy 375.391172 -26.952956) (xy 375.396147 -26.947523) (xy 375.402985 -26.934482) (xy 375.404634 -26.927302)
			(xy 375.404634 -26.926794) (xy 375.40565 -26.917396) (xy 375.40565 -24.081994) (xy 375.402856 -24.073866)
			(xy 375.392694 -24.043102) (xy 375.381705 -23.979257) (xy 375.381012 -23.946866) (xy 375.381716 -23.914475)
			(xy 375.392692 -23.850629) (xy 375.402856 -23.819866) (xy 375.40565 -23.811738) (xy 375.40565 -22.254718)
			(xy 375.404888 -22.24532) (xy 375.403807 -22.240237) (xy 375.399834 -22.230636) (xy 375.397014 -22.22627)
			(xy 375.39295 -22.220428) (xy 375.381266 -22.210776) (xy 375.374408 -22.207982) (xy 375.348667 -22.196753)
			(xy 375.30052 -22.167843) (xy 375.257133 -22.132187) (xy 375.219443 -22.090554) (xy 375.188264 -22.043846)
			(xy 375.164271 -21.99307) (xy 375.147981 -21.939326) (xy 375.139748 -21.883773) (xy 375.139749 -21.827614)
			(xy 375.147984 -21.772063) (xy 375.164275 -21.718318) (xy 375.18827 -21.667544) (xy 375.21945 -21.620836)
			(xy 375.257142 -21.579205) (xy 375.300531 -21.54355) (xy 375.348678 -21.514642) (xy 375.374408 -21.503386)
			(xy 375.381266 -21.500592) (xy 375.39295 -21.49094) (xy 375.397014 -21.485098) (xy 375.399803 -21.480717)
			(xy 375.403767 -21.471119) (xy 375.404888 -21.466048) (xy 375.40565 -21.45665) (xy 375.40565 -15.83436)
			(xy 375.405396 -15.830042) (xy 375.405396 -15.829534) (xy 375.40436 -15.821476) (xy 375.397869 -15.806591)
			(xy 375.392696 -15.800324) (xy 375.383298 -15.790672) (xy 375.383044 -15.790418) (xy 375.340626 -15.747746)
			(xy 375.337122 -15.74435) (xy 375.329064 -15.738849) (xy 375.324624 -15.736824) (xy 375.315988 -15.733014)
			(xy 375.305828 -15.73276) (xy 375.30532 -15.73276) (xy 375.279645 -15.731879) (xy 375.228868 -15.724075)
			(xy 375.179597 -15.709532) (xy 375.13272 -15.688514) (xy 375.089085 -15.6614) (xy 375.049479 -15.628681)
			(xy 375.031762 -15.610078) (xy 375.031508 -15.609824) (xy 375.024268 -15.602747) (xy 375.005796 -15.594502)
			(xy 374.995694 -15.593822) (xy 374.944386 -15.595092) (xy 374.916446 -15.595854) (xy 374.911043 -15.596123)
			(xy 374.900536 -15.598682) (xy 374.895618 -15.600934) (xy 374.885966 -15.605506) (xy 374.878854 -15.614142)
			(xy 374.860643 -15.635291) (xy 374.819095 -15.672554) (xy 374.772564 -15.703369) (xy 374.72204 -15.727077)
			(xy 374.668602 -15.743173) (xy 374.613389 -15.751314) (xy 374.585484 -15.75181) (xy 374.558233 -15.751323)
			(xy 374.504287 -15.743565) (xy 374.451994 -15.728208) (xy 374.402418 -15.705566) (xy 374.35657 -15.676099)
			(xy 374.315381 -15.640407) (xy 374.279691 -15.599217) (xy 374.250226 -15.553367) (xy 374.227586 -15.503791)
			(xy 374.212232 -15.451497) (xy 374.204476 -15.397551) (xy 374.204476 -15.343049) (xy 374.212232 -15.289103)
			(xy 374.227586 -15.236809) (xy 374.250226 -15.187233) (xy 374.279691 -15.141383) (xy 374.315381 -15.100193)
			(xy 374.35657 -15.064501) (xy 374.402418 -15.035034) (xy 374.451994 -15.012392) (xy 374.504287 -14.997035)
			(xy 374.558233 -14.989277) (xy 374.585484 -14.988794) (xy 374.611721 -14.98923) (xy 374.663699 -14.996425)
			(xy 374.714199 -15.010682) (xy 374.762267 -15.03173) (xy 374.806993 -15.059172) (xy 374.847533 -15.09249)
			(xy 374.865646 -15.111476) (xy 374.8659 -15.11173) (xy 374.873143 -15.1188) (xy 374.891615 -15.127033)
			(xy 374.901714 -15.127732) (xy 374.953022 -15.126462) (xy 374.980962 -15.1257) (xy 374.986364 -15.12543)
			(xy 374.99687 -15.122867) (xy 375.00179 -15.12062) (xy 375.011442 -15.116048) (xy 375.018554 -15.107412)
			(xy 375.036419 -15.086664) (xy 375.077078 -15.049997) (xy 375.122557 -15.019513) (xy 375.171924 -14.995835)
			(xy 375.224165 -14.979449) (xy 375.278211 -14.970692) (xy 375.305574 -14.969744) (xy 375.315988 -14.96949)
			(xy 375.324624 -14.96568) (xy 375.328521 -14.963891) (xy 375.335678 -14.95917) (xy 375.338848 -14.956282)
			(xy 375.383044 -14.912086) (xy 375.383552 -14.911578) (xy 375.392696 -14.90218) (xy 375.39788 -14.895923)
			(xy 375.404354 -14.881029) (xy 375.405396 -14.87297) (xy 375.405396 -14.872462) (xy 375.40565 -14.868144)
			(xy 375.40565 -13.73124) (xy 375.405482 -13.72523) (xy 375.402659 -13.713548) (xy 375.400062 -13.708126)
			(xy 375.398224 -13.704651) (xy 375.393632 -13.69827) (xy 375.390918 -13.695426) (xy 375.085102 -13.38961)
			(xy 375.08225 -13.386905) (xy 375.075871 -13.382314) (xy 375.072402 -13.380466) (xy 375.066976 -13.37788)
			(xy 375.055296 -13.375048) (xy 375.049288 -13.374878) (xy 370.342668 -13.374878) (xy 370.336658 -13.375043)
			(xy 370.324973 -13.377862) (xy 370.319554 -13.380466) (xy 370.31608 -13.382306) (xy 370.309702 -13.3869)
			(xy 370.306854 -13.38961) (xy 369.596162 -14.100302) (xy 374.343166 -14.100302) (xy 374.347237 -14.04468)
			(xy 374.359363 -13.990243) (xy 374.379286 -13.938152) (xy 374.406582 -13.889517) (xy 374.440668 -13.845374)
			(xy 374.480817 -13.806665) (xy 374.526175 -13.774214) (xy 374.575775 -13.748713) (xy 374.628559 -13.730706)
			(xy 374.683402 -13.720576) (xy 374.739136 -13.718539) (xy 374.794573 -13.724639) (xy 374.84853 -13.738745)
			(xy 374.899859 -13.760557) (xy 374.947465 -13.789611) (xy 374.990333 -13.825286) (xy 375.02755 -13.866823)
			(xy 375.058323 -13.913336) (xy 375.081995 -13.963833) (xy 375.098063 -14.01724) (xy 375.106183 -14.072416)
			(xy 375.106692 -14.100302) (xy 375.106183 -14.128188) (xy 375.098063 -14.183364) (xy 375.081995 -14.236771)
			(xy 375.058323 -14.287268) (xy 375.02755 -14.333781) (xy 374.990333 -14.375318) (xy 374.947465 -14.410993)
			(xy 374.899859 -14.440047) (xy 374.84853 -14.461859) (xy 374.794573 -14.475965) (xy 374.739136 -14.482065)
			(xy 374.683402 -14.480028) (xy 374.628559 -14.469898) (xy 374.575775 -14.451891) (xy 374.526175 -14.42639)
			(xy 374.480817 -14.393939) (xy 374.440668 -14.35523) (xy 374.406582 -14.311087) (xy 374.379286 -14.262452)
			(xy 374.359363 -14.210361) (xy 374.347237 -14.155924) (xy 374.343166 -14.100302) (xy 369.596162 -14.100302)
			(xy 368.9858 -14.710664) (xy 368.985546 -14.710664) (xy 368.973109 -14.711362) (xy 368.951163 -14.723089)
			(xy 368.943636 -14.733016) (xy 368.88928 -14.813788) (xy 368.888264 -14.82471) (xy 368.914843 -14.889586)
			(xy 368.960439 -15.02218) (xy 368.997229 -15.157483) (xy 369.025053 -15.294909) (xy 369.043792 -15.433866)
			(xy 369.053364 -15.573754) (xy 369.054126 -15.64386) (xy 369.054126 -15.653512) (xy 369.053482 -15.720802)
			(xy 369.044762 -15.855101) (xy 369.027597 -15.988584) (xy 369.002055 -16.12072) (xy 368.968238 -16.250984)
			(xy 368.926279 -16.378858) (xy 368.876347 -16.503834) (xy 368.818639 -16.625416) (xy 368.753384 -16.743119)
			(xy 368.680842 -16.856477) (xy 368.601302 -16.965039) (xy 368.515079 -17.068373) (xy 368.469164 -17.117568)
			(xy 368.422886 -17.165973) (xy 368.325158 -17.257554) (xy 368.221881 -17.342828) (xy 368.11346 -17.421458)
			(xy 368.000322 -17.493136) (xy 367.882913 -17.557579) (xy 367.761694 -17.614534) (xy 367.637143 -17.663777)
			(xy 367.50975 -17.705114) (xy 367.380015 -17.738382) (xy 367.24845 -17.763451) (xy 367.115572 -17.780221)
			(xy 366.981904 -17.788627) (xy 366.914938 -17.789144) (xy 366.850465 -17.788668) (xy 366.721755 -17.780885)
			(xy 366.59375 -17.765344) (xy 366.466916 -17.742103) (xy 366.341717 -17.711247) (xy 366.21861 -17.672888)
			(xy 366.098043 -17.627165) (xy 365.980457 -17.574246) (xy 365.866281 -17.514324) (xy 365.75593 -17.447618)
			(xy 365.649809 -17.374371) (xy 365.548304 -17.294849) (xy 365.451786 -17.209345) (xy 365.360606 -17.118168)
			(xy 365.275098 -17.021653) (xy 365.195573 -16.92015) (xy 365.122322 -16.814032) (xy 365.055612 -16.703684)
			(xy 364.995686 -16.58951) (xy 364.942763 -16.471925) (xy 364.897037 -16.35136) (xy 364.858673 -16.228254)
			(xy 364.827812 -16.103056) (xy 364.804567 -15.976223) (xy 364.789022 -15.848219) (xy 364.781234 -15.719509)
			(xy 364.78083 -15.655036) (xy 364.781388 -15.586296) (xy 364.790258 -15.449103) (xy 364.807936 -15.312764)
			(xy 364.834351 -15.177846) (xy 364.869392 -15.044906) (xy 364.912914 -14.914497) (xy 364.93831 -14.850618)
			(xy 364.93831 -14.850364) (xy 364.940492 -14.844593) (xy 364.942282 -14.83239) (xy 364.941866 -14.826234)
			(xy 364.940596 -14.813788) (xy 364.88624 -14.733016) (xy 364.878754 -14.723052) (xy 364.856777 -14.711357)
			(xy 364.84433 -14.710664) (xy 363.029246 -14.710664) (xy 363.02315 -14.710918) (xy 363.016322 -14.711953)
			(xy 363.003574 -14.717249) (xy 362.998004 -14.721332) (xy 362.994125 -14.724548) (xy 362.987601 -14.732226)
			(xy 362.98505 -14.736572) (xy 362.976922 -14.752574) (xy 362.976922 -14.753082) (xy 362.94314 -14.819122)
			(xy 362.940213 -14.825439) (xy 362.937503 -14.83909) (xy 362.937806 -14.846046) (xy 362.937806 -14.847062)
			(xy 362.951014 -14.865096) (xy 362.975659 -14.89961) (xy 363.019333 -14.972316) (xy 363.056278 -15.048662)
			(xy 363.086195 -15.128025) (xy 363.108839 -15.209761) (xy 363.124026 -15.293205) (xy 363.131633 -15.377678)
			(xy 363.132116 -15.420086) (xy 363.131562 -15.466593) (xy 363.1224 -15.559154) (xy 363.104145 -15.650358)
			(xy 363.076975 -15.739315) (xy 363.041156 -15.825154) (xy 363.019594 -15.866364) (xy 363.017816 -15.869666)
			(xy 363.015173 -15.875274) (xy 363.01236 -15.887343) (xy 363.012228 -15.893542) (xy 363.012228 -15.901162)
			(xy 363.032802 -15.939008) (xy 363.032802 -15.939516) (xy 363.06125 -15.990824) (xy 363.064079 -15.99503)
			(xy 363.071121 -16.002319) (xy 363.07522 -16.005302) (xy 363.075982 -16.00581) (xy 363.095794 -16.007588)
			(xy 363.096302 -16.007588) (xy 363.126625 -16.01036) (xy 363.186869 -16.019254) (xy 363.216698 -16.025368)
			(xy 363.260046 -16.035137) (xy 363.344881 -16.061592) (xy 363.426927 -16.095727) (xy 363.50549 -16.137255)
			(xy 363.579906 -16.185825) (xy 363.649546 -16.241026) (xy 363.71382 -16.30239) (xy 363.772186 -16.3694)
			(xy 363.824149 -16.441487) (xy 363.847126 -16.47952) (xy 363.847634 -16.480536) (xy 363.868812 -16.517493)
			(xy 363.905336 -16.594451) (xy 363.934942 -16.674325) (xy 363.957401 -16.756496) (xy 363.972538 -16.840326)
			(xy 363.980235 -16.925162) (xy 363.980434 -17.010347) (xy 363.973131 -17.095218) (xy 363.958384 -17.179117)
			(xy 363.936307 -17.261391) (xy 363.907073 -17.341403) (xy 363.870907 -17.418529) (xy 363.828091 -17.492172)
			(xy 363.778958 -17.561759) (xy 363.723888 -17.62675) (xy 363.693964 -17.657064) (xy 363.659815 -17.690483)
			(xy 363.585984 -17.75114) (xy 363.506518 -17.804201) (xy 363.422194 -17.849145) (xy 363.378242 -17.867884)
			(xy 363.337402 -17.884193) (xy 363.25339 -17.910204) (xy 363.167361 -17.928469) (xy 363.080028 -17.938837)
			(xy 362.992113 -17.941221) (xy 362.904347 -17.935603) (xy 362.817454 -17.922027) (xy 362.732156 -17.900608)
			(xy 362.649158 -17.871522) (xy 362.569149 -17.83501) (xy 362.492791 -17.791375) (xy 362.420716 -17.740978)
			(xy 362.353522 -17.684237) (xy 362.291766 -17.621622) (xy 362.235958 -17.55365) (xy 362.186561 -17.480887)
			(xy 362.143985 -17.403933) (xy 362.108581 -17.323427) (xy 362.080644 -17.240036) (xy 362.060405 -17.15445)
			(xy 362.048031 -17.067378) (xy 362.043625 -16.979542) (xy 362.047223 -16.891669) (xy 362.058796 -16.804487)
			(xy 362.078248 -16.718719) (xy 362.105417 -16.635074) (xy 362.140079 -16.554246) (xy 362.160566 -16.515334)
			(xy 362.161328 -16.514064) (xy 362.161582 -16.513302) (xy 362.162598 -16.511016) (xy 362.164618 -16.505989)
			(xy 362.166663 -16.495352) (xy 362.166662 -16.489934) (xy 362.166408 -16.476726) (xy 362.133388 -16.421354)
			(xy 362.133388 -16.420846) (xy 362.113322 -16.387826) (xy 362.111248 -16.384871) (xy 362.106399 -16.379522)
			(xy 362.10367 -16.377158) (xy 362.100622 -16.374618) (xy 362.094037 -16.370288) (xy 362.079034 -16.365495)
			(xy 362.071158 -16.36522) (xy 360.332782 -16.36522) (xy 360.289344 -16.364733) (xy 360.20284 -16.356715)
			(xy 360.117444 -16.34075) (xy 360.033885 -16.316973) (xy 359.952877 -16.285588) (xy 359.87511 -16.246863)
			(xy 359.801248 -16.201127) (xy 359.731922 -16.148771) (xy 359.667722 -16.090242) (xy 359.609196 -16.026038)
			(xy 359.556844 -15.956709) (xy 359.511112 -15.882844) (xy 359.47239 -15.805075) (xy 359.44101 -15.724065)
			(xy 359.417238 -15.640506) (xy 359.401278 -15.555109) (xy 359.393265 -15.468604) (xy 359.392728 -15.425166)
			(xy 359.392728 -15.424658) (xy 359.393199 -15.382443) (xy 359.400792 -15.298354) (xy 359.415896 -15.215285)
			(xy 359.438387 -15.133905) (xy 359.468086 -15.05487) (xy 359.504753 -14.978817) (xy 359.548092 -14.906358)
			(xy 359.57256 -14.871954) (xy 359.576624 -14.866366) (xy 359.58145 -14.853412) (xy 359.582212 -14.846046)
			(xy 359.582481 -14.839073) (xy 359.579638 -14.825416) (xy 359.576624 -14.819122) (xy 359.558082 -14.782546)
			(xy 359.53446 -14.736064) (xy 359.53251 -14.732785) (xy 359.527791 -14.726791) (xy 359.525062 -14.724126)
			(xy 359.51668 -14.717776) (xy 359.512616 -14.715744) (xy 359.50271 -14.712188) (xy 359.490518 -14.710664)
			(xy 350.16948 -14.710664) (xy 350.163469 -14.710828) (xy 350.151783 -14.713643) (xy 350.146366 -14.716252)
			(xy 350.142894 -14.718094) (xy 350.136519 -14.722692) (xy 350.133666 -14.725396) (xy 349.730568 -15.128494)
			(xy 349.72786 -15.131344) (xy 349.723264 -15.137721) (xy 349.721424 -15.141194) (xy 349.718845 -15.146622)
			(xy 349.716032 -15.158301) (xy 349.715836 -15.164308) (xy 349.715836 -18.44421) (xy 370.576346 -18.44421)
			(xy 370.580417 -18.388588) (xy 370.592543 -18.334151) (xy 370.612466 -18.28206) (xy 370.639762 -18.233425)
			(xy 370.673848 -18.189282) (xy 370.713997 -18.150573) (xy 370.759355 -18.118122) (xy 370.808955 -18.092621)
			(xy 370.861739 -18.074614) (xy 370.916582 -18.064484) (xy 370.972316 -18.062447) (xy 371.027753 -18.068547)
			(xy 371.08171 -18.082653) (xy 371.133039 -18.104465) (xy 371.180645 -18.133519) (xy 371.223513 -18.169194)
			(xy 371.26073 -18.210731) (xy 371.291503 -18.257244) (xy 371.315175 -18.307741) (xy 371.331243 -18.361148)
			(xy 371.339363 -18.416324) (xy 371.339872 -18.44421) (xy 371.339363 -18.472096) (xy 371.331243 -18.527272)
			(xy 371.315175 -18.580679) (xy 371.291503 -18.631176) (xy 371.26073 -18.677689) (xy 371.223513 -18.719226)
			(xy 371.180645 -18.754901) (xy 371.133039 -18.783955) (xy 371.08171 -18.805767) (xy 371.027753 -18.819873)
			(xy 370.972316 -18.825973) (xy 370.916582 -18.823936) (xy 370.861739 -18.813806) (xy 370.808955 -18.795799)
			(xy 370.759355 -18.770298) (xy 370.713997 -18.737847) (xy 370.673848 -18.699138) (xy 370.639762 -18.654995)
			(xy 370.612466 -18.60636) (xy 370.592543 -18.554269) (xy 370.580417 -18.499832) (xy 370.576346 -18.44421)
			(xy 349.715836 -18.44421) (xy 349.715836 -20.72513) (xy 353.480636 -20.72513) (xy 353.484606 -20.594996)
			(xy 353.496502 -20.465346) (xy 353.516281 -20.336663) (xy 353.543867 -20.209424) (xy 353.57916 -20.084105)
			(xy 353.622026 -19.961169) (xy 353.672308 -19.841076) (xy 353.729817 -19.724272) (xy 353.794341 -19.61119)
			(xy 353.865638 -19.502253) (xy 353.943443 -19.397865) (xy 354.027468 -19.298414) (xy 354.1174 -19.204271)
			(xy 354.212904 -19.115786) (xy 354.313624 -19.033287) (xy 354.419186 -18.957082) (xy 354.529198 -18.887455)
			(xy 354.64325 -18.824664) (xy 354.760918 -18.768942) (xy 354.881764 -18.720498) (xy 355.005339 -18.679511)
			(xy 355.131182 -18.646134) (xy 355.258827 -18.620491) (xy 355.387797 -18.602677) (xy 355.517613 -18.592759)
			(xy 355.647792 -18.590774) (xy 355.777851 -18.596728) (xy 355.907304 -18.610601) (xy 356.035671 -18.632339)
			(xy 356.162474 -18.661863) (xy 356.287241 -18.699062) (xy 356.409508 -18.743798) (xy 356.528821 -18.795906)
			(xy 356.644734 -18.855189) (xy 356.756819 -18.92143) (xy 356.864656 -18.99438) (xy 356.967845 -19.073768)
			(xy 357.066003 -19.1593) (xy 357.158764 -19.250657) (xy 357.245783 -19.347499) (xy 357.326736 -19.449466)
			(xy 357.401322 -19.556178) (xy 357.469263 -19.667239) (xy 357.530308 -19.782235) (xy 357.584229 -19.900739)
			(xy 357.630824 -20.02231) (xy 357.669922 -20.146495) (xy 357.701376 -20.272833) (xy 357.72507 -20.400854)
			(xy 357.740914 -20.53008) (xy 357.748852 -20.660033) (xy 357.749348 -20.72513) (xy 357.748852 -20.790227)
			(xy 357.740914 -20.92018) (xy 357.72507 -21.049406) (xy 357.701376 -21.177427) (xy 357.669922 -21.303765)
			(xy 357.630824 -21.42795) (xy 357.584229 -21.549521) (xy 357.530308 -21.668025) (xy 357.492984 -21.738336)
			(xy 359.716832 -21.738336) (xy 359.717335 -21.709597) (xy 359.725965 -21.652769) (xy 359.743021 -21.597879)
			(xy 359.768117 -21.546168) (xy 359.800685 -21.498805) (xy 359.819956 -21.477478) (xy 359.82656 -21.47062)
			(xy 359.833672 -21.452586) (xy 359.833672 -21.363686) (xy 359.82656 -21.345652) (xy 359.819956 -21.338794)
			(xy 359.800719 -21.317437) (xy 359.76815 -21.270081) (xy 359.743055 -21.218374) (xy 359.726 -21.163488)
			(xy 359.717374 -21.106664) (xy 359.71737 -21.049189) (xy 359.725989 -20.992364) (xy 359.743035 -20.937475)
			(xy 359.768124 -20.885765) (xy 359.800686 -20.838404) (xy 359.819956 -20.817078) (xy 359.82656 -20.81022)
			(xy 359.833672 -20.792186) (xy 359.833672 -20.703286) (xy 359.82656 -20.685252) (xy 359.819956 -20.678394)
			(xy 359.800719 -20.657037) (xy 359.76815 -20.609681) (xy 359.743055 -20.557974) (xy 359.726 -20.503088)
			(xy 359.717374 -20.446264) (xy 359.71737 -20.388789) (xy 359.725989 -20.331964) (xy 359.743035 -20.277075)
			(xy 359.768124 -20.225365) (xy 359.800686 -20.178004) (xy 359.819956 -20.156678) (xy 359.82656 -20.14982)
			(xy 359.833672 -20.131786) (xy 359.833672 -20.042886) (xy 359.82656 -20.024852) (xy 359.819956 -20.017994)
			(xy 359.800719 -19.996637) (xy 359.76815 -19.949281) (xy 359.743055 -19.897574) (xy 359.726 -19.842688)
			(xy 359.717374 -19.785864) (xy 359.71737 -19.728389) (xy 359.725989 -19.671564) (xy 359.743035 -19.616675)
			(xy 359.768124 -19.564965) (xy 359.800686 -19.517604) (xy 359.819956 -19.496278) (xy 359.82656 -19.48942)
			(xy 359.833672 -19.471386) (xy 359.833672 -19.382486) (xy 359.82656 -19.364452) (xy 359.819956 -19.357594)
			(xy 359.800705 -19.33625) (xy 359.768136 -19.288893) (xy 359.743039 -19.237185) (xy 359.725984 -19.182298)
			(xy 359.717356 -19.125474) (xy 359.716832 -19.096736) (xy 359.717318 -19.069485) (xy 359.725074 -19.015537)
			(xy 359.740429 -18.963242) (xy 359.763071 -18.913665) (xy 359.792537 -18.867815) (xy 359.828228 -18.826624)
			(xy 359.869419 -18.790933) (xy 359.915269 -18.761467) (xy 359.964846 -18.738825) (xy 360.017141 -18.72347)
			(xy 360.071089 -18.715714) (xy 360.125591 -18.715714) (xy 360.179539 -18.72347) (xy 360.231834 -18.738825)
			(xy 360.281411 -18.761467) (xy 360.327261 -18.790933) (xy 360.368452 -18.826624) (xy 360.404143 -18.867815)
			(xy 360.433609 -18.913665) (xy 360.456251 -18.963242) (xy 360.471606 -19.015537) (xy 360.479362 -19.069485)
			(xy 360.479848 -19.096736) (xy 360.479333 -19.125475) (xy 360.470707 -19.182302) (xy 360.453654 -19.237193)
			(xy 360.42856 -19.288904) (xy 360.395995 -19.336267) (xy 360.376724 -19.357594) (xy 360.37012 -19.364452)
			(xy 360.363008 -19.382486) (xy 360.363008 -19.471386) (xy 360.37012 -19.48942) (xy 360.376724 -19.496278)
			(xy 360.396028 -19.517575) (xy 360.428588 -19.564944) (xy 360.453675 -19.616661) (xy 360.47072 -19.671556)
			(xy 360.479338 -19.728386) (xy 360.479334 -19.785866) (xy 360.470708 -19.842696) (xy 360.453655 -19.897588)
			(xy 360.428562 -19.949302) (xy 360.395995 -19.996666) (xy 360.376724 -20.017994) (xy 360.37012 -20.024852)
			(xy 360.363008 -20.042886) (xy 360.363008 -20.131786) (xy 360.37012 -20.14982) (xy 360.376724 -20.156678)
			(xy 360.396028 -20.177975) (xy 360.428588 -20.225344) (xy 360.453675 -20.277061) (xy 360.47072 -20.331956)
			(xy 360.479338 -20.388786) (xy 360.479334 -20.446266) (xy 360.470708 -20.503096) (xy 360.453655 -20.557988)
			(xy 360.428562 -20.609702) (xy 360.395995 -20.657066) (xy 360.376724 -20.678394) (xy 360.37012 -20.685252)
			(xy 360.363008 -20.703286) (xy 360.363008 -20.792186) (xy 360.37012 -20.81022) (xy 360.376724 -20.817078)
			(xy 360.396028 -20.838375) (xy 360.428588 -20.885744) (xy 360.453675 -20.937461) (xy 360.47072 -20.992356)
			(xy 360.479338 -21.049186) (xy 360.479334 -21.106666) (xy 360.470708 -21.163496) (xy 360.453655 -21.218388)
			(xy 360.428562 -21.270102) (xy 360.395995 -21.317466) (xy 360.376724 -21.338794) (xy 360.37012 -21.345652)
			(xy 360.363008 -21.363686) (xy 360.363008 -21.452586) (xy 360.37012 -21.47062) (xy 360.376724 -21.477478)
			(xy 360.396006 -21.498796) (xy 360.428572 -21.54616) (xy 360.453663 -21.597874) (xy 360.466442 -21.639022)
			(xy 364.373922 -21.639022) (xy 364.37448 -21.610285) (xy 364.383097 -21.55346) (xy 364.400141 -21.49857)
			(xy 364.425224 -21.446858) (xy 364.45778 -21.399493) (xy 364.477046 -21.378164) (xy 364.48365 -21.371306)
			(xy 364.490762 -21.353272) (xy 364.490762 -21.264372) (xy 364.48365 -21.246338) (xy 364.477046 -21.23948)
			(xy 364.457796 -21.218135) (xy 364.425228 -21.170776) (xy 364.400134 -21.119068) (xy 364.383081 -21.064179)
			(xy 364.374456 -21.007354) (xy 364.374454 -20.949878) (xy 364.383074 -20.893052) (xy 364.400122 -20.838162)
			(xy 364.425212 -20.786452) (xy 364.457776 -20.73909) (xy 364.477046 -20.717764) (xy 364.48365 -20.710906)
			(xy 364.490762 -20.692872) (xy 364.490762 -20.603972) (xy 364.48365 -20.585938) (xy 364.477046 -20.57908)
			(xy 364.457796 -20.557735) (xy 364.425228 -20.510376) (xy 364.400134 -20.458668) (xy 364.383081 -20.403779)
			(xy 364.374456 -20.346954) (xy 364.374454 -20.289478) (xy 364.383074 -20.232652) (xy 364.400122 -20.177762)
			(xy 364.425212 -20.126052) (xy 364.457776 -20.07869) (xy 364.477046 -20.057364) (xy 364.48365 -20.050506)
			(xy 364.490762 -20.032472) (xy 364.490762 -19.943572) (xy 364.48365 -19.925538) (xy 364.477046 -19.91868)
			(xy 364.457796 -19.897335) (xy 364.425228 -19.849976) (xy 364.400134 -19.798268) (xy 364.383081 -19.743379)
			(xy 364.374456 -19.686554) (xy 364.374454 -19.629078) (xy 364.383074 -19.572252) (xy 364.400122 -19.517362)
			(xy 364.425212 -19.465652) (xy 364.457776 -19.41829) (xy 364.477046 -19.396964) (xy 364.48365 -19.390106)
			(xy 364.490762 -19.372072) (xy 364.490762 -19.283172) (xy 364.48365 -19.265138) (xy 364.477046 -19.25828)
			(xy 364.457787 -19.236943) (xy 364.425219 -19.189584) (xy 364.400124 -19.137875) (xy 364.383071 -19.082986)
			(xy 364.374445 -19.02616) (xy 364.373922 -18.997422) (xy 364.374408 -18.970171) (xy 364.382164 -18.916223)
			(xy 364.397519 -18.863928) (xy 364.420161 -18.814351) (xy 364.449627 -18.768501) (xy 364.485318 -18.72731)
			(xy 364.526509 -18.691619) (xy 364.572359 -18.662153) (xy 364.621936 -18.639511) (xy 364.674231 -18.624156)
			(xy 364.728179 -18.6164) (xy 364.782681 -18.6164) (xy 364.836629 -18.624156) (xy 364.888924 -18.639511)
			(xy 364.938501 -18.662153) (xy 364.984351 -18.691619) (xy 365.025542 -18.72731) (xy 365.061233 -18.768501)
			(xy 365.090699 -18.814351) (xy 365.113341 -18.863928) (xy 365.128696 -18.916223) (xy 365.136452 -18.970171)
			(xy 365.136938 -18.997422) (xy 365.136417 -19.026161) (xy 365.127793 -19.082988) (xy 365.110741 -19.137878)
			(xy 365.085649 -19.18959) (xy 365.053084 -19.236953) (xy 365.033814 -19.25828) (xy 365.02721 -19.265138)
			(xy 365.020098 -19.283172) (xy 365.020098 -19.366853) (xy 369.879338 -19.366853) (xy 369.879338 -19.312347)
			(xy 369.887094 -19.258396) (xy 369.90245 -19.206098) (xy 369.925091 -19.156518) (xy 369.954558 -19.110664)
			(xy 369.99025 -19.06947) (xy 370.031441 -19.033775) (xy 370.077293 -19.004305) (xy 370.126872 -18.98166)
			(xy 370.179169 -18.9663) (xy 370.233119 -18.95854) (xy 370.260372 -18.958052) (xy 370.287142 -18.958549)
			(xy 370.340155 -18.966042) (xy 370.391601 -18.980873) (xy 370.440468 -19.002749) (xy 370.485798 -19.03124)
			(xy 370.526701 -19.065788) (xy 370.562372 -19.105715) (xy 370.577618 -19.127724) (xy 370.577872 -19.127978)
			(xy 370.584106 -19.136369) (xy 370.601683 -19.147645) (xy 370.611908 -19.149822) (xy 370.68506 -19.16176)
			(xy 370.695509 -19.1629) (xy 370.715841 -19.157659) (xy 370.72443 -19.1516) (xy 370.744549 -19.136479)
			(xy 370.788027 -19.111128) (xy 370.834464 -19.091722) (xy 370.883052 -19.078599) (xy 370.932945 -19.071987)
			(xy 370.95811 -19.07159) (xy 370.958364 -19.07159) (xy 370.985618 -19.072055) (xy 371.039573 -19.079808)
			(xy 371.091875 -19.09516) (xy 371.141459 -19.117801) (xy 371.187317 -19.147268) (xy 371.228513 -19.182961)
			(xy 371.264211 -19.224155) (xy 371.293682 -19.270009) (xy 371.316327 -19.319591) (xy 371.331685 -19.371892)
			(xy 371.339443 -19.425846) (xy 371.339443 -19.480354) (xy 371.331685 -19.534308) (xy 371.316327 -19.586609)
			(xy 371.293682 -19.636191) (xy 371.264211 -19.682045) (xy 371.228513 -19.723239) (xy 371.187317 -19.758932)
			(xy 371.141459 -19.788399) (xy 371.091875 -19.81104) (xy 371.039573 -19.826392) (xy 370.985618 -19.834145)
			(xy 370.958364 -19.834606) (xy 370.931591 -19.834177) (xy 370.878574 -19.826673) (xy 370.827126 -19.811832)
			(xy 370.778258 -19.789946) (xy 370.732929 -19.761444) (xy 370.692029 -19.726885) (xy 370.656361 -19.686948)
			(xy 370.641118 -19.664934) (xy 370.640864 -19.66468) (xy 370.634603 -19.656312) (xy 370.617046 -19.645021)
			(xy 370.606828 -19.642836) (xy 370.533676 -19.630898) (xy 370.523226 -19.629767) (xy 370.502895 -19.635001)
			(xy 370.494306 -19.641058) (xy 370.474171 -19.656157) (xy 370.430698 -19.681512) (xy 370.384265 -19.700923)
			(xy 370.33568 -19.714052) (xy 370.28579 -19.720668) (xy 370.260626 -19.721068) (xy 370.260372 -19.721068)
			(xy 370.233119 -19.72066) (xy 370.179169 -19.7129) (xy 370.126872 -19.69754) (xy 370.077293 -19.674895)
			(xy 370.031441 -19.645425) (xy 369.99025 -19.60973) (xy 369.954558 -19.568536) (xy 369.925091 -19.522682)
			(xy 369.90245 -19.473102) (xy 369.887094 -19.420804) (xy 369.879338 -19.366853) (xy 365.020098 -19.366853)
			(xy 365.020098 -19.372072) (xy 365.02721 -19.390106) (xy 365.033814 -19.396964) (xy 365.053105 -19.418273)
			(xy 365.085666 -19.465639) (xy 365.110754 -19.517354) (xy 365.127801 -19.572247) (xy 365.13642 -19.629077)
			(xy 365.136418 -19.686556) (xy 365.127793 -19.743384) (xy 365.110742 -19.798276) (xy 365.08565 -19.849988)
			(xy 365.053085 -19.897352) (xy 365.033814 -19.91868) (xy 365.02721 -19.925538) (xy 365.020098 -19.943572)
			(xy 365.020098 -20.032472) (xy 365.02721 -20.050506) (xy 365.033814 -20.057364) (xy 365.053105 -20.078673)
			(xy 365.085666 -20.126039) (xy 365.110754 -20.177754) (xy 365.127801 -20.232647) (xy 365.13642 -20.289477)
			(xy 365.136418 -20.346956) (xy 365.135112 -20.35556) (xy 369.878354 -20.35556) (xy 369.882425 -20.299938)
			(xy 369.894551 -20.245501) (xy 369.914474 -20.19341) (xy 369.94177 -20.144775) (xy 369.975856 -20.100632)
			(xy 370.016005 -20.061923) (xy 370.061363 -20.029472) (xy 370.110963 -20.003971) (xy 370.163747 -19.985964)
			(xy 370.21859 -19.975834) (xy 370.274324 -19.973797) (xy 370.329761 -19.979897) (xy 370.383718 -19.994003)
			(xy 370.435047 -20.015815) (xy 370.482653 -20.044869) (xy 370.525521 -20.080544) (xy 370.562738 -20.122081)
			(xy 370.593511 -20.168594) (xy 370.617183 -20.219091) (xy 370.633251 -20.272498) (xy 370.641371 -20.327674)
			(xy 370.64188 -20.35556) (xy 370.641371 -20.383446) (xy 370.633251 -20.438622) (xy 370.617183 -20.492029)
			(xy 370.593511 -20.542526) (xy 370.562738 -20.589039) (xy 370.525521 -20.630576) (xy 370.482653 -20.666251)
			(xy 370.435047 -20.695305) (xy 370.383718 -20.717117) (xy 370.329761 -20.731223) (xy 370.274324 -20.737323)
			(xy 370.21859 -20.735286) (xy 370.163747 -20.725156) (xy 370.110963 -20.707149) (xy 370.061363 -20.681648)
			(xy 370.016005 -20.649197) (xy 369.975856 -20.610488) (xy 369.94177 -20.566345) (xy 369.914474 -20.51771)
			(xy 369.894551 -20.465619) (xy 369.882425 -20.411182) (xy 369.878354 -20.35556) (xy 365.135112 -20.35556)
			(xy 365.127793 -20.403784) (xy 365.110742 -20.458676) (xy 365.08565 -20.510388) (xy 365.053085 -20.557752)
			(xy 365.033814 -20.57908) (xy 365.02721 -20.585938) (xy 365.020098 -20.603972) (xy 365.020098 -20.692872)
			(xy 365.02721 -20.710906) (xy 365.033814 -20.717764) (xy 365.053105 -20.739073) (xy 365.085666 -20.786439)
			(xy 365.110754 -20.838154) (xy 365.127801 -20.893047) (xy 365.13642 -20.949877) (xy 365.136418 -21.007356)
			(xy 365.127793 -21.064184) (xy 365.110742 -21.119076) (xy 365.08565 -21.170788) (xy 365.053085 -21.218152)
			(xy 365.033814 -21.23948) (xy 365.02721 -21.246338) (xy 365.020098 -21.264372) (xy 365.020098 -21.353272)
			(xy 365.02721 -21.371306) (xy 365.027455 -21.37156) (xy 369.878354 -21.37156) (xy 369.882425 -21.315938)
			(xy 369.894551 -21.261501) (xy 369.914474 -21.20941) (xy 369.94177 -21.160775) (xy 369.975856 -21.116632)
			(xy 370.016005 -21.077923) (xy 370.061363 -21.045472) (xy 370.110963 -21.019971) (xy 370.163747 -21.001964)
			(xy 370.21859 -20.991834) (xy 370.274324 -20.989797) (xy 370.329761 -20.995897) (xy 370.383718 -21.010003)
			(xy 370.435047 -21.031815) (xy 370.482653 -21.060869) (xy 370.525521 -21.096544) (xy 370.562738 -21.138081)
			(xy 370.593511 -21.184594) (xy 370.617183 -21.235091) (xy 370.633251 -21.288498) (xy 370.641371 -21.343674)
			(xy 370.64188 -21.37156) (xy 370.641371 -21.399446) (xy 370.633251 -21.454622) (xy 370.617183 -21.508029)
			(xy 370.593511 -21.558526) (xy 370.562738 -21.605039) (xy 370.525521 -21.646576) (xy 370.482653 -21.682251)
			(xy 370.435047 -21.711305) (xy 370.383718 -21.733117) (xy 370.329761 -21.747223) (xy 370.274324 -21.753323)
			(xy 370.21859 -21.751286) (xy 370.163747 -21.741156) (xy 370.110963 -21.723149) (xy 370.061363 -21.697648)
			(xy 370.016005 -21.665197) (xy 369.975856 -21.626488) (xy 369.94177 -21.582345) (xy 369.914474 -21.53371)
			(xy 369.894551 -21.481619) (xy 369.882425 -21.427182) (xy 369.878354 -21.37156) (xy 365.027455 -21.37156)
			(xy 365.033814 -21.378164) (xy 365.053087 -21.399489) (xy 365.085655 -21.446851) (xy 365.110748 -21.498563)
			(xy 365.127798 -21.553454) (xy 365.136419 -21.610283) (xy 365.136938 -21.639022) (xy 365.136452 -21.666273)
			(xy 365.128696 -21.720221) (xy 365.113341 -21.772516) (xy 365.111899 -21.775674) (xy 374.235978 -21.775674)
			(xy 374.240049 -21.720052) (xy 374.252175 -21.665615) (xy 374.272098 -21.613524) (xy 374.299394 -21.564889)
			(xy 374.33348 -21.520746) (xy 374.373629 -21.482037) (xy 374.418987 -21.449586) (xy 374.468587 -21.424085)
			(xy 374.521371 -21.406078) (xy 374.576214 -21.395948) (xy 374.631948 -21.393911) (xy 374.687385 -21.400011)
			(xy 374.741342 -21.414117) (xy 374.792671 -21.435929) (xy 374.840277 -21.464983) (xy 374.883145 -21.500658)
			(xy 374.920362 -21.542195) (xy 374.951135 -21.588708) (xy 374.974807 -21.639205) (xy 374.990875 -21.692612)
			(xy 374.998995 -21.747788) (xy 374.999504 -21.775674) (xy 374.998995 -21.80356) (xy 374.990875 -21.858736)
			(xy 374.974807 -21.912143) (xy 374.951135 -21.96264) (xy 374.920362 -22.009153) (xy 374.883145 -22.05069)
			(xy 374.840277 -22.086365) (xy 374.792671 -22.115419) (xy 374.741342 -22.137231) (xy 374.687385 -22.151337)
			(xy 374.631948 -22.157437) (xy 374.576214 -22.1554) (xy 374.521371 -22.14527) (xy 374.468587 -22.127263)
			(xy 374.418987 -22.101762) (xy 374.373629 -22.069311) (xy 374.33348 -22.030602) (xy 374.299394 -21.986459)
			(xy 374.272098 -21.937824) (xy 374.252175 -21.885733) (xy 374.240049 -21.831296) (xy 374.235978 -21.775674)
			(xy 365.111899 -21.775674) (xy 365.090699 -21.822093) (xy 365.061233 -21.867943) (xy 365.025542 -21.909134)
			(xy 364.984351 -21.944825) (xy 364.938501 -21.974291) (xy 364.888924 -21.996933) (xy 364.836629 -22.012288)
			(xy 364.782681 -22.020044) (xy 364.728179 -22.020044) (xy 364.674231 -22.012288) (xy 364.621936 -21.996933)
			(xy 364.572359 -21.974291) (xy 364.526509 -21.944825) (xy 364.485318 -21.909134) (xy 364.449627 -21.867943)
			(xy 364.420161 -21.822093) (xy 364.397519 -21.772516) (xy 364.382164 -21.720221) (xy 364.374408 -21.666273)
			(xy 364.373922 -21.639022) (xy 360.466442 -21.639022) (xy 360.470711 -21.652767) (xy 360.47933 -21.709596)
			(xy 360.479848 -21.738336) (xy 360.479362 -21.765587) (xy 360.471606 -21.819535) (xy 360.456251 -21.87183)
			(xy 360.433609 -21.921407) (xy 360.404143 -21.967257) (xy 360.368452 -22.008448) (xy 360.327261 -22.044139)
			(xy 360.281411 -22.073605) (xy 360.231834 -22.096247) (xy 360.179539 -22.111602) (xy 360.125591 -22.119358)
			(xy 360.071089 -22.119358) (xy 360.017141 -22.111602) (xy 359.964846 -22.096247) (xy 359.915269 -22.073605)
			(xy 359.869419 -22.044139) (xy 359.828228 -22.008448) (xy 359.792537 -21.967257) (xy 359.763071 -21.921407)
			(xy 359.740429 -21.87183) (xy 359.725074 -21.819535) (xy 359.717318 -21.765587) (xy 359.716832 -21.738336)
			(xy 357.492984 -21.738336) (xy 357.469263 -21.783021) (xy 357.401322 -21.894082) (xy 357.326736 -22.000794)
			(xy 357.245783 -22.102761) (xy 357.158764 -22.199603) (xy 357.066003 -22.29096) (xy 356.967845 -22.376492)
			(xy 356.864656 -22.45588) (xy 356.756819 -22.52883) (xy 356.644734 -22.595071) (xy 356.528821 -22.654354)
			(xy 356.409508 -22.706462) (xy 356.287241 -22.751198) (xy 356.162474 -22.788397) (xy 356.035671 -22.817921)
			(xy 355.907304 -22.839659) (xy 355.777851 -22.853532) (xy 355.647792 -22.859486) (xy 355.517613 -22.857501)
			(xy 355.387797 -22.847583) (xy 355.258827 -22.829769) (xy 355.131182 -22.804126) (xy 355.005339 -22.770749)
			(xy 354.881764 -22.729762) (xy 354.760918 -22.681318) (xy 354.64325 -22.625596) (xy 354.529198 -22.562805)
			(xy 354.419186 -22.493178) (xy 354.313624 -22.416973) (xy 354.212904 -22.334474) (xy 354.1174 -22.245989)
			(xy 354.027468 -22.151846) (xy 353.943443 -22.052395) (xy 353.865638 -21.948007) (xy 353.794341 -21.83907)
			(xy 353.729817 -21.725988) (xy 353.672308 -21.609184) (xy 353.622026 -21.489091) (xy 353.57916 -21.366155)
			(xy 353.543867 -21.240836) (xy 353.516281 -21.113597) (xy 353.496502 -20.984914) (xy 353.484606 -20.855264)
			(xy 353.480636 -20.72513) (xy 349.715836 -20.72513) (xy 349.715836 -23.0251) (xy 359.662474 -23.0251)
			(xy 359.666545 -22.969478) (xy 359.678671 -22.915041) (xy 359.698594 -22.86295) (xy 359.72589 -22.814315)
			(xy 359.759976 -22.770172) (xy 359.800125 -22.731463) (xy 359.845483 -22.699012) (xy 359.895083 -22.673511)
			(xy 359.947867 -22.655504) (xy 360.00271 -22.645374) (xy 360.058444 -22.643337) (xy 360.113881 -22.649437)
			(xy 360.167838 -22.663543) (xy 360.219167 -22.685355) (xy 360.266773 -22.714409) (xy 360.309641 -22.750084)
			(xy 360.346858 -22.791621) (xy 360.377631 -22.838134) (xy 360.401303 -22.888631) (xy 360.417371 -22.942038)
			(xy 360.425491 -22.997214) (xy 360.426 -23.0251) (xy 360.425491 -23.052986) (xy 360.417371 -23.108162)
			(xy 360.401303 -23.161569) (xy 360.377631 -23.212066) (xy 360.346858 -23.258579) (xy 360.309641 -23.300116)
			(xy 360.266773 -23.335791) (xy 360.219167 -23.364845) (xy 360.167838 -23.386657) (xy 360.113881 -23.400763)
			(xy 360.058444 -23.406863) (xy 360.00271 -23.404826) (xy 359.947867 -23.394696) (xy 359.895083 -23.376689)
			(xy 359.845483 -23.351188) (xy 359.800125 -23.318737) (xy 359.759976 -23.280028) (xy 359.72589 -23.235885)
			(xy 359.698594 -23.18725) (xy 359.678671 -23.135159) (xy 359.666545 -23.080722) (xy 359.662474 -23.0251)
			(xy 349.715836 -23.0251) (xy 349.715836 -23.556367) (xy 360.366123 -23.556367) (xy 360.373876 -23.502429)
			(xy 360.389226 -23.450142) (xy 360.41186 -23.400572) (xy 360.441318 -23.354728) (xy 360.477001 -23.313542)
			(xy 360.518181 -23.277853) (xy 360.564021 -23.248388) (xy 360.613588 -23.225746) (xy 360.665872 -23.210388)
			(xy 360.719809 -23.202627) (xy 360.747056 -23.202138) (xy 360.771086 -23.202498) (xy 360.818764 -23.208543)
			(xy 360.865305 -23.220531) (xy 360.887772 -23.229062) (xy 360.90091 -23.233887) (xy 360.928742 -23.23678)
			(xy 360.956316 -23.23202) (xy 360.981567 -23.219962) (xy 361.002603 -23.20151) (xy 361.017848 -23.178045)
			(xy 361.026161 -23.151326) (xy 361.026918 -23.123354) (xy 361.023916 -23.109682) (xy 361.018465 -23.086699)
			(xy 361.012604 -23.039828) (xy 361.012232 -23.01621) (xy 361.012667 -22.988958) (xy 361.020422 -22.93501)
			(xy 361.035776 -22.882714) (xy 361.058415 -22.833136) (xy 361.08788 -22.787284) (xy 361.123571 -22.746092)
			(xy 361.16476 -22.710398) (xy 361.210609 -22.68093) (xy 361.260186 -22.658286) (xy 361.312481 -22.642928)
			(xy 361.366429 -22.635169) (xy 361.420932 -22.635166) (xy 361.47488 -22.64292) (xy 361.527176 -22.658272)
			(xy 361.576755 -22.680911) (xy 361.622608 -22.710374) (xy 361.663801 -22.746064) (xy 361.699496 -22.787252)
			(xy 361.728965 -22.833101) (xy 361.75161 -22.882677) (xy 361.766969 -22.934971) (xy 361.77473 -22.988919)
			(xy 361.774734 -23.043422) (xy 361.766982 -23.09737) (xy 361.751631 -23.149667) (xy 361.728994 -23.199247)
			(xy 361.699532 -23.2451) (xy 361.663843 -23.286294) (xy 361.622656 -23.32199) (xy 361.576808 -23.351461)
			(xy 361.527233 -23.374107) (xy 361.474939 -23.389467) (xy 361.420991 -23.397229) (xy 361.39374 -23.397718)
			(xy 361.36971 -23.397355) (xy 361.322032 -23.39131) (xy 361.275492 -23.379324) (xy 361.253024 -23.370794)
			(xy 361.239873 -23.366016) (xy 361.21205 -23.363127) (xy 361.184486 -23.367887) (xy 361.159243 -23.379939)
			(xy 361.138212 -23.398383) (xy 361.122968 -23.421836) (xy 361.114651 -23.448544) (xy 361.113884 -23.476505)
			(xy 361.11688 -23.490174) (xy 361.122341 -23.513155) (xy 361.128196 -23.560028) (xy 361.128564 -23.583646)
			(xy 361.12845 -23.589996) (xy 364.384588 -23.589996) (xy 364.388659 -23.534374) (xy 364.400785 -23.479937)
			(xy 364.420708 -23.427846) (xy 364.448004 -23.379211) (xy 364.48209 -23.335068) (xy 364.522239 -23.296359)
			(xy 364.567597 -23.263908) (xy 364.617197 -23.238407) (xy 364.669981 -23.2204) (xy 364.724824 -23.21027)
			(xy 364.780558 -23.208233) (xy 364.835995 -23.214333) (xy 364.889952 -23.228439) (xy 364.941281 -23.250251)
			(xy 364.988887 -23.279305) (xy 365.031755 -23.31498) (xy 365.068109 -23.355554) (xy 373.630698 -23.355554)
			(xy 373.631167 -23.328743) (xy 373.638674 -23.275648) (xy 373.653549 -23.22413) (xy 373.675496 -23.175205)
			(xy 373.704084 -23.129839) (xy 373.738747 -23.088927) (xy 373.778802 -23.053276) (xy 373.800878 -23.038054)
			(xy 373.812422 -23.029768) (xy 373.83083 -23.00814) (xy 373.842569 -22.982278) (xy 373.846734 -22.954184)
			(xy 373.843001 -22.926029) (xy 373.831659 -22.89999) (xy 373.813586 -22.878081) (xy 373.802148 -22.869652)
			(xy 373.780694 -22.854296) (xy 373.741783 -22.818668) (xy 373.708151 -22.778019) (xy 373.680441 -22.733125)
			(xy 373.65918 -22.68484) (xy 373.644774 -22.634087) (xy 373.637498 -22.581833) (xy 373.637048 -22.555454)
			(xy 373.637534 -22.528203) (xy 373.64529 -22.474255) (xy 373.660645 -22.42196) (xy 373.683287 -22.372383)
			(xy 373.712753 -22.326533) (xy 373.748444 -22.285342) (xy 373.789635 -22.249651) (xy 373.835485 -22.220185)
			(xy 373.885062 -22.197543) (xy 373.937357 -22.182188) (xy 373.991305 -22.174432) (xy 374.045807 -22.174432)
			(xy 374.099755 -22.182188) (xy 374.15205 -22.197543) (xy 374.201627 -22.220185) (xy 374.247477 -22.249651)
			(xy 374.288668 -22.285342) (xy 374.324359 -22.326533) (xy 374.353825 -22.372383) (xy 374.376467 -22.42196)
			(xy 374.391822 -22.474255) (xy 374.399578 -22.528203) (xy 374.400064 -22.555454) (xy 374.399574 -22.582264)
			(xy 374.392067 -22.635356) (xy 374.377194 -22.686873) (xy 374.355249 -22.735797) (xy 374.326666 -22.781163)
			(xy 374.292007 -22.822077) (xy 374.251957 -22.85773) (xy 374.229884 -22.872954) (xy 374.218335 -22.881232)
			(xy 374.199934 -22.902865) (xy 374.1882 -22.928727) (xy 374.184038 -22.956821) (xy 374.187771 -22.984975)
			(xy 374.19911 -23.011013) (xy 374.217179 -23.032924) (xy 374.228614 -23.041356) (xy 374.250063 -23.056719)
			(xy 374.288976 -23.092344) (xy 374.32261 -23.132991) (xy 374.350321 -23.177885) (xy 374.371583 -23.226169)
			(xy 374.385989 -23.276921) (xy 374.393265 -23.329175) (xy 374.393714 -23.355554) (xy 374.393228 -23.382805)
			(xy 374.385472 -23.436753) (xy 374.370117 -23.489048) (xy 374.347475 -23.538625) (xy 374.318009 -23.584475)
			(xy 374.282318 -23.625666) (xy 374.241127 -23.661357) (xy 374.195277 -23.690823) (xy 374.1457 -23.713465)
			(xy 374.093405 -23.72882) (xy 374.039457 -23.736576) (xy 373.984955 -23.736576) (xy 373.931007 -23.72882)
			(xy 373.878712 -23.713465) (xy 373.829135 -23.690823) (xy 373.783285 -23.661357) (xy 373.742094 -23.625666)
			(xy 373.706403 -23.584475) (xy 373.676937 -23.538625) (xy 373.654295 -23.489048) (xy 373.63894 -23.436753)
			(xy 373.631184 -23.382805) (xy 373.630698 -23.355554) (xy 365.068109 -23.355554) (xy 365.068972 -23.356517)
			(xy 365.099745 -23.40303) (xy 365.123417 -23.453527) (xy 365.139485 -23.506934) (xy 365.147605 -23.56211)
			(xy 365.148114 -23.589996) (xy 365.147605 -23.617882) (xy 365.139485 -23.673058) (xy 365.123417 -23.726465)
			(xy 365.099745 -23.776962) (xy 365.068972 -23.823475) (xy 365.031755 -23.865012) (xy 365.013363 -23.880318)
			(xy 365.540796 -23.880318) (xy 365.544867 -23.824696) (xy 365.556993 -23.770259) (xy 365.576916 -23.718168)
			(xy 365.604212 -23.669533) (xy 365.638298 -23.62539) (xy 365.678447 -23.586681) (xy 365.723805 -23.55423)
			(xy 365.773405 -23.528729) (xy 365.826189 -23.510722) (xy 365.881032 -23.500592) (xy 365.936766 -23.498555)
			(xy 365.992203 -23.504655) (xy 366.04616 -23.518761) (xy 366.097489 -23.540573) (xy 366.145095 -23.569627)
			(xy 366.187963 -23.605302) (xy 366.22518 -23.646839) (xy 366.255953 -23.693352) (xy 366.279625 -23.743849)
			(xy 366.295693 -23.797256) (xy 366.303813 -23.852432) (xy 366.304322 -23.880318) (xy 366.556796 -23.880318)
			(xy 366.560867 -23.824696) (xy 366.572993 -23.770259) (xy 366.592916 -23.718168) (xy 366.620212 -23.669533)
			(xy 366.654298 -23.62539) (xy 366.694447 -23.586681) (xy 366.739805 -23.55423) (xy 366.789405 -23.528729)
			(xy 366.842189 -23.510722) (xy 366.897032 -23.500592) (xy 366.952766 -23.498555) (xy 367.008203 -23.504655)
			(xy 367.06216 -23.518761) (xy 367.113489 -23.540573) (xy 367.161095 -23.569627) (xy 367.203963 -23.605302)
			(xy 367.24118 -23.646839) (xy 367.271953 -23.693352) (xy 367.295625 -23.743849) (xy 367.311693 -23.797256)
			(xy 367.319813 -23.852432) (xy 367.320322 -23.880318) (xy 367.572796 -23.880318) (xy 367.576867 -23.824696)
			(xy 367.588993 -23.770259) (xy 367.608916 -23.718168) (xy 367.636212 -23.669533) (xy 367.670298 -23.62539)
			(xy 367.710447 -23.586681) (xy 367.755805 -23.55423) (xy 367.805405 -23.528729) (xy 367.858189 -23.510722)
			(xy 367.913032 -23.500592) (xy 367.968766 -23.498555) (xy 368.024203 -23.504655) (xy 368.07816 -23.518761)
			(xy 368.129489 -23.540573) (xy 368.177095 -23.569627) (xy 368.219963 -23.605302) (xy 368.25718 -23.646839)
			(xy 368.287953 -23.693352) (xy 368.311625 -23.743849) (xy 368.327693 -23.797256) (xy 368.335813 -23.852432)
			(xy 368.336322 -23.880318) (xy 368.591082 -23.880318) (xy 368.595153 -23.824696) (xy 368.607279 -23.770259)
			(xy 368.627202 -23.718168) (xy 368.654498 -23.669533) (xy 368.688584 -23.62539) (xy 368.728733 -23.586681)
			(xy 368.774091 -23.55423) (xy 368.823691 -23.528729) (xy 368.876475 -23.510722) (xy 368.931318 -23.500592)
			(xy 368.987052 -23.498555) (xy 369.042489 -23.504655) (xy 369.096446 -23.518761) (xy 369.147775 -23.540573)
			(xy 369.195381 -23.569627) (xy 369.238249 -23.605302) (xy 369.275466 -23.646839) (xy 369.306239 -23.693352)
			(xy 369.329911 -23.743849) (xy 369.345979 -23.797256) (xy 369.354099 -23.852432) (xy 369.354608 -23.880318)
			(xy 369.354099 -23.908204) (xy 369.345979 -23.96338) (xy 369.345445 -23.965154) (xy 374.377456 -23.965154)
			(xy 374.381527 -23.909532) (xy 374.393653 -23.855095) (xy 374.413576 -23.803004) (xy 374.440872 -23.754369)
			(xy 374.474958 -23.710226) (xy 374.515107 -23.671517) (xy 374.560465 -23.639066) (xy 374.610065 -23.613565)
			(xy 374.662849 -23.595558) (xy 374.717692 -23.585428) (xy 374.773426 -23.583391) (xy 374.828863 -23.589491)
			(xy 374.88282 -23.603597) (xy 374.934149 -23.625409) (xy 374.981755 -23.654463) (xy 375.024623 -23.690138)
			(xy 375.06184 -23.731675) (xy 375.092613 -23.778188) (xy 375.116285 -23.828685) (xy 375.132353 -23.882092)
			(xy 375.140473 -23.937268) (xy 375.140982 -23.965154) (xy 375.140473 -23.99304) (xy 375.132353 -24.048216)
			(xy 375.116285 -24.101623) (xy 375.092613 -24.15212) (xy 375.06184 -24.198633) (xy 375.024623 -24.24017)
			(xy 374.981755 -24.275845) (xy 374.934149 -24.304899) (xy 374.88282 -24.326711) (xy 374.828863 -24.340817)
			(xy 374.773426 -24.346917) (xy 374.717692 -24.34488) (xy 374.662849 -24.33475) (xy 374.610065 -24.316743)
			(xy 374.560465 -24.291242) (xy 374.515107 -24.258791) (xy 374.474958 -24.220082) (xy 374.440872 -24.175939)
			(xy 374.413576 -24.127304) (xy 374.393653 -24.075213) (xy 374.381527 -24.020776) (xy 374.377456 -23.965154)
			(xy 369.345445 -23.965154) (xy 369.329911 -24.016787) (xy 369.306239 -24.067284) (xy 369.275466 -24.113797)
			(xy 369.238249 -24.155334) (xy 369.195381 -24.191009) (xy 369.147775 -24.220063) (xy 369.096446 -24.241875)
			(xy 369.042489 -24.255981) (xy 368.987052 -24.262081) (xy 368.931318 -24.260044) (xy 368.876475 -24.249914)
			(xy 368.823691 -24.231907) (xy 368.774091 -24.206406) (xy 368.728733 -24.173955) (xy 368.688584 -24.135246)
			(xy 368.654498 -24.091103) (xy 368.627202 -24.042468) (xy 368.607279 -23.990377) (xy 368.595153 -23.93594)
			(xy 368.591082 -23.880318) (xy 368.336322 -23.880318) (xy 368.335813 -23.908204) (xy 368.327693 -23.96338)
			(xy 368.311625 -24.016787) (xy 368.287953 -24.067284) (xy 368.25718 -24.113797) (xy 368.219963 -24.155334)
			(xy 368.177095 -24.191009) (xy 368.129489 -24.220063) (xy 368.07816 -24.241875) (xy 368.024203 -24.255981)
			(xy 367.968766 -24.262081) (xy 367.913032 -24.260044) (xy 367.858189 -24.249914) (xy 367.805405 -24.231907)
			(xy 367.755805 -24.206406) (xy 367.710447 -24.173955) (xy 367.670298 -24.135246) (xy 367.636212 -24.091103)
			(xy 367.608916 -24.042468) (xy 367.588993 -23.990377) (xy 367.576867 -23.93594) (xy 367.572796 -23.880318)
			(xy 367.320322 -23.880318) (xy 367.319813 -23.908204) (xy 367.311693 -23.96338) (xy 367.295625 -24.016787)
			(xy 367.271953 -24.067284) (xy 367.24118 -24.113797) (xy 367.203963 -24.155334) (xy 367.161095 -24.191009)
			(xy 367.113489 -24.220063) (xy 367.06216 -24.241875) (xy 367.008203 -24.255981) (xy 366.952766 -24.262081)
			(xy 366.897032 -24.260044) (xy 366.842189 -24.249914) (xy 366.789405 -24.231907) (xy 366.739805 -24.206406)
			(xy 366.694447 -24.173955) (xy 366.654298 -24.135246) (xy 366.620212 -24.091103) (xy 366.592916 -24.042468)
			(xy 366.572993 -23.990377) (xy 366.560867 -23.93594) (xy 366.556796 -23.880318) (xy 366.304322 -23.880318)
			(xy 366.303813 -23.908204) (xy 366.295693 -23.96338) (xy 366.279625 -24.016787) (xy 366.255953 -24.067284)
			(xy 366.22518 -24.113797) (xy 366.187963 -24.155334) (xy 366.145095 -24.191009) (xy 366.097489 -24.220063)
			(xy 366.04616 -24.241875) (xy 365.992203 -24.255981) (xy 365.936766 -24.262081) (xy 365.881032 -24.260044)
			(xy 365.826189 -24.249914) (xy 365.773405 -24.231907) (xy 365.723805 -24.206406) (xy 365.678447 -24.173955)
			(xy 365.638298 -24.135246) (xy 365.604212 -24.091103) (xy 365.576916 -24.042468) (xy 365.556993 -23.990377)
			(xy 365.544867 -23.93594) (xy 365.540796 -23.880318) (xy 365.013363 -23.880318) (xy 364.988887 -23.900687)
			(xy 364.941281 -23.929741) (xy 364.889952 -23.951553) (xy 364.835995 -23.965659) (xy 364.780558 -23.971759)
			(xy 364.724824 -23.969722) (xy 364.669981 -23.959592) (xy 364.617197 -23.941585) (xy 364.567597 -23.916084)
			(xy 364.522239 -23.883633) (xy 364.48209 -23.844924) (xy 364.448004 -23.800781) (xy 364.420708 -23.752146)
			(xy 364.400785 -23.700055) (xy 364.388659 -23.645618) (xy 364.384588 -23.589996) (xy 361.12845 -23.589996)
			(xy 361.128073 -23.610893) (xy 361.120311 -23.66483) (xy 361.104953 -23.717114) (xy 361.082311 -23.766681)
			(xy 361.052846 -23.812521) (xy 361.017157 -23.853701) (xy 360.975971 -23.889383) (xy 360.930126 -23.918841)
			(xy 360.880556 -23.941475) (xy 360.828269 -23.956825) (xy 360.774331 -23.964577) (xy 360.719837 -23.964575)
			(xy 360.665899 -23.956818) (xy 360.613614 -23.941464) (xy 360.564046 -23.918826) (xy 360.518204 -23.889364)
			(xy 360.477021 -23.853678) (xy 360.441335 -23.812495) (xy 360.411874 -23.766653) (xy 360.389236 -23.717084)
			(xy 360.373882 -23.664799) (xy 360.366125 -23.610861) (xy 360.366123 -23.556367) (xy 349.715836 -23.556367)
			(xy 349.715836 -24.158194) (xy 355.750874 -24.158194) (xy 355.754945 -24.102572) (xy 355.767071 -24.048135)
			(xy 355.786994 -23.996044) (xy 355.81429 -23.947409) (xy 355.848376 -23.903266) (xy 355.888525 -23.864557)
			(xy 355.933883 -23.832106) (xy 355.983483 -23.806605) (xy 356.036267 -23.788598) (xy 356.09111 -23.778468)
			(xy 356.146844 -23.776431) (xy 356.202281 -23.782531) (xy 356.256238 -23.796637) (xy 356.307567 -23.818449)
			(xy 356.355173 -23.847503) (xy 356.398041 -23.883178) (xy 356.435258 -23.924715) (xy 356.466031 -23.971228)
			(xy 356.489703 -24.021725) (xy 356.505771 -24.075132) (xy 356.513891 -24.130308) (xy 356.5144 -24.158194)
			(xy 356.513891 -24.18608) (xy 356.513322 -24.189944) (xy 359.598974 -24.189944) (xy 359.603045 -24.134322)
			(xy 359.615171 -24.079885) (xy 359.635094 -24.027794) (xy 359.66239 -23.979159) (xy 359.696476 -23.935016)
			(xy 359.736625 -23.896307) (xy 359.781983 -23.863856) (xy 359.831583 -23.838355) (xy 359.884367 -23.820348)
			(xy 359.93921 -23.810218) (xy 359.994944 -23.808181) (xy 360.050381 -23.814281) (xy 360.104338 -23.828387)
			(xy 360.155667 -23.850199) (xy 360.203273 -23.879253) (xy 360.246141 -23.914928) (xy 360.283358 -23.956465)
			(xy 360.314131 -24.002978) (xy 360.337803 -24.053475) (xy 360.353871 -24.106882) (xy 360.361991 -24.162058)
			(xy 360.3625 -24.189944) (xy 362.121956 -24.189944) (xy 362.126027 -24.134322) (xy 362.138153 -24.079885)
			(xy 362.158076 -24.027794) (xy 362.185372 -23.979159) (xy 362.219458 -23.935016) (xy 362.259607 -23.896307)
			(xy 362.304965 -23.863856) (xy 362.354565 -23.838355) (xy 362.407349 -23.820348) (xy 362.462192 -23.810218)
			(xy 362.517926 -23.808181) (xy 362.573363 -23.814281) (xy 362.62732 -23.828387) (xy 362.678649 -23.850199)
			(xy 362.726255 -23.879253) (xy 362.769123 -23.914928) (xy 362.80634 -23.956465) (xy 362.837113 -24.002978)
			(xy 362.860785 -24.053475) (xy 362.876853 -24.106882) (xy 362.884973 -24.162058) (xy 362.885482 -24.189944)
			(xy 362.884973 -24.21783) (xy 362.876853 -24.273006) (xy 362.860785 -24.326413) (xy 362.837113 -24.37691)
			(xy 362.80634 -24.423423) (xy 362.769123 -24.46496) (xy 362.726255 -24.500635) (xy 362.678649 -24.529689)
			(xy 362.62732 -24.551501) (xy 362.573363 -24.565607) (xy 362.517926 -24.571707) (xy 362.462192 -24.56967)
			(xy 362.407349 -24.55954) (xy 362.354565 -24.541533) (xy 362.304965 -24.516032) (xy 362.259607 -24.483581)
			(xy 362.219458 -24.444872) (xy 362.185372 -24.400729) (xy 362.158076 -24.352094) (xy 362.138153 -24.300003)
			(xy 362.126027 -24.245566) (xy 362.121956 -24.189944) (xy 360.3625 -24.189944) (xy 360.361991 -24.21783)
			(xy 360.353871 -24.273006) (xy 360.337803 -24.326413) (xy 360.314131 -24.37691) (xy 360.283358 -24.423423)
			(xy 360.246141 -24.46496) (xy 360.203273 -24.500635) (xy 360.155667 -24.529689) (xy 360.104338 -24.551501)
			(xy 360.050381 -24.565607) (xy 359.994944 -24.571707) (xy 359.93921 -24.56967) (xy 359.884367 -24.55954)
			(xy 359.831583 -24.541533) (xy 359.781983 -24.516032) (xy 359.736625 -24.483581) (xy 359.696476 -24.444872)
			(xy 359.66239 -24.400729) (xy 359.635094 -24.352094) (xy 359.615171 -24.300003) (xy 359.603045 -24.245566)
			(xy 359.598974 -24.189944) (xy 356.513322 -24.189944) (xy 356.505771 -24.241256) (xy 356.489703 -24.294663)
			(xy 356.466031 -24.34516) (xy 356.435258 -24.391673) (xy 356.398041 -24.43321) (xy 356.355173 -24.468885)
			(xy 356.307567 -24.497939) (xy 356.256238 -24.519751) (xy 356.202281 -24.533857) (xy 356.146844 -24.539957)
			(xy 356.09111 -24.53792) (xy 356.036267 -24.52779) (xy 355.983483 -24.509783) (xy 355.933883 -24.484282)
			(xy 355.888525 -24.451831) (xy 355.848376 -24.413122) (xy 355.81429 -24.368979) (xy 355.786994 -24.320344)
			(xy 355.767071 -24.268253) (xy 355.754945 -24.213816) (xy 355.750874 -24.158194) (xy 349.715836 -24.158194)
			(xy 349.715836 -24.328374) (xy 349.715582 -24.328628) (xy 349.71288 -24.331481) (xy 349.708294 -24.337864)
			(xy 349.706438 -24.341328) (xy 349.703852 -24.346754) (xy 349.701022 -24.358434) (xy 349.70085 -24.364442)
			(xy 349.70085 -24.807418) (xy 356.92029 -24.807418) (xy 356.924361 -24.751796) (xy 356.936487 -24.697359)
			(xy 356.95641 -24.645268) (xy 356.983706 -24.596633) (xy 357.017792 -24.55249) (xy 357.057941 -24.513781)
			(xy 357.103299 -24.48133) (xy 357.152899 -24.455829) (xy 357.205683 -24.437822) (xy 357.260526 -24.427692)
			(xy 357.31626 -24.425655) (xy 357.371697 -24.431755) (xy 357.425654 -24.445861) (xy 357.476983 -24.467673)
			(xy 357.524589 -24.496727) (xy 357.567457 -24.532402) (xy 357.604674 -24.573939) (xy 357.635447 -24.620452)
			(xy 357.659119 -24.670949) (xy 357.675187 -24.724356) (xy 357.680234 -24.75865) (xy 369.168678 -24.75865)
			(xy 369.172749 -24.703028) (xy 369.184875 -24.648591) (xy 369.204798 -24.5965) (xy 369.232094 -24.547865)
			(xy 369.26618 -24.503722) (xy 369.306329 -24.465013) (xy 369.351687 -24.432562) (xy 369.401287 -24.407061)
			(xy 369.454071 -24.389054) (xy 369.508914 -24.378924) (xy 369.564648 -24.376887) (xy 369.620085 -24.382987)
			(xy 369.674042 -24.397093) (xy 369.725371 -24.418905) (xy 369.772977 -24.447959) (xy 369.815845 -24.483634)
			(xy 369.853062 -24.525171) (xy 369.883835 -24.571684) (xy 369.907507 -24.622181) (xy 369.923575 -24.675588)
			(xy 369.931695 -24.730764) (xy 369.932204 -24.75865) (xy 369.931695 -24.786536) (xy 369.923575 -24.841712)
			(xy 369.907507 -24.895119) (xy 369.883835 -24.945616) (xy 369.853062 -24.992129) (xy 369.815845 -25.033666)
			(xy 369.772977 -25.069341) (xy 369.725371 -25.098395) (xy 369.674042 -25.120207) (xy 369.620085 -25.134313)
			(xy 369.564648 -25.140413) (xy 369.508914 -25.138376) (xy 369.454071 -25.128246) (xy 369.401287 -25.110239)
			(xy 369.351687 -25.084738) (xy 369.306329 -25.052287) (xy 369.26618 -25.013578) (xy 369.232094 -24.969435)
			(xy 369.204798 -24.9208) (xy 369.184875 -24.868709) (xy 369.172749 -24.814272) (xy 369.168678 -24.75865)
			(xy 357.680234 -24.75865) (xy 357.683307 -24.779532) (xy 357.683816 -24.807418) (xy 357.683307 -24.835304)
			(xy 357.675187 -24.89048) (xy 357.659119 -24.943887) (xy 357.635447 -24.994384) (xy 357.604674 -25.040897)
			(xy 357.567457 -25.082434) (xy 357.524589 -25.118109) (xy 357.476983 -25.147163) (xy 357.425654 -25.168975)
			(xy 357.371697 -25.183081) (xy 357.31626 -25.189181) (xy 357.260526 -25.187144) (xy 357.205683 -25.177014)
			(xy 357.152899 -25.159007) (xy 357.103299 -25.133506) (xy 357.057941 -25.101055) (xy 357.017792 -25.062346)
			(xy 356.983706 -25.018203) (xy 356.95641 -24.969568) (xy 356.936487 -24.917477) (xy 356.924361 -24.86304)
			(xy 356.92029 -24.807418) (xy 349.70085 -24.807418) (xy 349.70085 -25.390094) (xy 362.109766 -25.390094)
			(xy 362.110252 -25.362843) (xy 362.118008 -25.308895) (xy 362.133363 -25.2566) (xy 362.156005 -25.207023)
			(xy 362.185471 -25.161173) (xy 362.221162 -25.119982) (xy 362.262353 -25.084291) (xy 362.308203 -25.054825)
			(xy 362.35778 -25.032183) (xy 362.410075 -25.016828) (xy 362.464023 -25.009072) (xy 362.518525 -25.009072)
			(xy 362.572473 -25.016828) (xy 362.624768 -25.032183) (xy 362.674345 -25.054825) (xy 362.720195 -25.084291)
			(xy 362.761386 -25.119982) (xy 362.797077 -25.161173) (xy 362.826543 -25.207023) (xy 362.849185 -25.2566)
			(xy 362.86454 -25.308895) (xy 362.872296 -25.362843) (xy 362.872782 -25.390094) (xy 362.872199 -25.419113)
			(xy 362.863409 -25.476482) (xy 362.846033 -25.531858) (xy 362.82047 -25.583964) (xy 362.78731 -25.631597)
			(xy 362.747318 -25.673658) (xy 362.7247 -25.691846) (xy 362.714155 -25.700616) (xy 362.697713 -25.72255)
			(xy 362.687707 -25.748071) (xy 362.68486 -25.775336) (xy 362.689377 -25.802374) (xy 362.700933 -25.827232)
			(xy 362.718692 -25.848114) (xy 362.72978 -25.856184) (xy 362.751414 -25.871512) (xy 362.790672 -25.907148)
			(xy 362.824616 -25.947877) (xy 362.852591 -25.992916) (xy 362.874058 -26.041395) (xy 362.888604 -26.09238)
			(xy 362.895948 -26.144888) (xy 362.896404 -26.171398) (xy 362.895918 -26.198649) (xy 362.888162 -26.252597)
			(xy 362.872807 -26.304892) (xy 362.850165 -26.354469) (xy 362.820699 -26.400319) (xy 362.785008 -26.44151)
			(xy 362.743817 -26.477201) (xy 362.697967 -26.506667) (xy 362.64839 -26.529309) (xy 362.596095 -26.544664)
			(xy 362.542147 -26.55242) (xy 362.487645 -26.55242) (xy 362.433697 -26.544664) (xy 362.381402 -26.529309)
			(xy 362.331825 -26.506667) (xy 362.285975 -26.477201) (xy 362.244784 -26.44151) (xy 362.209093 -26.400319)
			(xy 362.179627 -26.354469) (xy 362.156985 -26.304892) (xy 362.14163 -26.252597) (xy 362.133874 -26.198649)
			(xy 362.133388 -26.171398) (xy 362.133939 -26.142377) (xy 362.142731 -26.085005) (xy 362.160112 -26.029628)
			(xy 362.185681 -25.977522) (xy 362.218848 -25.92989) (xy 362.258848 -25.887832) (xy 362.28147 -25.869646)
			(xy 362.292027 -25.860888) (xy 362.308474 -25.838953) (xy 362.318483 -25.813428) (xy 362.32133 -25.786159)
			(xy 362.316809 -25.759118) (xy 362.305248 -25.734258) (xy 362.287482 -25.713376) (xy 362.27639 -25.705308)
			(xy 362.254745 -25.689994) (xy 362.215489 -25.654355) (xy 362.181547 -25.613623) (xy 362.153574 -25.568582)
			(xy 362.132108 -25.520101) (xy 362.117564 -25.469114) (xy 362.110221 -25.416604) (xy 362.109766 -25.390094)
			(xy 349.70085 -25.390094) (xy 349.70085 -25.971246) (xy 350.259902 -25.971246) (xy 350.263973 -25.915624)
			(xy 350.276099 -25.861187) (xy 350.296022 -25.809096) (xy 350.323318 -25.760461) (xy 350.357404 -25.716318)
			(xy 350.397553 -25.677609) (xy 350.442911 -25.645158) (xy 350.492511 -25.619657) (xy 350.545295 -25.60165)
			(xy 350.600138 -25.59152) (xy 350.655872 -25.589483) (xy 350.711309 -25.595583) (xy 350.765266 -25.609689)
			(xy 350.816595 -25.631501) (xy 350.864201 -25.660555) (xy 350.907069 -25.69623) (xy 350.944286 -25.737767)
			(xy 350.975059 -25.78428) (xy 350.998731 -25.834777) (xy 351.014799 -25.888184) (xy 351.022919 -25.94336)
			(xy 351.023428 -25.971246) (xy 351.275902 -25.971246) (xy 351.279973 -25.915624) (xy 351.292099 -25.861187)
			(xy 351.312022 -25.809096) (xy 351.339318 -25.760461) (xy 351.373404 -25.716318) (xy 351.413553 -25.677609)
			(xy 351.458911 -25.645158) (xy 351.508511 -25.619657) (xy 351.561295 -25.60165) (xy 351.616138 -25.59152)
			(xy 351.671872 -25.589483) (xy 351.727309 -25.595583) (xy 351.781266 -25.609689) (xy 351.832595 -25.631501)
			(xy 351.880201 -25.660555) (xy 351.923069 -25.69623) (xy 351.960286 -25.737767) (xy 351.991059 -25.78428)
			(xy 352.014731 -25.834777) (xy 352.030799 -25.888184) (xy 352.038919 -25.94336) (xy 352.039428 -25.971246)
			(xy 352.291902 -25.971246) (xy 352.295973 -25.915624) (xy 352.308099 -25.861187) (xy 352.328022 -25.809096)
			(xy 352.355318 -25.760461) (xy 352.389404 -25.716318) (xy 352.429553 -25.677609) (xy 352.474911 -25.645158)
			(xy 352.524511 -25.619657) (xy 352.577295 -25.60165) (xy 352.632138 -25.59152) (xy 352.687872 -25.589483)
			(xy 352.743309 -25.595583) (xy 352.797266 -25.609689) (xy 352.848595 -25.631501) (xy 352.896201 -25.660555)
			(xy 352.939069 -25.69623) (xy 352.976286 -25.737767) (xy 353.007059 -25.78428) (xy 353.030731 -25.834777)
			(xy 353.046799 -25.888184) (xy 353.054919 -25.94336) (xy 353.055428 -25.971246) (xy 353.054919 -25.999132)
			(xy 353.049827 -26.03373) (xy 353.567998 -26.03373) (xy 353.572069 -25.978108) (xy 353.584195 -25.923671)
			(xy 353.604118 -25.87158) (xy 353.631414 -25.822945) (xy 353.6655 -25.778802) (xy 353.705649 -25.740093)
			(xy 353.751007 -25.707642) (xy 353.800607 -25.682141) (xy 353.853391 -25.664134) (xy 353.908234 -25.654004)
			(xy 353.963968 -25.651967) (xy 354.019405 -25.658067) (xy 354.073362 -25.672173) (xy 354.124691 -25.693985)
			(xy 354.172297 -25.723039) (xy 354.215165 -25.758714) (xy 354.252382 -25.800251) (xy 354.283155 -25.846764)
			(xy 354.306827 -25.897261) (xy 354.322895 -25.950668) (xy 354.331015 -26.005844) (xy 354.331524 -26.03373)
			(xy 354.331015 -26.061616) (xy 354.322895 -26.116792) (xy 354.306827 -26.170199) (xy 354.283155 -26.220696)
			(xy 354.252921 -26.266394) (xy 356.820724 -26.266394) (xy 356.82115 -26.23914) (xy 356.828908 -26.185186)
			(xy 356.844267 -26.132885) (xy 356.866912 -26.083303) (xy 356.896384 -26.037448) (xy 356.932082 -25.996255)
			(xy 356.973279 -25.960561) (xy 357.019136 -25.931094) (xy 357.068721 -25.908454) (xy 357.121023 -25.8931)
			(xy 357.174978 -25.885347) (xy 357.202232 -25.884886) (xy 357.231558 -25.885398) (xy 357.289517 -25.894386)
			(xy 357.345415 -25.912144) (xy 357.397935 -25.938253) (xy 357.422196 -25.954736) (xy 357.432698 -25.961206)
			(xy 357.45712 -25.964389) (xy 357.468932 -25.960832) (xy 357.547418 -25.931622) (xy 357.558838 -25.926773)
			(xy 357.575483 -25.908416) (xy 357.579168 -25.89657) (xy 357.586483 -25.869475) (xy 357.608045 -25.817661)
			(xy 357.636969 -25.769567) (xy 357.672628 -25.72623) (xy 357.714254 -25.688588) (xy 357.760947 -25.657452)
			(xy 357.811699 -25.633496) (xy 357.865413 -25.617237) (xy 357.920931 -25.609025) (xy 357.948992 -25.608534)
			(xy 357.976248 -25.608912) (xy 358.030206 -25.616669) (xy 358.082511 -25.632026) (xy 358.132097 -25.654671)
			(xy 358.177957 -25.684142) (xy 358.219155 -25.71984) (xy 358.254853 -25.761037) (xy 358.284325 -25.806896)
			(xy 358.306971 -25.856482) (xy 358.322329 -25.908786) (xy 358.330087 -25.962744) (xy 358.330087 -25.990042)
			(xy 359.598974 -25.990042) (xy 359.603045 -25.93442) (xy 359.615171 -25.879983) (xy 359.635094 -25.827892)
			(xy 359.66239 -25.779257) (xy 359.696476 -25.735114) (xy 359.736625 -25.696405) (xy 359.781983 -25.663954)
			(xy 359.831583 -25.638453) (xy 359.884367 -25.620446) (xy 359.93921 -25.610316) (xy 359.994944 -25.608279)
			(xy 360.050381 -25.614379) (xy 360.104338 -25.628485) (xy 360.155667 -25.650297) (xy 360.203273 -25.679351)
			(xy 360.246141 -25.715026) (xy 360.283358 -25.756563) (xy 360.314131 -25.803076) (xy 360.337803 -25.853573)
			(xy 360.353871 -25.90698) (xy 360.361991 -25.962156) (xy 360.3625 -25.990042) (xy 360.361991 -26.017928)
			(xy 360.353871 -26.073104) (xy 360.337803 -26.126511) (xy 360.314131 -26.177008) (xy 360.283358 -26.223521)
			(xy 360.246141 -26.265058) (xy 360.203273 -26.300733) (xy 360.155667 -26.329787) (xy 360.104338 -26.351599)
			(xy 360.050381 -26.365705) (xy 359.994944 -26.371805) (xy 359.93921 -26.369768) (xy 359.884367 -26.359638)
			(xy 359.831583 -26.341631) (xy 359.781983 -26.31613) (xy 359.736625 -26.283679) (xy 359.696476 -26.24497)
			(xy 359.66239 -26.200827) (xy 359.635094 -26.152192) (xy 359.615171 -26.100101) (xy 359.603045 -26.045664)
			(xy 359.598974 -25.990042) (xy 358.330087 -25.990042) (xy 358.330087 -26.017256) (xy 358.322329 -26.071214)
			(xy 358.306971 -26.123518) (xy 358.284325 -26.173104) (xy 358.254853 -26.218963) (xy 358.219155 -26.26016)
			(xy 358.177957 -26.295858) (xy 358.132097 -26.325329) (xy 358.082511 -26.347974) (xy 358.030206 -26.363331)
			(xy 357.976248 -26.371088) (xy 357.948992 -26.37155) (xy 357.919667 -26.371019) (xy 357.861709 -26.362036)
			(xy 357.805811 -26.344284) (xy 357.75329 -26.31818) (xy 357.729028 -26.3017) (xy 357.718517 -26.295246)
			(xy 357.694102 -26.292052) (xy 357.682292 -26.295604) (xy 357.603806 -26.324814) (xy 357.592361 -26.329616)
			(xy 357.575729 -26.348008) (xy 357.572056 -26.359866) (xy 357.565273 -26.384898) (xy 357.545857 -26.432989)
			(xy 357.5201 -26.478003) (xy 357.488479 -26.519109) (xy 357.451576 -26.555549) (xy 357.431086 -26.571448)
			(xy 357.421417 -26.579426) (xy 357.410768 -26.60209) (xy 357.410766 -26.614628) (xy 357.415338 -26.698956)
			(xy 357.416578 -26.711393) (xy 357.42938 -26.73283) (xy 357.439722 -26.73985) (xy 357.463464 -26.754747)
			(xy 357.506698 -26.790415) (xy 357.544248 -26.832024) (xy 357.575307 -26.878679) (xy 357.599206 -26.929377)
			(xy 357.61543 -26.983025) (xy 357.623631 -27.03847) (xy 357.624126 -27.066494) (xy 357.62364 -27.093745)
			(xy 357.615884 -27.147693) (xy 357.600529 -27.199988) (xy 357.577887 -27.249565) (xy 357.548421 -27.295415)
			(xy 357.51273 -27.336606) (xy 357.471539 -27.372297) (xy 357.425689 -27.401763) (xy 357.376112 -27.424405)
			(xy 357.323817 -27.43976) (xy 357.269869 -27.447516) (xy 357.215367 -27.447516) (xy 357.161419 -27.43976)
			(xy 357.109124 -27.424405) (xy 357.059547 -27.401763) (xy 357.013697 -27.372297) (xy 356.972506 -27.336606)
			(xy 356.936815 -27.295415) (xy 356.907349 -27.249565) (xy 356.884707 -27.199988) (xy 356.869352 -27.147693)
			(xy 356.861596 -27.093745) (xy 356.86111 -27.066494) (xy 356.861649 -27.037006) (xy 356.870746 -26.978734)
			(xy 356.888707 -26.922559) (xy 356.915102 -26.869818) (xy 356.949303 -26.821771) (xy 356.990495 -26.779562)
			(xy 357.013764 -26.76144) (xy 357.023431 -26.753458) (xy 357.034083 -26.730797) (xy 357.034084 -26.71826)
			(xy 357.029512 -26.633932) (xy 357.028258 -26.621499) (xy 357.015464 -26.600063) (xy 357.005128 -26.593038)
			(xy 356.981392 -26.578131) (xy 356.938156 -26.542467) (xy 356.900603 -26.50086) (xy 356.869542 -26.454207)
			(xy 356.845643 -26.40351) (xy 356.829418 -26.349862) (xy 356.821218 -26.294418) (xy 356.820724 -26.266394)
			(xy 354.252921 -26.266394) (xy 354.252382 -26.267209) (xy 354.215165 -26.308746) (xy 354.172297 -26.344421)
			(xy 354.124691 -26.373475) (xy 354.073362 -26.395287) (xy 354.019405 -26.409393) (xy 353.963968 -26.415493)
			(xy 353.908234 -26.413456) (xy 353.853391 -26.403326) (xy 353.800607 -26.385319) (xy 353.751007 -26.359818)
			(xy 353.705649 -26.327367) (xy 353.6655 -26.288658) (xy 353.631414 -26.244515) (xy 353.604118 -26.19588)
			(xy 353.584195 -26.143789) (xy 353.572069 -26.089352) (xy 353.567998 -26.03373) (xy 353.049827 -26.03373)
			(xy 353.046799 -26.054308) (xy 353.030731 -26.107715) (xy 353.007059 -26.158212) (xy 352.976286 -26.204725)
			(xy 352.939069 -26.246262) (xy 352.896201 -26.281937) (xy 352.848595 -26.310991) (xy 352.797266 -26.332803)
			(xy 352.743309 -26.346909) (xy 352.687872 -26.353009) (xy 352.632138 -26.350972) (xy 352.577295 -26.340842)
			(xy 352.524511 -26.322835) (xy 352.474911 -26.297334) (xy 352.429553 -26.264883) (xy 352.389404 -26.226174)
			(xy 352.355318 -26.182031) (xy 352.328022 -26.133396) (xy 352.308099 -26.081305) (xy 352.295973 -26.026868)
			(xy 352.291902 -25.971246) (xy 352.039428 -25.971246) (xy 352.038919 -25.999132) (xy 352.030799 -26.054308)
			(xy 352.014731 -26.107715) (xy 351.991059 -26.158212) (xy 351.960286 -26.204725) (xy 351.923069 -26.246262)
			(xy 351.880201 -26.281937) (xy 351.832595 -26.310991) (xy 351.781266 -26.332803) (xy 351.727309 -26.346909)
			(xy 351.671872 -26.353009) (xy 351.616138 -26.350972) (xy 351.561295 -26.340842) (xy 351.508511 -26.322835)
			(xy 351.458911 -26.297334) (xy 351.413553 -26.264883) (xy 351.373404 -26.226174) (xy 351.339318 -26.182031)
			(xy 351.312022 -26.133396) (xy 351.292099 -26.081305) (xy 351.279973 -26.026868) (xy 351.275902 -25.971246)
			(xy 351.023428 -25.971246) (xy 351.022919 -25.999132) (xy 351.014799 -26.054308) (xy 350.998731 -26.107715)
			(xy 350.975059 -26.158212) (xy 350.944286 -26.204725) (xy 350.907069 -26.246262) (xy 350.864201 -26.281937)
			(xy 350.816595 -26.310991) (xy 350.765266 -26.332803) (xy 350.711309 -26.346909) (xy 350.655872 -26.353009)
			(xy 350.600138 -26.350972) (xy 350.545295 -26.340842) (xy 350.492511 -26.322835) (xy 350.442911 -26.297334)
			(xy 350.397553 -26.264883) (xy 350.357404 -26.226174) (xy 350.323318 -26.182031) (xy 350.296022 -26.133396)
			(xy 350.276099 -26.081305) (xy 350.263973 -26.026868) (xy 350.259902 -25.971246) (xy 349.70085 -25.971246)
			(xy 349.70085 -27.655012) (xy 349.701097 -27.662193) (xy 349.705096 -27.675987) (xy 349.708724 -27.68219)
			(xy 349.712534 -27.688032) (xy 349.722948 -27.69743) (xy 349.729806 -27.700732) (xy 349.757178 -27.714499)
			(xy 349.807523 -27.749413) (xy 349.815357 -27.756955) (xy 353.059143 -27.756955) (xy 353.059143 -27.702445)
			(xy 353.066901 -27.648489) (xy 353.08226 -27.596186) (xy 353.104906 -27.546602) (xy 353.134378 -27.500745)
			(xy 353.170077 -27.45955) (xy 353.211276 -27.423855) (xy 353.257135 -27.394387) (xy 353.306722 -27.371746)
			(xy 353.359026 -27.356393) (xy 353.412982 -27.34864) (xy 353.440238 -27.34818) (xy 353.454323 -27.34828)
			(xy 353.482419 -27.350315) (xy 353.496372 -27.352244) (xy 353.510342 -27.354276) (xy 353.535996 -27.343862)
			(xy 353.598226 -27.261058) (xy 353.603359 -27.253535) (xy 353.608425 -27.236056) (xy 353.607044 -27.21791)
			(xy 353.60356 -27.209496) (xy 353.60356 -27.209242) (xy 353.592518 -27.184112) (xy 353.576915 -27.131489)
			(xy 353.569008 -27.077174) (xy 353.568508 -27.04973) (xy 353.568994 -27.022479) (xy 353.57675 -26.968531)
			(xy 353.592105 -26.916236) (xy 353.614747 -26.866659) (xy 353.644213 -26.820809) (xy 353.679904 -26.779618)
			(xy 353.721095 -26.743927) (xy 353.766945 -26.714461) (xy 353.816522 -26.691819) (xy 353.868817 -26.676464)
			(xy 353.922765 -26.668708) (xy 353.977267 -26.668708) (xy 354.031215 -26.676464) (xy 354.08351 -26.691819)
			(xy 354.133087 -26.714461) (xy 354.178937 -26.743927) (xy 354.220128 -26.779618) (xy 354.255819 -26.820809)
			(xy 354.285285 -26.866659) (xy 354.307927 -26.916236) (xy 354.323282 -26.968531) (xy 354.331038 -27.022479)
			(xy 354.331524 -27.04973) (xy 354.331524 -27.050238) (xy 354.330865 -27.081568) (xy 354.320577 -27.143379)
			(xy 354.300331 -27.20268) (xy 354.286058 -27.230578) (xy 354.280724 -27.24023) (xy 354.2792 -27.26182)
			(xy 354.31349 -27.354276) (xy 354.328476 -27.369516) (xy 354.338636 -27.37358) (xy 354.339144 -27.37358)
			(xy 354.365763 -27.384369) (xy 354.415677 -27.412787) (xy 354.460767 -27.448365) (xy 354.500015 -27.4903)
			(xy 354.532534 -27.537644) (xy 354.55759 -27.589328) (xy 354.574615 -27.644183) (xy 354.583226 -27.70097)
			(xy 354.583746 -27.729688) (xy 354.583211 -27.756937) (xy 354.575457 -27.810881) (xy 354.560105 -27.863173)
			(xy 354.537468 -27.912747) (xy 354.508007 -27.958596) (xy 354.47232 -27.999785) (xy 354.431136 -28.035477)
			(xy 354.385291 -28.064944) (xy 354.335719 -28.087588) (xy 354.28343 -28.102946) (xy 354.229487 -28.110707)
			(xy 354.202238 -28.111196) (xy 354.173322 -28.110652) (xy 354.116152 -28.101928) (xy 354.060954 -28.084676)
			(xy 354.008992 -28.059289) (xy 353.961457 -28.02635) (xy 353.919439 -27.986613) (xy 353.901248 -27.96413)
			(xy 353.893622 -27.955343) (xy 353.872735 -27.945151) (xy 353.861116 -27.944572) (xy 353.78136 -27.944572)
			(xy 353.769723 -27.945077) (xy 353.748812 -27.955288) (xy 353.741228 -27.96413) (xy 353.723029 -27.986606)
			(xy 353.68101 -28.026341) (xy 353.633476 -28.05928) (xy 353.581517 -28.084669) (xy 353.526321 -28.101927)
			(xy 353.469153 -28.110659) (xy 353.440238 -28.111196) (xy 353.412982 -28.11076) (xy 353.359026 -28.103007)
			(xy 353.306722 -28.087654) (xy 353.257135 -28.065013) (xy 353.211276 -28.035545) (xy 353.170077 -27.99985)
			(xy 353.134378 -27.958655) (xy 353.104906 -27.912798) (xy 353.08226 -27.863214) (xy 353.066901 -27.810911)
			(xy 353.059143 -27.756955) (xy 349.815357 -27.756955) (xy 349.851659 -27.791905) (xy 349.870522 -27.816048)
			(xy 349.876872 -27.82443) (xy 349.885 -27.829256) (xy 349.888746 -27.83138) (xy 349.896793 -27.834443)
			(xy 349.901002 -27.835352) (xy 349.977964 -27.846782) (xy 349.982189 -27.847012) (xy 349.990615 -27.846251)
			(xy 349.994728 -27.845258) (xy 350.002094 -27.843226) (xy 350.005904 -27.840432) (xy 350.01612 -27.832431)
			(xy 350.037475 -27.817687) (xy 350.048576 -27.810968) (xy 350.070254 -27.798591) (xy 350.116147 -27.778951)
			(xy 350.164207 -27.765457) (xy 350.213616 -27.758341) (xy 350.238568 -27.757628) (xy 350.24949 -27.757628)
			(xy 350.277995 -27.758621) (xy 350.334251 -27.76802) (xy 350.388481 -27.785686) (xy 350.439479 -27.811224)
			(xy 350.48611 -27.844065) (xy 350.527336 -27.883479) (xy 350.562238 -27.928589) (xy 350.576642 -27.953208)
			(xy 350.581879 -27.96169) (xy 350.597433 -27.974125) (xy 350.606868 -27.977338) (xy 350.61271 -27.978862)
			(xy 350.701356 -27.978862) (xy 350.708214 -27.978354) (xy 350.718845 -27.976189) (xy 350.737002 -27.964351)
			(xy 350.743266 -27.955494) (xy 350.750424 -27.943177) (xy 350.766313 -27.919529) (xy 350.775016 -27.90825)
			(xy 350.782806 -27.898578) (xy 350.799455 -27.880148) (xy 350.80829 -27.87142) (xy 350.808798 -27.870912)
			(xy 350.830438 -27.849846) (xy 350.879134 -27.814131) (xy 350.932849 -27.786533) (xy 350.99024 -27.76774)
			(xy 351.049875 -27.758223) (xy 351.08007 -27.757628) (xy 351.107323 -27.758089) (xy 351.161276 -27.765843)
			(xy 351.213575 -27.781197) (xy 351.263157 -27.803838) (xy 351.309011 -27.833306) (xy 351.350204 -27.869)
			(xy 351.385898 -27.910194) (xy 351.415365 -27.956049) (xy 351.438005 -28.005631) (xy 351.453358 -28.05793)
			(xy 351.461111 -28.111883) (xy 351.461578 -28.139136) (xy 351.968052 -28.139136) (xy 351.972123 -28.083514)
			(xy 351.984249 -28.029077) (xy 352.004172 -27.976986) (xy 352.031468 -27.928351) (xy 352.065554 -27.884208)
			(xy 352.105703 -27.845499) (xy 352.151061 -27.813048) (xy 352.200661 -27.787547) (xy 352.253445 -27.76954)
			(xy 352.308288 -27.75941) (xy 352.364022 -27.757373) (xy 352.419459 -27.763473) (xy 352.473416 -27.777579)
			(xy 352.524745 -27.799391) (xy 352.572351 -27.828445) (xy 352.615219 -27.86412) (xy 352.652436 -27.905657)
			(xy 352.683209 -27.95217) (xy 352.706881 -28.002667) (xy 352.722949 -28.056074) (xy 352.731069 -28.11125)
			(xy 352.731578 -28.139136) (xy 352.731069 -28.167022) (xy 352.722949 -28.222198) (xy 352.706881 -28.275605)
			(xy 352.683209 -28.326102) (xy 352.652436 -28.372615) (xy 352.615219 -28.414152) (xy 352.572351 -28.449827)
			(xy 352.524745 -28.478881) (xy 352.473416 -28.500693) (xy 352.419459 -28.514799) (xy 352.364022 -28.520899)
			(xy 352.308288 -28.518862) (xy 352.253445 -28.508732) (xy 352.200661 -28.490725) (xy 352.151061 -28.465224)
			(xy 352.105703 -28.432773) (xy 352.065554 -28.394064) (xy 352.031468 -28.349921) (xy 352.004172 -28.301286)
			(xy 351.984249 -28.249195) (xy 351.972123 -28.194758) (xy 351.968052 -28.139136) (xy 351.461578 -28.139136)
			(xy 351.460986 -28.169511) (xy 351.451353 -28.229491) (xy 351.432335 -28.287187) (xy 351.404414 -28.34114)
			(xy 351.368294 -28.389985) (xy 351.347024 -28.411678) (xy 351.346516 -28.412186) (xy 351.324869 -28.433298)
			(xy 351.276141 -28.469095) (xy 351.222379 -28.496761) (xy 351.164926 -28.515604) (xy 351.105222 -28.525152)
			(xy 351.07499 -28.525724) (xy 351.046314 -28.525214) (xy 350.989606 -28.516638) (xy 350.934822 -28.499666)
			(xy 350.883197 -28.474682) (xy 350.835896 -28.442248) (xy 350.793986 -28.403096) (xy 350.758412 -28.358109)
			(xy 350.743774 -28.333446) (xy 350.736637 -28.323385) (xy 350.715397 -28.310922) (xy 350.703134 -28.30957)
			(xy 350.622616 -28.30957) (xy 350.610424 -28.311094) (xy 350.603312 -28.31338) (xy 350.600264 -28.31465)
			(xy 350.592898 -28.317698) (xy 350.589262 -28.319325) (xy 350.582499 -28.323534) (xy 350.579436 -28.32608)
			(xy 350.57334 -28.33116) (xy 350.569022 -28.338272) (xy 350.55675 -28.357706) (xy 350.528219 -28.393743)
			(xy 350.512126 -28.410154) (xy 350.511618 -28.410662) (xy 350.493594 -28.428516) (xy 350.453648 -28.459792)
			(xy 350.409915 -28.485507) (xy 350.363164 -28.505209) (xy 350.314216 -28.518551) (xy 350.263934 -28.5253)
			(xy 350.238568 -28.525724) (xy 350.238314 -28.525724) (xy 350.208837 -28.525176) (xy 350.150585 -28.51611)
			(xy 350.094421 -28.498192) (xy 350.041682 -28.471847) (xy 349.993623 -28.437703) (xy 349.951388 -28.396574)
			(xy 349.93326 -28.373324) (xy 349.92691 -28.364942) (xy 349.918782 -28.360116) (xy 349.914973 -28.357982)
			(xy 349.9068 -28.354912) (xy 349.902526 -28.35402) (xy 349.879158 -28.350464) (xy 349.826326 -28.34259)
			(xy 349.821974 -28.342301) (xy 349.813287 -28.343066) (xy 349.809054 -28.344114) (xy 349.79991 -28.3464)
			(xy 349.797878 -28.347924) (xy 349.791528 -28.352496) (xy 349.779336 -28.361132) (xy 349.774256 -28.364688)
			(xy 349.7707 -28.368498) (xy 349.76308 -28.379166) (xy 349.75165 -28.400248) (xy 349.748998 -28.40566)
			(xy 349.746042 -28.41734) (xy 349.745808 -28.423362) (xy 349.745808 -28.429458) (xy 349.745993 -28.435405)
			(xy 349.748807 -28.446962) (xy 349.751396 -28.452318) (xy 349.754952 -28.458668) (xy 349.755968 -28.460446)
			(xy 349.763334 -28.470606) (xy 349.76816 -28.475686) (xy 349.773494 -28.478988) (xy 349.796554 -28.494044)
			(xy 349.838491 -28.529739) (xy 349.87486 -28.571093) (xy 349.904903 -28.617248) (xy 349.927997 -28.667243)
			(xy 349.943661 -28.72004) (xy 349.95157 -28.77454) (xy 349.952056 -28.802076) (xy 349.951472 -28.832019)
			(xy 349.942115 -28.891169) (xy 349.923628 -28.948129) (xy 349.896464 -29.001499) (xy 349.861292 -29.049968)
			(xy 349.84055 -29.07157) (xy 349.840042 -29.072078) (xy 349.815771 -29.096161) (xy 349.760318 -29.13615)
			(xy 349.729806 -29.15158) (xy 349.729552 -29.151834) (xy 349.723202 -29.155078) (xy 349.712504 -29.164495)
			(xy 349.70847 -29.170376) (xy 349.70466 -29.176218) (xy 349.702628 -29.18333) (xy 349.70085 -29.196538)
			(xy 349.70085 -29.230066) (xy 349.70091 -29.233672) (xy 349.701925 -29.240813) (xy 349.702882 -29.24429)
			(xy 349.728013 -29.25375) (xy 349.775656 -29.278522) (xy 349.819486 -29.309545) (xy 349.858687 -29.346242)
			(xy 349.892532 -29.387932) (xy 349.92039 -29.433839) (xy 349.941743 -29.483108) (xy 349.956195 -29.534825)
			(xy 349.963477 -29.588027) (xy 349.963994 -29.614876) (xy 349.963506 -29.64305) (xy 349.955455 -29.698819)
			(xy 349.939531 -29.75287) (xy 349.916057 -29.804095) (xy 349.885515 -29.851447) (xy 349.848529 -29.893957)
			(xy 349.805856 -29.930755) (xy 349.782384 -29.946346) (xy 349.78086 -29.953458) (xy 349.780352 -29.960316)
			(xy 349.780352 -30.041088) (xy 349.780537 -30.046257) (xy 349.782711 -30.056367) (xy 349.78467 -30.061154)
			(xy 349.806409 -30.07645) (xy 349.845836 -30.112098) (xy 349.879935 -30.152872) (xy 349.908045 -30.197984)
			(xy 349.929623 -30.246561) (xy 349.94425 -30.297663) (xy 349.951644 -30.350299) (xy 349.952056 -30.376876)
			(xy 349.951472 -30.406819) (xy 349.942115 -30.465969) (xy 349.923628 -30.522929) (xy 349.896464 -30.576299)
			(xy 349.861292 -30.624768) (xy 349.84055 -30.64637) (xy 349.840042 -30.646878) (xy 349.815771 -30.670961)
			(xy 349.760318 -30.71095) (xy 349.729806 -30.72638) (xy 349.729552 -30.726634) (xy 349.723202 -30.729878)
			(xy 349.712504 -30.739295) (xy 349.70847 -30.745176) (xy 349.70466 -30.751018) (xy 349.702628 -30.75813)
			(xy 349.70085 -30.771338) (xy 349.70085 -31.147512) (xy 349.701238 -31.156434) (xy 349.707338 -31.173204)
			(xy 349.712788 -31.180278) (xy 349.71863 -31.18739) (xy 349.743268 -31.191454) (xy 349.769674 -31.196295)
			(xy 349.820881 -31.212415) (xy 349.869322 -31.235556) (xy 349.914039 -31.265262) (xy 349.954148 -31.300945)
			(xy 349.988856 -31.341901) (xy 350.017479 -31.387319) (xy 350.039449 -31.436302) (xy 350.054332 -31.487882)
			(xy 350.061835 -31.54104) (xy 350.062292 -31.567882) (xy 350.062292 -31.571692) (xy 350.061422 -31.601462)
			(xy 350.051576 -31.660198) (xy 350.032716 -31.716687) (xy 350.031379 -31.719266) (xy 350.58553 -31.719266)
			(xy 350.589601 -31.663644) (xy 350.601727 -31.609207) (xy 350.62165 -31.557116) (xy 350.648946 -31.508481)
			(xy 350.683032 -31.464338) (xy 350.723181 -31.425629) (xy 350.768539 -31.393178) (xy 350.818139 -31.367677)
			(xy 350.870923 -31.34967) (xy 350.925766 -31.33954) (xy 350.9815 -31.337503) (xy 351.036937 -31.343603)
			(xy 351.090894 -31.357709) (xy 351.142223 -31.379521) (xy 351.189829 -31.408575) (xy 351.232697 -31.44425)
			(xy 351.269914 -31.485787) (xy 351.300687 -31.5323) (xy 351.324359 -31.582797) (xy 351.340427 -31.636204)
			(xy 351.344577 -31.664402) (xy 351.861118 -31.664402) (xy 351.865189 -31.60878) (xy 351.877315 -31.554343)
			(xy 351.897238 -31.502252) (xy 351.924534 -31.453617) (xy 351.95862 -31.409474) (xy 351.998769 -31.370765)
			(xy 352.044127 -31.338314) (xy 352.093727 -31.312813) (xy 352.146511 -31.294806) (xy 352.201354 -31.284676)
			(xy 352.257088 -31.282639) (xy 352.312525 -31.288739) (xy 352.366482 -31.302845) (xy 352.417811 -31.324657)
			(xy 352.465417 -31.353711) (xy 352.508285 -31.389386) (xy 352.545502 -31.430923) (xy 352.576275 -31.477436)
			(xy 352.599947 -31.527933) (xy 352.616015 -31.58134) (xy 352.624135 -31.636516) (xy 352.624644 -31.664402)
			(xy 352.624135 -31.692288) (xy 352.616015 -31.747464) (xy 352.607075 -31.777178) (xy 353.126292 -31.777178)
			(xy 353.130363 -31.721556) (xy 353.142489 -31.667119) (xy 353.162412 -31.615028) (xy 353.189708 -31.566393)
			(xy 353.223794 -31.52225) (xy 353.263943 -31.483541) (xy 353.309301 -31.45109) (xy 353.358901 -31.425589)
			(xy 353.411685 -31.407582) (xy 353.466528 -31.397452) (xy 353.522262 -31.395415) (xy 353.577699 -31.401515)
			(xy 353.631656 -31.415621) (xy 353.682985 -31.437433) (xy 353.730591 -31.466487) (xy 353.773459 -31.502162)
			(xy 353.810676 -31.543699) (xy 353.841449 -31.590212) (xy 353.865121 -31.640709) (xy 353.881189 -31.694116)
			(xy 353.889309 -31.749292) (xy 353.889818 -31.777178) (xy 353.889309 -31.805064) (xy 353.881189 -31.86024)
			(xy 353.865121 -31.913647) (xy 353.841449 -31.964144) (xy 353.810676 -32.010657) (xy 353.773459 -32.052194)
			(xy 353.730591 -32.087869) (xy 353.682985 -32.116923) (xy 353.631656 -32.138735) (xy 353.577699 -32.152841)
			(xy 353.522262 -32.158941) (xy 353.466528 -32.156904) (xy 353.411685 -32.146774) (xy 353.358901 -32.128767)
			(xy 353.309301 -32.103266) (xy 353.263943 -32.070815) (xy 353.223794 -32.032106) (xy 353.189708 -31.987963)
			(xy 353.162412 -31.939328) (xy 353.142489 -31.887237) (xy 353.130363 -31.8328) (xy 353.126292 -31.777178)
			(xy 352.607075 -31.777178) (xy 352.599947 -31.800871) (xy 352.576275 -31.851368) (xy 352.545502 -31.897881)
			(xy 352.508285 -31.939418) (xy 352.465417 -31.975093) (xy 352.417811 -32.004147) (xy 352.366482 -32.025959)
			(xy 352.312525 -32.040065) (xy 352.257088 -32.046165) (xy 352.201354 -32.044128) (xy 352.146511 -32.033998)
			(xy 352.093727 -32.015991) (xy 352.044127 -31.99049) (xy 351.998769 -31.958039) (xy 351.95862 -31.91933)
			(xy 351.924534 -31.875187) (xy 351.897238 -31.826552) (xy 351.877315 -31.774461) (xy 351.865189 -31.720024)
			(xy 351.861118 -31.664402) (xy 351.344577 -31.664402) (xy 351.348547 -31.69138) (xy 351.349056 -31.719266)
			(xy 351.348547 -31.747152) (xy 351.340427 -31.802328) (xy 351.324359 -31.855735) (xy 351.300687 -31.906232)
			(xy 351.269914 -31.952745) (xy 351.232697 -31.994282) (xy 351.189829 -32.029957) (xy 351.142223 -32.059011)
			(xy 351.090894 -32.080823) (xy 351.036937 -32.094929) (xy 350.9815 -32.101029) (xy 350.925766 -32.098992)
			(xy 350.870923 -32.088862) (xy 350.818139 -32.070855) (xy 350.768539 -32.045354) (xy 350.723181 -32.012903)
			(xy 350.683032 -31.974194) (xy 350.648946 -31.930051) (xy 350.62165 -31.881416) (xy 350.601727 -31.829325)
			(xy 350.589601 -31.774888) (xy 350.58553 -31.719266) (xy 350.031379 -31.719266) (xy 350.005301 -31.769557)
			(xy 349.969997 -31.81752) (xy 349.949262 -31.8389) (xy 349.948754 -31.839408) (xy 349.927668 -31.860239)
			(xy 349.88023 -31.895773) (xy 349.827866 -31.923539) (xy 349.771835 -31.942867) (xy 349.74276 -31.948628)
			(xy 349.739204 -31.94939) (xy 349.731587 -31.951625) (xy 349.718131 -31.96003) (xy 349.712788 -31.9659)
			(xy 349.706946 -31.972758) (xy 349.703898 -31.980632) (xy 349.701612 -31.98876) (xy 349.70085 -31.997904)
			(xy 349.70085 -33.51276) (xy 349.701104 -33.517332) (xy 349.701687 -33.522237) (xy 349.704494 -33.531705)
			(xy 349.706692 -33.536128) (xy 349.711005 -33.543679) (xy 349.72373 -33.555512) (xy 349.731584 -33.559242)
			(xy 349.74149 -33.56356) (xy 349.820484 -33.597342) (xy 349.826827 -33.59932) (xy 349.840071 -33.600338)
			(xy 349.846646 -33.599374) (xy 349.853504 -33.598104) (xy 349.866712 -33.5915) (xy 349.870268 -33.587944)
			(xy 349.872808 -33.585658) (xy 349.873062 -33.585404) (xy 349.894594 -33.565056) (xy 349.94278 -33.530595)
			(xy 349.995713 -33.503996) (xy 350.052122 -33.485898) (xy 350.11065 -33.476737) (xy 350.14027 -33.476184)
			(xy 350.167373 -33.476658) (xy 350.221034 -33.48433) (xy 350.273068 -33.499525) (xy 350.322426 -33.521935)
			(xy 350.368112 -33.551109) (xy 350.409206 -33.586459) (xy 350.44488 -33.627273) (xy 350.474415 -33.672727)
			(xy 350.497214 -33.721906) (xy 350.505522 -33.74771) (xy 350.505522 -33.747964) (xy 350.51111 -33.765998)
			(xy 350.512126 -33.767268) (xy 350.585532 -33.81121) (xy 350.593914 -33.812734) (xy 350.616475 -33.807503)
			(xy 350.66245 -33.801902) (xy 350.685608 -33.801558) (xy 350.71286 -33.802044) (xy 350.766808 -33.809802)
			(xy 350.819104 -33.825157) (xy 350.868683 -33.847798) (xy 350.884079 -33.857692) (xy 351.790252 -33.857692)
			(xy 351.794323 -33.80207) (xy 351.806449 -33.747633) (xy 351.826372 -33.695542) (xy 351.853668 -33.646907)
			(xy 351.887754 -33.602764) (xy 351.927903 -33.564055) (xy 351.973261 -33.531604) (xy 352.022861 -33.506103)
			(xy 352.075645 -33.488096) (xy 352.130488 -33.477966) (xy 352.186222 -33.475929) (xy 352.241659 -33.482029)
			(xy 352.295616 -33.496135) (xy 352.346945 -33.517947) (xy 352.394551 -33.547001) (xy 352.437419 -33.582676)
			(xy 352.474636 -33.624213) (xy 352.505409 -33.670726) (xy 352.529081 -33.721223) (xy 352.545149 -33.77463)
			(xy 352.553269 -33.829806) (xy 352.553778 -33.857692) (xy 352.553269 -33.885578) (xy 352.545149 -33.940754)
			(xy 352.529081 -33.994161) (xy 352.505409 -34.044658) (xy 352.474636 -34.091171) (xy 352.437419 -34.132708)
			(xy 352.394551 -34.168383) (xy 352.346945 -34.197437) (xy 352.295616 -34.219249) (xy 352.241659 -34.233355)
			(xy 352.186222 -34.239455) (xy 352.130488 -34.237418) (xy 352.075645 -34.227288) (xy 352.022861 -34.209281)
			(xy 351.973261 -34.18378) (xy 351.927903 -34.151329) (xy 351.887754 -34.11262) (xy 351.853668 -34.068477)
			(xy 351.826372 -34.019842) (xy 351.806449 -33.967751) (xy 351.794323 -33.913314) (xy 351.790252 -33.857692)
			(xy 350.884079 -33.857692) (xy 350.914534 -33.877264) (xy 350.955726 -33.912955) (xy 350.99142 -33.954145)
			(xy 351.020889 -33.999995) (xy 351.043534 -34.049571) (xy 351.058893 -34.101866) (xy 351.066654 -34.155814)
			(xy 351.067116 -34.183066) (xy 351.06653 -34.213442) (xy 351.056905 -34.273428) (xy 351.037892 -34.331129)
			(xy 351.009974 -34.385086) (xy 350.973855 -34.433936) (xy 350.952562 -34.455608) (xy 350.952054 -34.456116)
			(xy 350.930405 -34.477222) (xy 350.881674 -34.513009) (xy 350.827911 -34.540664) (xy 350.77046 -34.559496)
			(xy 350.710758 -34.569033) (xy 350.680528 -34.569654) (xy 350.653921 -34.569194) (xy 350.601224 -34.561804)
			(xy 350.550065 -34.547162) (xy 350.501436 -34.525554) (xy 350.456282 -34.497398) (xy 350.415478 -34.463241)
			(xy 350.379817 -34.423746) (xy 350.349989 -34.379678) (xy 350.326575 -34.331893) (xy 350.317816 -34.306764)
			(xy 350.314768 -34.297366) (xy 350.30918 -34.290508) (xy 350.306734 -34.287609) (xy 350.301119 -34.282511)
			(xy 350.298004 -34.280348) (xy 350.287844 -34.274252) (xy 350.287336 -34.273744) (xy 350.234504 -34.242502)
			(xy 350.221296 -34.23793) (xy 350.213168 -34.236406) (xy 350.203262 -34.238184) (xy 350.186452 -34.241028)
			(xy 350.152492 -34.244082) (xy 350.135444 -34.24428) (xy 350.13519 -34.24428) (xy 350.106178 -34.24374)
			(xy 350.048823 -34.234962) (xy 349.993454 -34.217612) (xy 349.941347 -34.192087) (xy 349.893699 -34.158974)
			(xy 349.8723 -34.139378) (xy 349.870776 -34.137854) (xy 349.865438 -34.133405) (xy 349.852936 -34.127355)
			(xy 349.846138 -34.125916) (xy 349.83928 -34.124646) (xy 349.83166 -34.125662) (xy 349.817944 -34.129218)
			(xy 349.753682 -34.156904) (xy 349.73006 -34.167064) (xy 349.724472 -34.171382) (xy 349.722186 -34.17316)
			(xy 349.714312 -34.178748) (xy 349.708911 -34.185132) (xy 349.702174 -34.200426) (xy 349.701104 -34.20872)
			(xy 349.701104 -34.209228) (xy 349.70085 -34.213038) (xy 349.70085 -35.264852) (xy 352.202494 -35.264852)
			(xy 352.206565 -35.20923) (xy 352.218691 -35.154793) (xy 352.238614 -35.102702) (xy 352.26591 -35.054067)
			(xy 352.299996 -35.009924) (xy 352.340145 -34.971215) (xy 352.385503 -34.938764) (xy 352.435103 -34.913263)
			(xy 352.487887 -34.895256) (xy 352.54273 -34.885126) (xy 352.598464 -34.883089) (xy 352.653901 -34.889189)
			(xy 352.707858 -34.903295) (xy 352.759187 -34.925107) (xy 352.806793 -34.954161) (xy 352.849661 -34.989836)
			(xy 352.874494 -35.017552) (xy 354.519956 -35.017552) (xy 354.519956 -34.963048) (xy 354.527713 -34.909097)
			(xy 354.543068 -34.8568) (xy 354.56571 -34.807221) (xy 354.595177 -34.761368) (xy 354.63087 -34.720176)
			(xy 354.672062 -34.684482) (xy 354.717914 -34.655014) (xy 354.767493 -34.632371) (xy 354.81979 -34.617014)
			(xy 354.87374 -34.609256) (xy 354.900992 -34.60877) (xy 354.918104 -34.608957) (xy 354.952191 -34.612012)
			(xy 354.969064 -34.614866) (xy 354.980355 -34.616242) (xy 355.002245 -34.610162) (xy 355.011228 -34.603182)
			(xy 355.035612 -34.5821) (xy 355.044032 -34.574175) (xy 355.053301 -34.553021) (xy 355.053392 -34.54146)
			(xy 355.052884 -34.522664) (xy 355.052884 -33.65881) (xy 355.053392 -33.638744) (xy 355.053168 -33.627301)
			(xy 355.044077 -33.606331) (xy 355.035866 -33.598358) (xy 355.011228 -33.577022) (xy 355.002225 -33.56995)
			(xy 354.980145 -33.563992) (xy 354.96881 -33.565592) (xy 354.952002 -33.568452) (xy 354.918041 -33.571506)
			(xy 354.900992 -33.571688) (xy 354.87374 -33.571242) (xy 354.81979 -33.563484) (xy 354.767493 -33.548127)
			(xy 354.717915 -33.525484) (xy 354.672063 -33.496016) (xy 354.630871 -33.460323) (xy 354.595179 -33.419131)
			(xy 354.565712 -33.373278) (xy 354.54307 -33.323699) (xy 354.527715 -33.271402) (xy 354.519958 -33.217452)
			(xy 354.519958 -33.162948) (xy 354.527715 -33.108998) (xy 354.54307 -33.056701) (xy 354.565712 -33.007122)
			(xy 354.595179 -32.961269) (xy 354.630871 -32.920077) (xy 354.672063 -32.884384) (xy 354.717915 -32.854916)
			(xy 354.767493 -32.832273) (xy 354.81979 -32.816916) (xy 354.87374 -32.809158) (xy 354.900992 -32.808672)
			(xy 354.928 -32.809127) (xy 354.981478 -32.816732) (xy 355.033348 -32.831806) (xy 355.082573 -32.854047)
			(xy 355.128168 -32.88301) (xy 355.169221 -32.918116) (xy 355.20491 -32.958662) (xy 355.234523 -33.003838)
			(xy 355.257465 -33.05274) (xy 355.27328 -33.104389) (xy 355.277928 -33.130998) (xy 355.279452 -33.141666)
			(xy 355.290882 -33.159446) (xy 355.362256 -33.206944) (xy 355.371179 -33.212304) (xy 355.391648 -33.215971)
			(xy 355.40188 -33.214056) (xy 355.402642 -33.214056) (xy 355.429211 -33.207939) (xy 355.483331 -33.201317)
			(xy 355.510592 -33.200848) (xy 355.537916 -33.201311) (xy 355.592164 -33.207927) (xy 355.618796 -33.214056)
			(xy 355.619304 -33.214056) (xy 355.629537 -33.215894) (xy 355.649981 -33.212236) (xy 355.658928 -33.206944)
			(xy 355.730302 -33.159446) (xy 355.741732 -33.141666) (xy 355.743256 -33.130998) (xy 355.747868 -33.104384)
			(xy 355.763703 -33.052743) (xy 355.78666 -33.003851) (xy 355.816282 -32.958684) (xy 355.851976 -32.918145)
			(xy 355.89303 -32.883044) (xy 355.938624 -32.854082) (xy 355.987845 -32.831839) (xy 356.039711 -32.816758)
			(xy 356.093185 -32.809141) (xy 356.120192 -32.808672) (xy 356.147563 -32.809125) (xy 356.201743 -32.816943)
			(xy 356.254247 -32.832435) (xy 356.303994 -32.85528) (xy 356.349959 -32.885008) (xy 356.37089 -32.902652)
			(xy 356.371144 -32.902906) (xy 356.378242 -32.908476) (xy 356.39515 -32.914732) (xy 356.404164 -32.915098)
			(xy 356.47122 -32.915098) (xy 356.480238 -32.914751) (xy 356.497155 -32.908496) (xy 356.50424 -32.902906)
			(xy 356.50424 -32.902652) (xy 356.504494 -32.902652) (xy 356.525424 -32.88501) (xy 356.571397 -32.855297)
			(xy 356.621145 -32.832461) (xy 356.673646 -32.816971) (xy 356.727823 -32.809144) (xy 356.755192 -32.808672)
			(xy 356.772304 -32.808859) (xy 356.806391 -32.811914) (xy 356.823264 -32.814768) (xy 356.834555 -32.816144)
			(xy 356.856445 -32.810064) (xy 356.865428 -32.803084) (xy 356.889812 -32.782002) (xy 356.898231 -32.774076)
			(xy 356.907501 -32.752923) (xy 356.907592 -32.741362) (xy 356.907084 -32.722566) (xy 356.907084 -31.858712)
			(xy 356.907592 -31.838646) (xy 356.907367 -31.827203) (xy 356.898276 -31.806233) (xy 356.890066 -31.79826)
			(xy 356.865428 -31.776924) (xy 356.856425 -31.769852) (xy 356.834345 -31.763894) (xy 356.82301 -31.765494)
			(xy 356.806202 -31.768354) (xy 356.772241 -31.771408) (xy 356.755192 -31.77159) (xy 356.727821 -31.771131)
			(xy 356.673642 -31.763312) (xy 356.621139 -31.747821) (xy 356.571392 -31.724978) (xy 356.525425 -31.695252)
			(xy 356.504494 -31.67761) (xy 356.497636 -31.671514) (xy 356.480618 -31.665164) (xy 356.395274 -31.665164)
			(xy 356.378002 -31.671768) (xy 356.371144 -31.677864) (xy 356.350214 -31.695506) (xy 356.304244 -31.725226)
			(xy 356.254497 -31.748065) (xy 356.201994 -31.763554) (xy 356.147816 -31.771375) (xy 356.120446 -31.771844)
			(xy 356.120192 -31.771844) (xy 356.093214 -31.771381) (xy 356.039795 -31.763799) (xy 355.987979 -31.748759)
			(xy 355.938801 -31.726561) (xy 355.893246 -31.69765) (xy 355.852224 -31.662604) (xy 355.816554 -31.622122)
			(xy 355.786949 -31.577014) (xy 355.764002 -31.528182) (xy 355.748171 -31.476602) (xy 355.74351 -31.450026)
			(xy 355.741335 -31.439799) (xy 355.730063 -31.422218) (xy 355.721666 -31.41599) (xy 355.650292 -31.368492)
			(xy 355.62921 -31.364682) (xy 355.61905 -31.367222) (xy 355.592349 -31.373301) (xy 355.537973 -31.379791)
			(xy 355.510592 -31.380176) (xy 355.48321 -31.379799) (xy 355.428834 -31.373306) (xy 355.402134 -31.367222)
			(xy 355.391974 -31.364682) (xy 355.370892 -31.368492) (xy 355.290628 -31.421832) (xy 355.279452 -31.439358)
			(xy 355.277674 -31.450026) (xy 355.272978 -31.476591) (xy 355.257124 -31.528153) (xy 355.234162 -31.576968)
			(xy 355.204553 -31.62206) (xy 355.168885 -31.662531) (xy 355.127872 -31.697573) (xy 355.08233 -31.726487)
			(xy 355.033169 -31.748696) (xy 354.981369 -31.763758) (xy 354.927964 -31.771371) (xy 354.900992 -31.771844)
			(xy 354.873744 -31.771285) (xy 354.819802 -31.763529) (xy 354.767513 -31.748174) (xy 354.717942 -31.725535)
			(xy 354.672097 -31.696071) (xy 354.630911 -31.660383) (xy 354.595224 -31.619197) (xy 354.565761 -31.573351)
			(xy 354.543123 -31.523779) (xy 354.52777 -31.47149) (xy 354.520014 -31.417548) (xy 354.520014 -31.363052)
			(xy 354.52777 -31.30911) (xy 354.543123 -31.256821) (xy 354.565761 -31.207249) (xy 354.595224 -31.161403)
			(xy 354.630911 -31.120217) (xy 354.672097 -31.084529) (xy 354.717942 -31.055065) (xy 354.767513 -31.032426)
			(xy 354.819802 -31.017071) (xy 354.873744 -31.009315) (xy 354.900992 -31.008828) (xy 354.918104 -31.009016)
			(xy 354.952191 -31.01207) (xy 354.969064 -31.014924) (xy 354.980355 -31.01631) (xy 355.002247 -31.010225)
			(xy 355.011228 -31.00324) (xy 355.035612 -30.982158) (xy 355.044052 -30.974251) (xy 355.05331 -30.953083)
			(xy 355.053392 -30.941518) (xy 355.052884 -30.922722) (xy 355.052884 -30.058868) (xy 355.053392 -30.038802)
			(xy 355.053193 -30.027356) (xy 355.044084 -30.006386) (xy 355.035866 -29.998416) (xy 355.011228 -29.97708)
			(xy 355.002221 -29.970013) (xy 354.980144 -29.96405) (xy 354.96881 -29.96565) (xy 354.952002 -29.968511)
			(xy 354.918041 -29.971564) (xy 354.900992 -29.971746) (xy 354.873744 -29.971183) (xy 354.819802 -29.963427)
			(xy 354.767514 -29.948072) (xy 354.717943 -29.925433) (xy 354.672098 -29.895969) (xy 354.630913 -29.860282)
			(xy 354.595226 -29.819096) (xy 354.565763 -29.77325) (xy 354.543125 -29.723679) (xy 354.527772 -29.67139)
			(xy 354.520016 -29.617448) (xy 354.520016 -29.562952) (xy 354.527772 -29.50901) (xy 354.543125 -29.456721)
			(xy 354.565763 -29.40715) (xy 354.595226 -29.361304) (xy 354.630913 -29.320118) (xy 354.672098 -29.284431)
			(xy 354.717943 -29.254967) (xy 354.767514 -29.232328) (xy 354.819802 -29.216973) (xy 354.873744 -29.209217)
			(xy 354.900992 -29.20873) (xy 354.927999 -29.20922) (xy 354.981474 -29.216825) (xy 355.033341 -29.231896)
			(xy 355.082564 -29.254134) (xy 355.128157 -29.283094) (xy 355.169209 -29.318195) (xy 355.204899 -29.358737)
			(xy 355.234513 -29.403908) (xy 355.257459 -29.452804) (xy 355.273277 -29.504449) (xy 355.277928 -29.531056)
			(xy 355.279452 -29.541724) (xy 355.290882 -29.559504) (xy 355.362256 -29.607002) (xy 355.371181 -29.61236)
			(xy 355.391648 -29.61603) (xy 355.40188 -29.614114) (xy 355.402642 -29.614114) (xy 355.429218 -29.608058)
			(xy 355.483338 -29.601568) (xy 355.510592 -29.60116) (xy 355.53791 -29.601542) (xy 355.592159 -29.60804)
			(xy 355.618796 -29.614114) (xy 355.619304 -29.614114) (xy 355.629537 -29.615943) (xy 355.649979 -29.612289)
			(xy 355.658928 -29.607002) (xy 355.730302 -29.559504) (xy 355.741732 -29.541724) (xy 355.743256 -29.531056)
			(xy 355.747913 -29.504451) (xy 355.763739 -29.45281) (xy 355.78669 -29.403917) (xy 355.816305 -29.358749)
			(xy 355.851995 -29.318208) (xy 355.893044 -29.283106) (xy 355.938633 -29.254143) (xy 355.987852 -29.231898)
			(xy 356.039715 -29.216816) (xy 356.093186 -29.209199) (xy 356.120192 -29.20873) (xy 356.147562 -29.209193)
			(xy 356.201742 -29.217011) (xy 356.254245 -29.2325) (xy 356.303992 -29.255343) (xy 356.349959 -29.285068)
			(xy 356.37089 -29.30271) (xy 356.371144 -29.302964) (xy 356.378237 -29.308541) (xy 356.395149 -29.314792)
			(xy 356.404164 -29.315156) (xy 356.47122 -29.315156) (xy 356.480239 -29.314818) (xy 356.497156 -29.308558)
			(xy 356.50424 -29.302964) (xy 356.50424 -29.30271) (xy 356.504494 -29.30271) (xy 356.525419 -29.285062)
			(xy 356.571393 -29.255351) (xy 356.621143 -29.232517) (xy 356.673645 -29.217028) (xy 356.727822 -29.209202)
			(xy 356.755192 -29.20873) (xy 356.772304 -29.208918) (xy 356.806391 -29.211972) (xy 356.823264 -29.214826)
			(xy 356.834555 -29.216212) (xy 356.856447 -29.210126) (xy 356.865428 -29.203142) (xy 356.889812 -29.18206)
			(xy 356.898251 -29.174152) (xy 356.907509 -29.152985) (xy 356.907592 -29.14142) (xy 356.907084 -29.122624)
			(xy 356.907084 -28.25877) (xy 356.907592 -28.238704) (xy 356.907392 -28.227259) (xy 356.898284 -28.206289)
			(xy 356.890066 -28.198318) (xy 356.865428 -28.176982) (xy 356.856421 -28.169915) (xy 356.834344 -28.163952)
			(xy 356.82301 -28.165552) (xy 356.806202 -28.168413) (xy 356.772241 -28.171466) (xy 356.755192 -28.171648)
			(xy 356.727944 -28.171081) (xy 356.674003 -28.163325) (xy 356.621715 -28.14797) (xy 356.572144 -28.125331)
			(xy 356.526299 -28.095868) (xy 356.485114 -28.06018) (xy 356.449427 -28.018994) (xy 356.419965 -27.973149)
			(xy 356.397327 -27.923578) (xy 356.381974 -27.871289) (xy 356.374218 -27.817348) (xy 356.374218 -27.762852)
			(xy 356.381974 -27.708911) (xy 356.397327 -27.656622) (xy 356.419965 -27.607051) (xy 356.449427 -27.561206)
			(xy 356.485114 -27.52002) (xy 356.526299 -27.484332) (xy 356.572144 -27.454869) (xy 356.621715 -27.43223)
			(xy 356.674003 -27.416875) (xy 356.727944 -27.409119) (xy 356.755192 -27.408632) (xy 356.782199 -27.409121)
			(xy 356.835674 -27.416725) (xy 356.887541 -27.431797) (xy 356.936764 -27.454035) (xy 356.982357 -27.482994)
			(xy 357.02341 -27.518096) (xy 357.0591 -27.558638) (xy 357.088713 -27.603809) (xy 357.111659 -27.652706)
			(xy 357.127477 -27.704351) (xy 357.132128 -27.730958) (xy 357.133652 -27.741626) (xy 357.145082 -27.759406)
			(xy 357.216456 -27.806904) (xy 357.22538 -27.812262) (xy 357.245848 -27.815933) (xy 357.25608 -27.814016)
			(xy 357.256842 -27.814016) (xy 357.283411 -27.807898) (xy 357.337531 -27.801277) (xy 357.364792 -27.800808)
			(xy 357.38697 -27.80111) (xy 357.431116 -27.805431) (xy 357.45293 -27.809444) (xy 357.46309 -27.811476)
			(xy 357.483156 -27.807412) (xy 357.551482 -27.760168) (xy 357.559651 -27.753961) (xy 357.570658 -27.736669)
			(xy 357.572818 -27.72664) (xy 357.577749 -27.700309) (xy 357.593963 -27.649252) (xy 357.61716 -27.600966)
			(xy 357.646884 -27.5564) (xy 357.682551 -27.516431) (xy 357.72346 -27.481845) (xy 357.768804 -27.453322)
			(xy 357.817693 -27.431424) (xy 357.869165 -27.416582) (xy 357.922207 -27.409086) (xy 357.948992 -27.408632)
			(xy 357.976248 -27.409014) (xy 358.030206 -27.416771) (xy 358.08251 -27.432128) (xy 358.132096 -27.454773)
			(xy 358.177955 -27.484244) (xy 358.219153 -27.519941) (xy 358.254852 -27.561138) (xy 358.284323 -27.606997)
			(xy 358.306969 -27.656583) (xy 358.322327 -27.708887) (xy 358.330085 -27.762844) (xy 358.330085 -27.817356)
			(xy 358.322327 -27.871313) (xy 358.306969 -27.923617) (xy 358.284323 -27.973203) (xy 358.254852 -28.019062)
			(xy 358.219153 -28.060259) (xy 358.177955 -28.095956) (xy 358.132096 -28.125427) (xy 358.08251 -28.148072)
			(xy 358.030206 -28.163429) (xy 357.976248 -28.171186) (xy 357.948992 -28.171648) (xy 357.94823 -28.171648)
			(xy 357.936898 -28.171534) (xy 357.914278 -28.170135) (xy 357.903018 -28.168854) (xy 357.892104 -28.1681)
			(xy 357.871306 -28.174822) (xy 357.862886 -28.181808) (xy 357.838756 -28.203652) (xy 357.831005 -28.211478)
			(xy 357.822453 -28.231755) (xy 357.822246 -28.242768) (xy 357.8225 -28.25877) (xy 357.8225 -29.12237)
			(xy 357.822246 -29.13761) (xy 357.822447 -29.14866) (xy 357.831157 -29.168948) (xy 357.83901 -29.176726)
			(xy 357.862886 -29.198316) (xy 357.871313 -29.205288) (xy 357.892105 -29.212006) (xy 357.903018 -29.21127)
			(xy 357.914277 -29.209981) (xy 357.936898 -29.20858) (xy 357.94823 -29.208476) (xy 357.948992 -29.208476)
			(xy 357.976244 -29.208971) (xy 358.030194 -29.216726) (xy 358.08249 -29.232081) (xy 358.132069 -29.254722)
			(xy 358.177921 -29.284189) (xy 358.219113 -29.319881) (xy 358.254806 -29.361072) (xy 358.284274 -29.406924)
			(xy 358.306916 -29.456502) (xy 358.322272 -29.508799) (xy 358.330029 -29.562748) (xy 358.330029 -29.617252)
			(xy 358.322272 -29.671201) (xy 358.306916 -29.723498) (xy 358.284274 -29.773076) (xy 358.254806 -29.818928)
			(xy 358.219113 -29.860119) (xy 358.177921 -29.895811) (xy 358.132069 -29.925278) (xy 358.08249 -29.947919)
			(xy 358.030194 -29.963274) (xy 357.976244 -29.971029) (xy 357.948992 -29.971492) (xy 357.922244 -29.97103)
			(xy 357.869276 -29.963535) (xy 357.817873 -29.948722) (xy 357.769039 -29.92688) (xy 357.723732 -29.898436)
			(xy 357.682838 -29.863948) (xy 357.647157 -29.82409) (xy 357.617388 -29.779643) (xy 357.594113 -29.731476)
			(xy 357.577788 -29.680532) (xy 357.572818 -29.654246) (xy 357.57104 -29.643832) (xy 357.560372 -29.627068)
			(xy 357.48341 -29.573728) (xy 357.463344 -29.569664) (xy 357.453184 -29.571696) (xy 357.43131 -29.57574)
			(xy 357.387035 -29.580068) (xy 357.364792 -29.580332) (xy 357.337404 -29.579893) (xy 357.283028 -29.573269)
			(xy 357.256334 -29.567124) (xy 357.246174 -29.564584) (xy 357.225092 -29.568394) (xy 357.144828 -29.621734)
			(xy 357.133652 -29.63926) (xy 357.131874 -29.649928) (xy 357.12718 -29.676493) (xy 357.111325 -29.728056)
			(xy 357.088363 -29.77687) (xy 357.058753 -29.821962) (xy 357.023086 -29.862433) (xy 356.982072 -29.897475)
			(xy 356.93653 -29.926389) (xy 356.887369 -29.948598) (xy 356.835569 -29.96366) (xy 356.782164 -29.971273)
			(xy 356.755192 -29.971746) (xy 356.727821 -29.971298) (xy 356.673641 -29.963478) (xy 356.621137 -29.947985)
			(xy 356.57139 -29.925139) (xy 356.525425 -29.89541) (xy 356.504494 -29.877766) (xy 356.50424 -29.877512)
			(xy 356.497145 -29.871937) (xy 356.480235 -29.865683) (xy 356.47122 -29.86532) (xy 356.404164 -29.86532)
			(xy 356.395145 -29.865656) (xy 356.378228 -29.871918) (xy 356.371144 -29.877512) (xy 356.371144 -29.877766)
			(xy 356.37089 -29.877766) (xy 356.349968 -29.895418) (xy 356.303993 -29.925129) (xy 356.254243 -29.947963)
			(xy 356.20174 -29.963451) (xy 356.147562 -29.971275) (xy 356.120192 -29.971746) (xy 356.103144 -29.971542)
			(xy 356.069185 -29.968492) (xy 356.052374 -29.96565) (xy 356.041045 -29.964247) (xy 356.019032 -29.97016)
			(xy 356.009956 -29.97708) (xy 355.985318 -29.998416) (xy 355.976973 -30.006292) (xy 355.967855 -30.027327)
			(xy 355.967792 -30.038802) (xy 355.9683 -30.058868) (xy 355.9683 -30.922722) (xy 355.967792 -30.941518)
			(xy 355.967864 -30.953081) (xy 355.977143 -30.974239) (xy 355.985572 -30.982158) (xy 356.009956 -31.00324)
			(xy 356.018919 -31.010252) (xy 356.040824 -31.016312) (xy 356.05212 -31.014924) (xy 356.06899 -31.012049)
			(xy 356.103079 -31.009) (xy 356.120192 -31.008828) (xy 356.147562 -31.009292) (xy 356.201742 -31.017109)
			(xy 356.254245 -31.032598) (xy 356.303992 -31.055441) (xy 356.349959 -31.085166) (xy 356.37089 -31.102808)
			(xy 356.377748 -31.108904) (xy 356.394766 -31.115254) (xy 356.48011 -31.115254) (xy 356.497382 -31.10865)
			(xy 356.50424 -31.102554) (xy 356.525179 -31.084922) (xy 356.571146 -31.055201) (xy 356.620891 -31.032359)
			(xy 356.673392 -31.016867) (xy 356.727569 -31.009044) (xy 356.754938 -31.008574) (xy 356.755192 -31.008574)
			(xy 356.7822 -31.009027) (xy 356.835678 -31.016633) (xy 356.887549 -31.031707) (xy 356.936774 -31.053948)
			(xy 356.982369 -31.082911) (xy 357.023421 -31.118017) (xy 357.059111 -31.158563) (xy 357.088723 -31.203739)
			(xy 357.111666 -31.252641) (xy 357.12748 -31.304291) (xy 357.132128 -31.3309) (xy 357.133652 -31.341568)
			(xy 357.145082 -31.359348) (xy 357.216456 -31.406846) (xy 357.225379 -31.412206) (xy 357.245848 -31.415873)
			(xy 357.25608 -31.413958) (xy 357.256842 -31.413958) (xy 357.283418 -31.407902) (xy 357.337538 -31.401412)
			(xy 357.364792 -31.401004) (xy 357.386965 -31.401234) (xy 357.431111 -31.405431) (xy 357.45293 -31.409386)
			(xy 357.46309 -31.411418) (xy 357.483156 -31.407354) (xy 357.551482 -31.36011) (xy 357.559671 -31.353926)
			(xy 357.570667 -31.336617) (xy 357.572818 -31.326582) (xy 357.577705 -31.300242) (xy 357.593926 -31.249185)
			(xy 357.61713 -31.2009) (xy 357.646861 -31.156335) (xy 357.682533 -31.116367) (xy 357.723446 -31.081783)
			(xy 357.768794 -31.053261) (xy 357.817687 -31.031365) (xy 357.869161 -31.016523) (xy 357.922206 -31.009027)
			(xy 357.948992 -31.008574) (xy 357.976244 -31.009073) (xy 358.030193 -31.016828) (xy 358.08249 -31.032183)
			(xy 358.132068 -31.054824) (xy 358.17792 -31.08429) (xy 358.219112 -31.119982) (xy 358.254805 -31.161173)
			(xy 358.284272 -31.207025) (xy 358.306914 -31.256603) (xy 358.32227 -31.308899) (xy 358.330027 -31.362848)
			(xy 358.330027 -31.417352) (xy 358.32227 -31.471301) (xy 358.306914 -31.523597) (xy 358.284272 -31.573175)
			(xy 358.254805 -31.619027) (xy 358.219112 -31.660218) (xy 358.17792 -31.69591) (xy 358.132068 -31.725376)
			(xy 358.08249 -31.748017) (xy 358.030193 -31.763372) (xy 357.976244 -31.771127) (xy 357.948992 -31.77159)
			(xy 357.94823 -31.77159) (xy 357.936898 -31.771476) (xy 357.914278 -31.770077) (xy 357.903018 -31.768796)
			(xy 357.892104 -31.768032) (xy 357.871305 -31.77476) (xy 357.862886 -31.78175) (xy 357.838756 -31.803594)
			(xy 357.830986 -31.811404) (xy 357.822445 -31.831693) (xy 357.822246 -31.84271) (xy 357.8225 -31.858712)
			(xy 357.8225 -32.722312) (xy 357.822246 -32.737806) (xy 357.822449 -32.748856) (xy 357.831157 -32.769144)
			(xy 357.83901 -32.776922) (xy 357.862886 -32.798512) (xy 357.871314 -32.805484) (xy 357.892106 -32.812202)
			(xy 357.903018 -32.811466) (xy 357.914277 -32.810177) (xy 357.936898 -32.808776) (xy 357.94823 -32.808672)
			(xy 357.948992 -32.808672) (xy 357.976244 -32.809175) (xy 358.030193 -32.81693) (xy 358.082489 -32.832285)
			(xy 358.132067 -32.854926) (xy 358.177919 -32.884392) (xy 358.219111 -32.920084) (xy 358.254803 -32.961275)
			(xy 358.28427 -33.007126) (xy 358.306912 -33.056704) (xy 358.322268 -33.108999) (xy 358.330025 -33.162948)
			(xy 358.330025 -33.217452) (xy 358.322268 -33.271401) (xy 358.306912 -33.323696) (xy 358.28427 -33.373274)
			(xy 358.254803 -33.419125) (xy 358.219111 -33.460316) (xy 358.177919 -33.496008) (xy 358.132067 -33.525474)
			(xy 358.082489 -33.548115) (xy 358.030193 -33.56347) (xy 357.976244 -33.571225) (xy 357.948992 -33.571688)
			(xy 357.922227 -33.571233) (xy 357.869219 -33.563774) (xy 357.817775 -33.548976) (xy 357.768905 -33.527129)
			(xy 357.723571 -33.498663) (xy 357.682663 -33.464138) (xy 357.646985 -33.424231) (xy 357.617238 -33.379727)
			(xy 357.594007 -33.3315) (xy 357.577748 -33.280499) (xy 357.572818 -33.254188) (xy 357.57104 -33.243774)
			(xy 357.560372 -33.22701) (xy 357.48341 -33.17367) (xy 357.463344 -33.169606) (xy 357.453184 -33.171638)
			(xy 357.431304 -33.175615) (xy 357.387029 -33.179817) (xy 357.364792 -33.18002) (xy 357.33741 -33.179644)
			(xy 357.283034 -33.17315) (xy 357.256334 -33.167066) (xy 357.246174 -33.164526) (xy 357.225092 -33.168336)
			(xy 357.144828 -33.221676) (xy 357.133652 -33.239202) (xy 357.131874 -33.24987) (xy 357.127136 -33.276427)
			(xy 357.111288 -33.327989) (xy 357.088334 -33.376804) (xy 357.05873 -33.421897) (xy 357.023068 -33.46237)
			(xy 356.982058 -33.497413) (xy 356.936521 -33.526328) (xy 356.887363 -33.548539) (xy 356.835566 -33.563601)
			(xy 356.782163 -33.571215) (xy 356.755192 -33.571688) (xy 356.727821 -33.57123) (xy 356.673642 -33.56341)
			(xy 356.621139 -33.54792) (xy 356.571392 -33.525076) (xy 356.525425 -33.49535) (xy 356.504494 -33.477708)
			(xy 356.50424 -33.477454) (xy 356.49715 -33.471872) (xy 356.480236 -33.465624) (xy 356.47122 -33.465262)
			(xy 356.404164 -33.465262) (xy 356.395146 -33.46561) (xy 356.37823 -33.471865) (xy 356.371144 -33.477454)
			(xy 356.371144 -33.477708) (xy 356.37089 -33.477708) (xy 356.349974 -33.495366) (xy 356.303996 -33.525075)
			(xy 356.254245 -33.547907) (xy 356.201741 -33.563394) (xy 356.147562 -33.571217) (xy 356.120192 -33.571688)
			(xy 356.103144 -33.571485) (xy 356.069184 -33.568435) (xy 356.052374 -33.565592) (xy 356.041046 -33.56418)
			(xy 356.019031 -33.570098) (xy 356.009956 -33.577022) (xy 355.985318 -33.598358) (xy 355.977001 -33.606259)
			(xy 355.967867 -33.627274) (xy 355.967792 -33.638744) (xy 355.9683 -33.65881) (xy 355.9683 -34.522664)
			(xy 355.967792 -34.54146) (xy 355.967898 -34.55302) (xy 355.977153 -34.574178) (xy 355.985572 -34.5821)
			(xy 356.009956 -34.603182) (xy 356.018923 -34.610189) (xy 356.040825 -34.616254) (xy 356.05212 -34.614866)
			(xy 356.06899 -34.611992) (xy 356.103079 -34.608942) (xy 356.120192 -34.60877) (xy 356.147444 -34.609277)
			(xy 356.201392 -34.617032) (xy 356.253688 -34.632387) (xy 356.303266 -34.655028) (xy 356.349118 -34.684494)
			(xy 356.390309 -34.720185) (xy 356.426002 -34.761376) (xy 356.455469 -34.807227) (xy 356.47811 -34.856804)
			(xy 356.493466 -34.9091) (xy 356.501223 -34.963048) (xy 356.501223 -34.990024) (xy 357.566974 -34.990024)
			(xy 357.571045 -34.934402) (xy 357.583171 -34.879965) (xy 357.603094 -34.827874) (xy 357.63039 -34.779239)
			(xy 357.664476 -34.735096) (xy 357.704625 -34.696387) (xy 357.749983 -34.663936) (xy 357.799583 -34.638435)
			(xy 357.852367 -34.620428) (xy 357.90721 -34.610298) (xy 357.962944 -34.608261) (xy 358.018381 -34.614361)
			(xy 358.072338 -34.628467) (xy 358.123667 -34.650279) (xy 358.171273 -34.679333) (xy 358.214141 -34.715008)
			(xy 358.251358 -34.756545) (xy 358.282131 -34.803058) (xy 358.305803 -34.853555) (xy 358.321871 -34.906962)
			(xy 358.329991 -34.962138) (xy 358.3305 -34.990024) (xy 358.329991 -35.01791) (xy 358.321871 -35.073086)
			(xy 358.305803 -35.126493) (xy 358.282131 -35.17699) (xy 358.251358 -35.223503) (xy 358.214141 -35.26504)
			(xy 358.171273 -35.300715) (xy 358.123667 -35.329769) (xy 358.072338 -35.351581) (xy 358.018381 -35.365687)
			(xy 357.962944 -35.371787) (xy 357.90721 -35.36975) (xy 357.852367 -35.35962) (xy 357.799583 -35.341613)
			(xy 357.749983 -35.316112) (xy 357.704625 -35.283661) (xy 357.664476 -35.244952) (xy 357.63039 -35.200809)
			(xy 357.603094 -35.152174) (xy 357.583171 -35.100083) (xy 357.571045 -35.045646) (xy 357.566974 -34.990024)
			(xy 356.501223 -34.990024) (xy 356.501223 -35.017552) (xy 356.493466 -35.0715) (xy 356.47811 -35.123796)
			(xy 356.455469 -35.173373) (xy 356.426002 -35.219224) (xy 356.390309 -35.260415) (xy 356.349118 -35.296106)
			(xy 356.303266 -35.325572) (xy 356.253688 -35.348213) (xy 356.201392 -35.363568) (xy 356.147444 -35.371323)
			(xy 356.120192 -35.371786) (xy 356.093216 -35.371288) (xy 356.0398 -35.363707) (xy 355.987986 -35.348669)
			(xy 355.938811 -35.326474) (xy 355.893257 -35.297567) (xy 355.852235 -35.262524) (xy 355.816565 -35.222047)
			(xy 355.786959 -35.176944) (xy 355.764009 -35.128117) (xy 355.748174 -35.076542) (xy 355.74351 -35.049968)
			(xy 355.741362 -35.039733) (xy 355.730071 -35.022156) (xy 355.721666 -35.015932) (xy 355.650292 -34.968434)
			(xy 355.62921 -34.964624) (xy 355.61905 -34.967164) (xy 355.592355 -34.973303) (xy 355.53798 -34.979925)
			(xy 355.510592 -34.980372) (xy 355.483204 -34.979932) (xy 355.428828 -34.973308) (xy 355.402134 -34.967164)
			(xy 355.391974 -34.964624) (xy 355.370892 -34.968434) (xy 355.290628 -35.021774) (xy 355.279452 -35.0393)
			(xy 355.277674 -35.049968) (xy 355.27301 -35.076539) (xy 355.25715 -35.128102) (xy 355.234184 -35.176915)
			(xy 355.20457 -35.222007) (xy 355.168898 -35.262477) (xy 355.127882 -35.297518) (xy 355.082337 -35.326431)
			(xy 355.033174 -35.348639) (xy 354.981372 -35.3637) (xy 354.927965 -35.371313) (xy 354.900992 -35.371786)
			(xy 354.87374 -35.371344) (xy 354.81979 -35.363586) (xy 354.767493 -35.348229) (xy 354.717914 -35.325586)
			(xy 354.672062 -35.296118) (xy 354.63087 -35.260424) (xy 354.595177 -35.219232) (xy 354.56571 -35.173379)
			(xy 354.543068 -35.1238) (xy 354.527713 -35.071503) (xy 354.519956 -35.017552) (xy 352.874494 -35.017552)
			(xy 352.886878 -35.031373) (xy 352.917651 -35.077886) (xy 352.941323 -35.128383) (xy 352.957391 -35.18179)
			(xy 352.965511 -35.236966) (xy 352.96602 -35.264852) (xy 352.965511 -35.292738) (xy 352.957391 -35.347914)
			(xy 352.941323 -35.401321) (xy 352.917651 -35.451818) (xy 352.886878 -35.498331) (xy 352.849661 -35.539868)
			(xy 352.806793 -35.575543) (xy 352.759187 -35.604597) (xy 352.707858 -35.626409) (xy 352.653901 -35.640515)
			(xy 352.598464 -35.646615) (xy 352.54273 -35.644578) (xy 352.487887 -35.634448) (xy 352.435103 -35.616441)
			(xy 352.385503 -35.59094) (xy 352.340145 -35.558489) (xy 352.299996 -35.51978) (xy 352.26591 -35.475637)
			(xy 352.238614 -35.427002) (xy 352.218691 -35.374911) (xy 352.206565 -35.320474) (xy 352.202494 -35.264852)
			(xy 349.70085 -35.264852) (xy 349.70085 -37.087048) (xy 353.500944 -37.087048) (xy 353.50141 -37.060444)
			(xy 353.508786 -37.007751) (xy 353.523416 -36.956595) (xy 353.545015 -36.90797) (xy 353.573165 -36.862819)
			(xy 353.607317 -36.82202) (xy 353.64681 -36.786364) (xy 353.668584 -36.771072) (xy 353.678508 -36.763541)
			(xy 353.690236 -36.741598) (xy 353.690936 -36.729162) (xy 353.690936 -36.644834) (xy 353.690265 -36.632384)
			(xy 353.678555 -36.610408) (xy 353.668584 -36.602924) (xy 353.646826 -36.587612) (xy 353.607344 -36.55195)
			(xy 353.573199 -36.51115) (xy 353.545051 -36.466003) (xy 353.523447 -36.417384) (xy 353.508805 -36.366236)
			(xy 353.501408 -36.313549) (xy 353.500944 -36.286948) (xy 353.501523 -36.2597) (xy 353.509271 -36.205758)
			(xy 353.524618 -36.153468) (xy 353.54725 -36.103894) (xy 353.576707 -36.058046) (xy 353.612389 -36.016857)
			(xy 353.653569 -35.981164) (xy 353.69941 -35.951696) (xy 353.748978 -35.929052) (xy 353.801264 -35.913692)
			(xy 353.855204 -35.90593) (xy 353.882452 -35.90544) (xy 353.887024 -35.90544) (xy 353.896233 -35.905165)
			(xy 353.913552 -35.898926) (xy 353.920806 -35.893248) (xy 353.971606 -35.84956) (xy 353.978311 -35.843323)
			(xy 353.987171 -35.827314) (xy 353.988878 -35.818318) (xy 353.988878 -35.818064) (xy 353.99323 -35.791134)
			(xy 354.00854 -35.738779) (xy 354.03115 -35.689137) (xy 354.060601 -35.643223) (xy 354.096291 -35.601971)
			(xy 354.137493 -35.566223) (xy 354.183367 -35.536707) (xy 354.232976 -35.514027) (xy 354.28531 -35.498643)
			(xy 354.339302 -35.490871) (xy 354.366576 -35.490404) (xy 354.393831 -35.490841) (xy 354.447786 -35.498596)
			(xy 354.500089 -35.51395) (xy 354.549673 -35.536592) (xy 354.595531 -35.56606) (xy 354.636728 -35.601755)
			(xy 354.672425 -35.64295) (xy 354.701896 -35.688806) (xy 354.724541 -35.738389) (xy 354.739899 -35.79069)
			(xy 354.747657 -35.844645) (xy 354.747657 -35.899155) (xy 354.739899 -35.95311) (xy 354.724541 -36.005411)
			(xy 354.701896 -36.054994) (xy 354.672425 -36.10085) (xy 354.636728 -36.142045) (xy 354.595531 -36.17774)
			(xy 354.549673 -36.207208) (xy 354.500089 -36.22985) (xy 354.447786 -36.245204) (xy 354.393831 -36.252959)
			(xy 354.366576 -36.25342) (xy 354.362004 -36.25342) (xy 354.35279 -36.253646) (xy 354.335471 -36.259917)
			(xy 354.328222 -36.265612) (xy 354.277422 -36.3093) (xy 354.2707 -36.315521) (xy 354.261849 -36.331541)
			(xy 354.26015 -36.340542) (xy 354.26015 -36.340796) (xy 354.255953 -36.366999) (xy 354.241269 -36.417994)
			(xy 354.219656 -36.46646) (xy 354.191531 -36.511461) (xy 354.188105 -36.515548) (xy 355.314248 -36.515548)
			(xy 355.318319 -36.459926) (xy 355.330445 -36.405489) (xy 355.350368 -36.353398) (xy 355.377664 -36.304763)
			(xy 355.41175 -36.26062) (xy 355.451899 -36.221911) (xy 355.497257 -36.18946) (xy 355.546857 -36.163959)
			(xy 355.599641 -36.145952) (xy 355.654484 -36.135822) (xy 355.710218 -36.133785) (xy 355.765655 -36.139885)
			(xy 355.819612 -36.153991) (xy 355.870941 -36.175803) (xy 355.918547 -36.204857) (xy 355.961415 -36.240532)
			(xy 355.998632 -36.282069) (xy 356.029405 -36.328582) (xy 356.053077 -36.379079) (xy 356.069145 -36.432486)
			(xy 356.077265 -36.487662) (xy 356.077774 -36.515548) (xy 356.077265 -36.543434) (xy 356.069145 -36.59861)
			(xy 356.053077 -36.652017) (xy 356.029405 -36.702514) (xy 355.998632 -36.749027) (xy 355.961415 -36.790564)
			(xy 355.918547 -36.826239) (xy 355.870941 -36.855293) (xy 355.819612 -36.877105) (xy 355.765655 -36.891211)
			(xy 355.710218 -36.897311) (xy 355.654484 -36.895274) (xy 355.599641 -36.885144) (xy 355.546857 -36.867137)
			(xy 355.497257 -36.841636) (xy 355.451899 -36.809185) (xy 355.41175 -36.770476) (xy 355.377664 -36.726333)
			(xy 355.350368 -36.677698) (xy 355.330445 -36.625607) (xy 355.318319 -36.57117) (xy 355.314248 -36.515548)
			(xy 354.188105 -36.515548) (xy 354.157439 -36.552127) (xy 354.118038 -36.587675) (xy 354.09632 -36.602924)
			(xy 354.086399 -36.610458) (xy 354.074669 -36.632399) (xy 354.073968 -36.644834) (xy 354.073968 -36.729162)
			(xy 354.07464 -36.741612) (xy 354.086349 -36.763588) (xy 354.09632 -36.771072) (xy 354.118077 -36.786385)
			(xy 354.157558 -36.822047) (xy 354.191704 -36.862847) (xy 354.219852 -36.907994) (xy 354.241456 -36.956612)
			(xy 354.256099 -37.007761) (xy 354.263495 -37.060447) (xy 354.26396 -37.087048) (xy 354.26396 -37.087302)
			(xy 354.263342 -37.119019) (xy 354.252841 -37.181577) (xy 354.232113 -37.241528) (xy 354.217478 -37.269674)
			(xy 354.212144 -37.27958) (xy 354.21062 -37.301678) (xy 354.242624 -37.384482) (xy 354.247119 -37.394567)
			(xy 354.262905 -37.409971) (xy 354.273104 -37.4142) (xy 354.297638 -37.423264) (xy 354.344168 -37.447147)
			(xy 354.386999 -37.477164) (xy 354.425328 -37.51275) (xy 354.458436 -37.553239) (xy 354.485702 -37.597872)
			(xy 354.506614 -37.645811) (xy 354.520782 -37.696157) (xy 354.527938 -37.747967) (xy 354.528374 -37.774118)
			(xy 354.527888 -37.801369) (xy 354.520132 -37.855317) (xy 354.504777 -37.907612) (xy 354.482135 -37.957189)
			(xy 354.452669 -38.003039) (xy 354.416978 -38.04423) (xy 354.375787 -38.079921) (xy 354.329937 -38.109387)
			(xy 354.28036 -38.132029) (xy 354.228065 -38.147384) (xy 354.174117 -38.15514) (xy 354.119615 -38.15514)
			(xy 354.065667 -38.147384) (xy 354.013372 -38.132029) (xy 353.963795 -38.109387) (xy 353.917945 -38.079921)
			(xy 353.876754 -38.04423) (xy 353.841063 -38.003039) (xy 353.811597 -37.957189) (xy 353.788955 -37.907612)
			(xy 353.7736 -37.855317) (xy 353.765844 -37.801369) (xy 353.765358 -37.774118) (xy 353.765358 -37.773864)
			(xy 353.76596 -37.742146) (xy 353.776467 -37.679588) (xy 353.797202 -37.619637) (xy 353.81184 -37.591492)
			(xy 353.817174 -37.581586) (xy 353.818698 -37.559488) (xy 353.786694 -37.476684) (xy 353.782246 -37.466573)
			(xy 353.766427 -37.451181) (xy 353.756214 -37.446966) (xy 353.731673 -37.437921) (xy 353.685141 -37.414036)
			(xy 353.642308 -37.384019) (xy 353.603979 -37.34843) (xy 353.570871 -37.307939) (xy 353.543606 -37.263303)
			(xy 353.522695 -37.215361) (xy 353.508531 -37.165012) (xy 353.501378 -37.1132) (xy 353.500944 -37.087048)
			(xy 349.70085 -37.087048) (xy 349.70085 -38.315138) (xy 354.71811 -38.315138) (xy 354.722181 -38.259516)
			(xy 354.734307 -38.205079) (xy 354.75423 -38.152988) (xy 354.781526 -38.104353) (xy 354.815612 -38.06021)
			(xy 354.855761 -38.021501) (xy 354.901119 -37.98905) (xy 354.950719 -37.963549) (xy 355.003503 -37.945542)
			(xy 355.058346 -37.935412) (xy 355.11408 -37.933375) (xy 355.169517 -37.939475) (xy 355.223474 -37.953581)
			(xy 355.274803 -37.975393) (xy 355.322409 -38.004447) (xy 355.365277 -38.040122) (xy 355.402494 -38.081659)
			(xy 355.433267 -38.128172) (xy 355.456939 -38.178669) (xy 355.473007 -38.232076) (xy 355.481127 -38.287252)
			(xy 355.481636 -38.315138) (xy 355.481127 -38.343024) (xy 355.473007 -38.3982) (xy 355.456939 -38.451607)
			(xy 355.433267 -38.502104) (xy 355.402494 -38.548617) (xy 355.365277 -38.590154) (xy 355.322409 -38.625829)
			(xy 355.274803 -38.654883) (xy 355.223474 -38.676695) (xy 355.169517 -38.690801) (xy 355.11408 -38.696901)
			(xy 355.058346 -38.694864) (xy 355.003503 -38.684734) (xy 354.950719 -38.666727) (xy 354.901119 -38.641226)
			(xy 354.855761 -38.608775) (xy 354.815612 -38.570066) (xy 354.781526 -38.525923) (xy 354.75423 -38.477288)
			(xy 354.734307 -38.425197) (xy 354.722181 -38.37076) (xy 354.71811 -38.315138) (xy 349.70085 -38.315138)
			(xy 349.70085 -49.601953) (xy 350.591059 -49.601953) (xy 350.591059 -49.547447) (xy 350.598817 -49.493494)
			(xy 350.614174 -49.441196) (xy 350.636817 -49.391615) (xy 350.666287 -49.345761) (xy 350.701982 -49.304568)
			(xy 350.743177 -49.268875) (xy 350.789032 -49.239408) (xy 350.838614 -49.216767) (xy 350.890914 -49.201413)
			(xy 350.944867 -49.193658) (xy 350.97212 -49.193196) (xy 350.999491 -49.193651) (xy 351.05367 -49.201472)
			(xy 351.106173 -49.216964) (xy 351.15592 -49.239808) (xy 351.201886 -49.269534) (xy 351.222818 -49.287176)
			(xy 351.223072 -49.28743) (xy 351.23016 -49.293014) (xy 351.247076 -49.299261) (xy 351.256092 -49.299622)
			(xy 351.323148 -49.299622) (xy 351.332162 -49.299235) (xy 351.349079 -49.293008) (xy 351.356168 -49.28743)
			(xy 351.356168 -49.287176) (xy 351.356422 -49.287176) (xy 351.377355 -49.269535) (xy 351.423323 -49.239811)
			(xy 351.473069 -49.216965) (xy 351.525571 -49.201469) (xy 351.579749 -49.19364) (xy 351.634491 -49.19364)
			(xy 351.688669 -49.201469) (xy 351.741171 -49.216965) (xy 351.790917 -49.239811) (xy 351.836885 -49.269535)
			(xy 351.857818 -49.287176) (xy 351.858072 -49.28743) (xy 351.86516 -49.293014) (xy 351.882076 -49.299261)
			(xy 351.891092 -49.299622) (xy 351.958148 -49.299622) (xy 351.967162 -49.299235) (xy 351.984079 -49.293008)
			(xy 351.991168 -49.28743) (xy 351.991168 -49.287176) (xy 351.991422 -49.287176) (xy 352.01237 -49.269556)
			(xy 352.058339 -49.239842) (xy 352.108082 -49.217003) (xy 352.160579 -49.201507) (xy 352.214752 -49.193673)
			(xy 352.24212 -49.193196) (xy 352.268434 -49.193651) (xy 352.320563 -49.200889) (xy 352.371206 -49.21521)
			(xy 352.419405 -49.236345) (xy 352.464248 -49.263893) (xy 352.504888 -49.297334) (xy 352.523044 -49.316386)
			(xy 352.530549 -49.323807) (xy 352.549842 -49.332321) (xy 352.560382 -49.332896) (xy 352.635058 -49.332896)
			(xy 352.645607 -49.332359) (xy 352.664902 -49.32383) (xy 352.672396 -49.316386) (xy 352.690558 -49.297337)
			(xy 352.731186 -49.26388) (xy 352.776026 -49.23632) (xy 352.824225 -49.215181) (xy 352.874871 -49.200862)
			(xy 352.927004 -49.193635) (xy 352.95332 -49.193196) (xy 352.980571 -49.193675) (xy 353.034517 -49.201434)
			(xy 353.08681 -49.216791) (xy 353.136385 -49.239434) (xy 353.182233 -49.268901) (xy 353.223422 -49.304593)
			(xy 353.259111 -49.345783) (xy 353.288576 -49.391633) (xy 353.311216 -49.441209) (xy 353.32657 -49.493503)
			(xy 353.334326 -49.547449) (xy 353.334326 -49.601951) (xy 353.32657 -49.655897) (xy 353.311216 -49.708191)
			(xy 353.288576 -49.757767) (xy 353.259111 -49.803617) (xy 353.223422 -49.844807) (xy 353.182233 -49.880499)
			(xy 353.136385 -49.909966) (xy 353.08681 -49.932609) (xy 353.034517 -49.947966) (xy 352.980571 -49.955725)
			(xy 352.95332 -49.956212) (xy 352.927007 -49.955727) (xy 352.874879 -49.948496) (xy 352.824237 -49.93418)
			(xy 352.776038 -49.91305) (xy 352.731194 -49.885507) (xy 352.690553 -49.852072) (xy 352.672396 -49.833022)
			(xy 352.664875 -49.82562) (xy 352.645595 -49.817095) (xy 352.635058 -49.816512) (xy 352.560382 -49.816512)
			(xy 352.549835 -49.817068) (xy 352.530539 -49.825584) (xy 352.523044 -49.833022) (xy 352.504913 -49.852102)
			(xy 352.464278 -49.885556) (xy 352.419432 -49.913111) (xy 352.371226 -49.934245) (xy 352.320575 -49.948558)
			(xy 352.268437 -49.955777) (xy 352.24212 -49.956212) (xy 352.21475 -49.955731) (xy 352.160572 -49.947917)
			(xy 352.108069 -49.932431) (xy 352.058322 -49.909592) (xy 352.012354 -49.879871) (xy 351.991422 -49.862232)
			(xy 351.991168 -49.861978) (xy 351.984068 -49.856411) (xy 351.967161 -49.850153) (xy 351.958148 -49.849786)
			(xy 351.891092 -49.849786) (xy 351.882075 -49.850142) (xy 351.865158 -49.856391) (xy 351.858072 -49.861978)
			(xy 351.858072 -49.862232) (xy 351.857818 -49.862232) (xy 351.836885 -49.879873) (xy 351.790917 -49.909597)
			(xy 351.741171 -49.932443) (xy 351.688669 -49.947939) (xy 351.634491 -49.955768) (xy 351.579749 -49.955768)
			(xy 351.525571 -49.947939) (xy 351.473069 -49.932443) (xy 351.423323 -49.909597) (xy 351.377355 -49.879873)
			(xy 351.356422 -49.862232) (xy 351.356168 -49.861978) (xy 351.349068 -49.856411) (xy 351.332161 -49.850153)
			(xy 351.323148 -49.849786) (xy 351.256092 -49.849786) (xy 351.247075 -49.850142) (xy 351.230158 -49.856391)
			(xy 351.223072 -49.861978) (xy 351.223072 -49.862232) (xy 351.222818 -49.862232) (xy 351.201894 -49.879881)
			(xy 351.155919 -49.90959) (xy 351.106169 -49.932424) (xy 351.053667 -49.947913) (xy 350.99949 -49.955739)
			(xy 350.97212 -49.956212) (xy 350.944867 -49.955742) (xy 350.890914 -49.947987) (xy 350.838614 -49.932633)
			(xy 350.789032 -49.909992) (xy 350.743177 -49.880525) (xy 350.701982 -49.844832) (xy 350.666287 -49.803639)
			(xy 350.636817 -49.757785) (xy 350.614174 -49.708204) (xy 350.598817 -49.655906) (xy 350.591059 -49.601953)
			(xy 349.70085 -49.601953) (xy 349.70085 -51.689048) (xy 350.5556 -51.689048) (xy 350.5556 -51.634552)
			(xy 350.563355 -51.580611) (xy 350.578707 -51.528323) (xy 350.601344 -51.478751) (xy 350.630805 -51.432905)
			(xy 350.66649 -51.391718) (xy 350.707673 -51.356029) (xy 350.753516 -51.326563) (xy 350.803085 -51.303921)
			(xy 350.855372 -51.288564) (xy 350.909312 -51.280803) (xy 350.93656 -51.280314) (xy 350.96393 -51.2808)
			(xy 351.018108 -51.288613) (xy 351.070611 -51.304097) (xy 351.120358 -51.326934) (xy 351.166326 -51.356655)
			(xy 351.187258 -51.374294) (xy 351.187512 -51.374548) (xy 351.194587 -51.380152) (xy 351.211513 -51.386387)
			(xy 351.220532 -51.38674) (xy 351.287588 -51.38674) (xy 351.296606 -51.38639) (xy 351.313523 -51.380139)
			(xy 351.320608 -51.374548) (xy 351.320608 -51.374294) (xy 351.320862 -51.374294) (xy 351.341797 -51.356658)
			(xy 351.387769 -51.326946) (xy 351.437516 -51.30411) (xy 351.490016 -51.288618) (xy 351.544191 -51.280789)
			(xy 351.57156 -51.280314) (xy 351.589903 -51.280549) (xy 351.626416 -51.28411) (xy 351.644458 -51.287426)
			(xy 351.655089 -51.289032) (xy 351.676009 -51.284156) (xy 351.684844 -51.278028) (xy 351.753932 -51.225704)
			(xy 351.764346 -51.206908) (xy 351.765108 -51.195986) (xy 351.76801 -51.167703) (xy 351.781047 -51.112366)
			(xy 351.802141 -51.059573) (xy 351.830828 -51.01049) (xy 351.866474 -50.9662) (xy 351.887028 -50.946558)
			(xy 351.89444 -50.939044) (xy 351.902961 -50.919759) (xy 351.903538 -50.90922) (xy 351.903538 -50.834544)
			(xy 351.902987 -50.823997) (xy 351.894466 -50.804702) (xy 351.887028 -50.797206) (xy 351.867988 -50.779035)
			(xy 351.834528 -50.738409) (xy 351.806966 -50.693572) (xy 351.785825 -50.645375) (xy 351.771505 -50.594729)
			(xy 351.764278 -50.542597) (xy 351.763838 -50.516282) (xy 351.764324 -50.489031) (xy 351.77208 -50.435083)
			(xy 351.787435 -50.382788) (xy 351.810077 -50.333211) (xy 351.839543 -50.287361) (xy 351.875234 -50.24617)
			(xy 351.916425 -50.210479) (xy 351.962275 -50.181013) (xy 352.011852 -50.158371) (xy 352.064147 -50.143016)
			(xy 352.118095 -50.13526) (xy 352.172597 -50.13526) (xy 352.226545 -50.143016) (xy 352.27884 -50.158371)
			(xy 352.328417 -50.181013) (xy 352.374267 -50.210479) (xy 352.415458 -50.24617) (xy 352.451149 -50.287361)
			(xy 352.480615 -50.333211) (xy 352.503257 -50.382788) (xy 352.518612 -50.435083) (xy 352.526368 -50.489031)
			(xy 352.526854 -50.516282) (xy 352.526389 -50.542596) (xy 352.519156 -50.594725) (xy 352.504837 -50.645369)
			(xy 352.483704 -50.693568) (xy 352.456157 -50.738411) (xy 352.422717 -50.77905) (xy 352.403664 -50.797206)
			(xy 352.396267 -50.804732) (xy 352.387738 -50.824008) (xy 352.387154 -50.834544) (xy 352.387154 -50.90922)
			(xy 352.387726 -50.919764) (xy 352.396233 -50.939059) (xy 352.403664 -50.946558) (xy 352.422753 -50.96468)
			(xy 352.456205 -51.005318) (xy 352.483758 -51.050166) (xy 352.50489 -51.098373) (xy 352.519201 -51.149026)
			(xy 352.526419 -51.201164) (xy 352.526854 -51.227482) (xy 352.526305 -51.254731) (xy 352.518552 -51.308674)
			(xy 352.503202 -51.360964) (xy 352.480566 -51.410538) (xy 352.451106 -51.456387) (xy 352.415421 -51.497576)
			(xy 352.374238 -51.533268) (xy 352.328395 -51.562735) (xy 352.278824 -51.585379) (xy 352.226536 -51.600739)
			(xy 352.172595 -51.608501) (xy 352.145346 -51.60899) (xy 352.127003 -51.608754) (xy 352.09049 -51.605193)
			(xy 352.072448 -51.601878) (xy 352.061816 -51.600294) (xy 352.0409 -51.605158) (xy 352.032062 -51.611276)
			(xy 351.962974 -51.6636) (xy 351.95256 -51.682396) (xy 351.951798 -51.693318) (xy 351.948861 -51.72157)
			(xy 351.93583 -51.776852) (xy 351.914749 -51.829592) (xy 351.886081 -51.878623) (xy 351.850462 -51.922863)
			(xy 351.808678 -51.961334) (xy 351.761652 -51.993185) (xy 351.710424 -52.017712) (xy 351.656126 -52.034375)
			(xy 351.599958 -52.042804) (xy 351.57156 -52.04333) (xy 351.54419 -52.042846) (xy 351.490011 -52.035035)
			(xy 351.437508 -52.019551) (xy 351.38776 -51.996713) (xy 351.341793 -51.966991) (xy 351.320862 -51.94935)
			(xy 351.320608 -51.949096) (xy 351.313524 -51.943506) (xy 351.296605 -51.937262) (xy 351.287588 -51.936904)
			(xy 351.220532 -51.936904) (xy 351.211517 -51.937275) (xy 351.194599 -51.943513) (xy 351.187512 -51.949096)
			(xy 351.187512 -51.94935) (xy 351.187258 -51.94935) (xy 351.166308 -51.966968) (xy 351.120341 -51.996684)
			(xy 351.070598 -52.019525) (xy 351.018101 -52.035021) (xy 350.963928 -52.042854) (xy 350.93656 -52.04333)
			(xy 350.909312 -52.042797) (xy 350.855372 -52.035036) (xy 350.803085 -52.019679) (xy 350.753516 -51.997037)
			(xy 350.707673 -51.967571) (xy 350.66649 -51.931882) (xy 350.630805 -51.890695) (xy 350.601344 -51.844849)
			(xy 350.578707 -51.795277) (xy 350.563355 -51.742989) (xy 350.5556 -51.689048) (xy 349.70085 -51.689048)
			(xy 349.70085 -52.564157) (xy 352.127207 -52.564157) (xy 352.127207 -52.509643) (xy 352.134965 -52.455684)
			(xy 352.150324 -52.403379) (xy 352.17297 -52.353792) (xy 352.202443 -52.307932) (xy 352.238142 -52.266734)
			(xy 352.279342 -52.231036) (xy 352.325202 -52.201564) (xy 352.37479 -52.17892) (xy 352.427096 -52.163563)
			(xy 352.481055 -52.155806) (xy 352.508312 -52.155344) (xy 352.535683 -52.155792) (xy 352.589863 -52.163613)
			(xy 352.642367 -52.179105) (xy 352.692114 -52.201951) (xy 352.738079 -52.23168) (xy 352.75901 -52.249324)
			(xy 352.759264 -52.249578) (xy 352.76635 -52.255165) (xy 352.783268 -52.261409) (xy 352.792284 -52.26177)
			(xy 352.85934 -52.26177) (xy 352.86836 -52.261439) (xy 352.885277 -52.255174) (xy 352.89236 -52.249578)
			(xy 352.89236 -52.249324) (xy 352.892614 -52.249324) (xy 352.913571 -52.231715) (xy 352.959536 -52.201998)
			(xy 353.009278 -52.179156) (xy 353.061773 -52.163658) (xy 353.115944 -52.155822) (xy 353.143312 -52.155344)
			(xy 353.170559 -52.155927) (xy 353.224499 -52.163684) (xy 353.276785 -52.179038) (xy 353.326355 -52.201677)
			(xy 353.372198 -52.23114) (xy 353.413382 -52.266827) (xy 353.449067 -52.308012) (xy 353.478529 -52.353856)
			(xy 353.501166 -52.403426) (xy 353.516519 -52.455713) (xy 353.524274 -52.509653) (xy 353.524274 -52.564147)
			(xy 353.516519 -52.618087) (xy 353.501166 -52.670374) (xy 353.478529 -52.719944) (xy 353.449067 -52.765788)
			(xy 353.413382 -52.806973) (xy 353.372198 -52.84266) (xy 353.326355 -52.872123) (xy 353.276785 -52.894762)
			(xy 353.224499 -52.910116) (xy 353.170559 -52.917873) (xy 353.143312 -52.91836) (xy 353.115942 -52.917897)
			(xy 353.061762 -52.91008) (xy 353.009258 -52.89459) (xy 352.959512 -52.871748) (xy 352.913545 -52.842022)
			(xy 352.892614 -52.82438) (xy 352.89236 -52.824126) (xy 352.885267 -52.81855) (xy 352.868355 -52.812299)
			(xy 352.85934 -52.811934) (xy 352.792284 -52.811934) (xy 352.783265 -52.812276) (xy 352.766348 -52.818533)
			(xy 352.759264 -52.824126) (xy 352.759264 -52.82438) (xy 352.75901 -52.82438) (xy 352.738082 -52.842025)
			(xy 352.692109 -52.871736) (xy 352.64236 -52.894572) (xy 352.589858 -52.910061) (xy 352.535682 -52.917887)
			(xy 352.508312 -52.91836) (xy 352.481055 -52.917994) (xy 352.427096 -52.910237) (xy 352.37479 -52.89488)
			(xy 352.325202 -52.872236) (xy 352.279342 -52.842764) (xy 352.238142 -52.807066) (xy 352.202443 -52.765868)
			(xy 352.17297 -52.720008) (xy 352.150324 -52.670421) (xy 352.134965 -52.618116) (xy 352.127207 -52.564157)
			(xy 349.70085 -52.564157) (xy 349.70085 -54.238906) (xy 356.686102 -54.238906) (xy 356.690173 -54.183284)
			(xy 356.702299 -54.128847) (xy 356.722222 -54.076756) (xy 356.749518 -54.028121) (xy 356.783604 -53.983978)
			(xy 356.823753 -53.945269) (xy 356.869111 -53.912818) (xy 356.918711 -53.887317) (xy 356.971495 -53.86931)
			(xy 357.026338 -53.85918) (xy 357.082072 -53.857143) (xy 357.137509 -53.863243) (xy 357.191466 -53.877349)
			(xy 357.242795 -53.899161) (xy 357.290401 -53.928215) (xy 357.333269 -53.96389) (xy 357.370486 -54.005427)
			(xy 357.401259 -54.05194) (xy 357.424931 -54.102437) (xy 357.440999 -54.155844) (xy 357.449119 -54.21102)
			(xy 357.449628 -54.238906) (xy 357.449119 -54.266792) (xy 357.440999 -54.321968) (xy 357.424931 -54.375375)
			(xy 357.401259 -54.425872) (xy 357.370486 -54.472385) (xy 357.333269 -54.513922) (xy 357.290401 -54.549597)
			(xy 357.242795 -54.578651) (xy 357.191466 -54.600463) (xy 357.137509 -54.614569) (xy 357.082072 -54.620669)
			(xy 357.026338 -54.618632) (xy 356.971495 -54.608502) (xy 356.918711 -54.590495) (xy 356.869111 -54.564994)
			(xy 356.823753 -54.532543) (xy 356.783604 -54.493834) (xy 356.749518 -54.449691) (xy 356.722222 -54.401056)
			(xy 356.702299 -54.348965) (xy 356.690173 -54.294528) (xy 356.686102 -54.238906) (xy 349.70085 -54.238906)
			(xy 349.70085 -54.989055) (xy 352.201145 -54.989055) (xy 352.201145 -54.934545) (xy 352.208903 -54.880591)
			(xy 352.224261 -54.828289) (xy 352.246906 -54.778706) (xy 352.276377 -54.73285) (xy 352.312074 -54.691656)
			(xy 352.353271 -54.655961) (xy 352.399129 -54.626493) (xy 352.448714 -54.603851) (xy 352.501016 -54.588497)
			(xy 352.554971 -54.580743) (xy 352.582226 -54.580282) (xy 352.610318 -54.580756) (xy 352.665896 -54.588987)
			(xy 352.719666 -54.605282) (xy 352.770463 -54.629288) (xy 352.81719 -54.660486) (xy 352.858835 -54.698201)
			(xy 352.894496 -54.741616) (xy 352.909378 -54.765448) (xy 352.914712 -54.774338) (xy 352.93173 -54.78653)
			(xy 353.024948 -54.80685) (xy 353.045522 -54.802532) (xy 353.054158 -54.79669) (xy 353.078231 -54.780705)
			(xy 353.130159 -54.755359) (xy 353.185314 -54.738129) (xy 353.242436 -54.729409) (xy 353.271328 -54.728872)
			(xy 353.298579 -54.729352) (xy 353.352526 -54.737112) (xy 353.40482 -54.752469) (xy 353.454396 -54.775112)
			(xy 353.500245 -54.804579) (xy 353.541434 -54.840271) (xy 353.577125 -54.881462) (xy 353.606592 -54.927311)
			(xy 353.629234 -54.976888) (xy 353.64459 -55.029182) (xy 353.652349 -55.083129) (xy 353.652836 -55.11038)
			(xy 353.652374 -55.137751) (xy 353.644557 -55.19193) (xy 353.629068 -55.244434) (xy 353.606225 -55.294181)
			(xy 353.576499 -55.340147) (xy 353.558856 -55.361078) (xy 353.558602 -55.361332) (xy 353.553038 -55.368434)
			(xy 353.546778 -55.385339) (xy 353.54641 -55.394352) (xy 353.54641 -55.461408) (xy 353.546761 -55.470426)
			(xy 353.553012 -55.487343) (xy 353.558602 -55.494428) (xy 353.558856 -55.494428) (xy 353.558856 -55.494682)
			(xy 353.576478 -55.51563) (xy 353.606205 -55.561595) (xy 353.629052 -55.611339) (xy 353.644551 -55.663838)
			(xy 353.652382 -55.718015) (xy 353.652384 -55.772755) (xy 353.644557 -55.826932) (xy 353.629063 -55.879433)
			(xy 353.606219 -55.929179) (xy 353.576496 -55.975146) (xy 353.558856 -55.996078) (xy 353.558602 -55.996332)
			(xy 353.553038 -56.003434) (xy 353.546778 -56.020339) (xy 353.54641 -56.029352) (xy 353.54641 -56.096408)
			(xy 353.546761 -56.105426) (xy 353.553012 -56.122343) (xy 353.558602 -56.129428) (xy 353.558856 -56.129428)
			(xy 353.558856 -56.129682) (xy 353.576493 -56.150616) (xy 353.606207 -56.196587) (xy 353.629044 -56.246334)
			(xy 353.644535 -56.298835) (xy 353.652363 -56.353011) (xy 353.652836 -56.38038) (xy 353.65235 -56.407631)
			(xy 353.644594 -56.461579) (xy 353.629239 -56.513874) (xy 353.606597 -56.563451) (xy 353.577131 -56.609301)
			(xy 353.54144 -56.650492) (xy 353.500249 -56.686183) (xy 353.454399 -56.715649) (xy 353.404822 -56.738291)
			(xy 353.352527 -56.753646) (xy 353.298579 -56.761402) (xy 353.244077 -56.761402) (xy 353.190129 -56.753646)
			(xy 353.137834 -56.738291) (xy 353.088257 -56.715649) (xy 353.042407 -56.686183) (xy 353.001216 -56.650492)
			(xy 352.965525 -56.609301) (xy 352.936059 -56.563451) (xy 352.913417 -56.513874) (xy 352.898062 -56.461579)
			(xy 352.890306 -56.407631) (xy 352.88982 -56.38038) (xy 352.890269 -56.353009) (xy 352.898091 -56.298829)
			(xy 352.913583 -56.246326) (xy 352.936429 -56.196579) (xy 352.966157 -56.150613) (xy 352.9838 -56.129682)
			(xy 352.984054 -56.129428) (xy 352.989641 -56.122342) (xy 352.995886 -56.105425) (xy 352.996246 -56.096408)
			(xy 352.996246 -56.029352) (xy 352.995876 -56.020336) (xy 352.989639 -56.003418) (xy 352.984054 -55.996332)
			(xy 352.9838 -55.996332) (xy 352.9838 -55.996078) (xy 352.966141 -55.975161) (xy 352.936419 -55.929189)
			(xy 352.913576 -55.879441) (xy 352.898083 -55.826936) (xy 352.890257 -55.772756) (xy 352.890259 -55.718014)
			(xy 352.898089 -55.663834) (xy 352.913587 -55.611331) (xy 352.936433 -55.561584) (xy 352.966159 -55.515615)
			(xy 352.9838 -55.494682) (xy 352.984054 -55.494428) (xy 352.989641 -55.487342) (xy 352.995886 -55.470425)
			(xy 352.996246 -55.461408) (xy 352.996246 -55.394352) (xy 352.995876 -55.385336) (xy 352.989639 -55.368418)
			(xy 352.984054 -55.361332) (xy 352.9838 -55.360824) (xy 352.972856 -55.348089) (xy 352.953015 -55.320998)
			(xy 352.944176 -55.306722) (xy 352.938842 -55.297832) (xy 352.921824 -55.28564) (xy 352.828606 -55.26532)
			(xy 352.808032 -55.269638) (xy 352.799396 -55.27548) (xy 352.775333 -55.291482) (xy 352.723402 -55.316825)
			(xy 352.668243 -55.33405) (xy 352.611119 -55.342764) (xy 352.582226 -55.343298) (xy 352.554971 -55.342857)
			(xy 352.501016 -55.335103) (xy 352.448714 -55.319749) (xy 352.399129 -55.297107) (xy 352.353271 -55.267639)
			(xy 352.312074 -55.231944) (xy 352.276377 -55.19075) (xy 352.246906 -55.144894) (xy 352.224261 -55.095311)
			(xy 352.208903 -55.043009) (xy 352.201145 -54.989055) (xy 349.70085 -54.989055) (xy 349.70085 -55.420855)
			(xy 350.524745 -55.420855) (xy 350.524745 -55.366345) (xy 350.532503 -55.312391) (xy 350.547861 -55.260089)
			(xy 350.570506 -55.210506) (xy 350.599977 -55.16465) (xy 350.635674 -55.123456) (xy 350.676871 -55.087761)
			(xy 350.722729 -55.058293) (xy 350.772314 -55.035651) (xy 350.824616 -55.020297) (xy 350.878571 -55.012543)
			(xy 350.905826 -55.012082) (xy 350.93214 -55.012538) (xy 350.984269 -55.019776) (xy 351.034912 -55.034098)
			(xy 351.083111 -55.055232) (xy 351.127954 -55.08278) (xy 351.168593 -55.11622) (xy 351.18675 -55.135272)
			(xy 351.194255 -55.142694) (xy 351.213547 -55.151208) (xy 351.224088 -55.151782) (xy 351.298764 -55.151782)
			(xy 351.309314 -55.151252) (xy 351.32861 -55.142718) (xy 351.336102 -55.135272) (xy 351.354258 -55.116217)
			(xy 351.394888 -55.082761) (xy 351.439729 -55.055203) (xy 351.487929 -55.034064) (xy 351.538576 -55.019747)
			(xy 351.59071 -55.012521) (xy 351.617026 -55.012082) (xy 351.644275 -55.01259) (xy 351.698219 -55.020349)
			(xy 351.750509 -55.035706) (xy 351.800082 -55.058348) (xy 351.845927 -55.087814) (xy 351.887113 -55.123505)
			(xy 351.922801 -55.164693) (xy 351.952264 -55.210541) (xy 351.974903 -55.260115) (xy 351.990256 -55.312407)
			(xy 351.998012 -55.366351) (xy 351.998012 -55.420849) (xy 351.990256 -55.474793) (xy 351.974903 -55.527085)
			(xy 351.952264 -55.576659) (xy 351.922801 -55.622507) (xy 351.887113 -55.663695) (xy 351.845927 -55.699386)
			(xy 351.800082 -55.728852) (xy 351.750509 -55.751494) (xy 351.698219 -55.766851) (xy 351.644275 -55.77461)
			(xy 351.617026 -55.775098) (xy 351.590713 -55.774614) (xy 351.538585 -55.767383) (xy 351.487942 -55.753067)
			(xy 351.439743 -55.731937) (xy 351.394899 -55.704394) (xy 351.354259 -55.670958) (xy 351.336102 -55.651908)
			(xy 351.32858 -55.644507) (xy 351.3093 -55.635982) (xy 351.298764 -55.635398) (xy 351.224088 -55.635398)
			(xy 351.213536 -55.635908) (xy 351.194241 -55.644457) (xy 351.18675 -55.651908) (xy 351.168613 -55.670982)
			(xy 351.127979 -55.704437) (xy 351.083135 -55.731994) (xy 351.034931 -55.753129) (xy 350.98428 -55.767442)
			(xy 350.932143 -55.774662) (xy 350.905826 -55.775098) (xy 350.878571 -55.774657) (xy 350.824616 -55.766903)
			(xy 350.772314 -55.751549) (xy 350.722729 -55.728907) (xy 350.676871 -55.699439) (xy 350.635674 -55.663744)
			(xy 350.599977 -55.62255) (xy 350.570506 -55.576694) (xy 350.547861 -55.527111) (xy 350.532503 -55.474809)
			(xy 350.524745 -55.420855) (xy 349.70085 -55.420855) (xy 349.70085 -57.48528) (xy 352.906074 -57.48528)
			(xy 352.910145 -57.429658) (xy 352.922271 -57.375221) (xy 352.942194 -57.32313) (xy 352.96949 -57.274495)
			(xy 353.003576 -57.230352) (xy 353.043725 -57.191643) (xy 353.089083 -57.159192) (xy 353.138683 -57.133691)
			(xy 353.191467 -57.115684) (xy 353.24631 -57.105554) (xy 353.302044 -57.103517) (xy 353.357481 -57.109617)
			(xy 353.411438 -57.123723) (xy 353.462767 -57.145535) (xy 353.510373 -57.174589) (xy 353.553241 -57.210264)
			(xy 353.590458 -57.251801) (xy 353.621231 -57.298314) (xy 353.644903 -57.348811) (xy 353.660971 -57.402218)
			(xy 353.669091 -57.457394) (xy 353.6696 -57.48528) (xy 353.669091 -57.513166) (xy 353.660971 -57.568342)
			(xy 353.644903 -57.621749) (xy 353.621231 -57.672246) (xy 353.590458 -57.718759) (xy 353.553241 -57.760296)
			(xy 353.510373 -57.795971) (xy 353.462767 -57.825025) (xy 353.411438 -57.846837) (xy 353.357481 -57.860943)
			(xy 353.302044 -57.867043) (xy 353.24631 -57.865006) (xy 353.191467 -57.854876) (xy 353.138683 -57.836869)
			(xy 353.089083 -57.811368) (xy 353.043725 -57.778917) (xy 353.003576 -57.740208) (xy 352.96949 -57.696065)
			(xy 352.942194 -57.64743) (xy 352.922271 -57.595339) (xy 352.910145 -57.540902) (xy 352.906074 -57.48528)
			(xy 349.70085 -57.48528) (xy 349.70085 -58.076084) (xy 353.658168 -58.076084) (xy 353.662239 -58.020462)
			(xy 353.674365 -57.966025) (xy 353.694288 -57.913934) (xy 353.721584 -57.865299) (xy 353.75567 -57.821156)
			(xy 353.795819 -57.782447) (xy 353.841177 -57.749996) (xy 353.890777 -57.724495) (xy 353.943561 -57.706488)
			(xy 353.998404 -57.696358) (xy 354.054138 -57.694321) (xy 354.109575 -57.700421) (xy 354.163532 -57.714527)
			(xy 354.214861 -57.736339) (xy 354.262467 -57.765393) (xy 354.305335 -57.801068) (xy 354.342552 -57.842605)
			(xy 354.358888 -57.867296) (xy 355.942898 -57.867296) (xy 355.946971 -57.811637) (xy 355.959106 -57.757164)
			(xy 355.979042 -57.705038) (xy 356.006356 -57.65637) (xy 356.040464 -57.612198) (xy 356.080641 -57.573463)
			(xy 356.126029 -57.540991) (xy 356.175661 -57.515473) (xy 356.228481 -57.497454) (xy 356.28336 -57.487317)
			(xy 356.339131 -57.485279) (xy 356.394605 -57.491382) (xy 356.448598 -57.505498) (xy 356.499961 -57.527325)
			(xy 356.547599 -57.556398) (xy 356.590495 -57.592097) (xy 356.627737 -57.633661) (xy 356.658531 -57.680205)
			(xy 356.682219 -57.730736) (xy 356.698297 -57.784178) (xy 356.706423 -57.839392) (xy 356.706932 -57.867296)
			(xy 356.706423 -57.8952) (xy 356.698297 -57.950414) (xy 356.682219 -58.003856) (xy 356.658531 -58.054387)
			(xy 356.627737 -58.100931) (xy 356.590495 -58.142495) (xy 356.547599 -58.178194) (xy 356.499961 -58.207267)
			(xy 356.448598 -58.229094) (xy 356.394605 -58.24321) (xy 356.339131 -58.249313) (xy 356.28336 -58.247275)
			(xy 356.228481 -58.237138) (xy 356.175661 -58.219119) (xy 356.126029 -58.193601) (xy 356.080641 -58.161129)
			(xy 356.040464 -58.122394) (xy 356.006356 -58.078222) (xy 355.979042 -58.029554) (xy 355.959106 -57.977428)
			(xy 355.946971 -57.922955) (xy 355.942898 -57.867296) (xy 354.358888 -57.867296) (xy 354.373325 -57.889118)
			(xy 354.396997 -57.939615) (xy 354.413065 -57.993022) (xy 354.421185 -58.048198) (xy 354.421694 -58.076084)
			(xy 354.421185 -58.10397) (xy 354.413065 -58.159146) (xy 354.396997 -58.212553) (xy 354.373325 -58.26305)
			(xy 354.342552 -58.309563) (xy 354.305335 -58.3511) (xy 354.262467 -58.386775) (xy 354.214861 -58.415829)
			(xy 354.163532 -58.437641) (xy 354.109575 -58.451747) (xy 354.054138 -58.457847) (xy 353.998404 -58.45581)
			(xy 353.943561 -58.44568) (xy 353.890777 -58.427673) (xy 353.841177 -58.402172) (xy 353.795819 -58.369721)
			(xy 353.75567 -58.331012) (xy 353.721584 -58.286869) (xy 353.694288 -58.238234) (xy 353.674365 -58.186143)
			(xy 353.662239 -58.131706) (xy 353.658168 -58.076084) (xy 349.70085 -58.076084) (xy 349.70085 -58.561224)
			(xy 354.862382 -58.561224) (xy 354.866453 -58.505602) (xy 354.878579 -58.451165) (xy 354.898502 -58.399074)
			(xy 354.925798 -58.350439) (xy 354.959884 -58.306296) (xy 355.000033 -58.267587) (xy 355.045391 -58.235136)
			(xy 355.094991 -58.209635) (xy 355.147775 -58.191628) (xy 355.202618 -58.181498) (xy 355.258352 -58.179461)
			(xy 355.313789 -58.185561) (xy 355.367746 -58.199667) (xy 355.419075 -58.221479) (xy 355.466681 -58.250533)
			(xy 355.509549 -58.286208) (xy 355.546766 -58.327745) (xy 355.577539 -58.374258) (xy 355.601211 -58.424755)
			(xy 355.608721 -58.449718) (xy 357.109012 -58.449718) (xy 357.113083 -58.394096) (xy 357.125209 -58.339659)
			(xy 357.145132 -58.287568) (xy 357.172428 -58.238933) (xy 357.206514 -58.19479) (xy 357.246663 -58.156081)
			(xy 357.292021 -58.12363) (xy 357.341621 -58.098129) (xy 357.394405 -58.080122) (xy 357.449248 -58.069992)
			(xy 357.504982 -58.067955) (xy 357.560419 -58.074055) (xy 357.614376 -58.088161) (xy 357.665705 -58.109973)
			(xy 357.713311 -58.139027) (xy 357.756179 -58.174702) (xy 357.793396 -58.216239) (xy 357.824169 -58.262752)
			(xy 357.847841 -58.313249) (xy 357.863909 -58.366656) (xy 357.872029 -58.421832) (xy 357.872538 -58.449718)
			(xy 357.872029 -58.477604) (xy 357.863909 -58.53278) (xy 357.847841 -58.586187) (xy 357.824169 -58.636684)
			(xy 357.793396 -58.683197) (xy 357.756179 -58.724734) (xy 357.713311 -58.760409) (xy 357.665705 -58.789463)
			(xy 357.614376 -58.811275) (xy 357.560419 -58.825381) (xy 357.504982 -58.831481) (xy 357.449248 -58.829444)
			(xy 357.394405 -58.819314) (xy 357.341621 -58.801307) (xy 357.292021 -58.775806) (xy 357.246663 -58.743355)
			(xy 357.206514 -58.704646) (xy 357.172428 -58.660503) (xy 357.145132 -58.611868) (xy 357.125209 -58.559777)
			(xy 357.113083 -58.50534) (xy 357.109012 -58.449718) (xy 355.608721 -58.449718) (xy 355.617279 -58.478162)
			(xy 355.625399 -58.533338) (xy 355.625908 -58.561224) (xy 355.625399 -58.58911) (xy 355.617279 -58.644286)
			(xy 355.601211 -58.697693) (xy 355.577539 -58.74819) (xy 355.546766 -58.794703) (xy 355.509549 -58.83624)
			(xy 355.466681 -58.871915) (xy 355.419075 -58.900969) (xy 355.367746 -58.922781) (xy 355.313789 -58.936887)
			(xy 355.258352 -58.942987) (xy 355.202618 -58.94095) (xy 355.147775 -58.93082) (xy 355.094991 -58.912813)
			(xy 355.045391 -58.887312) (xy 355.000033 -58.854861) (xy 354.959884 -58.816152) (xy 354.925798 -58.772009)
			(xy 354.898502 -58.723374) (xy 354.878579 -58.671283) (xy 354.866453 -58.616846) (xy 354.862382 -58.561224)
			(xy 349.70085 -58.561224) (xy 349.70085 -59.974734) (xy 353.387152 -59.974734) (xy 353.387561 -59.947906)
			(xy 353.395082 -59.89478) (xy 353.409968 -59.843229) (xy 353.431925 -59.794271) (xy 353.46052 -59.74887)
			(xy 353.49519 -59.707919) (xy 353.535252 -59.672225) (xy 353.557332 -59.65698) (xy 353.568897 -59.648762)
			(xy 353.5873 -59.627181) (xy 353.599051 -59.601369) (xy 353.603245 -59.573319) (xy 353.599557 -59.545199)
			(xy 353.588273 -59.519179) (xy 353.570262 -59.49727) (xy 353.558856 -59.488832) (xy 353.537395 -59.473486)
			(xy 353.498483 -59.437857) (xy 353.464852 -59.397206) (xy 353.437142 -59.35231) (xy 353.415882 -59.304024)
			(xy 353.401478 -59.253269) (xy 353.394204 -59.201014) (xy 353.393756 -59.174634) (xy 353.394242 -59.147383)
			(xy 353.401998 -59.093435) (xy 353.417353 -59.04114) (xy 353.439995 -58.991563) (xy 353.469461 -58.945713)
			(xy 353.505152 -58.904522) (xy 353.546343 -58.868831) (xy 353.592193 -58.839365) (xy 353.64177 -58.816723)
			(xy 353.694065 -58.801368) (xy 353.748013 -58.793612) (xy 353.802515 -58.793612) (xy 353.856463 -58.801368)
			(xy 353.908758 -58.816723) (xy 353.958335 -58.839365) (xy 354.004185 -58.868831) (xy 354.045376 -58.904522)
			(xy 354.081067 -58.945713) (xy 354.110533 -58.991563) (xy 354.133175 -59.04114) (xy 354.14853 -59.093435)
			(xy 354.156286 -59.147383) (xy 354.156772 -59.174634) (xy 354.156328 -59.201461) (xy 354.148812 -59.254585)
			(xy 354.133931 -59.306134) (xy 354.11198 -59.355092) (xy 354.083391 -59.400494) (xy 354.048726 -59.441446)
			(xy 354.00867 -59.477141) (xy 353.986592 -59.492388) (xy 353.975055 -59.500645) (xy 353.95665 -59.522216)
			(xy 353.944894 -59.54802) (xy 353.940695 -59.576063) (xy 353.944378 -59.604178) (xy 353.955658 -59.630194)
			(xy 353.973664 -59.652099) (xy 353.985068 -59.660536) (xy 354.006567 -59.675832) (xy 354.045476 -59.711471)
			(xy 354.079104 -59.75213) (xy 354.106809 -59.797035) (xy 354.128062 -59.845329) (xy 354.142459 -59.896091)
			(xy 354.149724 -59.948352) (xy 354.150168 -59.974734) (xy 354.149682 -60.001985) (xy 354.141926 -60.055933)
			(xy 354.126571 -60.108228) (xy 354.103929 -60.157805) (xy 354.074463 -60.203655) (xy 354.038772 -60.244846)
			(xy 353.997581 -60.280537) (xy 353.951731 -60.310003) (xy 353.902154 -60.332645) (xy 353.849859 -60.348)
			(xy 353.795911 -60.355756) (xy 353.741409 -60.355756) (xy 353.687461 -60.348) (xy 353.635166 -60.332645)
			(xy 353.585589 -60.310003) (xy 353.539739 -60.280537) (xy 353.498548 -60.244846) (xy 353.462857 -60.203655)
			(xy 353.433391 -60.157805) (xy 353.410749 -60.108228) (xy 353.395394 -60.055933) (xy 353.387638 -60.001985)
			(xy 353.387152 -59.974734) (xy 349.70085 -59.974734) (xy 349.70085 -60.601606) (xy 352.633278 -60.601606)
			(xy 352.637349 -60.545984) (xy 352.649475 -60.491547) (xy 352.669398 -60.439456) (xy 352.696694 -60.390821)
			(xy 352.73078 -60.346678) (xy 352.770929 -60.307969) (xy 352.816287 -60.275518) (xy 352.865887 -60.250017)
			(xy 352.918671 -60.23201) (xy 352.973514 -60.22188) (xy 353.029248 -60.219843) (xy 353.084685 -60.225943)
			(xy 353.138642 -60.240049) (xy 353.189971 -60.261861) (xy 353.237577 -60.290915) (xy 353.280445 -60.32659)
			(xy 353.317662 -60.368127) (xy 353.348435 -60.41464) (xy 353.372107 -60.465137) (xy 353.388175 -60.518544)
			(xy 353.396295 -60.57372) (xy 353.396804 -60.601606) (xy 353.39634 -60.627006) (xy 355.021386 -60.627006)
			(xy 355.025457 -60.571384) (xy 355.037583 -60.516947) (xy 355.057506 -60.464856) (xy 355.084802 -60.416221)
			(xy 355.118888 -60.372078) (xy 355.159037 -60.333369) (xy 355.204395 -60.300918) (xy 355.253995 -60.275417)
			(xy 355.306779 -60.25741) (xy 355.361622 -60.24728) (xy 355.417356 -60.245243) (xy 355.472793 -60.251343)
			(xy 355.52675 -60.265449) (xy 355.578079 -60.287261) (xy 355.625685 -60.316315) (xy 355.668553 -60.35199)
			(xy 355.70577 -60.393527) (xy 355.736543 -60.44004) (xy 355.760215 -60.490537) (xy 355.776283 -60.543944)
			(xy 355.784403 -60.59912) (xy 355.784912 -60.627006) (xy 355.784796 -60.633356) (xy 357.113076 -60.633356)
			(xy 357.117147 -60.577734) (xy 357.129273 -60.523297) (xy 357.149196 -60.471206) (xy 357.176492 -60.422571)
			(xy 357.210578 -60.378428) (xy 357.250727 -60.339719) (xy 357.296085 -60.307268) (xy 357.345685 -60.281767)
			(xy 357.398469 -60.26376) (xy 357.453312 -60.25363) (xy 357.509046 -60.251593) (xy 357.564483 -60.257693)
			(xy 357.61844 -60.271799) (xy 357.669769 -60.293611) (xy 357.717375 -60.322665) (xy 357.760243 -60.35834)
			(xy 357.79746 -60.399877) (xy 357.828233 -60.44639) (xy 357.851905 -60.496887) (xy 357.867973 -60.550294)
			(xy 357.876093 -60.60547) (xy 357.876602 -60.633356) (xy 357.876093 -60.661242) (xy 357.867973 -60.716418)
			(xy 357.851905 -60.769825) (xy 357.828233 -60.820322) (xy 357.79746 -60.866835) (xy 357.760243 -60.908372)
			(xy 357.717375 -60.944047) (xy 357.669769 -60.973101) (xy 357.61844 -60.994913) (xy 357.564483 -61.009019)
			(xy 357.509046 -61.015119) (xy 357.453312 -61.013082) (xy 357.398469 -61.002952) (xy 357.345685 -60.984945)
			(xy 357.296085 -60.959444) (xy 357.250727 -60.926993) (xy 357.210578 -60.888284) (xy 357.176492 -60.844141)
			(xy 357.149196 -60.795506) (xy 357.129273 -60.743415) (xy 357.117147 -60.688978) (xy 357.113076 -60.633356)
			(xy 355.784796 -60.633356) (xy 355.784403 -60.654892) (xy 355.776283 -60.710068) (xy 355.760215 -60.763475)
			(xy 355.736543 -60.813972) (xy 355.70577 -60.860485) (xy 355.668553 -60.902022) (xy 355.625685 -60.937697)
			(xy 355.578079 -60.966751) (xy 355.52675 -60.988563) (xy 355.472793 -61.002669) (xy 355.417356 -61.008769)
			(xy 355.361622 -61.006732) (xy 355.306779 -60.996602) (xy 355.253995 -60.978595) (xy 355.204395 -60.953094)
			(xy 355.159037 -60.920643) (xy 355.118888 -60.881934) (xy 355.084802 -60.837791) (xy 355.057506 -60.789156)
			(xy 355.037583 -60.737065) (xy 355.025457 -60.682628) (xy 355.021386 -60.627006) (xy 353.39634 -60.627006)
			(xy 353.396295 -60.629492) (xy 353.388175 -60.684668) (xy 353.372107 -60.738075) (xy 353.348435 -60.788572)
			(xy 353.317662 -60.835085) (xy 353.280445 -60.876622) (xy 353.237577 -60.912297) (xy 353.189971 -60.941351)
			(xy 353.138642 -60.963163) (xy 353.084685 -60.977269) (xy 353.029248 -60.983369) (xy 352.973514 -60.981332)
			(xy 352.918671 -60.971202) (xy 352.865887 -60.953195) (xy 352.816287 -60.927694) (xy 352.770929 -60.895243)
			(xy 352.73078 -60.856534) (xy 352.696694 -60.812391) (xy 352.669398 -60.763756) (xy 352.649475 -60.711665)
			(xy 352.637349 -60.657228) (xy 352.633278 -60.601606) (xy 349.70085 -60.601606) (xy 349.70085 -61.333126)
			(xy 349.701866 -61.342524) (xy 349.701866 -61.343032) (xy 349.703575 -61.350189) (xy 349.710414 -61.363209)
			(xy 349.715328 -61.368686) (xy 349.908876 -61.562234) (xy 349.91548 -61.567822) (xy 349.918825 -61.570112)
			(xy 349.926102 -61.573683) (xy 349.929958 -61.574934) (xy 349.930466 -61.574934) (xy 349.933768 -61.57595)
			(xy 349.938594 -61.575696) (xy 349.963486 -61.57468) (xy 352.483674 -61.57468) (xy 352.51263 -61.57595)
			(xy 352.513646 -61.57595) (xy 352.519234 -61.576458) (xy 352.519488 -61.576458) (xy 352.52406 -61.576966)
			(xy 353.323906 -61.576966)
		)
		(stroke
			(width 0)
			(type solid)
		)
		(fill yes)
		(layer "In9.Cu")
		(net "P3V3_SSD12")
	)
	(gr_poly
		(pts
			(xy 147.116292 -61.57595) (xy 147.128834 -61.57396) (xy 147.15414 -61.571799) (xy 147.166838 -61.571632)
			(xy 148.303742 -61.571632) (xy 148.313529 -61.571186) (xy 148.331685 -61.563871) (xy 148.339048 -61.557408)
			(xy 148.39188 -61.506608) (xy 148.400008 -61.488828) (xy 148.400262 -61.478668) (xy 148.401901 -61.449065)
			(xy 148.413202 -61.390867) (xy 148.433379 -61.335121) (xy 148.461945 -61.283172) (xy 148.498211 -61.236273)
			(xy 148.519388 -61.215524) (xy 148.519896 -61.215016) (xy 148.521674 -61.213238) (xy 148.543128 -61.193275)
			(xy 148.591022 -61.159506) (xy 148.643518 -61.133462) (xy 148.699381 -61.115757) (xy 148.757295 -61.106806)
			(xy 148.786596 -61.106304) (xy 148.813619 -61.106773) (xy 148.867125 -61.114398) (xy 148.919019 -61.129497)
			(xy 148.968264 -61.151766) (xy 149.013874 -61.180761) (xy 149.054936 -61.215901) (xy 149.09063 -61.256484)
			(xy 149.120241 -61.301696) (xy 149.143176 -61.350635) (xy 149.158976 -61.40232) (xy 149.167326 -61.455717)
			(xy 149.168104 -61.482732) (xy 149.168358 -61.492892) (xy 149.176232 -61.511434) (xy 149.223984 -61.557408)
			(xy 149.231336 -61.563888) (xy 149.249499 -61.571195) (xy 149.25929 -61.571632) (xy 152.875742 -61.571632)
			(xy 152.879716 -61.569717) (xy 152.887 -61.564741) (xy 152.89022 -61.561726) (xy 153.516584 -60.935108)
			(xy 153.523398 -60.927764) (xy 153.531136 -60.909302) (xy 153.53157 -60.899294) (xy 153.53157 -38.905688)
			(xy 153.530808 -38.896544) (xy 153.529792 -38.890956) (xy 153.528129 -38.883381) (xy 153.520886 -38.869677)
			(xy 153.515568 -38.864032) (xy 153.513282 -38.861746) (xy 153.512012 -38.86073) (xy 153.480124 -38.832049)
			(xy 153.421146 -38.769771) (xy 153.368086 -38.702379) (xy 153.321386 -38.630434) (xy 153.281433 -38.554534)
			(xy 153.24856 -38.47531) (xy 153.223041 -38.393422) (xy 153.205087 -38.309549) (xy 153.194849 -38.224389)
			(xy 153.192409 -38.138651) (xy 153.197791 -38.053047) (xy 153.210947 -37.968289) (xy 153.23177 -37.885082)
			(xy 153.260086 -37.804118) (xy 153.295659 -37.726069) (xy 153.338193 -37.651586) (xy 153.387336 -37.581286)
			(xy 153.442678 -37.515756) (xy 153.472896 -37.48532) (xy 153.473404 -37.484812) (xy 153.503122 -37.456364)
			(xy 153.50363 -37.455856) (xy 153.512266 -37.448236) (xy 153.51252 -37.447982) (xy 153.514552 -37.446204)
			(xy 153.522168 -37.438637) (xy 153.530963 -37.419078) (xy 153.53157 -37.408358) (xy 153.53157 -31.77667)
			(xy 153.528776 -31.768542) (xy 153.518737 -31.737951) (xy 153.507889 -31.674493) (xy 153.507186 -31.642304)
			(xy 153.507873 -31.610114) (xy 153.518723 -31.546654) (xy 153.528776 -31.516066) (xy 153.53157 -31.507938)
			(xy 153.53157 -31.23819) (xy 153.531689 -31.233236) (xy 153.533609 -31.223515) (xy 153.53538 -31.218886)
			(xy 153.540206 -31.207202) (xy 153.542049 -31.202521) (xy 153.544093 -31.192672) (xy 153.54427 -31.187644)
			(xy 153.54427 -29.841698) (xy 153.544001 -29.833762) (xy 153.539208 -29.818633) (xy 153.534872 -29.81198)
			(xy 153.518059 -29.787564) (xy 153.491392 -29.734621) (xy 153.473243 -29.678187) (xy 153.464052 -29.619624)
			(xy 153.463498 -29.589984) (xy 153.464082 -29.560347) (xy 153.473289 -29.501792) (xy 153.491432 -29.445362)
			(xy 153.518076 -29.392413) (xy 153.534872 -29.367988) (xy 153.539227 -29.361345) (xy 153.544011 -29.346209)
			(xy 153.54427 -29.33827) (xy 153.54427 -28.11272) (xy 153.544407 -28.108236) (xy 153.546061 -28.099418)
			(xy 153.547572 -28.095194) (xy 153.551128 -28.085542) (xy 153.55062 -28.074366) (xy 153.54808 -28.036774)
			(xy 153.543254 -28.023566) (xy 153.538682 -28.01747) (xy 153.520999 -27.992659) (xy 153.492917 -27.938594)
			(xy 153.473793 -27.880751) (xy 153.464112 -27.820602) (xy 153.463498 -27.79014) (xy 153.463959 -27.762885)
			(xy 153.471711 -27.708931) (xy 153.487064 -27.656628) (xy 153.509704 -27.607043) (xy 153.539171 -27.561186)
			(xy 153.574865 -27.519989) (xy 153.616058 -27.484291) (xy 153.661914 -27.45482) (xy 153.711496 -27.432176)
			(xy 153.763797 -27.416818) (xy 153.817751 -27.409061) (xy 153.845006 -27.408632) (xy 153.870526 -27.409078)
			(xy 153.921105 -27.41592) (xy 153.970322 -27.42944) (xy 154.017298 -27.449397) (xy 154.061196 -27.475436)
			(xy 154.08148 -27.490928) (xy 154.096974 -27.502866) (xy 154.135074 -27.500834) (xy 154.28849 -27.347418)
			(xy 154.295887 -27.340568) (xy 154.314485 -27.332827) (xy 154.324558 -27.332432) (xy 154.47264 -27.332432)
			(xy 154.476958 -27.33167) (xy 154.4895 -27.329678) (xy 154.514806 -27.327514) (xy 154.527504 -27.327352)
			(xy 158.572962 -27.327352) (xy 158.582939 -27.326941) (xy 158.601377 -27.319316) (xy 158.615492 -27.305214)
			(xy 158.623132 -27.286782) (xy 158.623508 -27.276806) (xy 158.623508 -26.476706) (xy 158.62378 -26.459101)
			(xy 158.626704 -26.424009) (xy 158.62935 -26.406602) (xy 158.631128 -26.396188) (xy 158.631636 -26.393902)
			(xy 158.632144 -26.389584) (xy 158.632546 -26.38068) (xy 158.627985 -26.363465) (xy 158.617846 -26.348824)
			(xy 158.610808 -26.343356) (xy 158.59125 -26.329386) (xy 158.563056 -26.327608) (xy 158.550356 -26.333958)
			(xy 158.523226 -26.347312) (xy 158.465791 -26.366211) (xy 158.40609 -26.375794) (xy 158.375858 -26.376376)
			(xy 158.34861 -26.375887) (xy 158.294668 -26.368125) (xy 158.24238 -26.352766) (xy 158.192811 -26.330122)
			(xy 158.146968 -26.300654) (xy 158.105785 -26.264962) (xy 158.070101 -26.223773) (xy 158.040642 -26.177924)
			(xy 158.018008 -26.12835) (xy 158.002659 -26.076059) (xy 157.994908 -26.022117) (xy 157.99435 -25.994868)
			(xy 157.994784 -25.969007) (xy 158.001779 -25.917759) (xy 158.015636 -25.867927) (xy 158.036102 -25.820426)
			(xy 158.062801 -25.776127) (xy 158.095242 -25.735842) (xy 158.11373 -25.717754) (xy 158.114238 -25.717246)
			(xy 158.116016 -25.715468) (xy 158.13747 -25.695506) (xy 158.185365 -25.66174) (xy 158.237861 -25.6357)
			(xy 158.293724 -25.617999) (xy 158.351638 -25.609053) (xy 158.380938 -25.608534) (xy 158.4099 -25.609074)
			(xy 158.467157 -25.617835) (xy 158.522432 -25.635149) (xy 158.574455 -25.660619) (xy 158.622031 -25.693659)
			(xy 158.664066 -25.73351) (xy 158.699595 -25.779257) (xy 158.727802 -25.829849) (xy 158.728624 -25.832054)
			(xy 160.287968 -25.832054) (xy 160.292039 -25.776432) (xy 160.304165 -25.721995) (xy 160.324088 -25.669904)
			(xy 160.351384 -25.621269) (xy 160.38547 -25.577126) (xy 160.425619 -25.538417) (xy 160.470977 -25.505966)
			(xy 160.520577 -25.480465) (xy 160.573361 -25.462458) (xy 160.628204 -25.452328) (xy 160.683938 -25.450291)
			(xy 160.739375 -25.456391) (xy 160.793332 -25.470497) (xy 160.844661 -25.492309) (xy 160.892267 -25.521363)
			(xy 160.935135 -25.557038) (xy 160.936669 -25.55875) (xy 164.742368 -25.55875) (xy 164.742854 -25.531499)
			(xy 164.75061 -25.477551) (xy 164.765965 -25.425256) (xy 164.788607 -25.375679) (xy 164.818073 -25.329829)
			(xy 164.853764 -25.288638) (xy 164.894955 -25.252947) (xy 164.940805 -25.223481) (xy 164.990382 -25.200839)
			(xy 165.042677 -25.185484) (xy 165.096625 -25.177728) (xy 165.151127 -25.177728) (xy 165.205075 -25.185484)
			(xy 165.25737 -25.200839) (xy 165.306947 -25.223481) (xy 165.352797 -25.252947) (xy 165.393988 -25.288638)
			(xy 165.429679 -25.329829) (xy 165.459145 -25.375679) (xy 165.481787 -25.425256) (xy 165.497142 -25.477551)
			(xy 165.504898 -25.531499) (xy 165.505384 -25.55875) (xy 165.504819 -25.589012) (xy 165.495268 -25.648778)
			(xy 165.476398 -25.706285) (xy 165.448682 -25.76009) (xy 165.431216 -25.78481) (xy 165.422907 -25.79694)
			(xy 165.412951 -25.824589) (xy 165.411281 -25.853929) (xy 165.418037 -25.88253) (xy 165.432659 -25.908022)
			(xy 165.453935 -25.928294) (xy 165.480104 -25.941666) (xy 165.494462 -25.94483) (xy 165.520365 -25.950129)
			(xy 165.570487 -25.966953) (xy 165.617806 -25.990539) (xy 165.661413 -26.020434) (xy 165.700474 -26.056065)
			(xy 165.734238 -26.09675) (xy 165.76206 -26.141709) (xy 165.783406 -26.190079) (xy 165.797866 -26.240934)
			(xy 165.805164 -26.293299) (xy 165.805612 -26.319734) (xy 166.942006 -26.319734) (xy 166.946077 -26.264112)
			(xy 166.958203 -26.209675) (xy 166.978126 -26.157584) (xy 167.005422 -26.108949) (xy 167.039508 -26.064806)
			(xy 167.079657 -26.026097) (xy 167.125015 -25.993646) (xy 167.174615 -25.968145) (xy 167.227399 -25.950138)
			(xy 167.282242 -25.940008) (xy 167.337976 -25.937971) (xy 167.393413 -25.944071) (xy 167.44737 -25.958177)
			(xy 167.498699 -25.979989) (xy 167.546305 -26.009043) (xy 167.589173 -26.044718) (xy 167.62639 -26.086255)
			(xy 167.657163 -26.132768) (xy 167.680835 -26.183265) (xy 167.696903 -26.236672) (xy 167.705023 -26.291848)
			(xy 167.705532 -26.319734) (xy 167.705023 -26.34762) (xy 167.696903 -26.402796) (xy 167.680835 -26.456203)
			(xy 167.657163 -26.5067) (xy 167.62639 -26.553213) (xy 167.589173 -26.59475) (xy 167.546305 -26.630425)
			(xy 167.498699 -26.659479) (xy 167.44737 -26.681291) (xy 167.393413 -26.695397) (xy 167.337976 -26.701497)
			(xy 167.282242 -26.69946) (xy 167.227399 -26.68933) (xy 167.174615 -26.671323) (xy 167.125015 -26.645822)
			(xy 167.079657 -26.613371) (xy 167.039508 -26.574662) (xy 167.005422 -26.530519) (xy 166.978126 -26.481884)
			(xy 166.958203 -26.429793) (xy 166.946077 -26.375356) (xy 166.942006 -26.319734) (xy 165.805612 -26.319734)
			(xy 165.805126 -26.346985) (xy 165.79737 -26.400933) (xy 165.782015 -26.453228) (xy 165.759373 -26.502805)
			(xy 165.729907 -26.548655) (xy 165.694216 -26.589846) (xy 165.653025 -26.625537) (xy 165.607175 -26.655003)
			(xy 165.557598 -26.677645) (xy 165.505303 -26.693) (xy 165.451355 -26.700756) (xy 165.396853 -26.700756)
			(xy 165.342905 -26.693) (xy 165.29061 -26.677645) (xy 165.241033 -26.655003) (xy 165.195183 -26.625537)
			(xy 165.153992 -26.589846) (xy 165.118301 -26.548655) (xy 165.088835 -26.502805) (xy 165.066193 -26.453228)
			(xy 165.050838 -26.400933) (xy 165.043082 -26.346985) (xy 165.042596 -26.319734) (xy 165.043157 -26.289472)
			(xy 165.05271 -26.229706) (xy 165.071581 -26.172199) (xy 165.099298 -26.118394) (xy 165.116764 -26.093674)
			(xy 165.125104 -26.081564) (xy 165.135062 -26.053908) (xy 165.13673 -26.024561) (xy 165.12997 -25.995954)
			(xy 165.115341 -25.970459) (xy 165.094057 -25.950186) (xy 165.067879 -25.936816) (xy 165.053518 -25.933654)
			(xy 165.027624 -25.928312) (xy 164.977501 -25.911497) (xy 164.93018 -25.887919) (xy 164.886571 -25.858031)
			(xy 164.847508 -25.822405) (xy 164.813741 -25.781724) (xy 164.785918 -25.736768) (xy 164.764572 -25.6884)
			(xy 164.750112 -25.637547) (xy 164.742815 -25.585185) (xy 164.742368 -25.55875) (xy 160.936669 -25.55875)
			(xy 160.972352 -25.598575) (xy 161.003125 -25.645088) (xy 161.026797 -25.695585) (xy 161.042865 -25.748992)
			(xy 161.050985 -25.804168) (xy 161.051494 -25.832054) (xy 161.050985 -25.85994) (xy 161.042865 -25.915116)
			(xy 161.026797 -25.968523) (xy 161.003125 -26.01902) (xy 160.972352 -26.065533) (xy 160.935135 -26.10707)
			(xy 160.892267 -26.142745) (xy 160.844661 -26.171799) (xy 160.793332 -26.193611) (xy 160.739375 -26.207717)
			(xy 160.683938 -26.213817) (xy 160.628204 -26.21178) (xy 160.573361 -26.20165) (xy 160.520577 -26.183643)
			(xy 160.470977 -26.158142) (xy 160.425619 -26.125691) (xy 160.38547 -26.086982) (xy 160.351384 -26.042839)
			(xy 160.324088 -25.994204) (xy 160.304165 -25.942113) (xy 160.292039 -25.887676) (xy 160.287968 -25.832054)
			(xy 158.728624 -25.832054) (xy 158.748038 -25.884123) (xy 158.759838 -25.940831) (xy 158.761938 -25.969722)
			(xy 158.7627 -25.982168) (xy 158.775146 -26.003504) (xy 158.867094 -26.060654) (xy 158.891224 -26.062432)
			(xy 158.902908 -26.057606) (xy 158.930903 -26.046253) (xy 158.989138 -26.03018) (xy 159.048981 -26.021912)
			(xy 159.079184 -26.021284) (xy 159.08147 -26.021284) (xy 159.111456 -26.021751) (xy 159.170915 -26.029576)
			(xy 159.228844 -26.045096) (xy 159.284251 -26.068045) (xy 159.336188 -26.09803) (xy 159.383767 -26.134538)
			(xy 159.426172 -26.176945) (xy 159.462679 -26.224525) (xy 159.492663 -26.276464) (xy 159.515609 -26.331872)
			(xy 159.52338 -26.360882) (xy 162.205668 -26.360882) (xy 162.209739 -26.30526) (xy 162.221865 -26.250823)
			(xy 162.241788 -26.198732) (xy 162.269084 -26.150097) (xy 162.30317 -26.105954) (xy 162.343319 -26.067245)
			(xy 162.388677 -26.034794) (xy 162.438277 -26.009293) (xy 162.491061 -25.991286) (xy 162.545904 -25.981156)
			(xy 162.601638 -25.979119) (xy 162.657075 -25.985219) (xy 162.711032 -25.999325) (xy 162.762361 -26.021137)
			(xy 162.809967 -26.050191) (xy 162.852835 -26.085866) (xy 162.890052 -26.127403) (xy 162.920825 -26.173916)
			(xy 162.944497 -26.224413) (xy 162.960565 -26.27782) (xy 162.968685 -26.332996) (xy 162.969194 -26.360882)
			(xy 162.968685 -26.388768) (xy 162.960565 -26.443944) (xy 162.944497 -26.497351) (xy 162.920825 -26.547848)
			(xy 162.890052 -26.594361) (xy 162.852835 -26.635898) (xy 162.809967 -26.671573) (xy 162.762361 -26.700627)
			(xy 162.711032 -26.722439) (xy 162.657075 -26.736545) (xy 162.601638 -26.742645) (xy 162.545904 -26.740608)
			(xy 162.491061 -26.730478) (xy 162.438277 -26.712471) (xy 162.388677 -26.68697) (xy 162.343319 -26.654519)
			(xy 162.30317 -26.61581) (xy 162.269084 -26.571667) (xy 162.241788 -26.523032) (xy 162.221865 -26.470941)
			(xy 162.209739 -26.416504) (xy 162.205668 -26.360882) (xy 159.52338 -26.360882) (xy 159.531127 -26.389801)
			(xy 159.53895 -26.44926) (xy 159.539432 -26.479246) (xy 159.539432 -27.276806) (xy 159.539819 -27.28679)
			(xy 159.547422 -27.30525) (xy 159.561537 -27.319369) (xy 159.579994 -27.326978) (xy 159.589978 -27.327352)
			(xy 168.795446 -27.327352) (xy 168.803828 -27.32659) (xy 168.811431 -27.325071) (xy 168.825258 -27.318078)
			(xy 168.831006 -27.312874) (xy 169.19067 -26.95321) (xy 169.191178 -26.952702) (xy 169.197751 -26.945317)
			(xy 169.205181 -26.927019) (xy 169.205656 -26.917142) (xy 169.205656 -25.07615) (xy 169.205078 -25.064949)
			(xy 169.1956 -25.044649) (xy 169.187368 -25.037034) (xy 169.127678 -24.986996) (xy 169.118722 -24.980301)
			(xy 169.097114 -24.97465) (xy 169.086022 -24.976074) (xy 169.085768 -24.976074) (xy 169.06902 -24.978905)
			(xy 169.035188 -24.981959) (xy 169.018204 -24.98217) (xy 169.017442 -24.98217) (xy 168.990188 -24.981709)
			(xy 168.936235 -24.973957) (xy 168.883934 -24.958604) (xy 168.834351 -24.935964) (xy 168.788495 -24.906496)
			(xy 168.747301 -24.870802) (xy 168.711606 -24.829608) (xy 168.682138 -24.783753) (xy 168.659497 -24.73417)
			(xy 168.644144 -24.681869) (xy 168.636391 -24.627916) (xy 168.635934 -24.600662) (xy 168.636567 -24.570021)
			(xy 168.646395 -24.509532) (xy 168.655492 -24.480266) (xy 168.659302 -24.468582) (xy 168.655492 -24.444452)
			(xy 168.593008 -24.357838) (xy 168.571164 -24.346662) (xy 168.558972 -24.346662) (xy 168.531747 -24.34614)
			(xy 168.477859 -24.338322) (xy 168.42563 -24.322921) (xy 168.376122 -24.300249) (xy 168.330341 -24.270768)
			(xy 168.289218 -24.235076) (xy 168.253588 -24.193899) (xy 168.224175 -24.148074) (xy 168.201578 -24.098532)
			(xy 168.186256 -24.04628) (xy 168.178519 -23.99238) (xy 168.177972 -23.965154) (xy 168.178458 -23.937903)
			(xy 168.186214 -23.883955) (xy 168.201569 -23.83166) (xy 168.224211 -23.782083) (xy 168.253677 -23.736233)
			(xy 168.289368 -23.695042) (xy 168.330559 -23.659351) (xy 168.376409 -23.629885) (xy 168.425986 -23.607243)
			(xy 168.478281 -23.591888) (xy 168.532229 -23.584132) (xy 168.586731 -23.584132) (xy 168.640679 -23.591888)
			(xy 168.692974 -23.607243) (xy 168.742551 -23.629885) (xy 168.788401 -23.659351) (xy 168.829592 -23.695042)
			(xy 168.865283 -23.736233) (xy 168.894749 -23.782083) (xy 168.917391 -23.83166) (xy 168.932746 -23.883955)
			(xy 168.940502 -23.937903) (xy 168.940988 -23.965154) (xy 168.940354 -23.995795) (xy 168.930524 -24.056283)
			(xy 168.92143 -24.08555) (xy 168.91762 -24.097234) (xy 168.92143 -24.121364) (xy 168.983914 -24.207978)
			(xy 169.005758 -24.219154) (xy 169.01795 -24.219154) (xy 169.034999 -24.219334) (xy 169.068961 -24.222383)
			(xy 169.085768 -24.22525) (xy 169.086022 -24.22525) (xy 169.097116 -24.226703) (xy 169.118737 -24.221051)
			(xy 169.127678 -24.214328) (xy 169.187368 -24.16429) (xy 169.195612 -24.156681) (xy 169.205092 -24.13638)
			(xy 169.205656 -24.125174) (xy 169.205656 -24.081994) (xy 169.202862 -24.073866) (xy 169.1927 -24.043102)
			(xy 169.181711 -23.979257) (xy 169.181018 -23.946866) (xy 169.181722 -23.914475) (xy 169.192698 -23.850629)
			(xy 169.202862 -23.819866) (xy 169.205656 -23.811738) (xy 169.205656 -22.239224) (xy 169.188892 -22.214078)
			(xy 169.174414 -22.207982) (xy 169.148672 -22.196753) (xy 169.100526 -22.167844) (xy 169.057138 -22.132188)
			(xy 169.019447 -22.090555) (xy 168.988267 -22.043847) (xy 168.964273 -21.993071) (xy 168.947984 -21.939326)
			(xy 168.939751 -21.883774) (xy 168.939751 -21.827614) (xy 168.947987 -21.772062) (xy 168.964278 -21.718318)
			(xy 168.988273 -21.667543) (xy 169.019454 -21.620835) (xy 169.057147 -21.579204) (xy 169.100536 -21.543549)
			(xy 169.148683 -21.514641) (xy 169.174414 -21.503386) (xy 169.188892 -21.49729) (xy 169.205656 -21.472144)
			(xy 169.205656 -15.834106) (xy 169.205182 -15.824139) (xy 169.197608 -15.8057) (xy 169.190924 -15.798292)
			(xy 169.134028 -15.740634) (xy 169.115994 -15.73276) (xy 169.105834 -15.73276) (xy 169.080116 -15.73191)
			(xy 169.029248 -15.72415) (xy 168.979883 -15.709628) (xy 168.932916 -15.688608) (xy 168.889197 -15.66147)
			(xy 168.849519 -15.628706) (xy 168.831768 -15.610078) (xy 168.824148 -15.60195) (xy 168.804082 -15.593568)
			(xy 168.70553 -15.596108) (xy 168.685972 -15.605506) (xy 168.67886 -15.614142) (xy 168.660649 -15.635291)
			(xy 168.619102 -15.672555) (xy 168.57257 -15.70337) (xy 168.522046 -15.727079) (xy 168.468608 -15.743177)
			(xy 168.413395 -15.751319) (xy 168.38549 -15.75181) (xy 168.358239 -15.751324) (xy 168.304292 -15.743566)
			(xy 168.251998 -15.72821) (xy 168.202422 -15.705568) (xy 168.156573 -15.676101) (xy 168.115383 -15.640409)
			(xy 168.079693 -15.599219) (xy 168.050227 -15.553369) (xy 168.027587 -15.503792) (xy 168.012232 -15.451498)
			(xy 168.004476 -15.397551) (xy 168.004476 -15.343049) (xy 168.012232 -15.289102) (xy 168.027587 -15.236808)
			(xy 168.050227 -15.187231) (xy 168.079693 -15.141381) (xy 168.115383 -15.100191) (xy 168.156573 -15.064499)
			(xy 168.202422 -15.035032) (xy 168.251998 -15.01239) (xy 168.304292 -14.997034) (xy 168.358239 -14.989276)
			(xy 168.38549 -14.988794) (xy 168.411727 -14.989231) (xy 168.463705 -14.996426) (xy 168.514204 -15.010684)
			(xy 168.562271 -15.031732) (xy 168.606997 -15.059175) (xy 168.647536 -15.092493) (xy 168.665652 -15.111476)
			(xy 168.673272 -15.119604) (xy 168.693338 -15.127986) (xy 168.79189 -15.125446) (xy 168.811448 -15.116048)
			(xy 168.81856 -15.107412) (xy 168.836038 -15.087051) (xy 168.875752 -15.050966) (xy 168.920145 -15.020823)
			(xy 168.944036 -15.008606) (xy 168.95572 -15.003018) (xy 168.970452 -14.982444) (xy 168.98493 -14.87297)
			(xy 168.97604 -14.849348) (xy 168.966134 -14.840966) (xy 168.946013 -14.822745) (xy 168.910616 -14.781594)
			(xy 168.881403 -14.735845) (xy 168.858964 -14.686419) (xy 168.843752 -14.634313) (xy 168.836073 -14.580578)
			(xy 168.835578 -14.553438) (xy 168.83606 -14.526219) (xy 168.843797 -14.472333) (xy 168.859118 -14.420095)
			(xy 168.881713 -14.370567) (xy 168.911123 -14.324755) (xy 168.946748 -14.283592) (xy 168.987866 -14.247914)
			(xy 169.033639 -14.218447) (xy 169.083138 -14.195789) (xy 169.135357 -14.1804) (xy 169.162222 -14.175994)
			(xy 169.181018 -14.1732) (xy 169.205656 -14.144752) (xy 169.205656 -13.730986) (xy 169.205229 -13.720918)
			(xy 169.197506 -13.702321) (xy 169.19067 -13.694918) (xy 168.885362 -13.38961) (xy 168.87825 -13.382244)
			(xy 168.859454 -13.374624) (xy 164.142674 -13.374624) (xy 164.132606 -13.375052) (xy 164.114011 -13.382776)
			(xy 164.106606 -13.38961) (xy 162.800792 -14.695424) (xy 162.795579 -14.700333) (xy 162.783074 -14.707298)
			(xy 162.776154 -14.70914) (xy 162.7759 -14.70914) (xy 162.76679 -14.711742) (xy 162.751255 -14.722566)
			(xy 162.745674 -14.730222) (xy 162.693604 -14.806676) (xy 162.691064 -14.831568) (xy 162.69589 -14.84376)
			(xy 162.721415 -14.907761) (xy 162.765147 -15.038439) (xy 162.800357 -15.171667) (xy 162.826897 -15.306889)
			(xy 162.844658 -15.443541) (xy 162.853564 -15.581055) (xy 162.854132 -15.649956) (xy 162.853624 -15.700756)
			(xy 162.851565 -15.766314) (xy 162.8404 -15.897015) (xy 162.821227 -16.026783) (xy 162.794118 -16.155128)
			(xy 162.759175 -16.281565) (xy 162.716531 -16.405617) (xy 162.666346 -16.526814) (xy 162.60881 -16.6447)
			(xy 162.544141 -16.758828) (xy 162.472582 -16.868768) (xy 162.394405 -16.974104) (xy 162.309904 -17.074438)
			(xy 162.219399 -17.169391) (xy 162.171634 -17.214342) (xy 162.170872 -17.215104) (xy 162.169856 -17.21612)
			(xy 162.120701 -17.26122) (xy 162.017602 -17.345901) (xy 161.909415 -17.423974) (xy 161.79656 -17.495136)
			(xy 161.679481 -17.559108) (xy 161.558633 -17.61564) (xy 161.434489 -17.664512) (xy 161.307534 -17.705531)
			(xy 161.178265 -17.738539) (xy 161.047186 -17.763406) (xy 160.914809 -17.780035) (xy 160.781653 -17.788361)
			(xy 160.714944 -17.78889) (xy 160.650472 -17.788414) (xy 160.521763 -17.780631) (xy 160.393758 -17.765091)
			(xy 160.266926 -17.74185) (xy 160.141728 -17.710994) (xy 160.018621 -17.672634) (xy 159.898055 -17.626912)
			(xy 159.78047 -17.573993) (xy 159.666295 -17.514071) (xy 159.555946 -17.447364) (xy 159.449827 -17.374116)
			(xy 159.348323 -17.294595) (xy 159.251806 -17.20909) (xy 159.160628 -17.117913) (xy 159.075122 -17.021397)
			(xy 158.995599 -16.919894) (xy 158.92235 -16.813775) (xy 158.855642 -16.703427) (xy 158.795719 -16.589253)
			(xy 158.742798 -16.471669) (xy 158.697074 -16.351103) (xy 158.658713 -16.227997) (xy 158.627855 -16.1028)
			(xy 158.604613 -15.975968) (xy 158.589071 -15.847963) (xy 158.581287 -15.719254) (xy 158.580836 -15.654782)
			(xy 158.581393 -15.586042) (xy 158.590259 -15.448848) (xy 158.607935 -15.312508) (xy 158.634347 -15.177589)
			(xy 158.669386 -15.044648) (xy 158.712906 -14.914238) (xy 158.738316 -14.850364) (xy 158.742488 -14.838535)
			(xy 158.739958 -14.813612) (xy 158.73349 -14.802866) (xy 158.686246 -14.732762) (xy 158.678716 -14.722746)
			(xy 158.656598 -14.711034) (xy 158.644082 -14.71041) (xy 156.814774 -14.71041) (xy 156.790644 -14.725396)
			(xy 156.78404 -14.73835) (xy 156.746702 -14.811756) (xy 156.743673 -14.818176) (xy 156.740955 -14.832102)
			(xy 156.741368 -14.839188) (xy 156.742638 -14.853158) (xy 156.75102 -14.864842) (xy 156.751274 -14.865096)
			(xy 156.775904 -14.899598) (xy 156.819556 -14.972276) (xy 156.85649 -15.048586) (xy 156.886407 -15.127911)
			(xy 156.909063 -15.209606) (xy 156.924276 -15.293009) (xy 156.93192 -15.377443) (xy 156.932376 -15.419832)
			(xy 156.932376 -15.425674) (xy 156.931533 -15.471623) (xy 156.921993 -15.563034) (xy 156.90358 -15.653078)
			(xy 156.876468 -15.740896) (xy 156.840916 -15.825649) (xy 156.8196 -15.866364) (xy 156.813504 -15.877794)
			(xy 156.813504 -15.903194) (xy 156.861764 -15.992602) (xy 156.8831 -16.006572) (xy 156.896054 -16.007588)
			(xy 156.940373 -16.011832) (xy 157.028033 -16.027439) (xy 157.113885 -16.051049) (xy 157.197198 -16.08246)
			(xy 157.277267 -16.121406) (xy 157.353412 -16.167556) (xy 157.424985 -16.220519) (xy 157.49138 -16.279845)
			(xy 157.552032 -16.34503) (xy 157.606427 -16.415522) (xy 157.654103 -16.49072) (xy 157.694656 -16.569988)
			(xy 157.72774 -16.652651) (xy 157.753075 -16.738009) (xy 157.770446 -16.825337) (xy 157.779705 -16.913892)
			(xy 157.780774 -17.002924) (xy 157.773644 -17.091677) (xy 157.758375 -17.179396) (xy 157.735097 -17.265338)
			(xy 157.704008 -17.348772) (xy 157.665371 -17.428991) (xy 157.619515 -17.505313) (xy 157.566828 -17.57709)
			(xy 157.507759 -17.643713) (xy 157.475682 -17.67459) (xy 157.475174 -17.675098) (xy 157.474666 -17.675606)
			(xy 157.442414 -17.705529) (xy 157.373335 -17.760024) (xy 157.299586 -17.80801) (xy 157.221779 -17.849088)
			(xy 157.140557 -17.882919) (xy 157.056594 -17.909222) (xy 156.970588 -17.927779) (xy 156.88325 -17.938436)
			(xy 156.795304 -17.941104) (xy 156.707481 -17.935762) (xy 156.620507 -17.922454) (xy 156.535104 -17.90129)
			(xy 156.451981 -17.872446) (xy 156.371826 -17.836161) (xy 156.295303 -17.792735) (xy 156.223048 -17.742529)
			(xy 156.155658 -17.685958) (xy 156.093694 -17.623493) (xy 156.037668 -17.55565) (xy 155.988046 -17.482993)
			(xy 155.945238 -17.406123) (xy 155.909599 -17.325678) (xy 155.881425 -17.242324) (xy 155.86095 -17.156754)
			(xy 155.848343 -17.069676) (xy 155.843709 -16.981812) (xy 155.847085 -16.893891) (xy 155.858445 -16.806642)
			(xy 155.877694 -16.720787) (xy 155.904673 -16.63704) (xy 155.939157 -16.556093) (xy 155.959556 -16.517112)
			(xy 155.96108 -16.514572) (xy 155.963112 -16.509492) (xy 155.965037 -16.504185) (xy 155.966821 -16.493038)
			(xy 155.966668 -16.487394) (xy 155.965906 -16.474948) (xy 155.914852 -16.390112) (xy 155.914852 -16.389604)
			(xy 155.914598 -16.38935) (xy 155.909773 -16.382104) (xy 155.896266 -16.371141) (xy 155.879863 -16.365346)
			(xy 155.871164 -16.364966) (xy 154.132788 -16.364966) (xy 154.08935 -16.364464) (xy 154.002845 -16.356447)
			(xy 153.917448 -16.340483) (xy 153.833889 -16.316707) (xy 153.75288 -16.285324) (xy 153.675112 -16.246599)
			(xy 153.601248 -16.200865) (xy 153.53192 -16.14851) (xy 153.467718 -16.089982) (xy 153.40919 -16.02578)
			(xy 153.356835 -15.956452) (xy 153.311101 -15.882588) (xy 153.272376 -15.80482) (xy 153.240993 -15.723811)
			(xy 153.217217 -15.640252) (xy 153.201253 -15.554855) (xy 153.193236 -15.46835) (xy 153.192734 -15.424912)
			(xy 153.192734 -15.424404) (xy 153.193229 -15.382208) (xy 153.200839 -15.298158) (xy 153.215951 -15.215129)
			(xy 153.238445 -15.133789) (xy 153.26814 -15.054792) (xy 153.304797 -14.978776) (xy 153.34812 -14.906351)
			(xy 153.372566 -14.871954) (xy 153.380948 -14.86027) (xy 153.383234 -14.832076) (xy 153.33599 -14.73835)
			(xy 153.332042 -14.731263) (xy 153.320519 -14.719856) (xy 153.313384 -14.715998) (xy 153.312876 -14.715744)
			(xy 153.307551 -14.713279) (xy 153.296135 -14.71058) (xy 153.29027 -14.71041) (xy 143.969486 -14.71041)
			(xy 143.959417 -14.710836) (xy 143.940817 -14.718555) (xy 143.933418 -14.725396) (xy 143.738854 -14.91996)
			(xy 143.731977 -14.92756) (xy 143.724363 -14.946571) (xy 143.72473 -14.967046) (xy 143.72844 -14.976602)
			(xy 143.773652 -15.077694) (xy 143.800322 -15.09395) (xy 143.81607 -15.093188) (xy 143.836898 -15.09268)
			(xy 143.864152 -15.093143) (xy 143.918105 -15.1009) (xy 143.970405 -15.116256) (xy 144.019987 -15.138899)
			(xy 144.065841 -15.168368) (xy 144.107036 -15.204063) (xy 144.142731 -15.245257) (xy 144.1722 -15.291112)
			(xy 144.194843 -15.340694) (xy 144.2102 -15.392993) (xy 144.217957 -15.446946) (xy 144.217957 -15.501454)
			(xy 144.2102 -15.555407) (xy 144.194843 -15.607706) (xy 144.1722 -15.657288) (xy 144.142731 -15.703143)
			(xy 144.107036 -15.744337) (xy 144.065841 -15.780032) (xy 144.019987 -15.809501) (xy 143.970405 -15.832144)
			(xy 143.918105 -15.8475) (xy 143.864152 -15.855257) (xy 143.836898 -15.855696) (xy 143.806908 -15.855141)
			(xy 143.747668 -15.845748) (xy 143.690634 -15.82718) (xy 143.66367 -15.81404) (xy 143.651732 -15.807944)
			(xy 143.62557 -15.80896) (xy 143.540226 -15.861284) (xy 143.5341 -15.865363) (xy 143.524298 -15.876334)
			(xy 143.520922 -15.882874) (xy 143.520668 -15.882874) (xy 143.518409 -15.888049) (xy 143.515979 -15.899073)
			(xy 143.515842 -15.904718) (xy 143.515842 -18.44421) (xy 164.376352 -18.44421) (xy 164.380423 -18.388588)
			(xy 164.392549 -18.334151) (xy 164.412472 -18.28206) (xy 164.439768 -18.233425) (xy 164.473854 -18.189282)
			(xy 164.514003 -18.150573) (xy 164.559361 -18.118122) (xy 164.608961 -18.092621) (xy 164.661745 -18.074614)
			(xy 164.716588 -18.064484) (xy 164.772322 -18.062447) (xy 164.827759 -18.068547) (xy 164.881716 -18.082653)
			(xy 164.933045 -18.104465) (xy 164.980651 -18.133519) (xy 165.023519 -18.169194) (xy 165.060736 -18.210731)
			(xy 165.091509 -18.257244) (xy 165.115181 -18.307741) (xy 165.131249 -18.361148) (xy 165.139369 -18.416324)
			(xy 165.139878 -18.44421) (xy 165.139369 -18.472096) (xy 165.131249 -18.527272) (xy 165.115181 -18.580679)
			(xy 165.091509 -18.631176) (xy 165.060736 -18.677689) (xy 165.023519 -18.719226) (xy 164.980651 -18.754901)
			(xy 164.933045 -18.783955) (xy 164.881716 -18.805767) (xy 164.827759 -18.819873) (xy 164.772322 -18.825973)
			(xy 164.716588 -18.823936) (xy 164.661745 -18.813806) (xy 164.608961 -18.795799) (xy 164.559361 -18.770298)
			(xy 164.514003 -18.737847) (xy 164.473854 -18.699138) (xy 164.439768 -18.654995) (xy 164.412472 -18.60636)
			(xy 164.392549 -18.554269) (xy 164.380423 -18.499832) (xy 164.376352 -18.44421) (xy 143.515842 -18.44421)
			(xy 143.515842 -20.724876) (xy 147.280388 -20.724876) (xy 147.284358 -20.594742) (xy 147.296254 -20.465092)
			(xy 147.316033 -20.336409) (xy 147.343619 -20.20917) (xy 147.378912 -20.083851) (xy 147.421778 -19.960915)
			(xy 147.47206 -19.840822) (xy 147.529569 -19.724018) (xy 147.594093 -19.610936) (xy 147.66539 -19.501999)
			(xy 147.743195 -19.397611) (xy 147.82722 -19.29816) (xy 147.917152 -19.204017) (xy 148.012656 -19.115532)
			(xy 148.113376 -19.033033) (xy 148.218938 -18.956828) (xy 148.32895 -18.887201) (xy 148.443002 -18.82441)
			(xy 148.56067 -18.768688) (xy 148.681516 -18.720244) (xy 148.805091 -18.679257) (xy 148.930934 -18.64588)
			(xy 149.058579 -18.620237) (xy 149.187549 -18.602423) (xy 149.317365 -18.592505) (xy 149.447544 -18.59052)
			(xy 149.577603 -18.596474) (xy 149.707056 -18.610347) (xy 149.835423 -18.632085) (xy 149.962226 -18.661609)
			(xy 150.086993 -18.698808) (xy 150.20926 -18.743544) (xy 150.328573 -18.795652) (xy 150.444486 -18.854935)
			(xy 150.556571 -18.921176) (xy 150.664408 -18.994126) (xy 150.767597 -19.073514) (xy 150.865755 -19.159046)
			(xy 150.958516 -19.250403) (xy 151.045535 -19.347245) (xy 151.126488 -19.449212) (xy 151.201074 -19.555924)
			(xy 151.269015 -19.666985) (xy 151.33006 -19.781981) (xy 151.383981 -19.900485) (xy 151.430576 -20.022056)
			(xy 151.469674 -20.146241) (xy 151.501128 -20.272579) (xy 151.524822 -20.4006) (xy 151.540666 -20.529826)
			(xy 151.548604 -20.659779) (xy 151.5491 -20.724876) (xy 151.548604 -20.789973) (xy 151.540666 -20.919926)
			(xy 151.524822 -21.049152) (xy 151.501128 -21.177173) (xy 151.469674 -21.303511) (xy 151.430576 -21.427696)
			(xy 151.383981 -21.549267) (xy 151.33006 -21.667771) (xy 151.292601 -21.738336) (xy 153.516838 -21.738336)
			(xy 153.517339 -21.709596) (xy 153.52597 -21.652769) (xy 153.543026 -21.597878) (xy 153.568122 -21.546167)
			(xy 153.60069 -21.498805) (xy 153.619962 -21.477478) (xy 153.626566 -21.470366) (xy 153.633678 -21.45284)
			(xy 153.633678 -21.363432) (xy 153.626566 -21.345906) (xy 153.619962 -21.338794) (xy 153.600725 -21.317437)
			(xy 153.568156 -21.270081) (xy 153.54306 -21.218374) (xy 153.526005 -21.163488) (xy 153.517378 -21.106664)
			(xy 153.517374 -21.049189) (xy 153.525993 -20.992364) (xy 153.54304 -20.937475) (xy 153.568129 -20.885765)
			(xy 153.600692 -20.838404) (xy 153.619962 -20.817078) (xy 153.626566 -20.809966) (xy 153.633678 -20.79244)
			(xy 153.633678 -20.703032) (xy 153.626566 -20.685506) (xy 153.619962 -20.678394) (xy 153.600725 -20.657037)
			(xy 153.568156 -20.609681) (xy 153.54306 -20.557974) (xy 153.526005 -20.503088) (xy 153.517378 -20.446264)
			(xy 153.517374 -20.388789) (xy 153.525993 -20.331964) (xy 153.54304 -20.277075) (xy 153.568129 -20.225365)
			(xy 153.600692 -20.178004) (xy 153.619962 -20.156678) (xy 153.626566 -20.149566) (xy 153.633678 -20.13204)
			(xy 153.633678 -20.042632) (xy 153.626566 -20.025106) (xy 153.619962 -20.017994) (xy 153.600725 -19.996637)
			(xy 153.568156 -19.949281) (xy 153.54306 -19.897574) (xy 153.526005 -19.842688) (xy 153.517378 -19.785864)
			(xy 153.517374 -19.728389) (xy 153.525993 -19.671564) (xy 153.54304 -19.616675) (xy 153.568129 -19.564965)
			(xy 153.600692 -19.517604) (xy 153.619962 -19.496278) (xy 153.626566 -19.489166) (xy 153.633678 -19.47164)
			(xy 153.633678 -19.382232) (xy 153.626566 -19.364706) (xy 153.619962 -19.357594) (xy 153.600712 -19.336249)
			(xy 153.568142 -19.288892) (xy 153.543045 -19.237185) (xy 153.52599 -19.182298) (xy 153.517362 -19.125474)
			(xy 153.516838 -19.096736) (xy 153.517324 -19.069485) (xy 153.52508 -19.015537) (xy 153.540435 -18.963242)
			(xy 153.563077 -18.913665) (xy 153.592543 -18.867815) (xy 153.628234 -18.826624) (xy 153.669425 -18.790933)
			(xy 153.715275 -18.761467) (xy 153.764852 -18.738825) (xy 153.817147 -18.72347) (xy 153.871095 -18.715714)
			(xy 153.925597 -18.715714) (xy 153.979545 -18.72347) (xy 154.03184 -18.738825) (xy 154.081417 -18.761467)
			(xy 154.127267 -18.790933) (xy 154.168458 -18.826624) (xy 154.204149 -18.867815) (xy 154.233615 -18.913665)
			(xy 154.256257 -18.963242) (xy 154.271612 -19.015537) (xy 154.279368 -19.069485) (xy 154.279854 -19.096736)
			(xy 154.279338 -19.125475) (xy 154.270711 -19.182302) (xy 154.253658 -19.237192) (xy 154.228566 -19.288904)
			(xy 154.196 -19.336267) (xy 154.17673 -19.357594) (xy 154.170126 -19.364706) (xy 154.163014 -19.382232)
			(xy 154.163014 -19.47164) (xy 154.170126 -19.489166) (xy 154.17673 -19.496278) (xy 154.196034 -19.517575)
			(xy 154.228594 -19.564944) (xy 154.25368 -19.616661) (xy 154.270724 -19.671556) (xy 154.279342 -19.728386)
			(xy 154.279338 -19.785866) (xy 154.270713 -19.842695) (xy 154.25366 -19.897588) (xy 154.228567 -19.949301)
			(xy 154.196001 -19.996666) (xy 154.17673 -20.017994) (xy 154.170126 -20.025106) (xy 154.163014 -20.042632)
			(xy 154.163014 -20.13204) (xy 154.170126 -20.149566) (xy 154.17673 -20.156678) (xy 154.196034 -20.177975)
			(xy 154.228594 -20.225344) (xy 154.25368 -20.277061) (xy 154.270724 -20.331956) (xy 154.279342 -20.388786)
			(xy 154.279338 -20.446266) (xy 154.270713 -20.503095) (xy 154.25366 -20.557988) (xy 154.228567 -20.609701)
			(xy 154.196001 -20.657066) (xy 154.17673 -20.678394) (xy 154.170126 -20.685506) (xy 154.163014 -20.703032)
			(xy 154.163014 -20.79244) (xy 154.170126 -20.809966) (xy 154.17673 -20.817078) (xy 154.196034 -20.838375)
			(xy 154.228594 -20.885744) (xy 154.25368 -20.937461) (xy 154.270724 -20.992356) (xy 154.279342 -21.049186)
			(xy 154.279338 -21.106666) (xy 154.270713 -21.163495) (xy 154.25366 -21.218388) (xy 154.228567 -21.270101)
			(xy 154.196001 -21.317466) (xy 154.17673 -21.338794) (xy 154.170126 -21.345906) (xy 154.163014 -21.363432)
			(xy 154.163014 -21.45284) (xy 154.170126 -21.470366) (xy 154.17673 -21.477478) (xy 154.196013 -21.498795)
			(xy 154.228578 -21.546159) (xy 154.253669 -21.597873) (xy 154.266448 -21.639022) (xy 158.173928 -21.639022)
			(xy 158.174484 -21.610285) (xy 158.183102 -21.55346) (xy 158.200145 -21.49857) (xy 158.225229 -21.446858)
			(xy 158.257786 -21.399493) (xy 158.277052 -21.378164) (xy 158.283656 -21.371052) (xy 158.290768 -21.353526)
			(xy 158.290768 -21.264118) (xy 158.283656 -21.246592) (xy 158.277052 -21.23948) (xy 158.257802 -21.218135)
			(xy 158.225233 -21.170776) (xy 158.200139 -21.119068) (xy 158.183086 -21.06418) (xy 158.17446 -21.007354)
			(xy 158.174458 -20.949878) (xy 158.183079 -20.893052) (xy 158.200127 -20.838162) (xy 158.225217 -20.786451)
			(xy 158.257782 -20.73909) (xy 158.277052 -20.717764) (xy 158.283656 -20.710652) (xy 158.290768 -20.693126)
			(xy 158.290768 -20.603718) (xy 158.283656 -20.586192) (xy 158.277052 -20.57908) (xy 158.257802 -20.557735)
			(xy 158.225233 -20.510376) (xy 158.200139 -20.458668) (xy 158.183086 -20.40378) (xy 158.17446 -20.346954)
			(xy 158.174458 -20.289478) (xy 158.183079 -20.232652) (xy 158.200127 -20.177762) (xy 158.225217 -20.126051)
			(xy 158.257782 -20.07869) (xy 158.277052 -20.057364) (xy 158.283656 -20.050252) (xy 158.290768 -20.032726)
			(xy 158.290768 -19.943318) (xy 158.283656 -19.925792) (xy 158.277052 -19.91868) (xy 158.257802 -19.897335)
			(xy 158.225233 -19.849976) (xy 158.200139 -19.798268) (xy 158.183086 -19.74338) (xy 158.17446 -19.686554)
			(xy 158.174458 -19.629078) (xy 158.183079 -19.572252) (xy 158.200127 -19.517362) (xy 158.225217 -19.465651)
			(xy 158.257782 -19.41829) (xy 158.277052 -19.396964) (xy 158.283656 -19.389852) (xy 158.290768 -19.372326)
			(xy 158.290768 -19.282918) (xy 158.283656 -19.265392) (xy 158.277052 -19.25828) (xy 158.257794 -19.236942)
			(xy 158.225225 -19.189583) (xy 158.20013 -19.137874) (xy 158.183077 -19.082986) (xy 158.174451 -19.02616)
			(xy 158.173928 -18.997422) (xy 158.174414 -18.970171) (xy 158.18217 -18.916223) (xy 158.197525 -18.863928)
			(xy 158.220167 -18.814351) (xy 158.249633 -18.768501) (xy 158.285324 -18.72731) (xy 158.326515 -18.691619)
			(xy 158.372365 -18.662153) (xy 158.421942 -18.639511) (xy 158.474237 -18.624156) (xy 158.528185 -18.6164)
			(xy 158.582687 -18.6164) (xy 158.636635 -18.624156) (xy 158.68893 -18.639511) (xy 158.738507 -18.662153)
			(xy 158.784357 -18.691619) (xy 158.825548 -18.72731) (xy 158.861239 -18.768501) (xy 158.890705 -18.814351)
			(xy 158.913347 -18.863928) (xy 158.928702 -18.916223) (xy 158.936458 -18.970171) (xy 158.936944 -18.997422)
			(xy 158.936422 -19.026161) (xy 158.927797 -19.082988) (xy 158.910746 -19.137878) (xy 158.885654 -19.18959)
			(xy 158.85309 -19.236953) (xy 158.83382 -19.25828) (xy 158.827216 -19.265392) (xy 158.820104 -19.282918)
			(xy 158.820104 -19.366853) (xy 163.679338 -19.366853) (xy 163.679338 -19.312347) (xy 163.687095 -19.258395)
			(xy 163.70245 -19.206097) (xy 163.725092 -19.156516) (xy 163.754559 -19.110662) (xy 163.790252 -19.069468)
			(xy 163.831444 -19.033773) (xy 163.877297 -19.004303) (xy 163.926876 -18.981658) (xy 163.979174 -18.966299)
			(xy 164.033125 -18.958539) (xy 164.060378 -18.958052) (xy 164.087148 -18.958544) (xy 164.140162 -18.966039)
			(xy 164.191607 -18.98087) (xy 164.240475 -19.002746) (xy 164.285805 -19.031239) (xy 164.326707 -19.065788)
			(xy 164.362378 -19.105714) (xy 164.377624 -19.127724) (xy 164.38372 -19.136614) (xy 164.401246 -19.148044)
			(xy 164.495734 -19.163284) (xy 164.516054 -19.158204) (xy 164.524436 -19.1516) (xy 164.544574 -19.136462)
			(xy 164.5881 -19.111092) (xy 164.63459 -19.091679) (xy 164.683232 -19.078563) (xy 164.73318 -19.071972)
			(xy 164.75837 -19.07159) (xy 164.785624 -19.072055) (xy 164.839578 -19.079809) (xy 164.891879 -19.095162)
			(xy 164.941463 -19.117803) (xy 164.987319 -19.14727) (xy 165.028515 -19.182963) (xy 165.064212 -19.224157)
			(xy 165.093683 -19.270011) (xy 165.116327 -19.319593) (xy 165.131685 -19.371893) (xy 165.139443 -19.425846)
			(xy 165.139443 -19.480354) (xy 165.131685 -19.534307) (xy 165.116327 -19.586607) (xy 165.093683 -19.636189)
			(xy 165.064212 -19.682043) (xy 165.028515 -19.723237) (xy 164.987319 -19.75893) (xy 164.941463 -19.788397)
			(xy 164.891879 -19.811038) (xy 164.839578 -19.826391) (xy 164.785624 -19.834145) (xy 164.75837 -19.834606)
			(xy 164.731598 -19.834172) (xy 164.678581 -19.826669) (xy 164.627133 -19.811829) (xy 164.578265 -19.789944)
			(xy 164.532935 -19.761442) (xy 164.492035 -19.726884) (xy 164.456367 -19.686948) (xy 164.441124 -19.664934)
			(xy 164.435028 -19.656044) (xy 164.417502 -19.644614) (xy 164.323014 -19.629374) (xy 164.302694 -19.634454)
			(xy 164.294312 -19.641058) (xy 164.274154 -19.656168) (xy 164.230634 -19.681544) (xy 164.18415 -19.700963)
			(xy 164.135511 -19.714086) (xy 164.085567 -19.720683) (xy 164.060378 -19.721068) (xy 164.033125 -19.720661)
			(xy 163.979174 -19.712901) (xy 163.926876 -19.697542) (xy 163.877297 -19.674897) (xy 163.831444 -19.645427)
			(xy 163.790252 -19.609732) (xy 163.754559 -19.568538) (xy 163.725092 -19.522684) (xy 163.70245 -19.473103)
			(xy 163.687095 -19.420805) (xy 163.679338 -19.366853) (xy 158.820104 -19.366853) (xy 158.820104 -19.372326)
			(xy 158.827216 -19.389852) (xy 158.83382 -19.396964) (xy 158.853111 -19.418273) (xy 158.885671 -19.46564)
			(xy 158.910759 -19.517355) (xy 158.927805 -19.572248) (xy 158.936425 -19.629077) (xy 158.936422 -19.686555)
			(xy 158.927798 -19.743384) (xy 158.910747 -19.798275) (xy 158.885655 -19.849988) (xy 158.85309 -19.897352)
			(xy 158.83382 -19.91868) (xy 158.827216 -19.925792) (xy 158.820104 -19.943318) (xy 158.820104 -20.032726)
			(xy 158.827216 -20.050252) (xy 158.83382 -20.057364) (xy 158.853111 -20.078673) (xy 158.885671 -20.12604)
			(xy 158.910759 -20.177755) (xy 158.927805 -20.232648) (xy 158.936425 -20.289477) (xy 158.936422 -20.346955)
			(xy 158.935116 -20.35556) (xy 163.67836 -20.35556) (xy 163.682431 -20.299938) (xy 163.694557 -20.245501)
			(xy 163.71448 -20.19341) (xy 163.741776 -20.144775) (xy 163.775862 -20.100632) (xy 163.816011 -20.061923)
			(xy 163.861369 -20.029472) (xy 163.910969 -20.003971) (xy 163.963753 -19.985964) (xy 164.018596 -19.975834)
			(xy 164.07433 -19.973797) (xy 164.129767 -19.979897) (xy 164.183724 -19.994003) (xy 164.235053 -20.015815)
			(xy 164.282659 -20.044869) (xy 164.325527 -20.080544) (xy 164.362744 -20.122081) (xy 164.393517 -20.168594)
			(xy 164.417189 -20.219091) (xy 164.433257 -20.272498) (xy 164.441377 -20.327674) (xy 164.441886 -20.35556)
			(xy 164.441377 -20.383446) (xy 164.433257 -20.438622) (xy 164.417189 -20.492029) (xy 164.393517 -20.542526)
			(xy 164.362744 -20.589039) (xy 164.325527 -20.630576) (xy 164.282659 -20.666251) (xy 164.235053 -20.695305)
			(xy 164.183724 -20.717117) (xy 164.129767 -20.731223) (xy 164.07433 -20.737323) (xy 164.018596 -20.735286)
			(xy 163.963753 -20.725156) (xy 163.910969 -20.707149) (xy 163.861369 -20.681648) (xy 163.816011 -20.649197)
			(xy 163.775862 -20.610488) (xy 163.741776 -20.566345) (xy 163.71448 -20.51771) (xy 163.694557 -20.465619)
			(xy 163.682431 -20.411182) (xy 163.67836 -20.35556) (xy 158.935116 -20.35556) (xy 158.927798 -20.403784)
			(xy 158.910747 -20.458675) (xy 158.885655 -20.510388) (xy 158.85309 -20.557752) (xy 158.83382 -20.57908)
			(xy 158.827216 -20.586192) (xy 158.820104 -20.603718) (xy 158.820104 -20.693126) (xy 158.827216 -20.710652)
			(xy 158.83382 -20.717764) (xy 158.853111 -20.739073) (xy 158.885671 -20.78644) (xy 158.910759 -20.838155)
			(xy 158.927805 -20.893048) (xy 158.936425 -20.949877) (xy 158.936422 -21.007355) (xy 158.927798 -21.064184)
			(xy 158.910747 -21.119075) (xy 158.885655 -21.170788) (xy 158.85309 -21.218152) (xy 158.83382 -21.23948)
			(xy 158.827216 -21.246592) (xy 158.820104 -21.264118) (xy 158.820104 -21.353526) (xy 158.827216 -21.371052)
			(xy 158.827688 -21.37156) (xy 163.67836 -21.37156) (xy 163.682431 -21.315938) (xy 163.694557 -21.261501)
			(xy 163.71448 -21.20941) (xy 163.741776 -21.160775) (xy 163.775862 -21.116632) (xy 163.816011 -21.077923)
			(xy 163.861369 -21.045472) (xy 163.910969 -21.019971) (xy 163.963753 -21.001964) (xy 164.018596 -20.991834)
			(xy 164.07433 -20.989797) (xy 164.129767 -20.995897) (xy 164.183724 -21.010003) (xy 164.235053 -21.031815)
			(xy 164.282659 -21.060869) (xy 164.325527 -21.096544) (xy 164.362744 -21.138081) (xy 164.393517 -21.184594)
			(xy 164.417189 -21.235091) (xy 164.433257 -21.288498) (xy 164.441377 -21.343674) (xy 164.441886 -21.37156)
			(xy 164.441377 -21.399446) (xy 164.433257 -21.454622) (xy 164.417189 -21.508029) (xy 164.393517 -21.558526)
			(xy 164.362744 -21.605039) (xy 164.325527 -21.646576) (xy 164.282659 -21.682251) (xy 164.235053 -21.711305)
			(xy 164.183724 -21.733117) (xy 164.129767 -21.747223) (xy 164.07433 -21.753323) (xy 164.018596 -21.751286)
			(xy 163.963753 -21.741156) (xy 163.910969 -21.723149) (xy 163.861369 -21.697648) (xy 163.816011 -21.665197)
			(xy 163.775862 -21.626488) (xy 163.741776 -21.582345) (xy 163.71448 -21.53371) (xy 163.694557 -21.481619)
			(xy 163.682431 -21.427182) (xy 163.67836 -21.37156) (xy 158.827688 -21.37156) (xy 158.83382 -21.378164)
			(xy 158.853094 -21.399488) (xy 158.885662 -21.44685) (xy 158.910754 -21.498562) (xy 158.927804 -21.553454)
			(xy 158.936425 -21.610283) (xy 158.936944 -21.639022) (xy 158.936458 -21.666273) (xy 158.928702 -21.720221)
			(xy 158.913347 -21.772516) (xy 158.911905 -21.775674) (xy 168.035984 -21.775674) (xy 168.040055 -21.720052)
			(xy 168.052181 -21.665615) (xy 168.072104 -21.613524) (xy 168.0994 -21.564889) (xy 168.133486 -21.520746)
			(xy 168.173635 -21.482037) (xy 168.218993 -21.449586) (xy 168.268593 -21.424085) (xy 168.321377 -21.406078)
			(xy 168.37622 -21.395948) (xy 168.431954 -21.393911) (xy 168.487391 -21.400011) (xy 168.541348 -21.414117)
			(xy 168.592677 -21.435929) (xy 168.640283 -21.464983) (xy 168.683151 -21.500658) (xy 168.720368 -21.542195)
			(xy 168.751141 -21.588708) (xy 168.774813 -21.639205) (xy 168.790881 -21.692612) (xy 168.799001 -21.747788)
			(xy 168.79951 -21.775674) (xy 168.799001 -21.80356) (xy 168.790881 -21.858736) (xy 168.774813 -21.912143)
			(xy 168.751141 -21.96264) (xy 168.720368 -22.009153) (xy 168.683151 -22.05069) (xy 168.640283 -22.086365)
			(xy 168.592677 -22.115419) (xy 168.541348 -22.137231) (xy 168.487391 -22.151337) (xy 168.431954 -22.157437)
			(xy 168.37622 -22.1554) (xy 168.321377 -22.14527) (xy 168.268593 -22.127263) (xy 168.218993 -22.101762)
			(xy 168.173635 -22.069311) (xy 168.133486 -22.030602) (xy 168.0994 -21.986459) (xy 168.072104 -21.937824)
			(xy 168.052181 -21.885733) (xy 168.040055 -21.831296) (xy 168.035984 -21.775674) (xy 158.911905 -21.775674)
			(xy 158.890705 -21.822093) (xy 158.861239 -21.867943) (xy 158.825548 -21.909134) (xy 158.784357 -21.944825)
			(xy 158.738507 -21.974291) (xy 158.68893 -21.996933) (xy 158.636635 -22.012288) (xy 158.582687 -22.020044)
			(xy 158.528185 -22.020044) (xy 158.474237 -22.012288) (xy 158.421942 -21.996933) (xy 158.372365 -21.974291)
			(xy 158.326515 -21.944825) (xy 158.285324 -21.909134) (xy 158.249633 -21.867943) (xy 158.220167 -21.822093)
			(xy 158.197525 -21.772516) (xy 158.18217 -21.720221) (xy 158.174414 -21.666273) (xy 158.173928 -21.639022)
			(xy 154.266448 -21.639022) (xy 154.270717 -21.652767) (xy 154.279336 -21.709596) (xy 154.279854 -21.738336)
			(xy 154.279368 -21.765587) (xy 154.271612 -21.819535) (xy 154.256257 -21.87183) (xy 154.233615 -21.921407)
			(xy 154.204149 -21.967257) (xy 154.168458 -22.008448) (xy 154.127267 -22.044139) (xy 154.081417 -22.073605)
			(xy 154.03184 -22.096247) (xy 153.979545 -22.111602) (xy 153.925597 -22.119358) (xy 153.871095 -22.119358)
			(xy 153.817147 -22.111602) (xy 153.764852 -22.096247) (xy 153.715275 -22.073605) (xy 153.669425 -22.044139)
			(xy 153.628234 -22.008448) (xy 153.592543 -21.967257) (xy 153.563077 -21.921407) (xy 153.540435 -21.87183)
			(xy 153.52508 -21.819535) (xy 153.517324 -21.765587) (xy 153.516838 -21.738336) (xy 151.292601 -21.738336)
			(xy 151.269015 -21.782767) (xy 151.201074 -21.893828) (xy 151.126488 -22.00054) (xy 151.045535 -22.102507)
			(xy 150.958516 -22.199349) (xy 150.865755 -22.290706) (xy 150.767597 -22.376238) (xy 150.664408 -22.455626)
			(xy 150.556571 -22.528576) (xy 150.444486 -22.594817) (xy 150.328573 -22.6541) (xy 150.20926 -22.706208)
			(xy 150.086993 -22.750944) (xy 149.962226 -22.788143) (xy 149.835423 -22.817667) (xy 149.707056 -22.839405)
			(xy 149.577603 -22.853278) (xy 149.447544 -22.859232) (xy 149.317365 -22.857247) (xy 149.187549 -22.847329)
			(xy 149.058579 -22.829515) (xy 148.930934 -22.803872) (xy 148.805091 -22.770495) (xy 148.681516 -22.729508)
			(xy 148.56067 -22.681064) (xy 148.443002 -22.625342) (xy 148.32895 -22.562551) (xy 148.218938 -22.492924)
			(xy 148.113376 -22.416719) (xy 148.012656 -22.33422) (xy 147.917152 -22.245735) (xy 147.82722 -22.151592)
			(xy 147.743195 -22.052141) (xy 147.66539 -21.947753) (xy 147.594093 -21.838816) (xy 147.529569 -21.725734)
			(xy 147.47206 -21.60893) (xy 147.421778 -21.488837) (xy 147.378912 -21.365901) (xy 147.343619 -21.240582)
			(xy 147.316033 -21.113343) (xy 147.296254 -20.98466) (xy 147.284358 -20.85501) (xy 147.280388 -20.724876)
			(xy 143.515842 -20.724876) (xy 143.515842 -21.500084) (xy 143.516391 -21.512474) (xy 143.527851 -21.534436)
			(xy 143.537686 -21.541994) (xy 143.56072 -21.558536) (xy 143.60209 -21.597319) (xy 143.637259 -21.641802)
			(xy 143.665452 -21.691004) (xy 143.686047 -21.743839) (xy 143.698589 -21.799141) (xy 143.702157 -21.847048)
			(xy 144.172938 -21.847048) (xy 144.177009 -21.791426) (xy 144.189135 -21.736989) (xy 144.209058 -21.684898)
			(xy 144.236354 -21.636263) (xy 144.27044 -21.59212) (xy 144.310589 -21.553411) (xy 144.355947 -21.52096)
			(xy 144.405547 -21.495459) (xy 144.458331 -21.477452) (xy 144.513174 -21.467322) (xy 144.568908 -21.465285)
			(xy 144.624345 -21.471385) (xy 144.678302 -21.485491) (xy 144.729631 -21.507303) (xy 144.777237 -21.536357)
			(xy 144.820105 -21.572032) (xy 144.857322 -21.613569) (xy 144.888095 -21.660082) (xy 144.911767 -21.710579)
			(xy 144.927835 -21.763986) (xy 144.935955 -21.819162) (xy 144.936464 -21.847048) (xy 144.935955 -21.874934)
			(xy 144.927835 -21.93011) (xy 144.911767 -21.983517) (xy 144.888095 -22.034014) (xy 144.857322 -22.080527)
			(xy 144.820105 -22.122064) (xy 144.777237 -22.157739) (xy 144.729631 -22.186793) (xy 144.678302 -22.208605)
			(xy 144.624345 -22.222711) (xy 144.568908 -22.228811) (xy 144.513174 -22.226774) (xy 144.458331 -22.216644)
			(xy 144.405547 -22.198637) (xy 144.355947 -22.173136) (xy 144.310589 -22.140685) (xy 144.27044 -22.101976)
			(xy 144.236354 -22.057833) (xy 144.209058 -22.009198) (xy 144.189135 -21.957107) (xy 144.177009 -21.90267)
			(xy 144.172938 -21.847048) (xy 143.702157 -21.847048) (xy 143.702801 -21.855691) (xy 143.698591 -21.912241)
			(xy 143.686052 -21.967544) (xy 143.66546 -22.02038) (xy 143.637269 -22.069583) (xy 143.602102 -22.114067)
			(xy 143.560734 -22.152853) (xy 143.537686 -22.169374) (xy 143.527984 -22.17704) (xy 143.516591 -22.19894)
			(xy 143.515842 -22.211284) (xy 143.515842 -23.0251) (xy 153.46248 -23.0251) (xy 153.466551 -22.969478)
			(xy 153.478677 -22.915041) (xy 153.4986 -22.86295) (xy 153.525896 -22.814315) (xy 153.559982 -22.770172)
			(xy 153.600131 -22.731463) (xy 153.645489 -22.699012) (xy 153.695089 -22.673511) (xy 153.747873 -22.655504)
			(xy 153.802716 -22.645374) (xy 153.85845 -22.643337) (xy 153.913887 -22.649437) (xy 153.967844 -22.663543)
			(xy 154.019173 -22.685355) (xy 154.066779 -22.714409) (xy 154.109647 -22.750084) (xy 154.146864 -22.791621)
			(xy 154.177637 -22.838134) (xy 154.201309 -22.888631) (xy 154.217377 -22.942038) (xy 154.225497 -22.997214)
			(xy 154.226006 -23.0251) (xy 154.225497 -23.052986) (xy 154.217377 -23.108162) (xy 154.201309 -23.161569)
			(xy 154.177637 -23.212066) (xy 154.146864 -23.258579) (xy 154.109647 -23.300116) (xy 154.066779 -23.335791)
			(xy 154.019173 -23.364845) (xy 153.967844 -23.386657) (xy 153.913887 -23.400763) (xy 153.85845 -23.406863)
			(xy 153.802716 -23.404826) (xy 153.747873 -23.394696) (xy 153.695089 -23.376689) (xy 153.645489 -23.351188)
			(xy 153.600131 -23.318737) (xy 153.559982 -23.280028) (xy 153.525896 -23.235885) (xy 153.4986 -23.18725)
			(xy 153.478677 -23.135159) (xy 153.466551 -23.080722) (xy 153.46248 -23.0251) (xy 143.515842 -23.0251)
			(xy 143.515842 -23.493476) (xy 143.516108 -23.501207) (xy 143.520761 -23.515952) (xy 143.524986 -23.522432)
			(xy 143.528542 -23.527512) (xy 143.55191 -23.551134) (xy 143.555277 -23.554334) (xy 143.558245 -23.556363)
			(xy 154.166123 -23.556363) (xy 154.173877 -23.502424) (xy 154.189227 -23.450138) (xy 154.211862 -23.400568)
			(xy 154.241321 -23.354724) (xy 154.277004 -23.313538) (xy 154.318185 -23.27785) (xy 154.364026 -23.248385)
			(xy 154.413593 -23.225744) (xy 154.465877 -23.210387) (xy 154.519815 -23.202627) (xy 154.547062 -23.202138)
			(xy 154.571092 -23.202496) (xy 154.61877 -23.208542) (xy 154.665311 -23.22053) (xy 154.687778 -23.229062)
			(xy 154.700914 -23.233893) (xy 154.728747 -23.236786) (xy 154.756321 -23.232025) (xy 154.781573 -23.219966)
			(xy 154.802609 -23.201512) (xy 154.817854 -23.178047) (xy 154.826167 -23.151327) (xy 154.826924 -23.123355)
			(xy 154.823922 -23.109682) (xy 154.818471 -23.086699) (xy 154.81261 -23.039828) (xy 154.812238 -23.01621)
			(xy 154.812667 -22.988959) (xy 154.820422 -22.93501) (xy 154.835776 -22.882715) (xy 154.858415 -22.833136)
			(xy 154.88788 -22.787285) (xy 154.92357 -22.746093) (xy 154.964759 -22.710399) (xy 155.010608 -22.680931)
			(xy 155.060185 -22.658287) (xy 155.112479 -22.642929) (xy 155.166427 -22.635169) (xy 155.220929 -22.635166)
			(xy 155.274878 -22.642919) (xy 155.327174 -22.658271) (xy 155.376753 -22.680909) (xy 155.422606 -22.710373)
			(xy 155.463799 -22.746061) (xy 155.499494 -22.787249) (xy 155.528964 -22.833098) (xy 155.551609 -22.882673)
			(xy 155.566969 -22.934967) (xy 155.57473 -22.988915) (xy 155.574735 -23.043417) (xy 155.566983 -23.097366)
			(xy 155.551633 -23.149663) (xy 155.528996 -23.199243) (xy 155.499535 -23.245096) (xy 155.463847 -23.28629)
			(xy 155.42266 -23.321987) (xy 155.376813 -23.351458) (xy 155.327238 -23.374105) (xy 155.274945 -23.389466)
			(xy 155.220997 -23.397229) (xy 155.193746 -23.397718) (xy 155.169716 -23.397353) (xy 155.122039 -23.391309)
			(xy 155.075498 -23.379324) (xy 155.05303 -23.370794) (xy 155.039876 -23.366023) (xy 155.012054 -23.363132)
			(xy 154.984491 -23.367891) (xy 154.959248 -23.379943) (xy 154.938218 -23.398385) (xy 154.922974 -23.421838)
			(xy 154.914657 -23.448545) (xy 154.91389 -23.476506) (xy 154.916886 -23.490174) (xy 154.922347 -23.513155)
			(xy 154.928202 -23.560028) (xy 154.92857 -23.583646) (xy 154.928454 -23.589996) (xy 158.184594 -23.589996)
			(xy 158.188665 -23.534374) (xy 158.200791 -23.479937) (xy 158.220714 -23.427846) (xy 158.24801 -23.379211)
			(xy 158.282096 -23.335068) (xy 158.322245 -23.296359) (xy 158.367603 -23.263908) (xy 158.417203 -23.238407)
			(xy 158.469987 -23.2204) (xy 158.52483 -23.21027) (xy 158.580564 -23.208233) (xy 158.636001 -23.214333)
			(xy 158.689958 -23.228439) (xy 158.741287 -23.250251) (xy 158.788893 -23.279305) (xy 158.831761 -23.31498)
			(xy 158.868115 -23.355554) (xy 167.430704 -23.355554) (xy 167.43117 -23.328743) (xy 167.438678 -23.275648)
			(xy 167.453552 -23.22413) (xy 167.4755 -23.175205) (xy 167.504088 -23.129838) (xy 167.538752 -23.088926)
			(xy 167.578808 -23.053276) (xy 167.600884 -23.038054) (xy 167.612428 -23.029768) (xy 167.630834 -23.008139)
			(xy 167.642573 -22.982278) (xy 167.646737 -22.954184) (xy 167.643005 -22.926029) (xy 167.631664 -22.899991)
			(xy 167.613591 -22.878082) (xy 167.602154 -22.869652) (xy 167.580702 -22.854294) (xy 167.54179 -22.818667)
			(xy 167.508158 -22.778018) (xy 167.480447 -22.733124) (xy 167.459186 -22.68484) (xy 167.44478 -22.634087)
			(xy 167.437504 -22.581833) (xy 167.437054 -22.555454) (xy 167.43754 -22.528203) (xy 167.445296 -22.474255)
			(xy 167.460651 -22.42196) (xy 167.483293 -22.372383) (xy 167.512759 -22.326533) (xy 167.54845 -22.285342)
			(xy 167.589641 -22.249651) (xy 167.635491 -22.220185) (xy 167.685068 -22.197543) (xy 167.737363 -22.182188)
			(xy 167.791311 -22.174432) (xy 167.845813 -22.174432) (xy 167.899761 -22.182188) (xy 167.952056 -22.197543)
			(xy 168.001633 -22.220185) (xy 168.047483 -22.249651) (xy 168.088674 -22.285342) (xy 168.124365 -22.326533)
			(xy 168.153831 -22.372383) (xy 168.176473 -22.42196) (xy 168.191828 -22.474255) (xy 168.199584 -22.528203)
			(xy 168.20007 -22.555454) (xy 168.199577 -22.582264) (xy 168.19207 -22.635356) (xy 168.177198 -22.686872)
			(xy 168.155253 -22.735796) (xy 168.12667 -22.781163) (xy 168.092012 -22.822076) (xy 168.051963 -22.85773)
			(xy 168.02989 -22.872954) (xy 168.018341 -22.881231) (xy 167.999939 -22.902864) (xy 167.988203 -22.928727)
			(xy 167.984041 -22.956821) (xy 167.987774 -22.984975) (xy 167.999114 -23.011014) (xy 168.017184 -23.032925)
			(xy 168.02862 -23.041356) (xy 168.05007 -23.056717) (xy 168.088983 -23.092343) (xy 168.122616 -23.13299)
			(xy 168.150328 -23.177884) (xy 168.171589 -23.226168) (xy 168.185995 -23.276921) (xy 168.193271 -23.329175)
			(xy 168.19372 -23.355554) (xy 168.193234 -23.382805) (xy 168.185478 -23.436753) (xy 168.170123 -23.489048)
			(xy 168.147481 -23.538625) (xy 168.118015 -23.584475) (xy 168.082324 -23.625666) (xy 168.041133 -23.661357)
			(xy 167.995283 -23.690823) (xy 167.945706 -23.713465) (xy 167.893411 -23.72882) (xy 167.839463 -23.736576)
			(xy 167.784961 -23.736576) (xy 167.731013 -23.72882) (xy 167.678718 -23.713465) (xy 167.629141 -23.690823)
			(xy 167.583291 -23.661357) (xy 167.5421 -23.625666) (xy 167.506409 -23.584475) (xy 167.476943 -23.538625)
			(xy 167.454301 -23.489048) (xy 167.438946 -23.436753) (xy 167.43119 -23.382805) (xy 167.430704 -23.355554)
			(xy 158.868115 -23.355554) (xy 158.868978 -23.356517) (xy 158.899751 -23.40303) (xy 158.923423 -23.453527)
			(xy 158.939491 -23.506934) (xy 158.947611 -23.56211) (xy 158.94812 -23.589996) (xy 158.947611 -23.617882)
			(xy 158.939491 -23.673058) (xy 158.923423 -23.726465) (xy 158.899751 -23.776962) (xy 158.868978 -23.823475)
			(xy 158.831761 -23.865012) (xy 158.813369 -23.880318) (xy 159.340802 -23.880318) (xy 159.344873 -23.824696)
			(xy 159.356999 -23.770259) (xy 159.376922 -23.718168) (xy 159.404218 -23.669533) (xy 159.438304 -23.62539)
			(xy 159.478453 -23.586681) (xy 159.523811 -23.55423) (xy 159.573411 -23.528729) (xy 159.626195 -23.510722)
			(xy 159.681038 -23.500592) (xy 159.736772 -23.498555) (xy 159.792209 -23.504655) (xy 159.846166 -23.518761)
			(xy 159.897495 -23.540573) (xy 159.945101 -23.569627) (xy 159.987969 -23.605302) (xy 160.025186 -23.646839)
			(xy 160.055959 -23.693352) (xy 160.079631 -23.743849) (xy 160.095699 -23.797256) (xy 160.103819 -23.852432)
			(xy 160.104328 -23.880318) (xy 160.356802 -23.880318) (xy 160.360873 -23.824696) (xy 160.372999 -23.770259)
			(xy 160.392922 -23.718168) (xy 160.420218 -23.669533) (xy 160.454304 -23.62539) (xy 160.494453 -23.586681)
			(xy 160.539811 -23.55423) (xy 160.589411 -23.528729) (xy 160.642195 -23.510722) (xy 160.697038 -23.500592)
			(xy 160.752772 -23.498555) (xy 160.808209 -23.504655) (xy 160.862166 -23.518761) (xy 160.913495 -23.540573)
			(xy 160.961101 -23.569627) (xy 161.003969 -23.605302) (xy 161.041186 -23.646839) (xy 161.071959 -23.693352)
			(xy 161.095631 -23.743849) (xy 161.111699 -23.797256) (xy 161.119819 -23.852432) (xy 161.120328 -23.880318)
			(xy 161.372802 -23.880318) (xy 161.376873 -23.824696) (xy 161.388999 -23.770259) (xy 161.408922 -23.718168)
			(xy 161.436218 -23.669533) (xy 161.470304 -23.62539) (xy 161.510453 -23.586681) (xy 161.555811 -23.55423)
			(xy 161.605411 -23.528729) (xy 161.658195 -23.510722) (xy 161.713038 -23.500592) (xy 161.768772 -23.498555)
			(xy 161.824209 -23.504655) (xy 161.878166 -23.518761) (xy 161.929495 -23.540573) (xy 161.977101 -23.569627)
			(xy 162.019969 -23.605302) (xy 162.057186 -23.646839) (xy 162.087959 -23.693352) (xy 162.111631 -23.743849)
			(xy 162.127699 -23.797256) (xy 162.135819 -23.852432) (xy 162.136328 -23.880318) (xy 162.391088 -23.880318)
			(xy 162.395159 -23.824696) (xy 162.407285 -23.770259) (xy 162.427208 -23.718168) (xy 162.454504 -23.669533)
			(xy 162.48859 -23.62539) (xy 162.528739 -23.586681) (xy 162.574097 -23.55423) (xy 162.623697 -23.528729)
			(xy 162.676481 -23.510722) (xy 162.731324 -23.500592) (xy 162.787058 -23.498555) (xy 162.842495 -23.504655)
			(xy 162.896452 -23.518761) (xy 162.947781 -23.540573) (xy 162.995387 -23.569627) (xy 163.038255 -23.605302)
			(xy 163.075472 -23.646839) (xy 163.106245 -23.693352) (xy 163.129917 -23.743849) (xy 163.145985 -23.797256)
			(xy 163.154105 -23.852432) (xy 163.154614 -23.880318) (xy 163.154105 -23.908204) (xy 163.145985 -23.96338)
			(xy 163.129917 -24.016787) (xy 163.106245 -24.067284) (xy 163.075472 -24.113797) (xy 163.038255 -24.155334)
			(xy 162.995387 -24.191009) (xy 162.947781 -24.220063) (xy 162.896452 -24.241875) (xy 162.842495 -24.255981)
			(xy 162.787058 -24.262081) (xy 162.731324 -24.260044) (xy 162.676481 -24.249914) (xy 162.623697 -24.231907)
			(xy 162.574097 -24.206406) (xy 162.528739 -24.173955) (xy 162.48859 -24.135246) (xy 162.454504 -24.091103)
			(xy 162.427208 -24.042468) (xy 162.407285 -23.990377) (xy 162.395159 -23.93594) (xy 162.391088 -23.880318)
			(xy 162.136328 -23.880318) (xy 162.135819 -23.908204) (xy 162.127699 -23.96338) (xy 162.111631 -24.016787)
			(xy 162.087959 -24.067284) (xy 162.057186 -24.113797) (xy 162.019969 -24.155334) (xy 161.977101 -24.191009)
			(xy 161.929495 -24.220063) (xy 161.878166 -24.241875) (xy 161.824209 -24.255981) (xy 161.768772 -24.262081)
			(xy 161.713038 -24.260044) (xy 161.658195 -24.249914) (xy 161.605411 -24.231907) (xy 161.555811 -24.206406)
			(xy 161.510453 -24.173955) (xy 161.470304 -24.135246) (xy 161.436218 -24.091103) (xy 161.408922 -24.042468)
			(xy 161.388999 -23.990377) (xy 161.376873 -23.93594) (xy 161.372802 -23.880318) (xy 161.120328 -23.880318)
			(xy 161.119819 -23.908204) (xy 161.111699 -23.96338) (xy 161.095631 -24.016787) (xy 161.071959 -24.067284)
			(xy 161.041186 -24.113797) (xy 161.003969 -24.155334) (xy 160.961101 -24.191009) (xy 160.913495 -24.220063)
			(xy 160.862166 -24.241875) (xy 160.808209 -24.255981) (xy 160.752772 -24.262081) (xy 160.697038 -24.260044)
			(xy 160.642195 -24.249914) (xy 160.589411 -24.231907) (xy 160.539811 -24.206406) (xy 160.494453 -24.173955)
			(xy 160.454304 -24.135246) (xy 160.420218 -24.091103) (xy 160.392922 -24.042468) (xy 160.372999 -23.990377)
			(xy 160.360873 -23.93594) (xy 160.356802 -23.880318) (xy 160.104328 -23.880318) (xy 160.103819 -23.908204)
			(xy 160.095699 -23.96338) (xy 160.079631 -24.016787) (xy 160.055959 -24.067284) (xy 160.025186 -24.113797)
			(xy 159.987969 -24.155334) (xy 159.945101 -24.191009) (xy 159.897495 -24.220063) (xy 159.846166 -24.241875)
			(xy 159.792209 -24.255981) (xy 159.736772 -24.262081) (xy 159.681038 -24.260044) (xy 159.626195 -24.249914)
			(xy 159.573411 -24.231907) (xy 159.523811 -24.206406) (xy 159.478453 -24.173955) (xy 159.438304 -24.135246)
			(xy 159.404218 -24.091103) (xy 159.376922 -24.042468) (xy 159.356999 -23.990377) (xy 159.344873 -23.93594)
			(xy 159.340802 -23.880318) (xy 158.813369 -23.880318) (xy 158.788893 -23.900687) (xy 158.741287 -23.929741)
			(xy 158.689958 -23.951553) (xy 158.636001 -23.965659) (xy 158.580564 -23.971759) (xy 158.52483 -23.969722)
			(xy 158.469987 -23.959592) (xy 158.417203 -23.941585) (xy 158.367603 -23.916084) (xy 158.322245 -23.883633)
			(xy 158.282096 -23.844924) (xy 158.24801 -23.800781) (xy 158.220714 -23.752146) (xy 158.200791 -23.700055)
			(xy 158.188665 -23.645618) (xy 158.184594 -23.589996) (xy 154.928454 -23.589996) (xy 154.928073 -23.610893)
			(xy 154.920311 -23.66483) (xy 154.904953 -23.717115) (xy 154.882311 -23.766681) (xy 154.852845 -23.812521)
			(xy 154.817156 -23.853701) (xy 154.77597 -23.889384) (xy 154.730125 -23.918842) (xy 154.680555 -23.941476)
			(xy 154.628268 -23.956825) (xy 154.574329 -23.964577) (xy 154.519835 -23.964575) (xy 154.465897 -23.956817)
			(xy 154.413612 -23.941463) (xy 154.364043 -23.918824) (xy 154.318201 -23.889362) (xy 154.277018 -23.853676)
			(xy 154.241333 -23.812492) (xy 154.211872 -23.76665) (xy 154.189234 -23.717081) (xy 154.173881 -23.664795)
			(xy 154.166125 -23.610857) (xy 154.166123 -23.556363) (xy 143.558245 -23.556363) (xy 143.562944 -23.559576)
			(xy 143.56715 -23.561548) (xy 143.57604 -23.565612) (xy 143.602646 -23.567014) (xy 143.655112 -23.576281)
			(xy 143.705779 -23.592758) (xy 143.75366 -23.616124) (xy 143.797824 -23.645924) (xy 143.837413 -23.68158)
			(xy 143.871655 -23.722397) (xy 143.899886 -23.767581) (xy 143.921555 -23.816253) (xy 143.936241 -23.867468)
			(xy 143.943658 -23.920227) (xy 143.944086 -23.946866) (xy 143.943638 -23.970996) (xy 144.172938 -23.970996)
			(xy 144.177009 -23.915374) (xy 144.189135 -23.860937) (xy 144.209058 -23.808846) (xy 144.236354 -23.760211)
			(xy 144.27044 -23.716068) (xy 144.310589 -23.677359) (xy 144.355947 -23.644908) (xy 144.405547 -23.619407)
			(xy 144.458331 -23.6014) (xy 144.513174 -23.59127) (xy 144.568908 -23.589233) (xy 144.624345 -23.595333)
			(xy 144.678302 -23.609439) (xy 144.729631 -23.631251) (xy 144.777237 -23.660305) (xy 144.820105 -23.69598)
			(xy 144.857322 -23.737517) (xy 144.888095 -23.78403) (xy 144.911767 -23.834527) (xy 144.927835 -23.887934)
			(xy 144.935955 -23.94311) (xy 144.936464 -23.970996) (xy 144.935955 -23.998882) (xy 144.927835 -24.054058)
			(xy 144.911767 -24.107465) (xy 144.888095 -24.157962) (xy 144.887942 -24.158194) (xy 149.55088 -24.158194)
			(xy 149.554951 -24.102572) (xy 149.567077 -24.048135) (xy 149.587 -23.996044) (xy 149.614296 -23.947409)
			(xy 149.648382 -23.903266) (xy 149.688531 -23.864557) (xy 149.733889 -23.832106) (xy 149.783489 -23.806605)
			(xy 149.836273 -23.788598) (xy 149.891116 -23.778468) (xy 149.94685 -23.776431) (xy 150.002287 -23.782531)
			(xy 150.056244 -23.796637) (xy 150.107573 -23.818449) (xy 150.155179 -23.847503) (xy 150.198047 -23.883178)
			(xy 150.235264 -23.924715) (xy 150.266037 -23.971228) (xy 150.289709 -24.021725) (xy 150.305777 -24.075132)
			(xy 150.313897 -24.130308) (xy 150.314406 -24.158194) (xy 150.313897 -24.18608) (xy 150.313328 -24.189944)
			(xy 153.39898 -24.189944) (xy 153.403051 -24.134322) (xy 153.415177 -24.079885) (xy 153.4351 -24.027794)
			(xy 153.462396 -23.979159) (xy 153.496482 -23.935016) (xy 153.536631 -23.896307) (xy 153.581989 -23.863856)
			(xy 153.631589 -23.838355) (xy 153.684373 -23.820348) (xy 153.739216 -23.810218) (xy 153.79495 -23.808181)
			(xy 153.850387 -23.814281) (xy 153.904344 -23.828387) (xy 153.955673 -23.850199) (xy 154.003279 -23.879253)
			(xy 154.046147 -23.914928) (xy 154.083364 -23.956465) (xy 154.114137 -24.002978) (xy 154.137809 -24.053475)
			(xy 154.153877 -24.106882) (xy 154.161997 -24.162058) (xy 154.162506 -24.189944) (xy 155.921962 -24.189944)
			(xy 155.926033 -24.134322) (xy 155.938159 -24.079885) (xy 155.958082 -24.027794) (xy 155.985378 -23.979159)
			(xy 156.019464 -23.935016) (xy 156.059613 -23.896307) (xy 156.104971 -23.863856) (xy 156.154571 -23.838355)
			(xy 156.207355 -23.820348) (xy 156.262198 -23.810218) (xy 156.317932 -23.808181) (xy 156.373369 -23.814281)
			(xy 156.427326 -23.828387) (xy 156.478655 -23.850199) (xy 156.526261 -23.879253) (xy 156.569129 -23.914928)
			(xy 156.606346 -23.956465) (xy 156.637119 -24.002978) (xy 156.660791 -24.053475) (xy 156.676859 -24.106882)
			(xy 156.684979 -24.162058) (xy 156.685488 -24.189944) (xy 156.684979 -24.21783) (xy 156.676859 -24.273006)
			(xy 156.660791 -24.326413) (xy 156.637119 -24.37691) (xy 156.606346 -24.423423) (xy 156.569129 -24.46496)
			(xy 156.526261 -24.500635) (xy 156.478655 -24.529689) (xy 156.427326 -24.551501) (xy 156.373369 -24.565607)
			(xy 156.317932 -24.571707) (xy 156.262198 -24.56967) (xy 156.207355 -24.55954) (xy 156.154571 -24.541533)
			(xy 156.104971 -24.516032) (xy 156.059613 -24.483581) (xy 156.019464 -24.444872) (xy 155.985378 -24.400729)
			(xy 155.958082 -24.352094) (xy 155.938159 -24.300003) (xy 155.926033 -24.245566) (xy 155.921962 -24.189944)
			(xy 154.162506 -24.189944) (xy 154.161997 -24.21783) (xy 154.153877 -24.273006) (xy 154.137809 -24.326413)
			(xy 154.114137 -24.37691) (xy 154.083364 -24.423423) (xy 154.046147 -24.46496) (xy 154.003279 -24.500635)
			(xy 153.955673 -24.529689) (xy 153.904344 -24.551501) (xy 153.850387 -24.565607) (xy 153.79495 -24.571707)
			(xy 153.739216 -24.56967) (xy 153.684373 -24.55954) (xy 153.631589 -24.541533) (xy 153.581989 -24.516032)
			(xy 153.536631 -24.483581) (xy 153.496482 -24.444872) (xy 153.462396 -24.400729) (xy 153.4351 -24.352094)
			(xy 153.415177 -24.300003) (xy 153.403051 -24.245566) (xy 153.39898 -24.189944) (xy 150.313328 -24.189944)
			(xy 150.305777 -24.241256) (xy 150.289709 -24.294663) (xy 150.266037 -24.34516) (xy 150.235264 -24.391673)
			(xy 150.198047 -24.43321) (xy 150.155179 -24.468885) (xy 150.107573 -24.497939) (xy 150.056244 -24.519751)
			(xy 150.002287 -24.533857) (xy 149.94685 -24.539957) (xy 149.891116 -24.53792) (xy 149.836273 -24.52779)
			(xy 149.783489 -24.509783) (xy 149.733889 -24.484282) (xy 149.688531 -24.451831) (xy 149.648382 -24.413122)
			(xy 149.614296 -24.368979) (xy 149.587 -24.320344) (xy 149.567077 -24.268253) (xy 149.554951 -24.213816)
			(xy 149.55088 -24.158194) (xy 144.887942 -24.158194) (xy 144.857322 -24.204475) (xy 144.820105 -24.246012)
			(xy 144.777237 -24.281687) (xy 144.729631 -24.310741) (xy 144.678302 -24.332553) (xy 144.624345 -24.346659)
			(xy 144.568908 -24.352759) (xy 144.513174 -24.350722) (xy 144.458331 -24.340592) (xy 144.405547 -24.322585)
			(xy 144.355947 -24.297084) (xy 144.310589 -24.264633) (xy 144.27044 -24.225924) (xy 144.236354 -24.181781)
			(xy 144.209058 -24.133146) (xy 144.189135 -24.081055) (xy 144.177009 -24.026618) (xy 144.172938 -23.970996)
			(xy 143.943638 -23.970996) (xy 143.943559 -23.975265) (xy 143.93513 -24.031436) (xy 143.918468 -24.085736)
			(xy 143.893941 -24.136967) (xy 143.862091 -24.183996) (xy 143.823622 -24.225784) (xy 143.779383 -24.261408)
			(xy 143.730352 -24.290081) (xy 143.677613 -24.31117) (xy 143.622331 -24.324208) (xy 143.594074 -24.327104)
			(xy 143.584422 -24.327866) (xy 143.567404 -24.336248) (xy 143.514318 -24.393906) (xy 143.508127 -24.401162)
			(xy 143.501198 -24.418918) (xy 143.500856 -24.42845) (xy 143.500856 -24.807418) (xy 150.720296 -24.807418)
			(xy 150.724367 -24.751796) (xy 150.736493 -24.697359) (xy 150.756416 -24.645268) (xy 150.783712 -24.596633)
			(xy 150.817798 -24.55249) (xy 150.857947 -24.513781) (xy 150.903305 -24.48133) (xy 150.952905 -24.455829)
			(xy 151.005689 -24.437822) (xy 151.060532 -24.427692) (xy 151.116266 -24.425655) (xy 151.171703 -24.431755)
			(xy 151.22566 -24.445861) (xy 151.276989 -24.467673) (xy 151.324595 -24.496727) (xy 151.367463 -24.532402)
			(xy 151.40468 -24.573939) (xy 151.435453 -24.620452) (xy 151.459125 -24.670949) (xy 151.475193 -24.724356)
			(xy 151.48024 -24.75865) (xy 162.968684 -24.75865) (xy 162.972755 -24.703028) (xy 162.984881 -24.648591)
			(xy 163.004804 -24.5965) (xy 163.0321 -24.547865) (xy 163.066186 -24.503722) (xy 163.106335 -24.465013)
			(xy 163.151693 -24.432562) (xy 163.201293 -24.407061) (xy 163.254077 -24.389054) (xy 163.30892 -24.378924)
			(xy 163.364654 -24.376887) (xy 163.420091 -24.382987) (xy 163.474048 -24.397093) (xy 163.525377 -24.418905)
			(xy 163.572983 -24.447959) (xy 163.615851 -24.483634) (xy 163.653068 -24.525171) (xy 163.683841 -24.571684)
			(xy 163.707513 -24.622181) (xy 163.723581 -24.675588) (xy 163.731701 -24.730764) (xy 163.73221 -24.75865)
			(xy 163.731701 -24.786536) (xy 163.723581 -24.841712) (xy 163.707513 -24.895119) (xy 163.683841 -24.945616)
			(xy 163.653068 -24.992129) (xy 163.615851 -25.033666) (xy 163.572983 -25.069341) (xy 163.525377 -25.098395)
			(xy 163.474048 -25.120207) (xy 163.420091 -25.134313) (xy 163.364654 -25.140413) (xy 163.30892 -25.138376)
			(xy 163.254077 -25.128246) (xy 163.201293 -25.110239) (xy 163.151693 -25.084738) (xy 163.106335 -25.052287)
			(xy 163.066186 -25.013578) (xy 163.0321 -24.969435) (xy 163.004804 -24.9208) (xy 162.984881 -24.868709)
			(xy 162.972755 -24.814272) (xy 162.968684 -24.75865) (xy 151.48024 -24.75865) (xy 151.483313 -24.779532)
			(xy 151.483822 -24.807418) (xy 151.483313 -24.835304) (xy 151.475193 -24.89048) (xy 151.459125 -24.943887)
			(xy 151.435453 -24.994384) (xy 151.40468 -25.040897) (xy 151.367463 -25.082434) (xy 151.324595 -25.118109)
			(xy 151.276989 -25.147163) (xy 151.22566 -25.168975) (xy 151.171703 -25.183081) (xy 151.116266 -25.189181)
			(xy 151.060532 -25.187144) (xy 151.005689 -25.177014) (xy 150.952905 -25.159007) (xy 150.903305 -25.133506)
			(xy 150.857947 -25.101055) (xy 150.817798 -25.062346) (xy 150.783712 -25.018203) (xy 150.756416 -24.969568)
			(xy 150.736493 -24.917477) (xy 150.724367 -24.86304) (xy 150.720296 -24.807418) (xy 143.500856 -24.807418)
			(xy 143.500856 -25.390094) (xy 155.909772 -25.390094) (xy 155.910258 -25.362843) (xy 155.918014 -25.308895)
			(xy 155.933369 -25.2566) (xy 155.956011 -25.207023) (xy 155.985477 -25.161173) (xy 156.021168 -25.119982)
			(xy 156.062359 -25.084291) (xy 156.108209 -25.054825) (xy 156.157786 -25.032183) (xy 156.210081 -25.016828)
			(xy 156.264029 -25.009072) (xy 156.318531 -25.009072) (xy 156.372479 -25.016828) (xy 156.424774 -25.032183)
			(xy 156.474351 -25.054825) (xy 156.520201 -25.084291) (xy 156.561392 -25.119982) (xy 156.597083 -25.161173)
			(xy 156.626549 -25.207023) (xy 156.649191 -25.2566) (xy 156.664546 -25.308895) (xy 156.672302 -25.362843)
			(xy 156.672788 -25.390094) (xy 156.672202 -25.419113) (xy 156.663413 -25.476482) (xy 156.646037 -25.531858)
			(xy 156.620474 -25.583963) (xy 156.587315 -25.631596) (xy 156.547324 -25.673658) (xy 156.524706 -25.691846)
			(xy 156.51416 -25.700615) (xy 156.497717 -25.722549) (xy 156.48771 -25.748071) (xy 156.484863 -25.775336)
			(xy 156.489381 -25.802374) (xy 156.500937 -25.827232) (xy 156.518697 -25.848115) (xy 156.529786 -25.856184)
			(xy 156.551422 -25.871511) (xy 156.590679 -25.907147) (xy 156.624623 -25.947876) (xy 156.652597 -25.992915)
			(xy 156.674065 -26.041394) (xy 156.68861 -26.09238) (xy 156.695954 -26.144888) (xy 156.69641 -26.171398)
			(xy 156.695924 -26.198649) (xy 156.688168 -26.252597) (xy 156.672813 -26.304892) (xy 156.650171 -26.354469)
			(xy 156.620705 -26.400319) (xy 156.585014 -26.44151) (xy 156.543823 -26.477201) (xy 156.497973 -26.506667)
			(xy 156.448396 -26.529309) (xy 156.396101 -26.544664) (xy 156.342153 -26.55242) (xy 156.287651 -26.55242)
			(xy 156.233703 -26.544664) (xy 156.181408 -26.529309) (xy 156.131831 -26.506667) (xy 156.085981 -26.477201)
			(xy 156.04479 -26.44151) (xy 156.009099 -26.400319) (xy 155.979633 -26.354469) (xy 155.956991 -26.304892)
			(xy 155.941636 -26.252597) (xy 155.93388 -26.198649) (xy 155.933394 -26.171398) (xy 155.933942 -26.142377)
			(xy 155.942735 -26.085005) (xy 155.960116 -26.029627) (xy 155.985686 -25.977521) (xy 156.018853 -25.929889)
			(xy 156.058853 -25.887832) (xy 156.081476 -25.869646) (xy 156.092032 -25.860888) (xy 156.108478 -25.838952)
			(xy 156.118486 -25.813427) (xy 156.121333 -25.786159) (xy 156.116813 -25.759118) (xy 156.105253 -25.734258)
			(xy 156.087487 -25.713376) (xy 156.076396 -25.705308) (xy 156.054753 -25.689992) (xy 156.015496 -25.654354)
			(xy 155.981554 -25.613622) (xy 155.95358 -25.568581) (xy 155.932114 -25.5201) (xy 155.91757 -25.469114)
			(xy 155.910227 -25.416604) (xy 155.909772 -25.390094) (xy 143.500856 -25.390094) (xy 143.500856 -25.971246)
			(xy 144.059908 -25.971246) (xy 144.063979 -25.915624) (xy 144.076105 -25.861187) (xy 144.096028 -25.809096)
			(xy 144.123324 -25.760461) (xy 144.15741 -25.716318) (xy 144.197559 -25.677609) (xy 144.242917 -25.645158)
			(xy 144.292517 -25.619657) (xy 144.345301 -25.60165) (xy 144.400144 -25.59152) (xy 144.455878 -25.589483)
			(xy 144.511315 -25.595583) (xy 144.565272 -25.609689) (xy 144.616601 -25.631501) (xy 144.664207 -25.660555)
			(xy 144.707075 -25.69623) (xy 144.744292 -25.737767) (xy 144.775065 -25.78428) (xy 144.798737 -25.834777)
			(xy 144.814805 -25.888184) (xy 144.822925 -25.94336) (xy 144.823434 -25.971246) (xy 145.075908 -25.971246)
			(xy 145.079979 -25.915624) (xy 145.092105 -25.861187) (xy 145.112028 -25.809096) (xy 145.139324 -25.760461)
			(xy 145.17341 -25.716318) (xy 145.213559 -25.677609) (xy 145.258917 -25.645158) (xy 145.308517 -25.619657)
			(xy 145.361301 -25.60165) (xy 145.416144 -25.59152) (xy 145.471878 -25.589483) (xy 145.527315 -25.595583)
			(xy 145.581272 -25.609689) (xy 145.632601 -25.631501) (xy 145.680207 -25.660555) (xy 145.723075 -25.69623)
			(xy 145.760292 -25.737767) (xy 145.791065 -25.78428) (xy 145.814737 -25.834777) (xy 145.830805 -25.888184)
			(xy 145.838925 -25.94336) (xy 145.839434 -25.971246) (xy 146.091908 -25.971246) (xy 146.095979 -25.915624)
			(xy 146.108105 -25.861187) (xy 146.128028 -25.809096) (xy 146.155324 -25.760461) (xy 146.18941 -25.716318)
			(xy 146.229559 -25.677609) (xy 146.274917 -25.645158) (xy 146.324517 -25.619657) (xy 146.377301 -25.60165)
			(xy 146.432144 -25.59152) (xy 146.487878 -25.589483) (xy 146.543315 -25.595583) (xy 146.597272 -25.609689)
			(xy 146.648601 -25.631501) (xy 146.696207 -25.660555) (xy 146.739075 -25.69623) (xy 146.776292 -25.737767)
			(xy 146.807065 -25.78428) (xy 146.830737 -25.834777) (xy 146.846805 -25.888184) (xy 146.854925 -25.94336)
			(xy 146.855434 -25.971246) (xy 146.854925 -25.999132) (xy 146.849833 -26.03373) (xy 147.368004 -26.03373)
			(xy 147.372075 -25.978108) (xy 147.384201 -25.923671) (xy 147.404124 -25.87158) (xy 147.43142 -25.822945)
			(xy 147.465506 -25.778802) (xy 147.505655 -25.740093) (xy 147.551013 -25.707642) (xy 147.600613 -25.682141)
			(xy 147.653397 -25.664134) (xy 147.70824 -25.654004) (xy 147.763974 -25.651967) (xy 147.819411 -25.658067)
			(xy 147.873368 -25.672173) (xy 147.924697 -25.693985) (xy 147.972303 -25.723039) (xy 148.015171 -25.758714)
			(xy 148.052388 -25.800251) (xy 148.083161 -25.846764) (xy 148.106833 -25.897261) (xy 148.122901 -25.950668)
			(xy 148.131021 -26.005844) (xy 148.13153 -26.03373) (xy 148.131021 -26.061616) (xy 148.122901 -26.116792)
			(xy 148.106833 -26.170199) (xy 148.083161 -26.220696) (xy 148.052927 -26.266394) (xy 150.62073 -26.266394)
			(xy 150.62115 -26.239139) (xy 150.628909 -26.185185) (xy 150.644267 -26.132884) (xy 150.666913 -26.083301)
			(xy 150.696385 -26.037446) (xy 150.732084 -25.996253) (xy 150.773282 -25.960559) (xy 150.81914 -25.931092)
			(xy 150.868725 -25.908452) (xy 150.921028 -25.893099) (xy 150.974983 -25.885347) (xy 151.002238 -25.884886)
			(xy 151.031564 -25.885395) (xy 151.089523 -25.894384) (xy 151.145421 -25.912143) (xy 151.197941 -25.938253)
			(xy 151.222202 -25.954736) (xy 151.232616 -25.961848) (xy 151.257 -25.96515) (xy 151.359362 -25.927304)
			(xy 151.376126 -25.908762) (xy 151.379174 -25.89657) (xy 151.386575 -25.869501) (xy 151.40813 -25.817692)
			(xy 151.437044 -25.769602) (xy 151.472693 -25.726267) (xy 151.514308 -25.688624) (xy 151.560989 -25.657485)
			(xy 151.611729 -25.633523) (xy 151.665433 -25.617255) (xy 151.720941 -25.609032) (xy 151.748998 -25.608534)
			(xy 151.776254 -25.608913) (xy 151.830211 -25.61667) (xy 151.882515 -25.632028) (xy 151.932101 -25.654673)
			(xy 151.977959 -25.684144) (xy 152.019157 -25.719842) (xy 152.054855 -25.761039) (xy 152.084326 -25.806897)
			(xy 152.106971 -25.856483) (xy 152.122329 -25.908787) (xy 152.130087 -25.962744) (xy 152.130087 -25.990042)
			(xy 153.39898 -25.990042) (xy 153.403051 -25.93442) (xy 153.415177 -25.879983) (xy 153.4351 -25.827892)
			(xy 153.462396 -25.779257) (xy 153.496482 -25.735114) (xy 153.536631 -25.696405) (xy 153.581989 -25.663954)
			(xy 153.631589 -25.638453) (xy 153.684373 -25.620446) (xy 153.739216 -25.610316) (xy 153.79495 -25.608279)
			(xy 153.850387 -25.614379) (xy 153.904344 -25.628485) (xy 153.955673 -25.650297) (xy 154.003279 -25.679351)
			(xy 154.046147 -25.715026) (xy 154.083364 -25.756563) (xy 154.114137 -25.803076) (xy 154.137809 -25.853573)
			(xy 154.153877 -25.90698) (xy 154.161997 -25.962156) (xy 154.162506 -25.990042) (xy 154.161997 -26.017928)
			(xy 154.153877 -26.073104) (xy 154.137809 -26.126511) (xy 154.114137 -26.177008) (xy 154.083364 -26.223521)
			(xy 154.046147 -26.265058) (xy 154.003279 -26.300733) (xy 153.955673 -26.329787) (xy 153.904344 -26.351599)
			(xy 153.850387 -26.365705) (xy 153.79495 -26.371805) (xy 153.739216 -26.369768) (xy 153.684373 -26.359638)
			(xy 153.631589 -26.341631) (xy 153.581989 -26.31613) (xy 153.536631 -26.283679) (xy 153.496482 -26.24497)
			(xy 153.462396 -26.200827) (xy 153.4351 -26.152192) (xy 153.415177 -26.100101) (xy 153.403051 -26.045664)
			(xy 153.39898 -25.990042) (xy 152.130087 -25.990042) (xy 152.130087 -26.017256) (xy 152.122329 -26.071213)
			(xy 152.106971 -26.123517) (xy 152.084326 -26.173103) (xy 152.054855 -26.218961) (xy 152.019157 -26.260158)
			(xy 151.977959 -26.295856) (xy 151.932101 -26.325327) (xy 151.882515 -26.347972) (xy 151.830211 -26.36333)
			(xy 151.776254 -26.371087) (xy 151.748998 -26.37155) (xy 151.719673 -26.371016) (xy 151.661715 -26.362034)
			(xy 151.605817 -26.344282) (xy 151.553296 -26.318179) (xy 151.529034 -26.3017) (xy 151.51862 -26.294588)
			(xy 151.494236 -26.291286) (xy 151.391874 -26.329132) (xy 151.37511 -26.347674) (xy 151.372062 -26.359866)
			(xy 151.365277 -26.384897) (xy 151.345861 -26.432988) (xy 151.320105 -26.478002) (xy 151.288484 -26.519109)
			(xy 151.251581 -26.555549) (xy 151.231092 -26.571448) (xy 151.220932 -26.579322) (xy 151.210264 -26.601928)
			(xy 151.215852 -26.711656) (xy 151.228806 -26.733246) (xy 151.239728 -26.73985) (xy 151.263471 -26.754745)
			(xy 151.306705 -26.790413) (xy 151.344255 -26.832023) (xy 151.375314 -26.878679) (xy 151.399212 -26.929376)
			(xy 151.415437 -26.983025) (xy 151.423637 -27.03847) (xy 151.424132 -27.066494) (xy 151.423646 -27.093745)
			(xy 151.41589 -27.147693) (xy 151.400535 -27.199988) (xy 151.377893 -27.249565) (xy 151.348427 -27.295415)
			(xy 151.312736 -27.336606) (xy 151.271545 -27.372297) (xy 151.225695 -27.401763) (xy 151.176118 -27.424405)
			(xy 151.123823 -27.43976) (xy 151.069875 -27.447516) (xy 151.015373 -27.447516) (xy 150.961425 -27.43976)
			(xy 150.90913 -27.424405) (xy 150.859553 -27.401763) (xy 150.813703 -27.372297) (xy 150.772512 -27.336606)
			(xy 150.736821 -27.295415) (xy 150.707355 -27.249565) (xy 150.684713 -27.199988) (xy 150.669358 -27.147693)
			(xy 150.661602 -27.093745) (xy 150.661116 -27.066494) (xy 150.661653 -27.037006) (xy 150.67075 -26.978734)
			(xy 150.688711 -26.922558) (xy 150.715107 -26.869818) (xy 150.749308 -26.82177) (xy 150.7905 -26.779562)
			(xy 150.81377 -26.76144) (xy 150.82393 -26.753566) (xy 150.834598 -26.73096) (xy 150.82901 -26.621232)
			(xy 150.816056 -26.599642) (xy 150.805134 -26.593038) (xy 150.7814 -26.578129) (xy 150.738163 -26.542466)
			(xy 150.70061 -26.500859) (xy 150.669549 -26.454206) (xy 150.645649 -26.40351) (xy 150.629424 -26.349862)
			(xy 150.621224 -26.294418) (xy 150.62073 -26.266394) (xy 148.052927 -26.266394) (xy 148.052388 -26.267209)
			(xy 148.015171 -26.308746) (xy 147.972303 -26.344421) (xy 147.924697 -26.373475) (xy 147.873368 -26.395287)
			(xy 147.819411 -26.409393) (xy 147.763974 -26.415493) (xy 147.70824 -26.413456) (xy 147.653397 -26.403326)
			(xy 147.600613 -26.385319) (xy 147.551013 -26.359818) (xy 147.505655 -26.327367) (xy 147.465506 -26.288658)
			(xy 147.43142 -26.244515) (xy 147.404124 -26.19588) (xy 147.384201 -26.143789) (xy 147.372075 -26.089352)
			(xy 147.368004 -26.03373) (xy 146.849833 -26.03373) (xy 146.846805 -26.054308) (xy 146.830737 -26.107715)
			(xy 146.807065 -26.158212) (xy 146.776292 -26.204725) (xy 146.739075 -26.246262) (xy 146.696207 -26.281937)
			(xy 146.648601 -26.310991) (xy 146.597272 -26.332803) (xy 146.543315 -26.346909) (xy 146.487878 -26.353009)
			(xy 146.432144 -26.350972) (xy 146.377301 -26.340842) (xy 146.324517 -26.322835) (xy 146.274917 -26.297334)
			(xy 146.229559 -26.264883) (xy 146.18941 -26.226174) (xy 146.155324 -26.182031) (xy 146.128028 -26.133396)
			(xy 146.108105 -26.081305) (xy 146.095979 -26.026868) (xy 146.091908 -25.971246) (xy 145.839434 -25.971246)
			(xy 145.838925 -25.999132) (xy 145.830805 -26.054308) (xy 145.814737 -26.107715) (xy 145.791065 -26.158212)
			(xy 145.760292 -26.204725) (xy 145.723075 -26.246262) (xy 145.680207 -26.281937) (xy 145.632601 -26.310991)
			(xy 145.581272 -26.332803) (xy 145.527315 -26.346909) (xy 145.471878 -26.353009) (xy 145.416144 -26.350972)
			(xy 145.361301 -26.340842) (xy 145.308517 -26.322835) (xy 145.258917 -26.297334) (xy 145.213559 -26.264883)
			(xy 145.17341 -26.226174) (xy 145.139324 -26.182031) (xy 145.112028 -26.133396) (xy 145.092105 -26.081305)
			(xy 145.079979 -26.026868) (xy 145.075908 -25.971246) (xy 144.823434 -25.971246) (xy 144.822925 -25.999132)
			(xy 144.814805 -26.054308) (xy 144.798737 -26.107715) (xy 144.775065 -26.158212) (xy 144.744292 -26.204725)
			(xy 144.707075 -26.246262) (xy 144.664207 -26.281937) (xy 144.616601 -26.310991) (xy 144.565272 -26.332803)
			(xy 144.511315 -26.346909) (xy 144.455878 -26.353009) (xy 144.400144 -26.350972) (xy 144.345301 -26.340842)
			(xy 144.292517 -26.322835) (xy 144.242917 -26.297334) (xy 144.197559 -26.264883) (xy 144.15741 -26.226174)
			(xy 144.123324 -26.182031) (xy 144.096028 -26.133396) (xy 144.076105 -26.081305) (xy 144.063979 -26.026868)
			(xy 144.059908 -25.971246) (xy 143.500856 -25.971246) (xy 143.500856 -27.669236) (xy 143.51635 -27.694128)
			(xy 143.529812 -27.700478) (xy 143.556461 -27.713917) (xy 143.605586 -27.747808) (xy 143.615211 -27.756956)
			(xy 146.859143 -27.756956) (xy 146.859143 -27.702444) (xy 146.866901 -27.648488) (xy 146.88226 -27.596185)
			(xy 146.904907 -27.5466) (xy 146.93438 -27.500743) (xy 146.970079 -27.459548) (xy 147.011278 -27.423853)
			(xy 147.057139 -27.394385) (xy 147.106726 -27.371745) (xy 147.159031 -27.356392) (xy 147.212988 -27.34864)
			(xy 147.240244 -27.34818) (xy 147.254329 -27.348279) (xy 147.282425 -27.350314) (xy 147.296378 -27.352244)
			(xy 147.310094 -27.354276) (xy 147.336002 -27.343862) (xy 147.40636 -27.249882) (xy 147.409408 -27.221942)
			(xy 147.403566 -27.209242) (xy 147.392524 -27.184112) (xy 147.376921 -27.131489) (xy 147.369014 -27.077174)
			(xy 147.368514 -27.04973) (xy 147.369 -27.022479) (xy 147.376756 -26.968531) (xy 147.392111 -26.916236)
			(xy 147.414753 -26.866659) (xy 147.444219 -26.820809) (xy 147.47991 -26.779618) (xy 147.521101 -26.743927)
			(xy 147.566951 -26.714461) (xy 147.616528 -26.691819) (xy 147.668823 -26.676464) (xy 147.722771 -26.668708)
			(xy 147.777273 -26.668708) (xy 147.831221 -26.676464) (xy 147.883516 -26.691819) (xy 147.933093 -26.714461)
			(xy 147.978943 -26.743927) (xy 148.020134 -26.779618) (xy 148.055825 -26.820809) (xy 148.085291 -26.866659)
			(xy 148.107933 -26.916236) (xy 148.123288 -26.968531) (xy 148.131044 -27.022479) (xy 148.13153 -27.04973)
			(xy 148.130906 -27.081146) (xy 148.120644 -27.143132) (xy 148.100371 -27.202602) (xy 148.086064 -27.230578)
			(xy 148.08073 -27.24023) (xy 148.079206 -27.262074) (xy 148.113496 -27.354022) (xy 148.128736 -27.369516)
			(xy 148.138896 -27.37358) (xy 148.165539 -27.384347) (xy 148.215507 -27.412726) (xy 148.26065 -27.448282)
			(xy 148.299945 -27.49021) (xy 148.332503 -27.537561) (xy 148.357586 -27.589261) (xy 148.374626 -27.644141)
			(xy 148.383237 -27.700956) (xy 148.383752 -27.729688) (xy 148.383211 -27.756937) (xy 148.375457 -27.81088)
			(xy 148.360106 -27.863171) (xy 148.337469 -27.912745) (xy 148.308008 -27.958594) (xy 148.272323 -27.999783)
			(xy 148.231139 -28.035475) (xy 148.185295 -28.064942) (xy 148.135724 -28.087586) (xy 148.083435 -28.102945)
			(xy 148.029493 -28.110707) (xy 148.002244 -28.111196) (xy 147.973328 -28.110648) (xy 147.916158 -28.101925)
			(xy 147.86096 -28.084673) (xy 147.808998 -28.059287) (xy 147.761463 -28.026349) (xy 147.719445 -27.986613)
			(xy 147.701254 -27.96413) (xy 147.69372 -27.95534) (xy 147.67294 -27.945175) (xy 147.661376 -27.944572)
			(xy 147.581112 -27.944572) (xy 147.569541 -27.945124) (xy 147.548769 -27.955329) (xy 147.541234 -27.96413)
			(xy 147.523031 -27.986603) (xy 147.481013 -28.026338) (xy 147.43348 -28.059277) (xy 147.381522 -28.084667)
			(xy 147.326326 -28.101926) (xy 147.269159 -28.110659) (xy 147.240244 -28.111196) (xy 147.212988 -28.11076)
			(xy 147.159031 -28.103008) (xy 147.106726 -28.087655) (xy 147.057139 -28.065015) (xy 147.011278 -28.035547)
			(xy 146.970079 -27.999852) (xy 146.93438 -27.958657) (xy 146.904907 -27.9128) (xy 146.88226 -27.863215)
			(xy 146.866901 -27.810912) (xy 146.859143 -27.756956) (xy 143.615211 -27.756956) (xy 143.648846 -27.788923)
			(xy 143.66748 -27.812238) (xy 143.667988 -27.812746) (xy 143.670274 -27.81554) (xy 143.676116 -27.821382)
			(xy 143.681949 -27.826714) (xy 143.696048 -27.833831) (xy 143.703802 -27.835352) (xy 143.704056 -27.835606)
			(xy 143.783812 -27.84729) (xy 143.80337 -27.84221) (xy 143.811752 -27.83586) (xy 143.836056 -27.818011)
			(xy 143.889134 -27.789404) (xy 143.946054 -27.769508) (xy 144.005396 -27.75882) (xy 144.035526 -27.757628)
			(xy 144.042892 -27.757374) (xy 144.055084 -27.757628) (xy 144.062196 -27.758136) (xy 144.06245 -27.758136)
			(xy 144.089929 -27.759989) (xy 144.143968 -27.770613) (xy 144.195917 -27.788902) (xy 144.244693 -27.814476)
			(xy 144.289282 -27.846803) (xy 144.328755 -27.885209) (xy 144.36229 -27.928895) (xy 144.37614 -27.9527)
			(xy 144.380889 -27.960372) (xy 144.394641 -27.972033) (xy 144.411574 -27.978229) (xy 144.42059 -27.978608)
			(xy 144.5006 -27.978608) (xy 144.509487 -27.978267) (xy 144.526184 -27.972172) (xy 144.539779 -27.960722)
			(xy 144.544542 -27.953208) (xy 144.55898 -27.92921) (xy 144.593792 -27.885341) (xy 144.613884 -27.865832)
			(xy 144.614392 -27.865324) (xy 144.61617 -27.863546) (xy 144.637616 -27.84379) (xy 144.685386 -27.810356)
			(xy 144.737683 -27.784574) (xy 144.793293 -27.767045) (xy 144.850922 -27.758175) (xy 144.880076 -27.757628)
			(xy 144.907329 -27.75809) (xy 144.961281 -27.765844) (xy 145.013579 -27.781198) (xy 145.06316 -27.80384)
			(xy 145.109014 -27.833308) (xy 145.150206 -27.869002) (xy 145.185899 -27.910196) (xy 145.215366 -27.95605)
			(xy 145.238006 -28.005632) (xy 145.253358 -28.057931) (xy 145.261111 -28.111883) (xy 145.261584 -28.139136)
			(xy 145.768058 -28.139136) (xy 145.772129 -28.083514) (xy 145.784255 -28.029077) (xy 145.804178 -27.976986)
			(xy 145.831474 -27.928351) (xy 145.86556 -27.884208) (xy 145.905709 -27.845499) (xy 145.951067 -27.813048)
			(xy 146.000667 -27.787547) (xy 146.053451 -27.76954) (xy 146.108294 -27.75941) (xy 146.164028 -27.757373)
			(xy 146.219465 -27.763473) (xy 146.273422 -27.777579) (xy 146.324751 -27.799391) (xy 146.372357 -27.828445)
			(xy 146.415225 -27.86412) (xy 146.452442 -27.905657) (xy 146.483215 -27.95217) (xy 146.506887 -28.002667)
			(xy 146.522955 -28.056074) (xy 146.531075 -28.11125) (xy 146.531584 -28.139136) (xy 146.531075 -28.167022)
			(xy 146.522955 -28.222198) (xy 146.506887 -28.275605) (xy 146.483215 -28.326102) (xy 146.452442 -28.372615)
			(xy 146.415225 -28.414152) (xy 146.372357 -28.449827) (xy 146.324751 -28.478881) (xy 146.273422 -28.500693)
			(xy 146.219465 -28.514799) (xy 146.164028 -28.520899) (xy 146.108294 -28.518862) (xy 146.053451 -28.508732)
			(xy 146.000667 -28.490725) (xy 145.951067 -28.465224) (xy 145.905709 -28.432773) (xy 145.86556 -28.394064)
			(xy 145.831474 -28.349921) (xy 145.804178 -28.301286) (xy 145.784255 -28.249195) (xy 145.772129 -28.194758)
			(xy 145.768058 -28.139136) (xy 145.261584 -28.139136) (xy 145.261151 -28.16509) (xy 145.254119 -28.216519)
			(xy 145.240177 -28.266519) (xy 145.219583 -28.314166) (xy 145.192716 -28.35858) (xy 145.160074 -28.398939)
			(xy 145.141442 -28.417012) (xy 145.140426 -28.418028) (xy 145.139918 -28.418536) (xy 145.118464 -28.4385)
			(xy 145.070571 -28.47227) (xy 145.018074 -28.498314) (xy 144.962211 -28.51602) (xy 144.904297 -28.524971)
			(xy 144.874996 -28.52547) (xy 144.846442 -28.524937) (xy 144.789971 -28.516427) (xy 144.735399 -28.499598)
			(xy 144.683943 -28.474826) (xy 144.636753 -28.442663) (xy 144.594882 -28.403828) (xy 144.559264 -28.359187)
			(xy 144.544542 -28.334716) (xy 144.539764 -28.327222) (xy 144.52616 -28.315807) (xy 144.509479 -28.309716)
			(xy 144.5006 -28.309316) (xy 144.414494 -28.309316) (xy 144.382236 -28.327858) (xy 144.372838 -28.33497)
			(xy 144.368266 -28.339288) (xy 144.364964 -28.344622) (xy 144.35074 -28.36545) (xy 144.350486 -28.36545)
			(xy 144.341279 -28.377699) (xy 144.321189 -28.400842) (xy 144.310354 -28.411678) (xy 144.304004 -28.417774)
			(xy 144.303496 -28.418282) (xy 144.282032 -28.438286) (xy 144.234104 -28.472127) (xy 144.181559 -28.498229)
			(xy 144.125636 -28.515976) (xy 144.067656 -28.524949) (xy 144.03832 -28.52547) (xy 144.009162 -28.524919)
			(xy 143.951524 -28.516048) (xy 143.895908 -28.498511) (xy 143.843608 -28.472715) (xy 143.795841 -28.439261)
			(xy 143.753722 -28.398929) (xy 143.735552 -28.376118) (xy 143.73352 -28.373324) (xy 143.727678 -28.367482)
			(xy 143.721712 -28.361986) (xy 143.707204 -28.354751) (xy 143.69923 -28.353258) (xy 143.629126 -28.342844)
			(xy 143.624292 -28.342274) (xy 143.614573 -28.342795) (xy 143.609822 -28.34386) (xy 143.599662 -28.346146)
			(xy 143.59128 -28.352242) (xy 143.584676 -28.357068) (xy 143.584422 -28.357322) (xy 143.57985 -28.360624)
			(xy 143.568166 -28.37307) (xy 143.560292 -28.383992) (xy 143.551656 -28.399994) (xy 143.548922 -28.405579)
			(xy 143.545966 -28.417654) (xy 143.545814 -28.42387) (xy 143.545814 -28.428696) (xy 143.546023 -28.435277)
			(xy 143.549364 -28.448009) (xy 143.552418 -28.453842) (xy 143.556482 -28.460954) (xy 143.5735 -28.478734)
			(xy 143.57858 -28.482036) (xy 143.601036 -28.497238) (xy 143.641824 -28.532974) (xy 143.677151 -28.574116)
			(xy 143.706308 -28.619839) (xy 143.728708 -28.669225) (xy 143.743902 -28.721281) (xy 143.751585 -28.774962)
			(xy 143.752062 -28.802076) (xy 143.752062 -28.802584) (xy 143.751634 -28.828234) (xy 143.744737 -28.879069)
			(xy 143.731093 -28.928523) (xy 143.710948 -28.975703) (xy 143.684664 -29.019759) (xy 143.652715 -29.059897)
			(xy 143.63446 -29.07792) (xy 143.633952 -29.078174) (xy 143.610749 -29.100199) (xy 143.558399 -29.136964)
			(xy 143.529812 -29.151326) (xy 143.51635 -29.157676) (xy 143.500856 -29.182314) (xy 143.500856 -29.217874)
			(xy 143.501325 -29.227748) (xy 143.508778 -29.246036) (xy 143.515334 -29.253434) (xy 143.515588 -29.253688)
			(xy 143.530066 -29.268166) (xy 143.537686 -29.271976) (xy 143.561439 -29.28407) (xy 143.605635 -29.313862)
			(xy 143.645256 -29.349516) (xy 143.679529 -29.390336) (xy 143.707787 -29.435529) (xy 143.729482 -29.484215)
			(xy 143.744189 -29.535446) (xy 143.751624 -29.588226) (xy 143.752062 -29.614876) (xy 143.751622 -29.640889)
			(xy 143.744555 -29.692433) (xy 143.730547 -29.742538) (xy 143.70986 -29.790274) (xy 143.682877 -29.834756)
			(xy 143.650098 -29.875158) (xy 143.631412 -29.89326) (xy 143.630904 -29.893768) (xy 143.623483 -29.900865)
			(xy 143.607982 -29.914337) (xy 143.599916 -29.920692) (xy 143.591086 -29.928282) (xy 143.580905 -29.949193)
			(xy 143.580358 -29.960824) (xy 143.580358 -30.031944) (xy 143.580899 -30.04377) (xy 143.591354 -30.064977)
			(xy 143.600424 -30.072584) (xy 143.623551 -30.090716) (xy 143.664472 -30.132889) (xy 143.698441 -30.180841)
			(xy 143.724651 -30.233436) (xy 143.742484 -30.289429) (xy 143.751517 -30.347494) (xy 143.752062 -30.376876)
			(xy 143.752062 -30.377384) (xy 143.751634 -30.403034) (xy 143.744737 -30.453869) (xy 143.731093 -30.503323)
			(xy 143.710948 -30.550503) (xy 143.684664 -30.594559) (xy 143.652715 -30.634697) (xy 143.63446 -30.65272)
			(xy 143.633952 -30.652974) (xy 143.610749 -30.674999) (xy 143.558399 -30.711764) (xy 143.529812 -30.726126)
			(xy 143.51635 -30.732476) (xy 143.500856 -30.757114) (xy 143.500856 -31.141416) (xy 143.501202 -31.150332)
			(xy 143.507325 -31.16708) (xy 143.518822 -31.180711) (xy 143.534297 -31.18957) (xy 143.54302 -31.191454)
			(xy 143.543274 -31.191454) (xy 143.56968 -31.196295) (xy 143.620886 -31.212416) (xy 143.669326 -31.235557)
			(xy 143.714042 -31.265263) (xy 143.754151 -31.300947) (xy 143.788859 -31.341902) (xy 143.81748 -31.38732)
			(xy 143.83945 -31.436303) (xy 143.854333 -31.487883) (xy 143.861836 -31.54104) (xy 143.862298 -31.567882)
			(xy 143.861862 -31.593834) (xy 143.854823 -31.645258) (xy 143.840874 -31.695253) (xy 143.83049 -31.719266)
			(xy 144.385536 -31.719266) (xy 144.389607 -31.663644) (xy 144.401733 -31.609207) (xy 144.421656 -31.557116)
			(xy 144.448952 -31.508481) (xy 144.483038 -31.464338) (xy 144.523187 -31.425629) (xy 144.568545 -31.393178)
			(xy 144.618145 -31.367677) (xy 144.670929 -31.34967) (xy 144.725772 -31.33954) (xy 144.781506 -31.337503)
			(xy 144.836943 -31.343603) (xy 144.8909 -31.357709) (xy 144.942229 -31.379521) (xy 144.989835 -31.408575)
			(xy 145.032703 -31.44425) (xy 145.06992 -31.485787) (xy 145.100693 -31.5323) (xy 145.124365 -31.582797)
			(xy 145.140433 -31.636204) (xy 145.144583 -31.664402) (xy 145.661124 -31.664402) (xy 145.665195 -31.60878)
			(xy 145.677321 -31.554343) (xy 145.697244 -31.502252) (xy 145.72454 -31.453617) (xy 145.758626 -31.409474)
			(xy 145.798775 -31.370765) (xy 145.844133 -31.338314) (xy 145.893733 -31.312813) (xy 145.946517 -31.294806)
			(xy 146.00136 -31.284676) (xy 146.057094 -31.282639) (xy 146.112531 -31.288739) (xy 146.166488 -31.302845)
			(xy 146.217817 -31.324657) (xy 146.265423 -31.353711) (xy 146.308291 -31.389386) (xy 146.345508 -31.430923)
			(xy 146.376281 -31.477436) (xy 146.399953 -31.527933) (xy 146.416021 -31.58134) (xy 146.424141 -31.636516)
			(xy 146.42465 -31.664402) (xy 146.424141 -31.692288) (xy 146.416021 -31.747464) (xy 146.407081 -31.777178)
			(xy 146.926298 -31.777178) (xy 146.930369 -31.721556) (xy 146.942495 -31.667119) (xy 146.962418 -31.615028)
			(xy 146.989714 -31.566393) (xy 147.0238 -31.52225) (xy 147.063949 -31.483541) (xy 147.109307 -31.45109)
			(xy 147.158907 -31.425589) (xy 147.211691 -31.407582) (xy 147.266534 -31.397452) (xy 147.322268 -31.395415)
			(xy 147.377705 -31.401515) (xy 147.431662 -31.415621) (xy 147.482991 -31.437433) (xy 147.530597 -31.466487)
			(xy 147.573465 -31.502162) (xy 147.610682 -31.543699) (xy 147.641455 -31.590212) (xy 147.665127 -31.640709)
			(xy 147.681195 -31.694116) (xy 147.689315 -31.749292) (xy 147.689824 -31.777178) (xy 147.689315 -31.805064)
			(xy 147.681195 -31.86024) (xy 147.665127 -31.913647) (xy 147.641455 -31.964144) (xy 147.610682 -32.010657)
			(xy 147.573465 -32.052194) (xy 147.530597 -32.087869) (xy 147.482991 -32.116923) (xy 147.431662 -32.138735)
			(xy 147.377705 -32.152841) (xy 147.322268 -32.158941) (xy 147.266534 -32.156904) (xy 147.211691 -32.146774)
			(xy 147.158907 -32.128767) (xy 147.109307 -32.103266) (xy 147.063949 -32.070815) (xy 147.0238 -32.032106)
			(xy 146.989714 -31.987963) (xy 146.962418 -31.939328) (xy 146.942495 -31.887237) (xy 146.930369 -31.8328)
			(xy 146.926298 -31.777178) (xy 146.407081 -31.777178) (xy 146.399953 -31.800871) (xy 146.376281 -31.851368)
			(xy 146.345508 -31.897881) (xy 146.308291 -31.939418) (xy 146.265423 -31.975093) (xy 146.217817 -32.004147)
			(xy 146.166488 -32.025959) (xy 146.112531 -32.040065) (xy 146.057094 -32.046165) (xy 146.00136 -32.044128)
			(xy 145.946517 -32.033998) (xy 145.893733 -32.015991) (xy 145.844133 -31.99049) (xy 145.798775 -31.958039)
			(xy 145.758626 -31.91933) (xy 145.72454 -31.875187) (xy 145.697244 -31.826552) (xy 145.677321 -31.774461)
			(xy 145.665195 -31.720024) (xy 145.661124 -31.664402) (xy 145.144583 -31.664402) (xy 145.148553 -31.69138)
			(xy 145.149062 -31.719266) (xy 145.148553 -31.747152) (xy 145.140433 -31.802328) (xy 145.124365 -31.855735)
			(xy 145.100693 -31.906232) (xy 145.06992 -31.952745) (xy 145.032703 -31.994282) (xy 144.989835 -32.029957)
			(xy 144.942229 -32.059011) (xy 144.8909 -32.080823) (xy 144.836943 -32.094929) (xy 144.781506 -32.101029)
			(xy 144.725772 -32.098992) (xy 144.670929 -32.088862) (xy 144.618145 -32.070855) (xy 144.568545 -32.045354)
			(xy 144.523187 -32.012903) (xy 144.483038 -31.974194) (xy 144.448952 -31.930051) (xy 144.421656 -31.881416)
			(xy 144.401733 -31.829325) (xy 144.389607 -31.774888) (xy 144.385536 -31.719266) (xy 143.83049 -31.719266)
			(xy 143.820272 -31.742893) (xy 143.793398 -31.787298) (xy 143.760749 -31.827647) (xy 143.742156 -31.845758)
			(xy 143.741648 -31.846266) (xy 143.740886 -31.847028) (xy 143.720238 -31.866303) (xy 143.674299 -31.899167)
			(xy 143.624012 -31.924889) (xy 143.570478 -31.942904) (xy 143.542766 -31.948374) (xy 143.524478 -31.951676)
			(xy 143.500856 -31.979616) (xy 143.500856 -33.512252) (xy 143.501094 -33.519204) (xy 143.504828 -33.532597)
			(xy 143.508222 -33.538668) (xy 143.511937 -33.544406) (xy 143.521853 -33.553805) (xy 143.52778 -33.55721)
			(xy 143.53032 -33.55848) (xy 143.616934 -33.595818) (xy 143.627389 -33.599683) (xy 143.649645 -33.599014)
			(xy 143.65986 -33.594548) (xy 143.666972 -33.590992) (xy 143.672306 -33.585912) (xy 143.683096 -33.575878)
			(xy 143.705981 -33.557314) (xy 143.718026 -33.548828) (xy 143.71828 -33.548574) (xy 143.725456 -33.543095)
			(xy 143.735722 -33.528258) (xy 143.738346 -33.519618) (xy 143.754856 -33.455356) (xy 143.756722 -33.446303)
			(xy 143.754631 -33.427951) (xy 143.750792 -33.419542) (xy 143.750792 -33.419288) (xy 143.74876 -33.415478)
			(xy 143.748252 -33.414208) (xy 143.736162 -33.387984) (xy 143.71914 -33.332806) (xy 143.710613 -33.275695)
			(xy 143.710152 -33.246822) (xy 143.710152 -33.242758) (xy 143.710999 -33.215757) (xy 143.719368 -33.16239)
			(xy 143.735181 -33.110737) (xy 143.758123 -33.061831) (xy 143.787735 -33.01665) (xy 143.823424 -32.976099)
			(xy 143.864477 -32.940988) (xy 143.910072 -32.912019) (xy 143.959298 -32.889772) (xy 144.01117 -32.874692)
			(xy 144.06465 -32.867079) (xy 144.09166 -32.866584) (xy 144.118915 -32.867045) (xy 144.172871 -32.874797)
			(xy 144.225174 -32.890149) (xy 144.274759 -32.912789) (xy 144.320618 -32.942256) (xy 144.361816 -32.97795)
			(xy 144.397515 -33.019143) (xy 144.426987 -33.064998) (xy 144.449634 -33.114581) (xy 144.464993 -33.166882)
			(xy 144.472752 -33.220837) (xy 144.473168 -33.248092) (xy 144.472725 -33.274147) (xy 144.465638 -33.325773)
			(xy 144.451595 -33.375956) (xy 144.430856 -33.423761) (xy 144.403808 -33.468302) (xy 144.370952 -33.508749)
			(xy 144.332901 -33.544352) (xy 144.311878 -33.55975) (xy 144.308322 -33.56229) (xy 144.30121 -33.569402)
			(xy 144.300956 -33.56991) (xy 144.296421 -33.574789) (xy 144.289852 -33.586372) (xy 144.288002 -33.59277)
			(xy 144.272 -33.655508) (xy 144.270986 -33.659941) (xy 144.270348 -33.669011) (xy 144.27073 -33.673542)
			(xy 144.271746 -33.682432) (xy 144.27581 -33.690814) (xy 144.276064 -33.691068) (xy 144.28231 -33.703848)
			(xy 144.293114 -33.730165) (xy 144.297654 -33.743646) (xy 144.300448 -33.752028) (xy 144.311878 -33.767014)
			(xy 144.32026 -33.77184) (xy 144.37233 -33.803082) (xy 144.376526 -33.805487) (xy 144.385606 -33.808818)
			(xy 144.390364 -33.809686) (xy 144.399508 -33.81121) (xy 144.405096 -33.810194) (xy 144.42498 -33.806152)
			(xy 144.465325 -33.801825) (xy 144.485614 -33.801558) (xy 144.512865 -33.802045) (xy 144.566814 -33.809803)
			(xy 144.619109 -33.825159) (xy 144.668686 -33.8478) (xy 144.684079 -33.857692) (xy 145.590258 -33.857692)
			(xy 145.594329 -33.80207) (xy 145.606455 -33.747633) (xy 145.626378 -33.695542) (xy 145.653674 -33.646907)
			(xy 145.68776 -33.602764) (xy 145.727909 -33.564055) (xy 145.773267 -33.531604) (xy 145.822867 -33.506103)
			(xy 145.875651 -33.488096) (xy 145.930494 -33.477966) (xy 145.986228 -33.475929) (xy 146.041665 -33.482029)
			(xy 146.095622 -33.496135) (xy 146.146951 -33.517947) (xy 146.194557 -33.547001) (xy 146.237425 -33.582676)
			(xy 146.274642 -33.624213) (xy 146.305415 -33.670726) (xy 146.329087 -33.721223) (xy 146.345155 -33.77463)
			(xy 146.353275 -33.829806) (xy 146.353784 -33.857692) (xy 146.353275 -33.885578) (xy 146.345155 -33.940754)
			(xy 146.329087 -33.994161) (xy 146.305415 -34.044658) (xy 146.274642 -34.091171) (xy 146.237425 -34.132708)
			(xy 146.194557 -34.168383) (xy 146.146951 -34.197437) (xy 146.095622 -34.219249) (xy 146.041665 -34.233355)
			(xy 145.986228 -34.239455) (xy 145.930494 -34.237418) (xy 145.875651 -34.227288) (xy 145.822867 -34.209281)
			(xy 145.773267 -34.18378) (xy 145.727909 -34.151329) (xy 145.68776 -34.11262) (xy 145.653674 -34.068477)
			(xy 145.626378 -34.019842) (xy 145.606455 -33.967751) (xy 145.594329 -33.913314) (xy 145.590258 -33.857692)
			(xy 144.684079 -33.857692) (xy 144.714537 -33.877266) (xy 144.755729 -33.912957) (xy 144.791422 -33.954147)
			(xy 144.82089 -33.999996) (xy 144.843534 -34.049573) (xy 144.858893 -34.101867) (xy 144.866654 -34.155815)
			(xy 144.867122 -34.183066) (xy 144.866687 -34.209019) (xy 144.859651 -34.260445) (xy 144.845704 -34.310441)
			(xy 144.825104 -34.358083) (xy 144.798233 -34.402491) (xy 144.765585 -34.442843) (xy 144.74698 -34.460942)
			(xy 144.745964 -34.461958) (xy 144.745456 -34.462466) (xy 144.724 -34.482425) (xy 144.676104 -34.516185)
			(xy 144.623607 -34.542218) (xy 144.567745 -34.559914) (xy 144.509833 -34.568854) (xy 144.480534 -34.5694)
			(xy 144.453905 -34.56894) (xy 144.401164 -34.561543) (xy 144.349962 -34.546887) (xy 144.301295 -34.525258)
			(xy 144.256106 -34.497074) (xy 144.215272 -34.462884) (xy 144.179586 -34.42335) (xy 144.149742 -34.379241)
			(xy 144.126317 -34.331411) (xy 144.117568 -34.306256) (xy 144.114774 -34.29762) (xy 144.103598 -34.283396)
			(xy 144.030192 -34.239454) (xy 144.012412 -34.236152) (xy 144.003268 -34.23793) (xy 143.986458 -34.240774)
			(xy 143.952498 -34.243828) (xy 143.93545 -34.244026) (xy 143.935196 -34.244026) (xy 143.906185 -34.243486)
			(xy 143.848829 -34.234709) (xy 143.793462 -34.217357) (xy 143.741356 -34.191829) (xy 143.693711 -34.158714)
			(xy 143.672306 -34.139124) (xy 143.666972 -34.134044) (xy 143.65986 -34.130488) (xy 143.649655 -34.125978)
			(xy 143.62738 -34.125304) (xy 143.616934 -34.129218) (xy 143.53159 -34.166048) (xy 143.522665 -34.17038)
			(xy 143.508776 -34.184517) (xy 143.501307 -34.202873) (xy 143.500856 -34.212784) (xy 143.500856 -35.264852)
			(xy 146.0025 -35.264852) (xy 146.006571 -35.20923) (xy 146.018697 -35.154793) (xy 146.03862 -35.102702)
			(xy 146.065916 -35.054067) (xy 146.100002 -35.009924) (xy 146.140151 -34.971215) (xy 146.185509 -34.938764)
			(xy 146.235109 -34.913263) (xy 146.287893 -34.895256) (xy 146.342736 -34.885126) (xy 146.39847 -34.883089)
			(xy 146.453907 -34.889189) (xy 146.507864 -34.903295) (xy 146.559193 -34.925107) (xy 146.606799 -34.954161)
			(xy 146.649667 -34.989836) (xy 146.674501 -35.017553) (xy 148.319956 -35.017553) (xy 148.319956 -34.963047)
			(xy 148.327713 -34.909097) (xy 148.343069 -34.856799) (xy 148.365711 -34.807219) (xy 148.395179 -34.761366)
			(xy 148.430872 -34.720174) (xy 148.472064 -34.68448) (xy 148.517917 -34.655012) (xy 148.567497 -34.632369)
			(xy 148.619795 -34.617013) (xy 148.673745 -34.609256) (xy 148.700998 -34.60877) (xy 148.71811 -34.608956)
			(xy 148.752197 -34.612012) (xy 148.76907 -34.614866) (xy 148.780337 -34.616235) (xy 148.802217 -34.610325)
			(xy 148.811234 -34.603436) (xy 148.835618 -34.582354) (xy 148.844015 -34.574436) (xy 148.853131 -34.553257)
			(xy 148.853144 -34.541714) (xy 148.852636 -34.52241) (xy 148.852636 -33.65881) (xy 148.853144 -33.638744)
			(xy 148.852971 -33.627235) (xy 148.843869 -33.606129) (xy 148.835618 -33.598104) (xy 148.811234 -33.577022)
			(xy 148.802227 -33.5701) (xy 148.780337 -33.564155) (xy 148.76907 -33.565592) (xy 148.7522 -33.568467)
			(xy 148.718111 -33.571516) (xy 148.700998 -33.571688) (xy 148.673745 -33.571242) (xy 148.619795 -33.563485)
			(xy 148.567498 -33.548129) (xy 148.517918 -33.525486) (xy 148.472066 -33.496018) (xy 148.430874 -33.460325)
			(xy 148.39518 -33.419133) (xy 148.365713 -33.37328) (xy 148.343071 -33.3237) (xy 148.327715 -33.271403)
			(xy 148.319958 -33.217453) (xy 148.319958 -33.162947) (xy 148.327715 -33.108997) (xy 148.343071 -33.0567)
			(xy 148.365713 -33.00712) (xy 148.39518 -32.961267) (xy 148.430874 -32.920075) (xy 148.472066 -32.884382)
			(xy 148.517918 -32.854914) (xy 148.567498 -32.832271) (xy 148.619795 -32.816915) (xy 148.673745 -32.809158)
			(xy 148.700998 -32.808672) (xy 148.728006 -32.809121) (xy 148.781485 -32.816728) (xy 148.833355 -32.831802)
			(xy 148.88258 -32.854044) (xy 148.928175 -32.883007) (xy 148.969227 -32.918114) (xy 149.004917 -32.958661)
			(xy 149.034529 -33.003837) (xy 149.057471 -33.052739) (xy 149.073286 -33.104389) (xy 149.077934 -33.130998)
			(xy 149.079458 -33.141666) (xy 149.090888 -33.159446) (xy 149.171152 -33.212786) (xy 149.191726 -33.216596)
			(xy 149.202394 -33.214056) (xy 149.229025 -33.207921) (xy 149.283273 -33.201303) (xy 149.310598 -33.200848)
			(xy 149.337922 -33.20131) (xy 149.39217 -33.207927) (xy 149.418802 -33.214056) (xy 149.42947 -33.216596)
			(xy 149.450044 -33.212786) (xy 149.530308 -33.159446) (xy 149.541738 -33.141666) (xy 149.543262 -33.130998)
			(xy 149.547869 -33.104383) (xy 149.563703 -33.052742) (xy 149.586661 -33.003849) (xy 149.616283 -32.958682)
			(xy 149.651979 -32.918143) (xy 149.693033 -32.883042) (xy 149.738627 -32.85408) (xy 149.787849 -32.831837)
			(xy 149.839716 -32.816757) (xy 149.893191 -32.80914) (xy 149.920198 -32.808672) (xy 149.947569 -32.809122)
			(xy 150.00175 -32.816941) (xy 150.054253 -32.832433) (xy 150.104 -32.855279) (xy 150.149966 -32.885008)
			(xy 150.170896 -32.902652) (xy 150.178008 -32.908748) (xy 150.195026 -32.915098) (xy 150.28037 -32.915098)
			(xy 150.297388 -32.908748) (xy 150.3045 -32.902652) (xy 150.325428 -32.885008) (xy 150.371401 -32.855295)
			(xy 150.42115 -32.832459) (xy 150.473651 -32.816969) (xy 150.527828 -32.809144) (xy 150.555198 -32.808672)
			(xy 150.57231 -32.808858) (xy 150.606397 -32.811914) (xy 150.62327 -32.814768) (xy 150.634537 -32.816137)
			(xy 150.656417 -32.810227) (xy 150.665434 -32.803338) (xy 150.689818 -32.782256) (xy 150.698214 -32.774337)
			(xy 150.707331 -32.753158) (xy 150.707344 -32.741616) (xy 150.706836 -32.722312) (xy 150.706836 -31.858712)
			(xy 150.707344 -31.838646) (xy 150.70717 -31.827137) (xy 150.698069 -31.806031) (xy 150.689818 -31.798006)
			(xy 150.665434 -31.776924) (xy 150.656427 -31.770002) (xy 150.634537 -31.764057) (xy 150.62327 -31.765494)
			(xy 150.6064 -31.768369) (xy 150.572311 -31.771418) (xy 150.555198 -31.77159) (xy 150.527828 -31.771128)
			(xy 150.473648 -31.763309) (xy 150.421145 -31.747819) (xy 150.371398 -31.724977) (xy 150.325432 -31.695252)
			(xy 150.3045 -31.67761) (xy 150.297388 -31.671514) (xy 150.280624 -31.665164) (xy 150.195026 -31.665164)
			(xy 150.178008 -31.671514) (xy 150.17115 -31.677864) (xy 150.150197 -31.695519) (xy 150.104182 -31.72526)
			(xy 150.054382 -31.748108) (xy 150.001826 -31.763591) (xy 149.947593 -31.771391) (xy 149.920198 -31.771844)
			(xy 149.89322 -31.771376) (xy 149.839801 -31.763794) (xy 149.787985 -31.748755) (xy 149.738808 -31.726558)
			(xy 149.693253 -31.697648) (xy 149.65223 -31.662602) (xy 149.61656 -31.62212) (xy 149.586955 -31.577013)
			(xy 149.564008 -31.528181) (xy 149.548177 -31.476602) (xy 149.543516 -31.450026) (xy 149.541738 -31.439358)
			(xy 149.530308 -31.421832) (xy 149.450044 -31.368238) (xy 149.42947 -31.364682) (xy 149.419056 -31.367222)
			(xy 149.392355 -31.3733) (xy 149.337979 -31.379791) (xy 149.310598 -31.380176) (xy 149.283216 -31.379798)
			(xy 149.22884 -31.373305) (xy 149.20214 -31.367222) (xy 149.191726 -31.364682) (xy 149.171152 -31.368238)
			(xy 149.090888 -31.421832) (xy 149.079458 -31.439358) (xy 149.07768 -31.450026) (xy 149.072979 -31.47659)
			(xy 149.057124 -31.528152) (xy 149.034163 -31.576966) (xy 149.004554 -31.622058) (xy 148.968887 -31.662529)
			(xy 148.927875 -31.697571) (xy 148.882334 -31.726485) (xy 148.833173 -31.748695) (xy 148.781374 -31.763757)
			(xy 148.72797 -31.77137) (xy 148.700998 -31.771844) (xy 148.673749 -31.771286) (xy 148.619807 -31.76353)
			(xy 148.567518 -31.748176) (xy 148.517945 -31.725537) (xy 148.4721 -31.696073) (xy 148.430913 -31.660385)
			(xy 148.395226 -31.619199) (xy 148.365762 -31.573353) (xy 148.343123 -31.523781) (xy 148.32777 -31.471491)
			(xy 148.320014 -31.417549) (xy 148.320014 -31.363051) (xy 148.32777 -31.309109) (xy 148.343123 -31.256819)
			(xy 148.365762 -31.207247) (xy 148.395226 -31.161401) (xy 148.430913 -31.120215) (xy 148.4721 -31.084527)
			(xy 148.517945 -31.055063) (xy 148.567518 -31.032424) (xy 148.619807 -31.01707) (xy 148.673749 -31.009314)
			(xy 148.700998 -31.008828) (xy 148.71811 -31.009015) (xy 148.752197 -31.01207) (xy 148.76907 -31.014924)
			(xy 148.780337 -31.016303) (xy 148.802218 -31.010387) (xy 148.811234 -31.003494) (xy 148.835618 -30.982412)
			(xy 148.843987 -30.974469) (xy 148.853119 -30.953309) (xy 148.853144 -30.941772) (xy 148.852636 -30.922468)
			(xy 148.852636 -30.058868) (xy 148.853144 -30.038802) (xy 148.852937 -30.027296) (xy 148.843859 -30.00619)
			(xy 148.835618 -29.998162) (xy 148.811234 -29.97708) (xy 148.80223 -29.970154) (xy 148.780338 -29.964213)
			(xy 148.76907 -29.96565) (xy 148.7522 -29.968526) (xy 148.718111 -29.971574) (xy 148.700998 -29.971746)
			(xy 148.67375 -29.971184) (xy 148.619808 -29.963428) (xy 148.567518 -29.948074) (xy 148.517946 -29.925435)
			(xy 148.472101 -29.895972) (xy 148.430915 -29.860284) (xy 148.395227 -29.819098) (xy 148.365764 -29.773252)
			(xy 148.343125 -29.72368) (xy 148.327772 -29.671391) (xy 148.320016 -29.617448) (xy 148.320016 -29.562952)
			(xy 148.327772 -29.509009) (xy 148.343125 -29.45672) (xy 148.365764 -29.407148) (xy 148.395227 -29.361302)
			(xy 148.430915 -29.320116) (xy 148.472101 -29.284428) (xy 148.517946 -29.254965) (xy 148.567518 -29.232326)
			(xy 148.619808 -29.216972) (xy 148.67375 -29.209216) (xy 148.700998 -29.20873) (xy 148.728005 -29.209215)
			(xy 148.78148 -29.21682) (xy 148.833347 -29.231893) (xy 148.88257 -29.254131) (xy 148.928163 -29.283091)
			(xy 148.969216 -29.318193) (xy 149.004905 -29.358735) (xy 149.034519 -29.403907) (xy 149.057465 -29.452804)
			(xy 149.073283 -29.504449) (xy 149.077934 -29.531056) (xy 149.079458 -29.541724) (xy 149.090888 -29.559504)
			(xy 149.171152 -29.612844) (xy 149.191726 -29.616654) (xy 149.202394 -29.614114) (xy 149.229034 -29.608055)
			(xy 149.283281 -29.601559) (xy 149.310598 -29.60116) (xy 149.337916 -29.601541) (xy 149.392165 -29.608039)
			(xy 149.418802 -29.614114) (xy 149.42947 -29.616654) (xy 149.450044 -29.612844) (xy 149.530308 -29.559504)
			(xy 149.541738 -29.541724) (xy 149.543262 -29.531056) (xy 149.547913 -29.504449) (xy 149.56374 -29.452808)
			(xy 149.586691 -29.403915) (xy 149.616307 -29.358747) (xy 149.651997 -29.318206) (xy 149.693047 -29.283104)
			(xy 149.738637 -29.254141) (xy 149.787856 -29.231897) (xy 149.83972 -29.216815) (xy 149.893192 -29.209198)
			(xy 149.920198 -29.20873) (xy 149.947569 -29.20919) (xy 150.001748 -29.217008) (xy 150.054252 -29.232498)
			(xy 150.103998 -29.255342) (xy 150.149965 -29.285068) (xy 150.170896 -29.30271) (xy 150.178008 -29.308806)
			(xy 150.195026 -29.315156) (xy 150.28037 -29.315156) (xy 150.297388 -29.308806) (xy 150.3045 -29.30271)
			(xy 150.325423 -29.285059) (xy 150.371398 -29.255349) (xy 150.421148 -29.232515) (xy 150.473651 -29.217027)
			(xy 150.527828 -29.209202) (xy 150.555198 -29.20873) (xy 150.57231 -29.208917) (xy 150.606397 -29.211972)
			(xy 150.62327 -29.214826) (xy 150.634537 -29.216204) (xy 150.656418 -29.210289) (xy 150.665434 -29.203396)
			(xy 150.689818 -29.182314) (xy 150.698186 -29.174371) (xy 150.707319 -29.153211) (xy 150.707344 -29.141674)
			(xy 150.706836 -29.12237) (xy 150.706836 -28.25877) (xy 150.707344 -28.238704) (xy 150.707136 -28.227198)
			(xy 150.698059 -28.206092) (xy 150.689818 -28.198064) (xy 150.665434 -28.176982) (xy 150.65643 -28.170056)
			(xy 150.634538 -28.164115) (xy 150.62327 -28.165552) (xy 150.6064 -28.168428) (xy 150.572311 -28.171476)
			(xy 150.555198 -28.171648) (xy 150.52795 -28.171082) (xy 150.474008 -28.163326) (xy 150.421719 -28.147972)
			(xy 150.372147 -28.125333) (xy 150.326302 -28.09587) (xy 150.285116 -28.060182) (xy 150.249429 -28.018996)
			(xy 150.219966 -27.973151) (xy 150.197327 -27.923579) (xy 150.181974 -27.87129) (xy 150.174218 -27.817348)
			(xy 150.174218 -27.762852) (xy 150.181974 -27.70891) (xy 150.197327 -27.656621) (xy 150.219966 -27.607049)
			(xy 150.249429 -27.561204) (xy 150.285116 -27.520018) (xy 150.326302 -27.48433) (xy 150.372147 -27.454867)
			(xy 150.421719 -27.432228) (xy 150.474008 -27.416874) (xy 150.52795 -27.409118) (xy 150.555198 -27.408632)
			(xy 150.582205 -27.409115) (xy 150.63568 -27.41672) (xy 150.687548 -27.431793) (xy 150.736771 -27.454032)
			(xy 150.782364 -27.482992) (xy 150.823416 -27.518094) (xy 150.859106 -27.558636) (xy 150.88872 -27.603808)
			(xy 150.911665 -27.652705) (xy 150.927483 -27.704351) (xy 150.932134 -27.730958) (xy 150.933658 -27.741626)
			(xy 150.945088 -27.759406) (xy 151.025352 -27.812746) (xy 151.045926 -27.816556) (xy 151.056594 -27.814016)
			(xy 151.083224 -27.80788) (xy 151.137473 -27.801263) (xy 151.164798 -27.800808) (xy 151.186976 -27.801109)
			(xy 151.231122 -27.805431) (xy 151.252936 -27.809444) (xy 151.26335 -27.811476) (xy 151.283162 -27.807412)
			(xy 151.360124 -27.754072) (xy 151.371046 -27.737054) (xy 151.372824 -27.72664) (xy 151.377749 -27.700308)
			(xy 151.393963 -27.64925) (xy 151.417161 -27.600964) (xy 151.446886 -27.556398) (xy 151.482554 -27.516429)
			(xy 151.523463 -27.481843) (xy 151.568808 -27.45332) (xy 151.617698 -27.431423) (xy 151.66917 -27.41658)
			(xy 151.722213 -27.409085) (xy 151.748998 -27.408632) (xy 151.776254 -27.409015) (xy 151.830211 -27.416772)
			(xy 151.882514 -27.43213) (xy 151.9321 -27.454775) (xy 151.977958 -27.484246) (xy 152.019155 -27.519943)
			(xy 152.054853 -27.56114) (xy 152.084324 -27.606998) (xy 152.106969 -27.656584) (xy 152.122327 -27.708887)
			(xy 152.130085 -27.762844) (xy 152.130085 -27.817356) (xy 152.122327 -27.871313) (xy 152.106969 -27.923616)
			(xy 152.084324 -27.973202) (xy 152.054853 -28.01906) (xy 152.019155 -28.060257) (xy 151.977958 -28.095954)
			(xy 151.9321 -28.125425) (xy 151.882514 -28.14807) (xy 151.830211 -28.163428) (xy 151.776254 -28.171185)
			(xy 151.748998 -28.171648) (xy 151.737476 -28.171551) (xy 151.714473 -28.170155) (xy 151.703024 -28.168854)
			(xy 151.69211 -28.168103) (xy 151.671313 -28.174823) (xy 151.662892 -28.181808) (xy 151.639016 -28.203398)
			(xy 151.631155 -28.211243) (xy 151.622474 -28.231663) (xy 151.622252 -28.242768) (xy 151.62276 -28.25877)
			(xy 151.62276 -29.12237) (xy 151.622506 -29.137356) (xy 151.62265 -29.14844) (xy 151.631207 -29.168859)
			(xy 151.639016 -29.176726) (xy 151.662892 -29.198316) (xy 151.671317 -29.205291) (xy 151.692111 -29.212007)
			(xy 151.703024 -29.21127) (xy 151.714472 -29.209959) (xy 151.737475 -29.208561) (xy 151.748998 -29.208476)
			(xy 151.77625 -29.208971) (xy 151.830199 -29.216728) (xy 151.882495 -29.232083) (xy 151.932073 -29.254724)
			(xy 151.977924 -29.284191) (xy 152.019115 -29.319883) (xy 152.054808 -29.361074) (xy 152.084275 -29.406925)
			(xy 152.106917 -29.456504) (xy 152.122272 -29.508799) (xy 152.130029 -29.562748) (xy 152.130029 -29.617252)
			(xy 152.122272 -29.671201) (xy 152.106917 -29.723496) (xy 152.084275 -29.773075) (xy 152.054808 -29.818926)
			(xy 152.019115 -29.860117) (xy 151.977924 -29.895809) (xy 151.932073 -29.925276) (xy 151.882495 -29.947917)
			(xy 151.830199 -29.963272) (xy 151.77625 -29.971029) (xy 151.748998 -29.971492) (xy 151.722251 -29.971024)
			(xy 151.669283 -29.96353) (xy 151.617879 -29.948718) (xy 151.569046 -29.926876) (xy 151.523739 -29.898433)
			(xy 151.482845 -29.863946) (xy 151.447164 -29.824088) (xy 151.417395 -29.779641) (xy 151.39412 -29.731475)
			(xy 151.377795 -29.680532) (xy 151.372824 -29.654246) (xy 151.371046 -29.643832) (xy 151.360378 -29.626814)
			(xy 151.283162 -29.573728) (xy 151.26335 -29.569664) (xy 151.25319 -29.571696) (xy 151.231316 -29.57574)
			(xy 151.187041 -29.580068) (xy 151.164798 -29.580332) (xy 151.13741 -29.579892) (xy 151.083034 -29.573268)
			(xy 151.05634 -29.567124) (xy 151.045926 -29.564584) (xy 151.025352 -29.56814) (xy 150.945088 -29.621734)
			(xy 150.933658 -29.63926) (xy 150.93188 -29.649928) (xy 150.92718 -29.676492) (xy 150.911326 -29.728054)
			(xy 150.888364 -29.776868) (xy 150.858755 -29.82196) (xy 150.823088 -29.862431) (xy 150.782075 -29.897473)
			(xy 150.736534 -29.926387) (xy 150.687374 -29.948597) (xy 150.635575 -29.963659) (xy 150.58217 -29.971272)
			(xy 150.555198 -29.971746) (xy 150.527827 -29.971294) (xy 150.473647 -29.963475) (xy 150.421143 -29.947983)
			(xy 150.371396 -29.925138) (xy 150.325431 -29.895409) (xy 150.3045 -29.877766) (xy 150.297388 -29.87167)
			(xy 150.28037 -29.86532) (xy 150.195026 -29.86532) (xy 150.178008 -29.87167) (xy 150.170896 -29.877766)
			(xy 150.149972 -29.895415) (xy 150.103997 -29.925127) (xy 150.054248 -29.947961) (xy 150.001745 -29.96345)
			(xy 149.947568 -29.971274) (xy 149.920198 -29.971746) (xy 149.903086 -29.97156) (xy 149.868999 -29.968504)
			(xy 149.852126 -29.96565) (xy 149.840859 -29.964275) (xy 149.818979 -29.970188) (xy 149.809962 -29.97708)
			(xy 149.785578 -29.998162) (xy 149.777173 -30.006072) (xy 149.768061 -30.027258) (xy 149.768052 -30.038802)
			(xy 149.76856 -30.058868) (xy 149.76856 -30.922468) (xy 149.768052 -30.941772) (xy 149.768217 -30.953281)
			(xy 149.777324 -30.974388) (xy 149.785578 -30.982412) (xy 149.809962 -31.003494) (xy 149.818969 -31.010415)
			(xy 149.840859 -31.01636) (xy 149.852126 -31.014924) (xy 149.868996 -31.012048) (xy 149.903085 -31.009)
			(xy 149.920198 -31.008828) (xy 149.947569 -31.009288) (xy 150.001748 -31.017107) (xy 150.054252 -31.032597)
			(xy 150.103998 -31.05544) (xy 150.149965 -31.085166) (xy 150.170896 -31.102808) (xy 150.178008 -31.108904)
			(xy 150.194772 -31.115254) (xy 150.28037 -31.115254) (xy 150.297388 -31.108904) (xy 150.304246 -31.102554)
			(xy 150.325203 -31.084904) (xy 150.371217 -31.055161) (xy 150.421015 -31.032313) (xy 150.473571 -31.016828)
			(xy 150.527803 -31.009027) (xy 150.555198 -31.008574) (xy 150.582206 -31.009022) (xy 150.635685 -31.016628)
			(xy 150.687555 -31.031703) (xy 150.73678 -31.053944) (xy 150.782375 -31.082908) (xy 150.823428 -31.118015)
			(xy 150.859117 -31.158562) (xy 150.888729 -31.203738) (xy 150.911672 -31.252641) (xy 150.927486 -31.304291)
			(xy 150.932134 -31.3309) (xy 150.933658 -31.341568) (xy 150.945088 -31.359348) (xy 151.025352 -31.412688)
			(xy 151.045926 -31.416498) (xy 151.056594 -31.413958) (xy 151.083234 -31.4079) (xy 151.137481 -31.401403)
			(xy 151.164798 -31.401004) (xy 151.186971 -31.401233) (xy 151.231117 -31.405431) (xy 151.252936 -31.409386)
			(xy 151.26335 -31.411418) (xy 151.283162 -31.407354) (xy 151.360124 -31.354014) (xy 151.371046 -31.336996)
			(xy 151.372824 -31.326582) (xy 151.377705 -31.300241) (xy 151.393927 -31.249184) (xy 151.417131 -31.200898)
			(xy 151.446862 -31.156333) (xy 151.482535 -31.116365) (xy 151.523449 -31.08178) (xy 151.568798 -31.053259)
			(xy 151.617691 -31.031363) (xy 151.669166 -31.016521) (xy 151.722212 -31.009027) (xy 151.748998 -31.008574)
			(xy 151.77625 -31.009073) (xy 151.830198 -31.01683) (xy 151.882494 -31.032185) (xy 151.932072 -31.054826)
			(xy 151.977923 -31.084293) (xy 152.019114 -31.119985) (xy 152.054806 -31.161175) (xy 152.084273 -31.207026)
			(xy 152.106915 -31.256604) (xy 152.12227 -31.3089) (xy 152.130027 -31.362848) (xy 152.130027 -31.417352)
			(xy 152.12227 -31.4713) (xy 152.106915 -31.523596) (xy 152.084273 -31.573174) (xy 152.054806 -31.619025)
			(xy 152.019114 -31.660215) (xy 151.977923 -31.695907) (xy 151.932072 -31.725374) (xy 151.882494 -31.748015)
			(xy 151.830198 -31.76337) (xy 151.77625 -31.771127) (xy 151.748998 -31.77159) (xy 151.737476 -31.771491)
			(xy 151.714473 -31.770095) (xy 151.703024 -31.768796) (xy 151.69211 -31.768035) (xy 151.671311 -31.774761)
			(xy 151.662892 -31.78175) (xy 151.639016 -31.80334) (xy 151.631182 -31.811208) (xy 151.622486 -31.83161)
			(xy 151.622252 -31.84271) (xy 151.62276 -31.858712) (xy 151.62276 -32.722312) (xy 151.622252 -32.737552)
			(xy 151.622418 -32.748666) (xy 151.631125 -32.769092) (xy 151.639016 -32.776922) (xy 151.662892 -32.798512)
			(xy 151.671318 -32.805487) (xy 151.692111 -32.812203) (xy 151.703024 -32.811466) (xy 151.714472 -32.810155)
			(xy 151.737475 -32.808757) (xy 151.748998 -32.808672) (xy 151.77625 -32.809175) (xy 151.830198 -32.816931)
			(xy 151.882493 -32.832287) (xy 151.932071 -32.854928) (xy 151.977922 -32.884394) (xy 152.019113 -32.920086)
			(xy 152.054805 -32.961276) (xy 152.084271 -33.007127) (xy 152.106913 -33.056705) (xy 152.122268 -33.109)
			(xy 152.130025 -33.162948) (xy 152.130025 -33.217452) (xy 152.122268 -33.2714) (xy 152.106913 -33.323695)
			(xy 152.084271 -33.373273) (xy 152.054805 -33.419124) (xy 152.019113 -33.460314) (xy 151.977922 -33.496006)
			(xy 151.932071 -33.525472) (xy 151.882493 -33.548113) (xy 151.830198 -33.563469) (xy 151.77625 -33.571225)
			(xy 151.748998 -33.571688) (xy 151.72223 -33.571319) (xy 151.669219 -33.563847) (xy 151.617773 -33.549037)
			(xy 151.568903 -33.527179) (xy 151.523569 -33.498703) (xy 151.482662 -33.464168) (xy 151.446985 -33.424253)
			(xy 151.41724 -33.379742) (xy 151.39401 -33.331509) (xy 151.377753 -33.280502) (xy 151.372824 -33.254188)
			(xy 151.371046 -33.243774) (xy 151.360378 -33.226756) (xy 151.283162 -33.17367) (xy 151.26335 -33.169606)
			(xy 151.25319 -33.171638) (xy 151.23131 -33.175614) (xy 151.187035 -33.179816) (xy 151.164798 -33.18002)
			(xy 151.137416 -33.179643) (xy 151.08304 -33.17315) (xy 151.05634 -33.167066) (xy 151.045926 -33.164526)
			(xy 151.025352 -33.168082) (xy 150.945088 -33.221676) (xy 150.933658 -33.239202) (xy 150.93188 -33.24987)
			(xy 150.927136 -33.276426) (xy 150.911289 -33.327988) (xy 150.888335 -33.376802) (xy 150.858732 -33.421895)
			(xy 150.82307 -33.462367) (xy 150.782061 -33.497411) (xy 150.736524 -33.526326) (xy 150.687367 -33.548537)
			(xy 150.635571 -33.5636) (xy 150.582169 -33.571214) (xy 150.555198 -33.571688) (xy 150.527828 -33.571226)
			(xy 150.473648 -33.563408) (xy 150.421145 -33.547918) (xy 150.371398 -33.525075) (xy 150.325432 -33.49535)
			(xy 150.3045 -33.477708) (xy 150.297388 -33.471612) (xy 150.28037 -33.465262) (xy 150.195026 -33.465262)
			(xy 150.178008 -33.471612) (xy 150.170896 -33.477708) (xy 150.149977 -33.495364) (xy 150.104001 -33.525073)
			(xy 150.05425 -33.547905) (xy 150.001746 -33.563393) (xy 149.947568 -33.571216) (xy 149.920198 -33.571688)
			(xy 149.903086 -33.571501) (xy 149.868999 -33.568446) (xy 149.852126 -33.565592) (xy 149.840859 -33.564207)
			(xy 149.818977 -33.570126) (xy 149.809962 -33.577022) (xy 149.785578 -33.598104) (xy 149.777201 -33.606039)
			(xy 149.768073 -33.627205) (xy 149.768052 -33.638744) (xy 149.76856 -33.65881) (xy 149.76856 -34.52241)
			(xy 149.768052 -34.541714) (xy 149.76825 -34.553221) (xy 149.777334 -34.574327) (xy 149.785578 -34.582354)
			(xy 149.809962 -34.603436) (xy 149.818973 -34.610352) (xy 149.84086 -34.616302) (xy 149.852126 -34.614866)
			(xy 149.868996 -34.611991) (xy 149.903085 -34.608942) (xy 149.920198 -34.60877) (xy 149.947449 -34.609277)
			(xy 150.001397 -34.617033) (xy 150.053692 -34.632388) (xy 150.10327 -34.655029) (xy 150.149121 -34.684496)
			(xy 150.190311 -34.720187) (xy 150.226003 -34.761378) (xy 150.25547 -34.807228) (xy 150.278111 -34.856806)
			(xy 150.293466 -34.909101) (xy 150.301223 -34.963049) (xy 150.301223 -34.990024) (xy 151.36698 -34.990024)
			(xy 151.371051 -34.934402) (xy 151.383177 -34.879965) (xy 151.4031 -34.827874) (xy 151.430396 -34.779239)
			(xy 151.464482 -34.735096) (xy 151.504631 -34.696387) (xy 151.549989 -34.663936) (xy 151.599589 -34.638435)
			(xy 151.652373 -34.620428) (xy 151.707216 -34.610298) (xy 151.76295 -34.608261) (xy 151.818387 -34.614361)
			(xy 151.872344 -34.628467) (xy 151.923673 -34.650279) (xy 151.971279 -34.679333) (xy 152.014147 -34.715008)
			(xy 152.051364 -34.756545) (xy 152.082137 -34.803058) (xy 152.105809 -34.853555) (xy 152.121877 -34.906962)
			(xy 152.129997 -34.962138) (xy 152.130506 -34.990024) (xy 152.129997 -35.01791) (xy 152.121877 -35.073086)
			(xy 152.105809 -35.126493) (xy 152.082137 -35.17699) (xy 152.051364 -35.223503) (xy 152.014147 -35.26504)
			(xy 151.971279 -35.300715) (xy 151.923673 -35.329769) (xy 151.872344 -35.351581) (xy 151.818387 -35.365687)
			(xy 151.76295 -35.371787) (xy 151.707216 -35.36975) (xy 151.652373 -35.35962) (xy 151.599589 -35.341613)
			(xy 151.549989 -35.316112) (xy 151.504631 -35.283661) (xy 151.464482 -35.244952) (xy 151.430396 -35.200809)
			(xy 151.4031 -35.152174) (xy 151.383177 -35.100083) (xy 151.371051 -35.045646) (xy 151.36698 -34.990024)
			(xy 150.301223 -34.990024) (xy 150.301223 -35.017551) (xy 150.293466 -35.071499) (xy 150.278111 -35.123794)
			(xy 150.25547 -35.173372) (xy 150.226003 -35.219222) (xy 150.190311 -35.260413) (xy 150.149121 -35.296104)
			(xy 150.10327 -35.325571) (xy 150.053692 -35.348212) (xy 150.001397 -35.363567) (xy 149.947449 -35.371323)
			(xy 149.920198 -35.371786) (xy 149.893222 -35.371283) (xy 149.839806 -35.363702) (xy 149.787993 -35.348665)
			(xy 149.738818 -35.326471) (xy 149.693264 -35.297564) (xy 149.652242 -35.262522) (xy 149.616571 -35.222046)
			(xy 149.586965 -35.176943) (xy 149.564015 -35.128117) (xy 149.54818 -35.076542) (xy 149.543516 -35.049968)
			(xy 149.541738 -35.0393) (xy 149.530308 -35.021774) (xy 149.450044 -34.96818) (xy 149.42947 -34.964624)
			(xy 149.419056 -34.967164) (xy 149.392361 -34.973302) (xy 149.337986 -34.979925) (xy 149.310598 -34.980372)
			(xy 149.28321 -34.979931) (xy 149.228834 -34.973308) (xy 149.20214 -34.967164) (xy 149.191726 -34.964624)
			(xy 149.171152 -34.96818) (xy 149.090888 -35.021774) (xy 149.079458 -35.0393) (xy 149.07768 -35.049968)
			(xy 149.073011 -35.076538) (xy 149.057151 -35.1281) (xy 149.034185 -35.176913) (xy 149.004571 -35.222005)
			(xy 148.968901 -35.262475) (xy 148.927885 -35.297516) (xy 148.882341 -35.326429) (xy 148.833178 -35.348638)
			(xy 148.781377 -35.363699) (xy 148.727971 -35.371313) (xy 148.700998 -35.371786) (xy 148.673745 -35.371344)
			(xy 148.619795 -35.363587) (xy 148.567497 -35.348231) (xy 148.517917 -35.325588) (xy 148.472064 -35.29612)
			(xy 148.430872 -35.260426) (xy 148.395179 -35.219234) (xy 148.365711 -35.173381) (xy 148.343069 -35.123801)
			(xy 148.327713 -35.071503) (xy 148.319956 -35.017553) (xy 146.674501 -35.017553) (xy 146.686884 -35.031373)
			(xy 146.717657 -35.077886) (xy 146.741329 -35.128383) (xy 146.757397 -35.18179) (xy 146.765517 -35.236966)
			(xy 146.766026 -35.264852) (xy 146.765517 -35.292738) (xy 146.757397 -35.347914) (xy 146.741329 -35.401321)
			(xy 146.717657 -35.451818) (xy 146.686884 -35.498331) (xy 146.649667 -35.539868) (xy 146.606799 -35.575543)
			(xy 146.559193 -35.604597) (xy 146.507864 -35.626409) (xy 146.453907 -35.640515) (xy 146.39847 -35.646615)
			(xy 146.342736 -35.644578) (xy 146.287893 -35.634448) (xy 146.235109 -35.616441) (xy 146.185509 -35.59094)
			(xy 146.140151 -35.558489) (xy 146.100002 -35.51978) (xy 146.065916 -35.475637) (xy 146.03862 -35.427002)
			(xy 146.018697 -35.374911) (xy 146.006571 -35.320474) (xy 146.0025 -35.264852) (xy 143.500856 -35.264852)
			(xy 143.500856 -37.087048) (xy 147.30095 -37.087048) (xy 147.301413 -37.060444) (xy 147.30879 -37.007751)
			(xy 147.32342 -36.956595) (xy 147.345019 -36.907969) (xy 147.373169 -36.862818) (xy 147.407322 -36.822019)
			(xy 147.446816 -36.786364) (xy 147.46859 -36.771072) (xy 147.478515 -36.763542) (xy 147.490242 -36.741598)
			(xy 147.490942 -36.729162) (xy 147.490942 -36.644834) (xy 147.490308 -36.632378) (xy 147.478575 -36.610399)
			(xy 147.46859 -36.602924) (xy 147.446833 -36.58761) (xy 147.407352 -36.551949) (xy 147.373206 -36.511149)
			(xy 147.345058 -36.466003) (xy 147.323453 -36.417384) (xy 147.308811 -36.366236) (xy 147.301414 -36.313549)
			(xy 147.30095 -36.286948) (xy 147.3015 -36.259698) (xy 147.309249 -36.205753) (xy 147.324597 -36.153459)
			(xy 147.347231 -36.103882) (xy 147.37669 -36.05803) (xy 147.412375 -36.016838) (xy 147.453558 -35.981144)
			(xy 147.499403 -35.951674) (xy 147.548974 -35.929028) (xy 147.601265 -35.913668) (xy 147.655208 -35.905906)
			(xy 147.682458 -35.90544) (xy 147.68703 -35.90544) (xy 147.696682 -35.905694) (xy 147.713446 -35.899344)
			(xy 147.778978 -35.843464) (xy 147.787614 -35.827462) (xy 147.788884 -35.818064) (xy 147.79323 -35.791133)
			(xy 147.80854 -35.738777) (xy 147.831151 -35.689136) (xy 147.860603 -35.643221) (xy 147.896294 -35.601968)
			(xy 147.937496 -35.56622) (xy 147.98337 -35.536705) (xy 148.032981 -35.514025) (xy 148.085315 -35.498642)
			(xy 148.139308 -35.49087) (xy 148.166582 -35.490404) (xy 148.193837 -35.490842) (xy 148.247791 -35.498597)
			(xy 148.300093 -35.513952) (xy 148.349677 -35.536594) (xy 148.395534 -35.566062) (xy 148.43673 -35.601757)
			(xy 148.472427 -35.642952) (xy 148.501897 -35.688807) (xy 148.524542 -35.73839) (xy 148.539899 -35.790691)
			(xy 148.547657 -35.844645) (xy 148.547657 -35.899155) (xy 148.539899 -35.953109) (xy 148.524542 -36.00541)
			(xy 148.501897 -36.054993) (xy 148.472427 -36.100848) (xy 148.43673 -36.142043) (xy 148.395534 -36.177738)
			(xy 148.349677 -36.207206) (xy 148.300093 -36.229848) (xy 148.247791 -36.245203) (xy 148.193837 -36.252958)
			(xy 148.166582 -36.25342) (xy 148.16201 -36.25342) (xy 148.152358 -36.253166) (xy 148.135594 -36.259516)
			(xy 148.070062 -36.315396) (xy 148.061426 -36.331398) (xy 148.060156 -36.340796) (xy 148.055956 -36.366999)
			(xy 148.041272 -36.417993) (xy 148.01966 -36.466459) (xy 147.991536 -36.51146) (xy 147.988109 -36.515548)
			(xy 149.114254 -36.515548) (xy 149.118325 -36.459926) (xy 149.130451 -36.405489) (xy 149.150374 -36.353398)
			(xy 149.17767 -36.304763) (xy 149.211756 -36.26062) (xy 149.251905 -36.221911) (xy 149.297263 -36.18946)
			(xy 149.346863 -36.163959) (xy 149.399647 -36.145952) (xy 149.45449 -36.135822) (xy 149.510224 -36.133785)
			(xy 149.565661 -36.139885) (xy 149.619618 -36.153991) (xy 149.670947 -36.175803) (xy 149.718553 -36.204857)
			(xy 149.761421 -36.240532) (xy 149.798638 -36.282069) (xy 149.829411 -36.328582) (xy 149.853083 -36.379079)
			(xy 149.869151 -36.432486) (xy 149.877271 -36.487662) (xy 149.87778 -36.515548) (xy 149.877271 -36.543434)
			(xy 149.869151 -36.59861) (xy 149.853083 -36.652017) (xy 149.829411 -36.702514) (xy 149.798638 -36.749027)
			(xy 149.761421 -36.790564) (xy 149.718553 -36.826239) (xy 149.670947 -36.855293) (xy 149.619618 -36.877105)
			(xy 149.565661 -36.891211) (xy 149.510224 -36.897311) (xy 149.45449 -36.895274) (xy 149.399647 -36.885144)
			(xy 149.346863 -36.867137) (xy 149.297263 -36.841636) (xy 149.251905 -36.809185) (xy 149.211756 -36.770476)
			(xy 149.17767 -36.726333) (xy 149.150374 -36.677698) (xy 149.130451 -36.625607) (xy 149.118325 -36.57117)
			(xy 149.114254 -36.515548) (xy 147.988109 -36.515548) (xy 147.957445 -36.552127) (xy 147.918044 -36.587674)
			(xy 147.896326 -36.602924) (xy 147.886406 -36.610459) (xy 147.874675 -36.632399) (xy 147.873974 -36.644834)
			(xy 147.873974 -36.729162) (xy 147.874644 -36.741612) (xy 147.886354 -36.763589) (xy 147.896326 -36.771072)
			(xy 147.918084 -36.786383) (xy 147.957565 -36.822046) (xy 147.991711 -36.862846) (xy 148.019858 -36.907993)
			(xy 148.041463 -36.956612) (xy 148.056105 -37.00776) (xy 148.063501 -37.060447) (xy 148.063966 -37.087048)
			(xy 148.063365 -37.118808) (xy 148.052878 -37.181454) (xy 148.032136 -37.241489) (xy 148.017484 -37.269674)
			(xy 148.01215 -37.27958) (xy 148.010626 -37.301678) (xy 148.04644 -37.394896) (xy 148.062442 -37.41039)
			(xy 148.07311 -37.4142) (xy 148.097645 -37.42326) (xy 148.144175 -37.447145) (xy 148.187006 -37.477162)
			(xy 148.225335 -37.512749) (xy 148.258442 -37.553238) (xy 148.285708 -37.597871) (xy 148.30662 -37.64581)
			(xy 148.320788 -37.696157) (xy 148.327944 -37.747967) (xy 148.32838 -37.774118) (xy 148.327894 -37.801369)
			(xy 148.320138 -37.855317) (xy 148.304783 -37.907612) (xy 148.282141 -37.957189) (xy 148.252675 -38.003039)
			(xy 148.216984 -38.04423) (xy 148.175793 -38.079921) (xy 148.129943 -38.109387) (xy 148.080366 -38.132029)
			(xy 148.028071 -38.147384) (xy 147.974123 -38.15514) (xy 147.919621 -38.15514) (xy 147.865673 -38.147384)
			(xy 147.813378 -38.132029) (xy 147.763801 -38.109387) (xy 147.717951 -38.079921) (xy 147.67676 -38.04423)
			(xy 147.641069 -38.003039) (xy 147.611603 -37.957189) (xy 147.588961 -37.907612) (xy 147.573606 -37.855317)
			(xy 147.56585 -37.801369) (xy 147.565364 -37.774118) (xy 147.56596 -37.742358) (xy 147.57645 -37.679712)
			(xy 147.597194 -37.619677) (xy 147.611846 -37.591492) (xy 147.61718 -37.581586) (xy 147.618704 -37.559488)
			(xy 147.58289 -37.46627) (xy 147.566888 -37.450776) (xy 147.55622 -37.446966) (xy 147.53168 -37.437917)
			(xy 147.485148 -37.414034) (xy 147.442315 -37.384016) (xy 147.403986 -37.348429) (xy 147.370878 -37.307937)
			(xy 147.343613 -37.263302) (xy 147.322702 -37.215361) (xy 147.308537 -37.165012) (xy 147.301384 -37.1132)
			(xy 147.30095 -37.087048) (xy 143.500856 -37.087048) (xy 143.500856 -38.315138) (xy 148.518116 -38.315138)
			(xy 148.522187 -38.259516) (xy 148.534313 -38.205079) (xy 148.554236 -38.152988) (xy 148.581532 -38.104353)
			(xy 148.615618 -38.06021) (xy 148.655767 -38.021501) (xy 148.701125 -37.98905) (xy 148.750725 -37.963549)
			(xy 148.803509 -37.945542) (xy 148.858352 -37.935412) (xy 148.914086 -37.933375) (xy 148.969523 -37.939475)
			(xy 149.02348 -37.953581) (xy 149.074809 -37.975393) (xy 149.122415 -38.004447) (xy 149.165283 -38.040122)
			(xy 149.2025 -38.081659) (xy 149.233273 -38.128172) (xy 149.256945 -38.178669) (xy 149.273013 -38.232076)
			(xy 149.281133 -38.287252) (xy 149.281642 -38.315138) (xy 149.281133 -38.343024) (xy 149.273013 -38.3982)
			(xy 149.256945 -38.451607) (xy 149.233273 -38.502104) (xy 149.2025 -38.548617) (xy 149.165283 -38.590154)
			(xy 149.122415 -38.625829) (xy 149.074809 -38.654883) (xy 149.02348 -38.676695) (xy 148.969523 -38.690801)
			(xy 148.914086 -38.696901) (xy 148.858352 -38.694864) (xy 148.803509 -38.684734) (xy 148.750725 -38.666727)
			(xy 148.701125 -38.641226) (xy 148.655767 -38.608775) (xy 148.615618 -38.570066) (xy 148.581532 -38.525923)
			(xy 148.554236 -38.477288) (xy 148.534313 -38.425197) (xy 148.522187 -38.37076) (xy 148.518116 -38.315138)
			(xy 143.500856 -38.315138) (xy 143.500856 -42.44721) (xy 143.519906 -42.473626) (xy 143.535654 -42.47896)
			(xy 143.56065 -42.487755) (xy 143.608131 -42.511279) (xy 143.6519 -42.541148) (xy 143.691114 -42.576785)
			(xy 143.72502 -42.617506) (xy 143.752965 -42.662527) (xy 143.774412 -42.710982) (xy 143.788948 -42.761938)
			(xy 143.796292 -42.814416) (xy 143.796766 -42.84091) (xy 143.796687 -42.853648) (xy 143.795033 -42.879069)
			(xy 143.793464 -42.89171) (xy 143.789558 -42.917581) (xy 143.775571 -42.967999) (xy 143.754814 -43.016028)
			(xy 143.727678 -43.060763) (xy 143.694673 -43.101362) (xy 143.675862 -43.119548) (xy 143.675608 -43.119802)
			(xy 143.672814 -43.122342) (xy 143.670274 -43.124628) (xy 143.669512 -43.125136) (xy 143.649896 -43.142794)
			(xy 143.606676 -43.173084) (xy 143.559682 -43.197106) (xy 143.534892 -43.206162) (xy 143.519652 -43.211496)
			(xy 143.500856 -43.237912) (xy 143.500856 -43.46321) (xy 143.519906 -43.489626) (xy 143.535654 -43.49496)
			(xy 143.56065 -43.503755) (xy 143.608131 -43.527279) (xy 143.6519 -43.557148) (xy 143.691114 -43.592785)
			(xy 143.72502 -43.633506) (xy 143.752965 -43.678527) (xy 143.774412 -43.726982) (xy 143.788948 -43.777938)
			(xy 143.796292 -43.830416) (xy 143.796766 -43.85691) (xy 143.796687 -43.869648) (xy 143.795033 -43.895069)
			(xy 143.793464 -43.90771) (xy 143.789558 -43.933581) (xy 143.775571 -43.983999) (xy 143.754814 -44.032028)
			(xy 143.727678 -44.076763) (xy 143.694673 -44.117362) (xy 143.675862 -44.135548) (xy 143.675608 -44.135802)
			(xy 143.672814 -44.138342) (xy 143.670274 -44.140628) (xy 143.669512 -44.141136) (xy 143.649896 -44.158794)
			(xy 143.606676 -44.189084) (xy 143.559682 -44.213106) (xy 143.534892 -44.222162) (xy 143.519652 -44.227496)
			(xy 143.500856 -44.253912) (xy 143.500856 -44.47921) (xy 143.519906 -44.505626) (xy 143.535654 -44.51096)
			(xy 143.56065 -44.519755) (xy 143.608131 -44.543279) (xy 143.6519 -44.573148) (xy 143.691114 -44.608785)
			(xy 143.72502 -44.649506) (xy 143.752965 -44.694527) (xy 143.774412 -44.742982) (xy 143.788948 -44.793938)
			(xy 143.796292 -44.846416) (xy 143.796766 -44.87291) (xy 143.796687 -44.885648) (xy 143.795033 -44.911069)
			(xy 143.793464 -44.92371) (xy 143.789558 -44.949581) (xy 143.775571 -44.999999) (xy 143.754814 -45.048028)
			(xy 143.727678 -45.092763) (xy 143.694673 -45.133362) (xy 143.675862 -45.151548) (xy 143.675608 -45.151802)
			(xy 143.672814 -45.154342) (xy 143.670274 -45.156628) (xy 143.669512 -45.157136) (xy 143.649896 -45.174794)
			(xy 143.606676 -45.205084) (xy 143.559682 -45.229106) (xy 143.534892 -45.238162) (xy 143.519652 -45.243496)
			(xy 143.500856 -45.269912) (xy 143.500856 -45.49521) (xy 143.519906 -45.521626) (xy 143.535654 -45.52696)
			(xy 143.56065 -45.535755) (xy 143.608131 -45.559279) (xy 143.6519 -45.589148) (xy 143.691114 -45.624785)
			(xy 143.72502 -45.665506) (xy 143.752965 -45.710527) (xy 143.774412 -45.758982) (xy 143.788948 -45.809938)
			(xy 143.796292 -45.862416) (xy 143.796766 -45.88891) (xy 143.796687 -45.901648) (xy 143.795033 -45.927069)
			(xy 143.793464 -45.93971) (xy 143.789558 -45.965581) (xy 143.775571 -46.015999) (xy 143.754814 -46.064028)
			(xy 143.727678 -46.108763) (xy 143.694673 -46.149362) (xy 143.675862 -46.167548) (xy 143.675608 -46.167802)
			(xy 143.672814 -46.170342) (xy 143.670274 -46.172628) (xy 143.669512 -46.173136) (xy 143.649896 -46.190794)
			(xy 143.606676 -46.221084) (xy 143.559682 -46.245106) (xy 143.534892 -46.254162) (xy 143.519652 -46.259496)
			(xy 143.500856 -46.285912) (xy 143.500856 -47.040292) (xy 143.521938 -47.067724) (xy 143.538956 -47.072042)
			(xy 143.565936 -47.079476) (xy 143.617527 -47.101164) (xy 143.665394 -47.130157) (xy 143.708511 -47.165834)
			(xy 143.745953 -47.207427) (xy 143.776915 -47.254045) (xy 143.800733 -47.304687) (xy 143.816897 -47.358265)
			(xy 143.825057 -47.41363) (xy 143.825468 -47.441612) (xy 143.825038 -47.467536) (xy 143.818024 -47.518906)
			(xy 143.804113 -47.568853) (xy 143.783562 -47.616453) (xy 143.75675 -47.66083) (xy 143.724172 -47.701163)
			(xy 143.70558 -47.719234) (xy 143.705072 -47.719742) (xy 143.68744 -47.736385) (xy 143.648698 -47.76554)
			(xy 143.606575 -47.789553) (xy 143.56175 -47.808038) (xy 143.538448 -47.814738) (xy 143.521684 -47.81931)
			(xy 143.500856 -47.846488) (xy 143.500856 -48.54321) (xy 143.519906 -48.569626) (xy 143.535654 -48.57496)
			(xy 143.56065 -48.583755) (xy 143.608131 -48.607279) (xy 143.6519 -48.637148) (xy 143.691114 -48.672785)
			(xy 143.72502 -48.713506) (xy 143.752965 -48.758527) (xy 143.774412 -48.806982) (xy 143.788948 -48.857938)
			(xy 143.796292 -48.910416) (xy 143.796766 -48.93691) (xy 143.796687 -48.949648) (xy 143.795033 -48.975069)
			(xy 143.793464 -48.98771) (xy 143.789558 -49.013581) (xy 143.775571 -49.063999) (xy 143.754814 -49.112028)
			(xy 143.727678 -49.156763) (xy 143.694673 -49.197362) (xy 143.675862 -49.215548) (xy 143.675608 -49.215802)
			(xy 143.672814 -49.218342) (xy 143.670274 -49.220628) (xy 143.669512 -49.221136) (xy 143.649896 -49.238794)
			(xy 143.606676 -49.269084) (xy 143.559682 -49.293106) (xy 143.534892 -49.302162) (xy 143.519652 -49.307496)
			(xy 143.500856 -49.333912) (xy 143.500856 -49.55921) (xy 143.519906 -49.585626) (xy 143.535654 -49.59096)
			(xy 143.56065 -49.599755) (xy 143.565088 -49.601954) (xy 144.391059 -49.601954) (xy 144.391059 -49.547446)
			(xy 144.398817 -49.493494) (xy 144.414174 -49.441194) (xy 144.436818 -49.391613) (xy 144.466288 -49.345759)
			(xy 144.501985 -49.304566) (xy 144.54318 -49.268873) (xy 144.589036 -49.239406) (xy 144.638619 -49.216765)
			(xy 144.690919 -49.201411) (xy 144.744872 -49.193658) (xy 144.772126 -49.193196) (xy 144.799497 -49.193648)
			(xy 144.853676 -49.201469) (xy 144.90618 -49.216962) (xy 144.955926 -49.239807) (xy 145.001893 -49.269534)
			(xy 145.022824 -49.287176) (xy 145.029936 -49.293272) (xy 145.046954 -49.299622) (xy 145.132298 -49.299622)
			(xy 145.149316 -49.293272) (xy 145.156428 -49.287176) (xy 145.177361 -49.269535) (xy 145.223329 -49.239811)
			(xy 145.273075 -49.216965) (xy 145.325577 -49.201469) (xy 145.379755 -49.19364) (xy 145.434497 -49.19364)
			(xy 145.488675 -49.201469) (xy 145.541177 -49.216965) (xy 145.590923 -49.239811) (xy 145.636891 -49.269535)
			(xy 145.657824 -49.287176) (xy 145.664936 -49.293272) (xy 145.681954 -49.299622) (xy 145.767298 -49.299622)
			(xy 145.784316 -49.293272) (xy 145.791428 -49.287176) (xy 145.812373 -49.269553) (xy 145.858343 -49.23984)
			(xy 145.908087 -49.217001) (xy 145.960585 -49.201506) (xy 146.014758 -49.193673) (xy 146.042126 -49.193196)
			(xy 146.068442 -49.193653) (xy 146.120576 -49.200873) (xy 146.171224 -49.215185) (xy 146.219426 -49.236319)
			(xy 146.264268 -49.263873) (xy 146.3049 -49.297326) (xy 146.32305 -49.316386) (xy 146.330553 -49.32381)
			(xy 146.349847 -49.332322) (xy 146.360388 -49.332896) (xy 146.435064 -49.332896) (xy 146.445613 -49.332362)
			(xy 146.464909 -49.32383) (xy 146.472402 -49.316386) (xy 146.490533 -49.297303) (xy 146.531155 -49.263826)
			(xy 146.575996 -49.236256) (xy 146.624204 -49.215118) (xy 146.674862 -49.200814) (xy 146.727006 -49.193617)
			(xy 146.753326 -49.193196) (xy 146.780576 -49.193676) (xy 146.834522 -49.201435) (xy 146.886814 -49.216793)
			(xy 146.936388 -49.239436) (xy 146.982236 -49.268903) (xy 147.023424 -49.304595) (xy 147.059113 -49.345785)
			(xy 147.088577 -49.391634) (xy 147.111216 -49.44121) (xy 147.12657 -49.493504) (xy 147.134326 -49.54745)
			(xy 147.134326 -49.60195) (xy 147.12657 -49.655896) (xy 147.111216 -49.70819) (xy 147.088577 -49.757766)
			(xy 147.059113 -49.803615) (xy 147.023424 -49.844805) (xy 146.982236 -49.880497) (xy 146.936388 -49.909964)
			(xy 146.886814 -49.932607) (xy 146.834522 -49.947965) (xy 146.780576 -49.955724) (xy 146.753326 -49.956212)
			(xy 146.727009 -49.955784) (xy 146.674874 -49.948558) (xy 146.624226 -49.93424) (xy 146.576024 -49.913101)
			(xy 146.531183 -49.885541) (xy 146.490552 -49.852084) (xy 146.472402 -49.833022) (xy 146.464879 -49.825622)
			(xy 146.4456 -49.817096) (xy 146.435064 -49.816512) (xy 146.360388 -49.816512) (xy 146.349835 -49.817017)
			(xy 146.33054 -49.825569) (xy 146.32305 -49.833022) (xy 146.304924 -49.852111) (xy 146.264304 -49.885591)
			(xy 146.219462 -49.913162) (xy 146.171252 -49.9343) (xy 146.120592 -49.948601) (xy 146.068446 -49.955795)
			(xy 146.042126 -49.956212) (xy 146.014756 -49.955728) (xy 145.960578 -49.947914) (xy 145.908075 -49.932429)
			(xy 145.858328 -49.909591) (xy 145.812361 -49.879871) (xy 145.791428 -49.862232) (xy 145.784316 -49.856136)
			(xy 145.767298 -49.849786) (xy 145.681954 -49.849786) (xy 145.664936 -49.856136) (xy 145.657824 -49.862232)
			(xy 145.636891 -49.879873) (xy 145.590923 -49.909597) (xy 145.541177 -49.932443) (xy 145.488675 -49.947939)
			(xy 145.434497 -49.955768) (xy 145.379755 -49.955768) (xy 145.325577 -49.947939) (xy 145.273075 -49.932443)
			(xy 145.223329 -49.909597) (xy 145.177361 -49.879873) (xy 145.156428 -49.862232) (xy 145.149316 -49.856136)
			(xy 145.132298 -49.849786) (xy 145.046954 -49.849786) (xy 145.029936 -49.856136) (xy 145.022824 -49.862232)
			(xy 145.001898 -49.879878) (xy 144.955923 -49.909588) (xy 144.906174 -49.932422) (xy 144.853672 -49.947911)
			(xy 144.799495 -49.955738) (xy 144.772126 -49.956212) (xy 144.744872 -49.955742) (xy 144.690919 -49.947989)
			(xy 144.638619 -49.932635) (xy 144.589036 -49.909994) (xy 144.54318 -49.880527) (xy 144.501985 -49.844834)
			(xy 144.466288 -49.803641) (xy 144.436818 -49.757787) (xy 144.414174 -49.708206) (xy 144.398817 -49.655906)
			(xy 144.391059 -49.601954) (xy 143.565088 -49.601954) (xy 143.608131 -49.623279) (xy 143.6519 -49.653148)
			(xy 143.691114 -49.688785) (xy 143.72502 -49.729506) (xy 143.752965 -49.774527) (xy 143.774412 -49.822982)
			(xy 143.788948 -49.873938) (xy 143.796292 -49.926416) (xy 143.796766 -49.95291) (xy 143.796687 -49.965648)
			(xy 143.795033 -49.991069) (xy 143.793464 -50.00371) (xy 143.789558 -50.029581) (xy 143.775571 -50.079999)
			(xy 143.754814 -50.128028) (xy 143.727678 -50.172763) (xy 143.694673 -50.213362) (xy 143.675862 -50.231548)
			(xy 143.675608 -50.231802) (xy 143.672814 -50.234342) (xy 143.670274 -50.236628) (xy 143.669512 -50.237136)
			(xy 143.649896 -50.254794) (xy 143.606676 -50.285084) (xy 143.559682 -50.309106) (xy 143.534892 -50.318162)
			(xy 143.519652 -50.323496) (xy 143.500856 -50.349912) (xy 143.500856 -50.62347) (xy 143.520414 -50.65014)
			(xy 143.53667 -50.65522) (xy 143.562229 -50.663655) (xy 143.610864 -50.686707) (xy 143.655778 -50.716364)
			(xy 143.696079 -50.752038) (xy 143.730968 -50.79302) (xy 143.759752 -50.838498) (xy 143.781861 -50.887569)
			(xy 143.796855 -50.93926) (xy 143.804438 -50.992545) (xy 143.804894 -51.019456) (xy 143.804457 -51.045439)
			(xy 143.797407 -51.096925) (xy 143.783432 -51.146977) (xy 143.76279 -51.194668) (xy 143.735863 -51.239114)
			(xy 143.703152 -51.279493) (xy 143.684498 -51.297586) (xy 143.68399 -51.298094) (xy 143.662742 -51.317947)
			(xy 143.615349 -51.351639) (xy 143.563395 -51.377757) (xy 143.535908 -51.387248) (xy 143.52016 -51.392328)
			(xy 143.500856 -51.418998) (xy 143.500856 -51.615086) (xy 143.50133 -51.625328) (xy 143.509331 -51.644187)
			(xy 143.51635 -51.651662) (xy 143.536416 -51.670966) (xy 143.547084 -51.674522) (xy 143.571827 -51.683469)
			(xy 143.582864 -51.689048) (xy 144.3556 -51.689048) (xy 144.3556 -51.634552) (xy 144.363355 -51.58061)
			(xy 144.378708 -51.528321) (xy 144.401345 -51.478749) (xy 144.430807 -51.432903) (xy 144.466492 -51.391716)
			(xy 144.507676 -51.356027) (xy 144.553519 -51.326561) (xy 144.603089 -51.30392) (xy 144.655377 -51.288563)
			(xy 144.709318 -51.280803) (xy 144.736566 -51.280314) (xy 144.763936 -51.280797) (xy 144.818114 -51.28861)
			(xy 144.870617 -51.304095) (xy 144.920364 -51.326933) (xy 144.966332 -51.356654) (xy 144.987264 -51.374294)
			(xy 144.994376 -51.38039) (xy 145.011394 -51.38674) (xy 145.096738 -51.38674) (xy 145.113756 -51.38039)
			(xy 145.120868 -51.374294) (xy 145.141801 -51.356656) (xy 145.187773 -51.326944) (xy 145.237521 -51.304108)
			(xy 145.290021 -51.288617) (xy 145.344197 -51.280788) (xy 145.371566 -51.280314) (xy 145.389909 -51.280548)
			(xy 145.426422 -51.28411) (xy 145.444464 -51.287426) (xy 145.455386 -51.289458) (xy 145.47596 -51.284632)
			(xy 145.553938 -51.225704) (xy 145.564352 -51.206908) (xy 145.565114 -51.195986) (xy 145.568014 -51.167703)
			(xy 145.581051 -51.112366) (xy 145.602146 -51.059573) (xy 145.630833 -51.010489) (xy 145.666479 -50.9662)
			(xy 145.687034 -50.946558) (xy 145.694446 -50.939045) (xy 145.702967 -50.919759) (xy 145.703544 -50.90922)
			(xy 145.703544 -50.834544) (xy 145.702991 -50.823997) (xy 145.694471 -50.804703) (xy 145.687034 -50.797206)
			(xy 145.667964 -50.779062) (xy 145.634484 -50.738444) (xy 145.606911 -50.693606) (xy 145.585771 -50.6454)
			(xy 145.571465 -50.594744) (xy 145.564265 -50.542601) (xy 145.563844 -50.516282) (xy 145.56433 -50.489031)
			(xy 145.572086 -50.435083) (xy 145.587441 -50.382788) (xy 145.610083 -50.333211) (xy 145.639549 -50.287361)
			(xy 145.67524 -50.24617) (xy 145.716431 -50.210479) (xy 145.762281 -50.181013) (xy 145.811858 -50.158371)
			(xy 145.864153 -50.143016) (xy 145.918101 -50.13526) (xy 145.972603 -50.13526) (xy 146.026551 -50.143016)
			(xy 146.078846 -50.158371) (xy 146.128423 -50.181013) (xy 146.174273 -50.210479) (xy 146.215464 -50.24617)
			(xy 146.251155 -50.287361) (xy 146.280621 -50.333211) (xy 146.303263 -50.382788) (xy 146.318618 -50.435083)
			(xy 146.326374 -50.489031) (xy 146.32686 -50.516282) (xy 146.326454 -50.5426) (xy 146.319226 -50.594736)
			(xy 146.304905 -50.645386) (xy 146.283762 -50.693588) (xy 146.256197 -50.738429) (xy 146.222735 -50.779058)
			(xy 146.20367 -50.797206) (xy 146.196274 -50.804733) (xy 146.187744 -50.824008) (xy 146.18716 -50.834544)
			(xy 146.18716 -50.90922) (xy 146.187731 -50.919765) (xy 146.196238 -50.93906) (xy 146.20367 -50.946558)
			(xy 146.222723 -50.964719) (xy 146.256205 -51.005333) (xy 146.283779 -51.050168) (xy 146.304923 -51.09837)
			(xy 146.319233 -51.149023) (xy 146.326436 -51.201164) (xy 146.32686 -51.227482) (xy 146.326428 -51.254737)
			(xy 146.318672 -51.308691) (xy 146.303316 -51.360993) (xy 146.280672 -51.410576) (xy 146.251201 -51.456431)
			(xy 146.215504 -51.497625) (xy 146.174307 -51.533319) (xy 146.128449 -51.562786) (xy 146.078864 -51.585426)
			(xy 146.026562 -51.600778) (xy 145.972607 -51.60853) (xy 145.945352 -51.60899) (xy 145.927009 -51.608754)
			(xy 145.890496 -51.605193) (xy 145.872454 -51.601878) (xy 145.861532 -51.599846) (xy 145.840958 -51.604672)
			(xy 145.76298 -51.6636) (xy 145.752566 -51.682396) (xy 145.751804 -51.693318) (xy 145.748861 -51.72157)
			(xy 145.735831 -51.776851) (xy 145.714749 -51.82959) (xy 145.686083 -51.878621) (xy 145.650464 -51.922861)
			(xy 145.60868 -51.961331) (xy 145.561656 -51.993183) (xy 145.510429 -52.017711) (xy 145.456132 -52.034374)
			(xy 145.399964 -52.042803) (xy 145.371566 -52.04333) (xy 145.344194 -52.042901) (xy 145.290013 -52.035077)
			(xy 145.237509 -52.01958) (xy 145.187762 -51.99673) (xy 145.141798 -51.966996) (xy 145.120868 -51.94935)
			(xy 145.113756 -51.943254) (xy 145.096738 -51.936904) (xy 145.011394 -51.936904) (xy 144.994376 -51.943254)
			(xy 144.987264 -51.94935) (xy 144.966312 -51.966965) (xy 144.920346 -51.996682) (xy 144.870603 -52.019523)
			(xy 144.818107 -52.03502) (xy 144.763934 -52.042853) (xy 144.736566 -52.04333) (xy 144.709318 -52.042797)
			(xy 144.655377 -52.035037) (xy 144.603089 -52.01968) (xy 144.553519 -51.997039) (xy 144.507676 -51.967573)
			(xy 144.466492 -51.931884) (xy 144.430807 -51.890697) (xy 144.401345 -51.844851) (xy 144.378708 -51.795279)
			(xy 144.363355 -51.74299) (xy 144.3556 -51.689048) (xy 143.582864 -51.689048) (xy 143.618784 -51.707205)
			(xy 143.662032 -51.73717) (xy 143.700753 -51.772794) (xy 143.73421 -51.813401) (xy 143.761769 -51.85822)
			(xy 143.782908 -51.906402) (xy 143.797225 -51.957032) (xy 143.804448 -52.009149) (xy 143.804894 -52.035456)
			(xy 143.804457 -52.061439) (xy 143.797407 -52.112925) (xy 143.783432 -52.162977) (xy 143.76279 -52.210668)
			(xy 143.735863 -52.255114) (xy 143.703152 -52.295493) (xy 143.684498 -52.313586) (xy 143.68399 -52.314094)
			(xy 143.679672 -52.318158) (xy 143.672518 -52.325636) (xy 143.6644 -52.344649) (xy 143.663924 -52.354988)
			(xy 143.663924 -52.564157) (xy 145.927207 -52.564157) (xy 145.927207 -52.509643) (xy 145.934965 -52.455684)
			(xy 145.950324 -52.403378) (xy 145.972971 -52.35379) (xy 146.002444 -52.30793) (xy 146.038145 -52.266732)
			(xy 146.079345 -52.231034) (xy 146.125206 -52.201562) (xy 146.174794 -52.178918) (xy 146.227101 -52.163562)
			(xy 146.281061 -52.155806) (xy 146.308318 -52.155344) (xy 146.335689 -52.155789) (xy 146.38987 -52.16361)
			(xy 146.442373 -52.179104) (xy 146.49212 -52.20195) (xy 146.538085 -52.23168) (xy 146.559016 -52.249324)
			(xy 146.566128 -52.25542) (xy 146.583146 -52.26177) (xy 146.66849 -52.26177) (xy 146.685508 -52.25542)
			(xy 146.69262 -52.249324) (xy 146.713575 -52.231713) (xy 146.759541 -52.201996) (xy 146.809283 -52.179154)
			(xy 146.861778 -52.163657) (xy 146.91595 -52.155822) (xy 146.943318 -52.155344) (xy 146.970565 -52.155927)
			(xy 147.024504 -52.163685) (xy 147.07679 -52.17904) (xy 147.126358 -52.201679) (xy 147.172201 -52.231142)
			(xy 147.213384 -52.266829) (xy 147.249069 -52.308014) (xy 147.27853 -52.353857) (xy 147.301167 -52.403427)
			(xy 147.316519 -52.455714) (xy 147.324274 -52.509653) (xy 147.324274 -52.564147) (xy 147.316519 -52.618086)
			(xy 147.301167 -52.670373) (xy 147.27853 -52.719943) (xy 147.249069 -52.765786) (xy 147.213384 -52.806971)
			(xy 147.172201 -52.842658) (xy 147.126358 -52.872121) (xy 147.07679 -52.89476) (xy 147.024504 -52.910115)
			(xy 146.970565 -52.917873) (xy 146.943318 -52.91836) (xy 146.915948 -52.917893) (xy 146.861768 -52.910077)
			(xy 146.809265 -52.894589) (xy 146.759518 -52.871747) (xy 146.713551 -52.842022) (xy 146.69262 -52.82438)
			(xy 146.685508 -52.818284) (xy 146.66849 -52.811934) (xy 146.583146 -52.811934) (xy 146.566128 -52.818284)
			(xy 146.559016 -52.82438) (xy 146.538086 -52.842022) (xy 146.492113 -52.871734) (xy 146.442365 -52.89457)
			(xy 146.389864 -52.91006) (xy 146.335687 -52.917887) (xy 146.308318 -52.91836) (xy 146.281061 -52.917994)
			(xy 146.227101 -52.910238) (xy 146.174794 -52.894882) (xy 146.125206 -52.872238) (xy 146.079345 -52.842766)
			(xy 146.038145 -52.807068) (xy 146.002444 -52.76587) (xy 145.972971 -52.72001) (xy 145.950324 -52.670422)
			(xy 145.934965 -52.618116) (xy 145.927207 -52.564157) (xy 143.663924 -52.564157) (xy 143.663924 -52.731924)
			(xy 143.664324 -52.742558) (xy 143.672876 -52.762024) (xy 143.680434 -52.769516) (xy 143.699678 -52.787667)
			(xy 143.733474 -52.828363) (xy 143.761322 -52.873339) (xy 143.782687 -52.921732) (xy 143.79716 -52.972613)
			(xy 143.804462 -53.025006) (xy 143.804894 -53.051456) (xy 143.804457 -53.077439) (xy 143.797407 -53.128925)
			(xy 143.783432 -53.178977) (xy 143.76279 -53.226668) (xy 143.735863 -53.271114) (xy 143.703152 -53.311493)
			(xy 143.684498 -53.329586) (xy 143.68399 -53.330094) (xy 143.679672 -53.334158) (xy 143.672518 -53.341636)
			(xy 143.6644 -53.360649) (xy 143.663924 -53.370988) (xy 143.663924 -53.747924) (xy 143.664324 -53.758558)
			(xy 143.672876 -53.778024) (xy 143.680434 -53.785516) (xy 143.699678 -53.803667) (xy 143.733474 -53.844363)
			(xy 143.761322 -53.889339) (xy 143.782687 -53.937732) (xy 143.79716 -53.988613) (xy 143.804462 -54.041006)
			(xy 143.804894 -54.067456) (xy 143.804457 -54.093439) (xy 143.797407 -54.144925) (xy 143.783432 -54.194977)
			(xy 143.764418 -54.238906) (xy 150.486108 -54.238906) (xy 150.490179 -54.183284) (xy 150.502305 -54.128847)
			(xy 150.522228 -54.076756) (xy 150.549524 -54.028121) (xy 150.58361 -53.983978) (xy 150.623759 -53.945269)
			(xy 150.669117 -53.912818) (xy 150.718717 -53.887317) (xy 150.771501 -53.86931) (xy 150.826344 -53.85918)
			(xy 150.882078 -53.857143) (xy 150.937515 -53.863243) (xy 150.991472 -53.877349) (xy 151.042801 -53.899161)
			(xy 151.090407 -53.928215) (xy 151.133275 -53.96389) (xy 151.170492 -54.005427) (xy 151.201265 -54.05194)
			(xy 151.224937 -54.102437) (xy 151.241005 -54.155844) (xy 151.249125 -54.21102) (xy 151.249634 -54.238906)
			(xy 151.249125 -54.266792) (xy 151.241005 -54.321968) (xy 151.224937 -54.375375) (xy 151.201265 -54.425872)
			(xy 151.170492 -54.472385) (xy 151.133275 -54.513922) (xy 151.090407 -54.549597) (xy 151.042801 -54.578651)
			(xy 150.991472 -54.600463) (xy 150.937515 -54.614569) (xy 150.882078 -54.620669) (xy 150.826344 -54.618632)
			(xy 150.771501 -54.608502) (xy 150.718717 -54.590495) (xy 150.669117 -54.564994) (xy 150.623759 -54.532543)
			(xy 150.58361 -54.493834) (xy 150.549524 -54.449691) (xy 150.522228 -54.401056) (xy 150.502305 -54.348965)
			(xy 150.490179 -54.294528) (xy 150.486108 -54.238906) (xy 143.764418 -54.238906) (xy 143.76279 -54.242668)
			(xy 143.735863 -54.287114) (xy 143.703152 -54.327493) (xy 143.684498 -54.345586) (xy 143.68399 -54.346094)
			(xy 143.679672 -54.350158) (xy 143.672518 -54.357636) (xy 143.6644 -54.376649) (xy 143.663924 -54.386988)
			(xy 143.663924 -54.763924) (xy 143.664324 -54.774558) (xy 143.672876 -54.794024) (xy 143.680434 -54.801516)
			(xy 143.699678 -54.819667) (xy 143.733474 -54.860363) (xy 143.761322 -54.905339) (xy 143.782687 -54.953732)
			(xy 143.792735 -54.989055) (xy 146.001145 -54.989055) (xy 146.001145 -54.934545) (xy 146.008903 -54.88059)
			(xy 146.024261 -54.828288) (xy 146.046906 -54.778704) (xy 146.076378 -54.732848) (xy 146.112076 -54.691654)
			(xy 146.153274 -54.655959) (xy 146.199132 -54.626491) (xy 146.248718 -54.60385) (xy 146.301021 -54.588496)
			(xy 146.354977 -54.580743) (xy 146.382232 -54.580282) (xy 146.410324 -54.580751) (xy 146.465903 -54.588983)
			(xy 146.519672 -54.605279) (xy 146.57047 -54.629286) (xy 146.617196 -54.660484) (xy 146.658841 -54.6982)
			(xy 146.694502 -54.741616) (xy 146.709384 -54.765448) (xy 146.714718 -54.774592) (xy 146.731736 -54.786784)
			(xy 146.824954 -54.80685) (xy 146.845528 -54.802786) (xy 146.854164 -54.79669) (xy 146.878235 -54.780702)
			(xy 146.930164 -54.755357) (xy 146.98532 -54.738128) (xy 147.042442 -54.729409) (xy 147.071334 -54.728872)
			(xy 147.098585 -54.729346) (xy 147.152532 -54.737107) (xy 147.204826 -54.752465) (xy 147.254402 -54.775109)
			(xy 147.300251 -54.804577) (xy 147.341441 -54.840269) (xy 147.377132 -54.88146) (xy 147.406598 -54.92731)
			(xy 147.42924 -54.976887) (xy 147.444596 -55.029181) (xy 147.452355 -55.083129) (xy 147.452842 -55.11038)
			(xy 147.452378 -55.13775) (xy 147.444562 -55.19193) (xy 147.429073 -55.244434) (xy 147.406231 -55.294181)
			(xy 147.376504 -55.340147) (xy 147.358862 -55.361078) (xy 147.352766 -55.36819) (xy 147.346416 -55.385208)
			(xy 147.346416 -55.470552) (xy 147.352766 -55.48757) (xy 147.358862 -55.494682) (xy 147.376484 -55.51563)
			(xy 147.40621 -55.561595) (xy 147.429057 -55.611339) (xy 147.444555 -55.663839) (xy 147.452386 -55.718015)
			(xy 147.452388 -55.772755) (xy 147.444562 -55.826932) (xy 147.429068 -55.879433) (xy 147.406225 -55.929178)
			(xy 147.376502 -55.975146) (xy 147.358862 -55.996078) (xy 147.352766 -56.00319) (xy 147.346416 -56.020208)
			(xy 147.346416 -56.105552) (xy 147.352766 -56.12257) (xy 147.358862 -56.129682) (xy 147.3765 -56.150615)
			(xy 147.406213 -56.196587) (xy 147.42905 -56.246334) (xy 147.444541 -56.298835) (xy 147.452369 -56.353011)
			(xy 147.452842 -56.38038) (xy 147.452356 -56.407631) (xy 147.4446 -56.461579) (xy 147.429245 -56.513874)
			(xy 147.406603 -56.563451) (xy 147.377137 -56.609301) (xy 147.341446 -56.650492) (xy 147.300255 -56.686183)
			(xy 147.254405 -56.715649) (xy 147.204828 -56.738291) (xy 147.152533 -56.753646) (xy 147.098585 -56.761402)
			(xy 147.044083 -56.761402) (xy 146.990135 -56.753646) (xy 146.93784 -56.738291) (xy 146.888263 -56.715649)
			(xy 146.842413 -56.686183) (xy 146.801222 -56.650492) (xy 146.765531 -56.609301) (xy 146.736065 -56.563451)
			(xy 146.713423 -56.513874) (xy 146.698068 -56.461579) (xy 146.690312 -56.407631) (xy 146.689826 -56.38038)
			(xy 146.690274 -56.353009) (xy 146.698095 -56.298829) (xy 146.713588 -56.246325) (xy 146.736434 -56.196579)
			(xy 146.766163 -56.150613) (xy 146.783806 -56.129682) (xy 146.789902 -56.12257) (xy 146.796252 -56.105552)
			(xy 146.796252 -56.020208) (xy 146.789902 -56.00319) (xy 146.783806 -55.996078) (xy 146.766147 -55.975161)
			(xy 146.736424 -55.92919) (xy 146.713581 -55.879441) (xy 146.698087 -55.826937) (xy 146.690261 -55.772756)
			(xy 146.690263 -55.718014) (xy 146.698094 -55.663834) (xy 146.713592 -55.611331) (xy 146.736439 -55.561584)
			(xy 146.766165 -55.515615) (xy 146.783806 -55.494682) (xy 146.789902 -55.48757) (xy 146.796252 -55.470552)
			(xy 146.796252 -55.385208) (xy 146.789902 -55.36819) (xy 146.783806 -55.361078) (xy 146.772854 -55.348282)
			(xy 146.753014 -55.321063) (xy 146.744182 -55.306722) (xy 146.738848 -55.297578) (xy 146.72183 -55.285386)
			(xy 146.628612 -55.26532) (xy 146.608038 -55.269384) (xy 146.599402 -55.27548) (xy 146.575338 -55.291479)
			(xy 146.523407 -55.316823) (xy 146.468249 -55.334049) (xy 146.411125 -55.342764) (xy 146.382232 -55.343298)
			(xy 146.354977 -55.342857) (xy 146.301021 -55.335104) (xy 146.248718 -55.31975) (xy 146.199132 -55.297109)
			(xy 146.153274 -55.267641) (xy 146.112076 -55.231946) (xy 146.076378 -55.190752) (xy 146.046906 -55.144896)
			(xy 146.024261 -55.095312) (xy 146.008903 -55.04301) (xy 146.001145 -54.989055) (xy 143.792735 -54.989055)
			(xy 143.79716 -55.004613) (xy 143.804462 -55.057006) (xy 143.804894 -55.083456) (xy 143.804457 -55.109439)
			(xy 143.797407 -55.160925) (xy 143.783432 -55.210977) (xy 143.76279 -55.258668) (xy 143.735863 -55.303114)
			(xy 143.703152 -55.343493) (xy 143.684498 -55.361586) (xy 143.68399 -55.362094) (xy 143.679672 -55.366158)
			(xy 143.672518 -55.373636) (xy 143.6644 -55.392649) (xy 143.663924 -55.402988) (xy 143.663924 -55.420855)
			(xy 144.324745 -55.420855) (xy 144.324745 -55.366345) (xy 144.332503 -55.31239) (xy 144.347861 -55.260088)
			(xy 144.370506 -55.210504) (xy 144.399978 -55.164648) (xy 144.435676 -55.123454) (xy 144.476874 -55.087759)
			(xy 144.522732 -55.058291) (xy 144.572318 -55.03565) (xy 144.624621 -55.020296) (xy 144.678577 -55.012543)
			(xy 144.705832 -55.012082) (xy 144.732148 -55.01254) (xy 144.784281 -55.01976) (xy 144.834929 -55.034072)
			(xy 144.883131 -55.055206) (xy 144.927973 -55.08276) (xy 144.968606 -55.116212) (xy 144.986756 -55.135272)
			(xy 144.994296 -55.142652) (xy 145.013562 -55.15119) (xy 145.024094 -55.151782) (xy 145.09877 -55.151782)
			(xy 145.10932 -55.151256) (xy 145.128616 -55.142719) (xy 145.136108 -55.135272) (xy 145.154253 -55.116202)
			(xy 145.19487 -55.082721) (xy 145.239707 -55.055147) (xy 145.287913 -55.034006) (xy 145.33857 -55.019701)
			(xy 145.390713 -55.012502) (xy 145.417032 -55.012082) (xy 145.444281 -55.01259) (xy 145.498224 -55.02035)
			(xy 145.550513 -55.035708) (xy 145.600085 -55.05835) (xy 145.64593 -55.087817) (xy 145.687116 -55.123507)
			(xy 145.722803 -55.164695) (xy 145.752265 -55.210543) (xy 145.774903 -55.260117) (xy 145.790256 -55.312408)
			(xy 145.798012 -55.366351) (xy 145.798012 -55.420849) (xy 145.790256 -55.474792) (xy 145.774903 -55.527083)
			(xy 145.752265 -55.576657) (xy 145.722803 -55.622505) (xy 145.687116 -55.663693) (xy 145.64593 -55.699383)
			(xy 145.600085 -55.72885) (xy 145.550513 -55.751492) (xy 145.498224 -55.76685) (xy 145.444281 -55.77461)
			(xy 145.417032 -55.775098) (xy 145.390715 -55.774671) (xy 145.33858 -55.767445) (xy 145.287931 -55.753127)
			(xy 145.239729 -55.731988) (xy 145.194888 -55.704428) (xy 145.154257 -55.67097) (xy 145.136108 -55.651908)
			(xy 145.128584 -55.644509) (xy 145.109306 -55.635983) (xy 145.09877 -55.635398) (xy 145.024094 -55.635398)
			(xy 145.013542 -55.635911) (xy 144.994247 -55.644457) (xy 144.986756 -55.651908) (xy 144.968644 -55.67101)
			(xy 144.928019 -55.704486) (xy 144.883173 -55.732053) (xy 144.834961 -55.753188) (xy 144.7843 -55.767487)
			(xy 144.732153 -55.77468) (xy 144.705832 -55.775098) (xy 144.678577 -55.774657) (xy 144.624621 -55.766904)
			(xy 144.572318 -55.75155) (xy 144.522732 -55.728909) (xy 144.476874 -55.699441) (xy 144.435676 -55.663746)
			(xy 144.399978 -55.622552) (xy 144.370506 -55.576696) (xy 144.347861 -55.527112) (xy 144.332503 -55.47481)
			(xy 144.324745 -55.420855) (xy 143.663924 -55.420855) (xy 143.663924 -56.033924) (xy 143.664324 -56.044558)
			(xy 143.672876 -56.064024) (xy 143.680434 -56.071516) (xy 143.699678 -56.089667) (xy 143.733474 -56.130363)
			(xy 143.761322 -56.175339) (xy 143.782687 -56.223732) (xy 143.79716 -56.274613) (xy 143.804462 -56.327006)
			(xy 143.804894 -56.353456) (xy 143.804457 -56.379439) (xy 143.797407 -56.430925) (xy 143.783432 -56.480977)
			(xy 143.76279 -56.528668) (xy 143.735863 -56.573114) (xy 143.703152 -56.613493) (xy 143.684498 -56.631586)
			(xy 143.68399 -56.632094) (xy 143.679672 -56.636158) (xy 143.672518 -56.643636) (xy 143.6644 -56.662649)
			(xy 143.663924 -56.672988) (xy 143.663924 -57.48528) (xy 146.70608 -57.48528) (xy 146.710151 -57.429658)
			(xy 146.722277 -57.375221) (xy 146.7422 -57.32313) (xy 146.769496 -57.274495) (xy 146.803582 -57.230352)
			(xy 146.843731 -57.191643) (xy 146.889089 -57.159192) (xy 146.938689 -57.133691) (xy 146.991473 -57.115684)
			(xy 147.046316 -57.105554) (xy 147.10205 -57.103517) (xy 147.157487 -57.109617) (xy 147.211444 -57.123723)
			(xy 147.262773 -57.145535) (xy 147.310379 -57.174589) (xy 147.353247 -57.210264) (xy 147.390464 -57.251801)
			(xy 147.421237 -57.298314) (xy 147.444909 -57.348811) (xy 147.460977 -57.402218) (xy 147.469097 -57.457394)
			(xy 147.469606 -57.48528) (xy 147.469097 -57.513166) (xy 147.460977 -57.568342) (xy 147.444909 -57.621749)
			(xy 147.421237 -57.672246) (xy 147.390464 -57.718759) (xy 147.353247 -57.760296) (xy 147.310379 -57.795971)
			(xy 147.262773 -57.825025) (xy 147.211444 -57.846837) (xy 147.157487 -57.860943) (xy 147.10205 -57.867043)
			(xy 147.046316 -57.865006) (xy 146.991473 -57.854876) (xy 146.938689 -57.836869) (xy 146.889089 -57.811368)
			(xy 146.843731 -57.778917) (xy 146.803582 -57.740208) (xy 146.769496 -57.696065) (xy 146.7422 -57.64743)
			(xy 146.722277 -57.595339) (xy 146.710151 -57.540902) (xy 146.70608 -57.48528) (xy 143.663924 -57.48528)
			(xy 143.663924 -58.076084) (xy 147.458174 -58.076084) (xy 147.462245 -58.020462) (xy 147.474371 -57.966025)
			(xy 147.494294 -57.913934) (xy 147.52159 -57.865299) (xy 147.555676 -57.821156) (xy 147.595825 -57.782447)
			(xy 147.641183 -57.749996) (xy 147.690783 -57.724495) (xy 147.743567 -57.706488) (xy 147.79841 -57.696358)
			(xy 147.854144 -57.694321) (xy 147.909581 -57.700421) (xy 147.963538 -57.714527) (xy 148.014867 -57.736339)
			(xy 148.062473 -57.765393) (xy 148.105341 -57.801068) (xy 148.142558 -57.842605) (xy 148.158894 -57.867296)
			(xy 149.742904 -57.867296) (xy 149.746977 -57.811637) (xy 149.759112 -57.757164) (xy 149.779048 -57.705038)
			(xy 149.806362 -57.65637) (xy 149.84047 -57.612198) (xy 149.880647 -57.573463) (xy 149.926035 -57.540991)
			(xy 149.975667 -57.515473) (xy 150.028487 -57.497454) (xy 150.083366 -57.487317) (xy 150.139137 -57.485279)
			(xy 150.194611 -57.491382) (xy 150.248604 -57.505498) (xy 150.299967 -57.527325) (xy 150.347605 -57.556398)
			(xy 150.390501 -57.592097) (xy 150.427743 -57.633661) (xy 150.458537 -57.680205) (xy 150.482225 -57.730736)
			(xy 150.498303 -57.784178) (xy 150.506429 -57.839392) (xy 150.506938 -57.867296) (xy 150.506429 -57.8952)
			(xy 150.498303 -57.950414) (xy 150.482225 -58.003856) (xy 150.458537 -58.054387) (xy 150.427743 -58.100931)
			(xy 150.390501 -58.142495) (xy 150.347605 -58.178194) (xy 150.299967 -58.207267) (xy 150.248604 -58.229094)
			(xy 150.194611 -58.24321) (xy 150.139137 -58.249313) (xy 150.083366 -58.247275) (xy 150.028487 -58.237138)
			(xy 149.975667 -58.219119) (xy 149.926035 -58.193601) (xy 149.880647 -58.161129) (xy 149.84047 -58.122394)
			(xy 149.806362 -58.078222) (xy 149.779048 -58.029554) (xy 149.759112 -57.977428) (xy 149.746977 -57.922955)
			(xy 149.742904 -57.867296) (xy 148.158894 -57.867296) (xy 148.173331 -57.889118) (xy 148.197003 -57.939615)
			(xy 148.213071 -57.993022) (xy 148.221191 -58.048198) (xy 148.2217 -58.076084) (xy 148.221191 -58.10397)
			(xy 148.213071 -58.159146) (xy 148.197003 -58.212553) (xy 148.173331 -58.26305) (xy 148.142558 -58.309563)
			(xy 148.105341 -58.3511) (xy 148.062473 -58.386775) (xy 148.014867 -58.415829) (xy 147.963538 -58.437641)
			(xy 147.909581 -58.451747) (xy 147.854144 -58.457847) (xy 147.79841 -58.45581) (xy 147.743567 -58.44568)
			(xy 147.690783 -58.427673) (xy 147.641183 -58.402172) (xy 147.595825 -58.369721) (xy 147.555676 -58.331012)
			(xy 147.52159 -58.286869) (xy 147.494294 -58.238234) (xy 147.474371 -58.186143) (xy 147.462245 -58.131706)
			(xy 147.458174 -58.076084) (xy 143.663924 -58.076084) (xy 143.663924 -58.561224) (xy 148.662388 -58.561224)
			(xy 148.666459 -58.505602) (xy 148.678585 -58.451165) (xy 148.698508 -58.399074) (xy 148.725804 -58.350439)
			(xy 148.75989 -58.306296) (xy 148.800039 -58.267587) (xy 148.845397 -58.235136) (xy 148.894997 -58.209635)
			(xy 148.947781 -58.191628) (xy 149.002624 -58.181498) (xy 149.058358 -58.179461) (xy 149.113795 -58.185561)
			(xy 149.167752 -58.199667) (xy 149.219081 -58.221479) (xy 149.266687 -58.250533) (xy 149.309555 -58.286208)
			(xy 149.346772 -58.327745) (xy 149.377545 -58.374258) (xy 149.401217 -58.424755) (xy 149.408727 -58.449718)
			(xy 150.909018 -58.449718) (xy 150.913089 -58.394096) (xy 150.925215 -58.339659) (xy 150.945138 -58.287568)
			(xy 150.972434 -58.238933) (xy 151.00652 -58.19479) (xy 151.046669 -58.156081) (xy 151.092027 -58.12363)
			(xy 151.141627 -58.098129) (xy 151.194411 -58.080122) (xy 151.249254 -58.069992) (xy 151.304988 -58.067955)
			(xy 151.360425 -58.074055) (xy 151.414382 -58.088161) (xy 151.465711 -58.109973) (xy 151.513317 -58.139027)
			(xy 151.556185 -58.174702) (xy 151.593402 -58.216239) (xy 151.624175 -58.262752) (xy 151.647847 -58.313249)
			(xy 151.663915 -58.366656) (xy 151.672035 -58.421832) (xy 151.672544 -58.449718) (xy 151.672035 -58.477604)
			(xy 151.663915 -58.53278) (xy 151.647847 -58.586187) (xy 151.624175 -58.636684) (xy 151.593402 -58.683197)
			(xy 151.556185 -58.724734) (xy 151.513317 -58.760409) (xy 151.465711 -58.789463) (xy 151.414382 -58.811275)
			(xy 151.360425 -58.825381) (xy 151.304988 -58.831481) (xy 151.249254 -58.829444) (xy 151.194411 -58.819314)
			(xy 151.141627 -58.801307) (xy 151.092027 -58.775806) (xy 151.046669 -58.743355) (xy 151.00652 -58.704646)
			(xy 150.972434 -58.660503) (xy 150.945138 -58.611868) (xy 150.925215 -58.559777) (xy 150.913089 -58.50534)
			(xy 150.909018 -58.449718) (xy 149.408727 -58.449718) (xy 149.417285 -58.478162) (xy 149.425405 -58.533338)
			(xy 149.425914 -58.561224) (xy 149.425405 -58.58911) (xy 149.417285 -58.644286) (xy 149.401217 -58.697693)
			(xy 149.377545 -58.74819) (xy 149.346772 -58.794703) (xy 149.309555 -58.83624) (xy 149.266687 -58.871915)
			(xy 149.219081 -58.900969) (xy 149.167752 -58.922781) (xy 149.113795 -58.936887) (xy 149.058358 -58.942987)
			(xy 149.002624 -58.94095) (xy 148.947781 -58.93082) (xy 148.894997 -58.912813) (xy 148.845397 -58.887312)
			(xy 148.800039 -58.854861) (xy 148.75989 -58.816152) (xy 148.725804 -58.772009) (xy 148.698508 -58.723374)
			(xy 148.678585 -58.671283) (xy 148.666459 -58.616846) (xy 148.662388 -58.561224) (xy 143.663924 -58.561224)
			(xy 143.663924 -59.974734) (xy 147.187158 -59.974734) (xy 147.187608 -59.947908) (xy 147.195128 -59.894785)
			(xy 147.210009 -59.843238) (xy 147.23196 -59.794281) (xy 147.260548 -59.748879) (xy 147.295209 -59.707926)
			(xy 147.335262 -59.672228) (xy 147.357338 -59.65698) (xy 147.368903 -59.648762) (xy 147.387304 -59.62718)
			(xy 147.399055 -59.601369) (xy 147.403249 -59.573319) (xy 147.399561 -59.545199) (xy 147.388277 -59.51918)
			(xy 147.370268 -59.497271) (xy 147.358862 -59.488832) (xy 147.337402 -59.473484) (xy 147.29849 -59.437855)
			(xy 147.264859 -59.397205) (xy 147.237148 -59.352309) (xy 147.215888 -59.304023) (xy 147.201484 -59.253269)
			(xy 147.19421 -59.201013) (xy 147.193762 -59.174634) (xy 147.194248 -59.147383) (xy 147.202004 -59.093435)
			(xy 147.217359 -59.04114) (xy 147.240001 -58.991563) (xy 147.269467 -58.945713) (xy 147.305158 -58.904522)
			(xy 147.346349 -58.868831) (xy 147.392199 -58.839365) (xy 147.441776 -58.816723) (xy 147.494071 -58.801368)
			(xy 147.548019 -58.793612) (xy 147.602521 -58.793612) (xy 147.656469 -58.801368) (xy 147.708764 -58.816723)
			(xy 147.758341 -58.839365) (xy 147.804191 -58.868831) (xy 147.845382 -58.904522) (xy 147.881073 -58.945713)
			(xy 147.910539 -58.991563) (xy 147.933181 -59.04114) (xy 147.948536 -59.093435) (xy 147.956292 -59.147383)
			(xy 147.956778 -59.174634) (xy 147.956332 -59.201461) (xy 147.948815 -59.254585) (xy 147.933935 -59.306133)
			(xy 147.911984 -59.355091) (xy 147.883395 -59.400493) (xy 147.848731 -59.441445) (xy 147.808675 -59.477141)
			(xy 147.786598 -59.492388) (xy 147.775061 -59.500644) (xy 147.756654 -59.522215) (xy 147.744897 -59.548019)
			(xy 147.740698 -59.576063) (xy 147.744381 -59.604179) (xy 147.755662 -59.630195) (xy 147.773669 -59.6521)
			(xy 147.785074 -59.660536) (xy 147.806574 -59.67583) (xy 147.845483 -59.711469) (xy 147.87911 -59.752129)
			(xy 147.906815 -59.797034) (xy 147.928069 -59.845329) (xy 147.942465 -59.896091) (xy 147.94973 -59.948352)
			(xy 147.950174 -59.974734) (xy 147.949688 -60.001985) (xy 147.941932 -60.055933) (xy 147.926577 -60.108228)
			(xy 147.903935 -60.157805) (xy 147.874469 -60.203655) (xy 147.838778 -60.244846) (xy 147.797587 -60.280537)
			(xy 147.751737 -60.310003) (xy 147.70216 -60.332645) (xy 147.649865 -60.348) (xy 147.595917 -60.355756)
			(xy 147.541415 -60.355756) (xy 147.487467 -60.348) (xy 147.435172 -60.332645) (xy 147.385595 -60.310003)
			(xy 147.339745 -60.280537) (xy 147.298554 -60.244846) (xy 147.262863 -60.203655) (xy 147.233397 -60.157805)
			(xy 147.210755 -60.108228) (xy 147.1954 -60.055933) (xy 147.187644 -60.001985) (xy 147.187158 -59.974734)
			(xy 143.663924 -59.974734) (xy 143.663924 -60.601606) (xy 146.433284 -60.601606) (xy 146.437355 -60.545984)
			(xy 146.449481 -60.491547) (xy 146.469404 -60.439456) (xy 146.4967 -60.390821) (xy 146.530786 -60.346678)
			(xy 146.570935 -60.307969) (xy 146.616293 -60.275518) (xy 146.665893 -60.250017) (xy 146.718677 -60.23201)
			(xy 146.77352 -60.22188) (xy 146.829254 -60.219843) (xy 146.884691 -60.225943) (xy 146.938648 -60.240049)
			(xy 146.989977 -60.261861) (xy 147.037583 -60.290915) (xy 147.080451 -60.32659) (xy 147.117668 -60.368127)
			(xy 147.148441 -60.41464) (xy 147.172113 -60.465137) (xy 147.188181 -60.518544) (xy 147.196301 -60.57372)
			(xy 147.19681 -60.601606) (xy 147.196346 -60.627006) (xy 148.821392 -60.627006) (xy 148.825463 -60.571384)
			(xy 148.837589 -60.516947) (xy 148.857512 -60.464856) (xy 148.884808 -60.416221) (xy 148.918894 -60.372078)
			(xy 148.959043 -60.333369) (xy 149.004401 -60.300918) (xy 149.054001 -60.275417) (xy 149.106785 -60.25741)
			(xy 149.161628 -60.24728) (xy 149.217362 -60.245243) (xy 149.272799 -60.251343) (xy 149.326756 -60.265449)
			(xy 149.378085 -60.287261) (xy 149.425691 -60.316315) (xy 149.468559 -60.35199) (xy 149.505776 -60.393527)
			(xy 149.536549 -60.44004) (xy 149.560221 -60.490537) (xy 149.576289 -60.543944) (xy 149.584409 -60.59912)
			(xy 149.584918 -60.627006) (xy 149.584802 -60.633356) (xy 150.913082 -60.633356) (xy 150.917153 -60.577734)
			(xy 150.929279 -60.523297) (xy 150.949202 -60.471206) (xy 150.976498 -60.422571) (xy 151.010584 -60.378428)
			(xy 151.050733 -60.339719) (xy 151.096091 -60.307268) (xy 151.145691 -60.281767) (xy 151.198475 -60.26376)
			(xy 151.253318 -60.25363) (xy 151.309052 -60.251593) (xy 151.364489 -60.257693) (xy 151.418446 -60.271799)
			(xy 151.469775 -60.293611) (xy 151.517381 -60.322665) (xy 151.560249 -60.35834) (xy 151.597466 -60.399877)
			(xy 151.628239 -60.44639) (xy 151.651911 -60.496887) (xy 151.667979 -60.550294) (xy 151.676099 -60.60547)
			(xy 151.676608 -60.633356) (xy 151.676099 -60.661242) (xy 151.667979 -60.716418) (xy 151.651911 -60.769825)
			(xy 151.628239 -60.820322) (xy 151.597466 -60.866835) (xy 151.560249 -60.908372) (xy 151.517381 -60.944047)
			(xy 151.469775 -60.973101) (xy 151.418446 -60.994913) (xy 151.364489 -61.009019) (xy 151.309052 -61.015119)
			(xy 151.253318 -61.013082) (xy 151.198475 -61.002952) (xy 151.145691 -60.984945) (xy 151.096091 -60.959444)
			(xy 151.050733 -60.926993) (xy 151.010584 -60.888284) (xy 150.976498 -60.844141) (xy 150.949202 -60.795506)
			(xy 150.929279 -60.743415) (xy 150.917153 -60.688978) (xy 150.913082 -60.633356) (xy 149.584802 -60.633356)
			(xy 149.584409 -60.654892) (xy 149.576289 -60.710068) (xy 149.560221 -60.763475) (xy 149.536549 -60.813972)
			(xy 149.505776 -60.860485) (xy 149.468559 -60.902022) (xy 149.425691 -60.937697) (xy 149.378085 -60.966751)
			(xy 149.326756 -60.988563) (xy 149.272799 -61.002669) (xy 149.217362 -61.008769) (xy 149.161628 -61.006732)
			(xy 149.106785 -60.996602) (xy 149.054001 -60.978595) (xy 149.004401 -60.953094) (xy 148.959043 -60.920643)
			(xy 148.918894 -60.881934) (xy 148.884808 -60.837791) (xy 148.857512 -60.789156) (xy 148.837589 -60.737065)
			(xy 148.825463 -60.682628) (xy 148.821392 -60.627006) (xy 147.196346 -60.627006) (xy 147.196301 -60.629492)
			(xy 147.188181 -60.684668) (xy 147.172113 -60.738075) (xy 147.148441 -60.788572) (xy 147.117668 -60.835085)
			(xy 147.080451 -60.876622) (xy 147.037583 -60.912297) (xy 146.989977 -60.941351) (xy 146.938648 -60.963163)
			(xy 146.884691 -60.977269) (xy 146.829254 -60.983369) (xy 146.77352 -60.981332) (xy 146.718677 -60.971202)
			(xy 146.665893 -60.953195) (xy 146.616293 -60.927694) (xy 146.570935 -60.895243) (xy 146.530786 -60.856534)
			(xy 146.4967 -60.812391) (xy 146.469404 -60.763756) (xy 146.449481 -60.711665) (xy 146.437355 -60.657228)
			(xy 146.433284 -60.601606) (xy 143.663924 -60.601606) (xy 143.663924 -61.49594) (xy 143.664406 -61.505904)
			(xy 143.67199 -61.524333) (xy 143.678656 -61.531754) (xy 143.703548 -61.556646) (xy 143.710947 -61.563491)
			(xy 143.729545 -61.571216) (xy 143.739616 -61.571632) (xy 146.281902 -61.571632) (xy 146.294601 -61.571779)
			(xy 146.319908 -61.573941) (xy 146.332448 -61.57595) (xy 146.336766 -61.576712) (xy 147.111974 -61.576712)
		)
		(stroke
			(width 0)
			(type solid)
		)
		(fill yes)
		(layer "In9.Cu")
		(net "P3V3_SSD5")
	)
	(gr_poly
		(pts
			(xy 173.128686 -61.576712) (xy 173.163484 -61.57468) (xy 174.30115 -61.57468) (xy 174.310869 -61.574189)
			(xy 174.328881 -61.566868) (xy 174.336202 -61.560456) (xy 174.38497 -61.51372) (xy 174.389034 -61.504576)
			(xy 174.400464 -61.479176) (xy 174.400972 -61.470032) (xy 174.402941 -61.444477) (xy 174.412869 -61.394194)
			(xy 174.429436 -61.345692) (xy 174.452345 -61.299842) (xy 174.481182 -61.257471) (xy 174.498 -61.23813)
			(xy 174.498508 -61.237622) (xy 174.499524 -61.236352) (xy 174.519844 -61.214762) (xy 174.541371 -61.194527)
			(xy 174.589506 -61.160277) (xy 174.642347 -61.133856) (xy 174.698628 -61.115896) (xy 174.757005 -61.106826)
			(xy 174.786544 -61.106304) (xy 174.813327 -61.106752) (xy 174.866368 -61.114236) (xy 174.917842 -61.129064)
			(xy 174.966736 -61.150945) (xy 175.012089 -61.179448) (xy 175.05301 -61.214014) (xy 175.088695 -61.253963)
			(xy 175.118443 -61.298511) (xy 175.141668 -61.34678) (xy 175.157914 -61.397824) (xy 175.166862 -61.450637)
			(xy 175.168052 -61.477398) (xy 175.169068 -61.486542) (xy 175.17237 -61.502544) (xy 175.176688 -61.512196)
			(xy 175.184308 -61.519308) (xy 175.226472 -61.559948) (xy 175.232045 -61.564897) (xy 175.245342 -61.571614)
			(xy 175.252634 -61.573156) (xy 175.260762 -61.57468) (xy 176.243234 -61.57468) (xy 176.252208 -61.574731)
			(xy 176.270126 -61.575749) (xy 176.279048 -61.576712) (xy 177.143156 -61.576712) (xy 177.152078 -61.575746)
			(xy 177.169996 -61.57473) (xy 177.17897 -61.57468) (xy 178.852576 -61.57468) (xy 178.861212 -61.573918)
			(xy 178.862228 -61.573918) (xy 178.869865 -61.572272) (xy 178.883699 -61.565029) (xy 178.889406 -61.559694)
			(xy 179.512468 -60.936632) (xy 179.515516 -60.93333) (xy 179.52593 -60.922916) (xy 179.528601 -60.917444)
			(xy 179.531553 -60.905633) (xy 179.531772 -60.899548) (xy 179.531772 -38.90772) (xy 179.53101 -38.898322)
			(xy 179.527962 -38.882066) (xy 179.51958 -38.867588) (xy 179.512976 -38.861746) (xy 179.480568 -38.832662)
			(xy 179.420697 -38.769424) (xy 179.366932 -38.70092) (xy 179.319733 -38.627737) (xy 179.279504 -38.550502)
			(xy 179.246592 -38.469877) (xy 179.221278 -38.386554) (xy 179.203778 -38.301247) (xy 179.194244 -38.214687)
			(xy 179.192756 -38.127616) (xy 179.199327 -38.040781) (xy 179.213902 -37.954925) (xy 179.236355 -37.870786)
			(xy 179.266494 -37.789084) (xy 179.30406 -37.71052) (xy 179.348732 -37.635767) (xy 179.400126 -37.565466)
			(xy 179.428648 -37.532564) (xy 179.442469 -37.516896) (xy 179.471309 -37.486658) (xy 179.486306 -37.472112)
			(xy 179.497736 -37.461444) (xy 179.49799 -37.46119) (xy 179.50688 -37.452808) (xy 179.514754 -37.44595)
			(xy 179.5272 -37.418264) (xy 179.529311 -37.413316) (xy 179.531623 -37.402813) (xy 179.531772 -37.397436)
			(xy 179.531772 -31.777432) (xy 179.528978 -31.769304) (xy 179.518821 -31.738539) (xy 179.507841 -31.674695)
			(xy 179.507134 -31.642304) (xy 179.507844 -31.609914) (xy 179.518829 -31.546071) (xy 179.528978 -31.515304)
			(xy 179.531772 -31.507176) (xy 179.531772 -31.238444) (xy 179.531886 -31.233489) (xy 179.533796 -31.223764)
			(xy 179.535582 -31.21914) (xy 179.540662 -31.206948) (xy 179.54244 -31.202321) (xy 179.544368 -31.192599)
			(xy 179.544472 -31.187644) (xy 179.544472 -29.841952) (xy 179.544211 -29.834013) (xy 179.539431 -29.818875)
			(xy 179.535074 -29.812234) (xy 179.518219 -29.787796) (xy 179.491476 -29.7348) (xy 179.47326 -29.678301)
			(xy 179.464011 -29.619664) (xy 179.463446 -29.589984) (xy 179.464028 -29.560303) (xy 179.47326 -29.501663)
			(xy 179.491466 -29.445162) (xy 179.518208 -29.392164) (xy 179.535074 -29.367734) (xy 179.539435 -29.361093)
			(xy 179.544232 -29.345957) (xy 179.544472 -29.338016) (xy 179.544472 -28.112974) (xy 179.544592 -28.108426)
			(xy 179.546247 -28.09948) (xy 179.547774 -28.095194) (xy 179.54954 -28.090052) (xy 179.551074 -28.07929)
			(xy 179.550822 -28.073858) (xy 179.548536 -28.044394) (xy 179.5478 -28.037202) (xy 179.542763 -28.023656)
			(xy 179.53863 -28.017724) (xy 179.520944 -27.992879) (xy 179.492861 -27.938747) (xy 179.473736 -27.880841)
			(xy 179.464055 -27.820631) (xy 179.463446 -27.79014) (xy 179.463929 -27.762886) (xy 179.471681 -27.708931)
			(xy 179.487032 -27.656629) (xy 179.50967 -27.607044) (xy 179.539135 -27.561185) (xy 179.574825 -27.519986)
			(xy 179.616016 -27.484286) (xy 179.661868 -27.454811) (xy 179.711448 -27.432162) (xy 179.763747 -27.416799)
			(xy 179.8177 -27.409035) (xy 179.844954 -27.408632) (xy 179.8705 -27.409044) (xy 179.921136 -27.415866)
			(xy 179.970409 -27.429381) (xy 180.01744 -27.449346) (xy 180.061387 -27.475407) (xy 180.081682 -27.490928)
			(xy 180.097176 -27.50312) (xy 180.135276 -27.501088) (xy 180.288692 -27.347672) (xy 180.296087 -27.340816)
			(xy 180.314685 -27.333068) (xy 180.32476 -27.332686) (xy 180.470556 -27.332686) (xy 180.475128 -27.331924)
			(xy 180.488099 -27.329729) (xy 180.514298 -27.327314) (xy 180.527452 -27.327098) (xy 184.572656 -27.327352)
			(xy 184.58268 -27.326939) (xy 184.601203 -27.319276) (xy 184.615378 -27.3051) (xy 184.62304 -27.286576)
			(xy 184.623456 -27.276552) (xy 184.623456 -26.478992) (xy 184.62369 -26.458819) (xy 184.627254 -26.418629)
			(xy 184.630568 -26.398728) (xy 184.631584 -26.39314) (xy 184.631076 -26.381456) (xy 184.630014 -26.369683)
			(xy 184.618629 -26.349001) (xy 184.609232 -26.341832) (xy 184.602628 -26.33726) (xy 184.592157 -26.330886)
			(xy 184.567872 -26.32784) (xy 184.556146 -26.331418) (xy 184.528279 -26.345635) (xy 184.469056 -26.365782)
			(xy 184.407338 -26.375988) (xy 184.37606 -26.37663) (xy 184.34881 -26.376142) (xy 184.294865 -26.36838)
			(xy 184.242574 -26.353022) (xy 184.193001 -26.330379) (xy 184.147154 -26.300912) (xy 184.105966 -26.265221)
			(xy 184.070277 -26.224032) (xy 184.040812 -26.178183) (xy 184.018172 -26.128609) (xy 184.002816 -26.076317)
			(xy 183.995057 -26.022372) (xy 183.994552 -25.995122) (xy 183.995105 -25.965933) (xy 184.003993 -25.908234)
			(xy 184.021563 -25.852562) (xy 184.047408 -25.800216) (xy 184.080923 -25.752416) (xy 184.100724 -25.730962)
			(xy 184.102502 -25.729184) (xy 184.10301 -25.728676) (xy 184.123432 -25.707787) (xy 184.169477 -25.67184)
			(xy 184.220458 -25.643321) (xy 184.275186 -25.622897) (xy 184.30367 -25.616408) (xy 184.322637 -25.61275)
			(xy 184.361064 -25.608806) (xy 184.380378 -25.608534) (xy 184.380886 -25.608534) (xy 184.40985 -25.609071)
			(xy 184.467113 -25.617825) (xy 184.522395 -25.635134) (xy 184.574425 -25.660601) (xy 184.622008 -25.69364)
			(xy 184.66405 -25.733492) (xy 184.699584 -25.779241) (xy 184.727796 -25.829835) (xy 184.728623 -25.832054)
			(xy 186.287916 -25.832054) (xy 186.291987 -25.776432) (xy 186.304113 -25.721995) (xy 186.324036 -25.669904)
			(xy 186.351332 -25.621269) (xy 186.385418 -25.577126) (xy 186.425567 -25.538417) (xy 186.470925 -25.505966)
			(xy 186.520525 -25.480465) (xy 186.573309 -25.462458) (xy 186.628152 -25.452328) (xy 186.683886 -25.450291)
			(xy 186.739323 -25.456391) (xy 186.79328 -25.470497) (xy 186.844609 -25.492309) (xy 186.892215 -25.521363)
			(xy 186.935083 -25.557038) (xy 186.936617 -25.55875) (xy 190.742316 -25.55875) (xy 190.742802 -25.531499)
			(xy 190.750558 -25.477551) (xy 190.765913 -25.425256) (xy 190.788555 -25.375679) (xy 190.818021 -25.329829)
			(xy 190.853712 -25.288638) (xy 190.894903 -25.252947) (xy 190.940753 -25.223481) (xy 190.99033 -25.200839)
			(xy 191.042625 -25.185484) (xy 191.096573 -25.177728) (xy 191.151075 -25.177728) (xy 191.205023 -25.185484)
			(xy 191.257318 -25.200839) (xy 191.306895 -25.223481) (xy 191.352745 -25.252947) (xy 191.393936 -25.288638)
			(xy 191.429627 -25.329829) (xy 191.459093 -25.375679) (xy 191.481735 -25.425256) (xy 191.49709 -25.477551)
			(xy 191.504846 -25.531499) (xy 191.505332 -25.55875) (xy 191.504777 -25.589013) (xy 191.495225 -25.648779)
			(xy 191.476352 -25.706287) (xy 191.448632 -25.760091) (xy 191.431164 -25.78481) (xy 191.422887 -25.796957)
			(xy 191.412939 -25.8246) (xy 191.411272 -25.853932) (xy 191.418024 -25.882524) (xy 191.432638 -25.908011)
			(xy 191.453902 -25.928282) (xy 191.480058 -25.941661) (xy 191.49441 -25.94483) (xy 191.520304 -25.950167)
			(xy 191.570427 -25.966984) (xy 191.617746 -25.990564) (xy 191.661355 -26.020454) (xy 191.700417 -26.056081)
			(xy 191.734183 -26.096762) (xy 191.762006 -26.141717) (xy 191.783353 -26.190085) (xy 191.797814 -26.240937)
			(xy 191.805112 -26.2933) (xy 191.80556 -26.319734) (xy 192.941954 -26.319734) (xy 192.946025 -26.264112)
			(xy 192.958151 -26.209675) (xy 192.978074 -26.157584) (xy 193.00537 -26.108949) (xy 193.039456 -26.064806)
			(xy 193.079605 -26.026097) (xy 193.124963 -25.993646) (xy 193.174563 -25.968145) (xy 193.227347 -25.950138)
			(xy 193.28219 -25.940008) (xy 193.337924 -25.937971) (xy 193.393361 -25.944071) (xy 193.447318 -25.958177)
			(xy 193.498647 -25.979989) (xy 193.546253 -26.009043) (xy 193.589121 -26.044718) (xy 193.626338 -26.086255)
			(xy 193.657111 -26.132768) (xy 193.680783 -26.183265) (xy 193.696851 -26.236672) (xy 193.704971 -26.291848)
			(xy 193.70548 -26.319734) (xy 193.704971 -26.34762) (xy 193.696851 -26.402796) (xy 193.680783 -26.456203)
			(xy 193.657111 -26.5067) (xy 193.626338 -26.553213) (xy 193.589121 -26.59475) (xy 193.546253 -26.630425)
			(xy 193.498647 -26.659479) (xy 193.447318 -26.681291) (xy 193.393361 -26.695397) (xy 193.337924 -26.701497)
			(xy 193.28219 -26.69946) (xy 193.227347 -26.68933) (xy 193.174563 -26.671323) (xy 193.124963 -26.645822)
			(xy 193.079605 -26.613371) (xy 193.039456 -26.574662) (xy 193.00537 -26.530519) (xy 192.978074 -26.481884)
			(xy 192.958151 -26.429793) (xy 192.946025 -26.375356) (xy 192.941954 -26.319734) (xy 191.80556 -26.319734)
			(xy 191.805074 -26.346985) (xy 191.797318 -26.400933) (xy 191.781963 -26.453228) (xy 191.759321 -26.502805)
			(xy 191.729855 -26.548655) (xy 191.694164 -26.589846) (xy 191.652973 -26.625537) (xy 191.607123 -26.655003)
			(xy 191.557546 -26.677645) (xy 191.505251 -26.693) (xy 191.451303 -26.700756) (xy 191.396801 -26.700756)
			(xy 191.342853 -26.693) (xy 191.290558 -26.677645) (xy 191.240981 -26.655003) (xy 191.195131 -26.625537)
			(xy 191.15394 -26.589846) (xy 191.118249 -26.548655) (xy 191.088783 -26.502805) (xy 191.066141 -26.453228)
			(xy 191.050786 -26.400933) (xy 191.04303 -26.346985) (xy 191.042544 -26.319734) (xy 191.043095 -26.289471)
			(xy 191.05265 -26.229705) (xy 191.071524 -26.172198) (xy 191.099244 -26.118393) (xy 191.116712 -26.093674)
			(xy 191.125023 -26.081548) (xy 191.134973 -26.053897) (xy 191.136639 -26.024559) (xy 191.129881 -25.99596)
			(xy 191.115261 -25.970469) (xy 191.093987 -25.950197) (xy 191.067822 -25.936821) (xy 191.053466 -25.933654)
			(xy 191.027564 -25.92835) (xy 190.977441 -25.911528) (xy 190.930121 -25.887945) (xy 190.886512 -25.858051)
			(xy 190.847451 -25.82242) (xy 190.813686 -25.781735) (xy 190.785864 -25.736777) (xy 190.764519 -25.688406)
			(xy 190.750059 -25.637551) (xy 190.742763 -25.585186) (xy 190.742316 -25.55875) (xy 186.936617 -25.55875)
			(xy 186.9723 -25.598575) (xy 187.003073 -25.645088) (xy 187.026745 -25.695585) (xy 187.042813 -25.748992)
			(xy 187.050933 -25.804168) (xy 187.051442 -25.832054) (xy 187.050933 -25.85994) (xy 187.042813 -25.915116)
			(xy 187.026745 -25.968523) (xy 187.003073 -26.01902) (xy 186.9723 -26.065533) (xy 186.935083 -26.10707)
			(xy 186.892215 -26.142745) (xy 186.844609 -26.171799) (xy 186.79328 -26.193611) (xy 186.739323 -26.207717)
			(xy 186.683886 -26.213817) (xy 186.628152 -26.21178) (xy 186.573309 -26.20165) (xy 186.520525 -26.183643)
			(xy 186.470925 -26.158142) (xy 186.425567 -26.125691) (xy 186.385418 -26.086982) (xy 186.351332 -26.042839)
			(xy 186.324036 -25.994204) (xy 186.304113 -25.942113) (xy 186.291987 -25.887676) (xy 186.287916 -25.832054)
			(xy 184.728623 -25.832054) (xy 184.748035 -25.884113) (xy 184.759837 -25.940826) (xy 184.761886 -25.969722)
			(xy 184.762648 -25.982168) (xy 184.775094 -26.003504) (xy 184.85485 -26.053034) (xy 184.855358 -26.053034)
			(xy 184.862978 -26.05786) (xy 184.873392 -26.059638) (xy 184.88279 -26.061416) (xy 184.902094 -26.05786)
			(xy 184.907174 -26.055828) (xy 184.934874 -26.044931) (xy 184.992386 -26.029579) (xy 185.051402 -26.021809)
			(xy 185.081164 -26.021284) (xy 185.081418 -26.021284) (xy 185.111402 -26.021754) (xy 185.170856 -26.029584)
			(xy 185.22878 -26.045108) (xy 185.284181 -26.06806) (xy 185.336113 -26.098046) (xy 185.383686 -26.134556)
			(xy 185.426087 -26.176962) (xy 185.462589 -26.22454) (xy 185.492569 -26.276476) (xy 185.515513 -26.331881)
			(xy 185.523281 -26.360882) (xy 188.205616 -26.360882) (xy 188.209687 -26.30526) (xy 188.221813 -26.250823)
			(xy 188.241736 -26.198732) (xy 188.269032 -26.150097) (xy 188.303118 -26.105954) (xy 188.343267 -26.067245)
			(xy 188.388625 -26.034794) (xy 188.438225 -26.009293) (xy 188.491009 -25.991286) (xy 188.545852 -25.981156)
			(xy 188.601586 -25.979119) (xy 188.657023 -25.985219) (xy 188.71098 -25.999325) (xy 188.762309 -26.021137)
			(xy 188.809915 -26.050191) (xy 188.852783 -26.085866) (xy 188.89 -26.127403) (xy 188.920773 -26.173916)
			(xy 188.944445 -26.224413) (xy 188.960513 -26.27782) (xy 188.968633 -26.332996) (xy 188.969142 -26.360882)
			(xy 188.968633 -26.388768) (xy 188.960513 -26.443944) (xy 188.944445 -26.497351) (xy 188.920773 -26.547848)
			(xy 188.89 -26.594361) (xy 188.852783 -26.635898) (xy 188.809915 -26.671573) (xy 188.762309 -26.700627)
			(xy 188.71098 -26.722439) (xy 188.657023 -26.736545) (xy 188.601586 -26.742645) (xy 188.545852 -26.740608)
			(xy 188.491009 -26.730478) (xy 188.438225 -26.712471) (xy 188.388625 -26.68697) (xy 188.343267 -26.654519)
			(xy 188.303118 -26.61581) (xy 188.269032 -26.571667) (xy 188.241736 -26.523032) (xy 188.221813 -26.470941)
			(xy 188.209687 -26.416504) (xy 188.205616 -26.360882) (xy 185.523281 -26.360882) (xy 185.531028 -26.389807)
			(xy 185.53885 -26.449262) (xy 185.53938 -26.479246) (xy 185.53938 -27.276806) (xy 185.539768 -27.286786)
			(xy 185.547372 -27.305238) (xy 185.561489 -27.319346) (xy 185.579945 -27.326939) (xy 185.589926 -27.327352)
			(xy 194.814698 -27.327352) (xy 194.81673 -27.327606) (xy 195.190872 -26.953464) (xy 195.197716 -26.946065)
			(xy 195.205442 -26.927467) (xy 195.205858 -26.917396) (xy 195.205858 -25.090628) (xy 195.205433 -25.079907)
			(xy 195.196737 -25.060315) (xy 195.189094 -25.052782) (xy 195.124832 -24.99487) (xy 195.104512 -24.988266)
			(xy 195.09359 -24.989536) (xy 195.083712 -24.990496) (xy 195.06389 -24.99151) (xy 195.053966 -24.991568)
			(xy 195.026716 -24.991102) (xy 194.972771 -24.983341) (xy 194.920479 -24.967982) (xy 194.870906 -24.945337)
			(xy 194.82506 -24.915867) (xy 194.783875 -24.880173) (xy 194.748188 -24.838981) (xy 194.718728 -24.793129)
			(xy 194.696092 -24.743551) (xy 194.680743 -24.691257) (xy 194.672992 -24.63731) (xy 194.672458 -24.61006)
			(xy 194.673168 -24.577125) (xy 194.68453 -24.512241) (xy 194.695064 -24.481028) (xy 194.699382 -24.468836)
			(xy 194.695318 -24.443182) (xy 194.6275 -24.35479) (xy 194.603878 -24.344376) (xy 194.590924 -24.345392)
			(xy 194.559428 -24.346662) (xy 194.53218 -24.346178) (xy 194.478239 -24.338426) (xy 194.42595 -24.323077)
			(xy 194.376378 -24.300443) (xy 194.330531 -24.270984) (xy 194.289343 -24.235301) (xy 194.253653 -24.194119)
			(xy 194.224187 -24.148277) (xy 194.201544 -24.098708) (xy 194.186187 -24.046422) (xy 194.178427 -23.992482)
			(xy 194.178422 -23.937986) (xy 194.186172 -23.884045) (xy 194.201521 -23.831756) (xy 194.224154 -23.782183)
			(xy 194.253612 -23.736336) (xy 194.289295 -23.695147) (xy 194.330476 -23.659457) (xy 194.376318 -23.62999)
			(xy 194.425886 -23.607347) (xy 194.478173 -23.591988) (xy 194.532112 -23.584227) (xy 194.586608 -23.584221)
			(xy 194.640549 -23.591971) (xy 194.692839 -23.607319) (xy 194.742412 -23.629951) (xy 194.788259 -23.659409)
			(xy 194.829448 -23.695091) (xy 194.86514 -23.736272) (xy 194.894607 -23.782113) (xy 194.917251 -23.831681)
			(xy 194.932611 -23.883967) (xy 194.940373 -23.937906) (xy 194.940936 -23.965154) (xy 194.940224 -23.998089)
			(xy 194.92886 -24.062972) (xy 194.91833 -24.094186) (xy 194.914012 -24.106378) (xy 194.918076 -24.132032)
			(xy 194.985894 -24.220424) (xy 195.009516 -24.230838) (xy 195.02247 -24.229822) (xy 195.053966 -24.228552)
			(xy 195.06389 -24.22861) (xy 195.083712 -24.229625) (xy 195.09359 -24.230584) (xy 195.104512 -24.231854)
			(xy 195.124832 -24.22525) (xy 195.189094 -24.167338) (xy 195.196643 -24.159742) (xy 195.205314 -24.140187)
			(xy 195.205858 -24.129492) (xy 195.205858 -24.082756) (xy 195.20281 -24.07412) (xy 195.194566 -24.049502)
			(xy 195.184052 -23.998663) (xy 195.180528 -23.946868) (xy 195.184061 -23.895073) (xy 195.194584 -23.844236)
			(xy 195.20281 -23.819612) (xy 195.205858 -23.810976) (xy 195.205858 -22.255226) (xy 195.205437 -22.245179)
			(xy 195.197733 -22.226622) (xy 195.183494 -22.212445) (xy 195.174362 -22.208236) (xy 195.149602 -22.197463)
			(xy 195.103139 -22.169956) (xy 195.061018 -22.136172) (xy 195.02408 -22.096787) (xy 194.993065 -22.052588)
			(xy 194.96859 -22.004458) (xy 194.951146 -21.953358) (xy 194.941081 -21.900309) (xy 194.938596 -21.84637)
			(xy 194.94374 -21.79262) (xy 194.956411 -21.740133) (xy 194.976356 -21.689956) (xy 195.003175 -21.643092)
			(xy 195.036335 -21.600477) (xy 195.075171 -21.562964) (xy 195.118908 -21.5313) (xy 195.142612 -21.518372)
			(xy 195.174616 -21.503386) (xy 195.18884 -21.49729) (xy 195.205858 -21.47189) (xy 195.205858 -15.834106)
			(xy 195.205384 -15.824139) (xy 195.19781 -15.8057) (xy 195.191126 -15.798292) (xy 195.166742 -15.773654)
			(xy 195.133976 -15.740634) (xy 195.115942 -15.733014) (xy 195.105782 -15.73276) (xy 195.080042 -15.731926)
			(xy 195.029127 -15.724188) (xy 194.979714 -15.709679) (xy 194.932698 -15.68866) (xy 194.888934 -15.661515)
			(xy 194.849214 -15.628734) (xy 194.831462 -15.610078) (xy 194.824096 -15.60195) (xy 194.80403 -15.593568)
			(xy 194.705478 -15.596108) (xy 194.68592 -15.60576) (xy 194.678808 -15.614142) (xy 194.660598 -15.635293)
			(xy 194.619052 -15.672563) (xy 194.572521 -15.703384) (xy 194.521998 -15.727099) (xy 194.468559 -15.743203)
			(xy 194.413344 -15.751352) (xy 194.385438 -15.75181) (xy 194.358183 -15.751349) (xy 194.304228 -15.743597)
			(xy 194.251925 -15.728244) (xy 194.20234 -15.705603) (xy 194.156482 -15.676136) (xy 194.115285 -15.640442)
			(xy 194.079587 -15.599249) (xy 194.050115 -15.553393) (xy 194.027469 -15.50381) (xy 194.012111 -15.451509)
			(xy 194.004353 -15.397555) (xy 194.004353 -15.343045) (xy 194.012111 -15.289091) (xy 194.027469 -15.23679)
			(xy 194.050115 -15.187207) (xy 194.079587 -15.141351) (xy 194.115285 -15.100158) (xy 194.156482 -15.064464)
			(xy 194.20234 -15.034997) (xy 194.251925 -15.012356) (xy 194.304228 -14.997003) (xy 194.358183 -14.989251)
			(xy 194.385438 -14.988794) (xy 194.411673 -14.989234) (xy 194.463648 -14.996436) (xy 194.514144 -15.010698)
			(xy 194.562206 -15.03175) (xy 194.606927 -15.059196) (xy 194.64746 -15.092516) (xy 194.6656 -15.111476)
			(xy 194.67322 -15.119604) (xy 194.693286 -15.127986) (xy 194.791838 -15.125446) (xy 194.811396 -15.115794)
			(xy 194.818508 -15.107412) (xy 194.83629 -15.086789) (xy 194.876702 -15.050294) (xy 194.921885 -15.019904)
			(xy 194.970925 -14.996236) (xy 195.022827 -14.979769) (xy 195.076542 -14.970836) (xy 195.10375 -14.969744)
			(xy 195.107306 -14.969744) (xy 195.116707 -14.968895) (xy 195.133924 -14.96119) (xy 195.140834 -14.954758)
			(xy 195.188586 -14.906752) (xy 195.190872 -14.904466) (xy 195.197716 -14.897067) (xy 195.205443 -14.878469)
			(xy 195.205858 -14.868398) (xy 195.205858 -13.73124) (xy 195.205423 -13.721176) (xy 195.197688 -13.702591)
			(xy 195.190872 -13.695172) (xy 194.885564 -13.389864) (xy 194.878167 -13.383016) (xy 194.859568 -13.375285)
			(xy 194.849496 -13.374878) (xy 190.142876 -13.374878) (xy 190.132807 -13.375305) (xy 190.114207 -13.383023)
			(xy 190.106808 -13.389864) (xy 189.39637 -14.100302) (xy 194.14312 -14.100302) (xy 194.147191 -14.04468)
			(xy 194.159317 -13.990243) (xy 194.17924 -13.938152) (xy 194.206536 -13.889517) (xy 194.240622 -13.845374)
			(xy 194.280771 -13.806665) (xy 194.326129 -13.774214) (xy 194.375729 -13.748713) (xy 194.428513 -13.730706)
			(xy 194.483356 -13.720576) (xy 194.53909 -13.718539) (xy 194.594527 -13.724639) (xy 194.648484 -13.738745)
			(xy 194.699813 -13.760557) (xy 194.747419 -13.789611) (xy 194.790287 -13.825286) (xy 194.827504 -13.866823)
			(xy 194.858277 -13.913336) (xy 194.881949 -13.963833) (xy 194.898017 -14.01724) (xy 194.906137 -14.072416)
			(xy 194.906646 -14.100302) (xy 194.906137 -14.128188) (xy 194.898017 -14.183364) (xy 194.881949 -14.236771)
			(xy 194.858277 -14.287268) (xy 194.827504 -14.333781) (xy 194.790287 -14.375318) (xy 194.747419 -14.410993)
			(xy 194.699813 -14.440047) (xy 194.648484 -14.461859) (xy 194.594527 -14.475965) (xy 194.53909 -14.482065)
			(xy 194.483356 -14.480028) (xy 194.428513 -14.469898) (xy 194.375729 -14.451891) (xy 194.326129 -14.42639)
			(xy 194.280771 -14.393939) (xy 194.240622 -14.35523) (xy 194.206536 -14.311087) (xy 194.17924 -14.262452)
			(xy 194.159317 -14.210361) (xy 194.147191 -14.155924) (xy 194.14312 -14.100302) (xy 189.39637 -14.100302)
			(xy 188.800994 -14.695678) (xy 188.795826 -14.700548) (xy 188.783457 -14.707513) (xy 188.77661 -14.709394)
			(xy 188.76745 -14.711895) (xy 188.751776 -14.722589) (xy 188.74613 -14.730222) (xy 188.704982 -14.790674)
			(xy 188.700664 -14.797278) (xy 188.698378 -14.804644) (xy 188.697323 -14.808301) (xy 188.696173 -14.815825)
			(xy 188.696092 -14.81963) (xy 188.696092 -14.832584) (xy 188.69914 -14.84757) (xy 188.700156 -14.853158)
			(xy 188.701934 -14.857476) (xy 188.726548 -14.920464) (xy 188.768716 -15.04897) (xy 188.802667 -15.179888)
			(xy 188.828263 -15.312692) (xy 188.845403 -15.44685) (xy 188.854017 -15.581824) (xy 188.854588 -15.649448)
			(xy 188.854588 -15.649956) (xy 188.854118 -15.713217) (xy 188.84662 -15.839517) (xy 188.831654 -15.965151)
			(xy 188.809271 -16.089677) (xy 188.779552 -16.212659) (xy 188.7426 -16.333665) (xy 188.698545 -16.452269)
			(xy 188.647542 -16.568056) (xy 188.589769 -16.680618) (xy 188.52543 -16.78956) (xy 188.454751 -16.894499)
			(xy 188.37798 -16.995068) (xy 188.295386 -17.090912) (xy 188.20726 -17.181695) (xy 188.160914 -17.224756)
			(xy 188.111886 -17.269228) (xy 188.009147 -17.352712) (xy 187.90143 -17.429666) (xy 187.789149 -17.499793)
			(xy 187.672736 -17.562824) (xy 187.552639 -17.618516) (xy 187.429321 -17.666655) (xy 187.303254 -17.707055)
			(xy 187.174926 -17.739562) (xy 187.044829 -17.764049) (xy 186.913464 -17.780423) (xy 186.781337 -17.788622)
			(xy 186.715146 -17.789144) (xy 186.650673 -17.788668) (xy 186.521963 -17.780885) (xy 186.393957 -17.765345)
			(xy 186.267123 -17.742105) (xy 186.141924 -17.711249) (xy 186.018816 -17.67289) (xy 185.898249 -17.627167)
			(xy 185.780662 -17.574249) (xy 185.666485 -17.514327) (xy 185.556135 -17.447621) (xy 185.450013 -17.374373)
			(xy 185.348508 -17.294852) (xy 185.251989 -17.209347) (xy 185.160809 -17.118171) (xy 185.0753 -17.021655)
			(xy 184.995775 -16.920153) (xy 184.922524 -16.814034) (xy 184.855813 -16.703686) (xy 184.795887 -16.589512)
			(xy 184.742964 -16.471927) (xy 184.697237 -16.351362) (xy 184.658873 -16.228255) (xy 184.628012 -16.103057)
			(xy 184.604767 -15.976224) (xy 184.589222 -15.848219) (xy 184.581434 -15.719509) (xy 184.581038 -15.655036)
			(xy 184.581596 -15.586296) (xy 184.590466 -15.449103) (xy 184.608144 -15.312764) (xy 184.634559 -15.177846)
			(xy 184.6696 -15.044906) (xy 184.713123 -14.914497) (xy 184.738518 -14.850618) (xy 184.742678 -14.838791)
			(xy 184.74013 -14.813881) (xy 184.733692 -14.80312) (xy 184.686448 -14.733016) (xy 184.678914 -14.723007)
			(xy 184.656798 -14.711305) (xy 184.644284 -14.710664) (xy 182.830216 -14.710664) (xy 182.820154 -14.711104)
			(xy 182.801578 -14.718847) (xy 182.794148 -14.72565) (xy 182.787036 -14.732762) (xy 182.754016 -14.79804)
			(xy 182.751533 -14.803426) (xy 182.748838 -14.814972) (xy 182.748682 -14.8209) (xy 182.748682 -14.844014)
			(xy 182.748829 -14.849883) (xy 182.751519 -14.861307) (xy 182.754016 -14.86662) (xy 182.756556 -14.8717)
			(xy 182.758842 -14.874748) (xy 182.782533 -14.908866) (xy 182.824501 -14.980552) (xy 182.859985 -15.05566)
			(xy 182.888709 -15.133604) (xy 182.91045 -15.213776) (xy 182.925037 -15.295553) (xy 182.932358 -15.378298)
			(xy 182.932832 -15.419832) (xy 182.932832 -15.420086) (xy 182.932255 -15.466656) (xy 182.923028 -15.559339)
			(xy 182.904682 -15.650655) (xy 182.877399 -15.739711) (xy 182.841444 -15.825632) (xy 182.819802 -15.866872)
			(xy 182.813706 -15.878302) (xy 182.813706 -15.903702) (xy 182.861712 -15.992602) (xy 182.883048 -16.006572)
			(xy 182.896002 -16.007588) (xy 182.939515 -16.011744) (xy 183.025602 -16.026925) (xy 183.109966 -16.049822)
			(xy 183.191915 -16.080249) (xy 183.27078 -16.117956) (xy 183.345915 -16.162636) (xy 183.416705 -16.213922)
			(xy 183.482572 -16.271394) (xy 183.542976 -16.334584) (xy 183.597422 -16.402973) (xy 183.645467 -16.476001)
			(xy 183.686716 -16.553073) (xy 183.720832 -16.633556) (xy 183.747536 -16.716793) (xy 183.76661 -16.802103)
			(xy 183.777897 -16.888787) (xy 183.781305 -16.976136) (xy 183.776806 -17.063436) (xy 183.764437 -17.149972)
			(xy 183.7443 -17.235037) (xy 183.716558 -17.317934) (xy 183.681439 -17.397985) (xy 183.63923 -17.474535)
			(xy 183.590277 -17.546958) (xy 183.563006 -17.581118) (xy 183.562752 -17.581372) (xy 183.534398 -17.615794)
			(xy 183.472323 -17.679832) (xy 183.404609 -17.737875) (xy 183.331833 -17.78943) (xy 183.254615 -17.834057)
			(xy 183.173613 -17.871377) (xy 183.089515 -17.901071) (xy 183.003038 -17.922887) (xy 182.914918 -17.93664)
			(xy 182.825906 -17.942211) (xy 182.736759 -17.939554) (xy 182.648237 -17.92869) (xy 182.561093 -17.909714)
			(xy 182.476069 -17.882786) (xy 182.393889 -17.848135) (xy 182.315253 -17.806057) (xy 182.24083 -17.756909)
			(xy 182.171255 -17.701111) (xy 182.107118 -17.639137) (xy 182.048968 -17.571516) (xy 181.997298 -17.498822)
			(xy 181.952548 -17.421675) (xy 181.9151 -17.340731) (xy 181.885273 -17.256681) (xy 181.863319 -17.170238)
			(xy 181.849428 -17.082141) (xy 181.843715 -16.993137) (xy 181.846231 -16.903986) (xy 181.856954 -16.815447)
			(xy 181.875793 -16.728273) (xy 181.902586 -16.643207) (xy 181.937107 -16.560972) (xy 181.957726 -16.52143)
			(xy 181.959758 -16.51762) (xy 181.960012 -16.516858) (xy 181.96179 -16.513302) (xy 181.964256 -16.507977)
			(xy 181.966959 -16.496561) (xy 181.967124 -16.490696) (xy 181.967124 -16.475964) (xy 181.925468 -16.407384)
			(xy 181.92623 -16.40332) (xy 181.911244 -16.384524) (xy 181.906133 -16.378528) (xy 181.893067 -16.369738)
			(xy 181.88559 -16.367252) (xy 181.878478 -16.36522) (xy 180.13299 -16.36522) (xy 180.089552 -16.364733)
			(xy 180.003047 -16.356716) (xy 179.91765 -16.340751) (xy 179.834091 -16.316975) (xy 179.753082 -16.285591)
			(xy 179.675315 -16.246866) (xy 179.601452 -16.20113) (xy 179.532125 -16.148774) (xy 179.467924 -16.090245)
			(xy 179.409398 -16.026041) (xy 179.357045 -15.956711) (xy 179.311313 -15.882847) (xy 179.272591 -15.805077)
			(xy 179.241211 -15.724067) (xy 179.217439 -15.640507) (xy 179.201478 -15.55511) (xy 179.193465 -15.468604)
			(xy 179.192936 -15.425166) (xy 179.192936 -15.424658) (xy 179.193585 -15.3783) (xy 179.20289 -15.28605)
			(xy 179.22123 -15.195163) (xy 179.248425 -15.106523) (xy 179.284213 -15.020989) (xy 179.328244 -14.939393)
			(xy 179.353718 -14.900656) (xy 179.353972 -14.900402) (xy 179.362608 -14.887448) (xy 179.36337 -14.886178)
			(xy 179.369974 -14.877034) (xy 179.375803 -14.868013) (xy 179.379999 -14.846967) (xy 179.378102 -14.836394)
			(xy 179.372514 -14.811756) (xy 179.370482 -14.802358) (xy 179.365148 -14.794484) (xy 179.360576 -14.786102)
			(xy 179.359814 -14.784324) (xy 179.336192 -14.73835) (xy 179.33099 -14.729284) (xy 179.314854 -14.716037)
			(xy 179.30495 -14.712696) (xy 179.297838 -14.710664) (xy 169.969688 -14.710664) (xy 169.95962 -14.711091)
			(xy 169.941025 -14.718816) (xy 169.93362 -14.72565) (xy 169.73931 -14.91996) (xy 169.732468 -14.927476)
			(xy 169.724879 -14.94631) (xy 169.725229 -14.966614) (xy 169.728896 -14.976094) (xy 169.728896 -14.976348)
			(xy 169.767504 -15.062962) (xy 169.771854 -15.071724) (xy 169.785866 -15.085348) (xy 169.803962 -15.092731)
			(xy 169.813732 -15.093188) (xy 169.818304 -15.093188) (xy 169.836338 -15.09268) (xy 169.837354 -15.09268)
			(xy 169.86458 -15.093204) (xy 169.918468 -15.101024) (xy 169.970697 -15.116427) (xy 170.020205 -15.139099)
			(xy 170.065987 -15.168581) (xy 170.107112 -15.204272) (xy 170.142745 -15.245447) (xy 170.172161 -15.291271)
			(xy 170.194763 -15.340811) (xy 170.210092 -15.393062) (xy 170.217836 -15.446962) (xy 170.218354 -15.474188)
			(xy 170.217869 -15.501441) (xy 170.210114 -15.555392) (xy 170.194761 -15.607691) (xy 170.172121 -15.657273)
			(xy 170.142656 -15.703128) (xy 170.106965 -15.744324) (xy 170.065775 -15.780021) (xy 170.019924 -15.809493)
			(xy 169.970346 -15.83214) (xy 169.918049 -15.847502) (xy 169.864099 -15.855265) (xy 169.836846 -15.855696)
			(xy 169.806855 -15.855145) (xy 169.747612 -15.845759) (xy 169.690574 -15.827197) (xy 169.663618 -15.81404)
			(xy 169.65168 -15.807944) (xy 169.625518 -15.80896) (xy 169.540174 -15.861538) (xy 169.533008 -15.866368)
			(xy 169.52216 -15.879808) (xy 169.516379 -15.896083) (xy 169.516044 -15.904718) (xy 169.516044 -18.44421)
			(xy 190.3763 -18.44421) (xy 190.380371 -18.388588) (xy 190.392497 -18.334151) (xy 190.41242 -18.28206)
			(xy 190.439716 -18.233425) (xy 190.473802 -18.189282) (xy 190.513951 -18.150573) (xy 190.559309 -18.118122)
			(xy 190.608909 -18.092621) (xy 190.661693 -18.074614) (xy 190.716536 -18.064484) (xy 190.77227 -18.062447)
			(xy 190.827707 -18.068547) (xy 190.881664 -18.082653) (xy 190.932993 -18.104465) (xy 190.980599 -18.133519)
			(xy 191.023467 -18.169194) (xy 191.060684 -18.210731) (xy 191.091457 -18.257244) (xy 191.115129 -18.307741)
			(xy 191.131197 -18.361148) (xy 191.139317 -18.416324) (xy 191.139826 -18.44421) (xy 191.139317 -18.472096)
			(xy 191.131197 -18.527272) (xy 191.115129 -18.580679) (xy 191.091457 -18.631176) (xy 191.060684 -18.677689)
			(xy 191.023467 -18.719226) (xy 190.980599 -18.754901) (xy 190.932993 -18.783955) (xy 190.881664 -18.805767)
			(xy 190.827707 -18.819873) (xy 190.77227 -18.825973) (xy 190.716536 -18.823936) (xy 190.661693 -18.813806)
			(xy 190.608909 -18.795799) (xy 190.559309 -18.770298) (xy 190.513951 -18.737847) (xy 190.473802 -18.699138)
			(xy 190.439716 -18.654995) (xy 190.41242 -18.60636) (xy 190.392497 -18.554269) (xy 190.380371 -18.499832)
			(xy 190.3763 -18.44421) (xy 169.516044 -18.44421) (xy 169.516044 -20.72513) (xy 173.28059 -20.72513)
			(xy 173.28456 -20.594996) (xy 173.296456 -20.465346) (xy 173.316235 -20.336663) (xy 173.343821 -20.209424)
			(xy 173.379114 -20.084105) (xy 173.42198 -19.961169) (xy 173.472262 -19.841076) (xy 173.529771 -19.724272)
			(xy 173.594295 -19.61119) (xy 173.665592 -19.502253) (xy 173.743397 -19.397865) (xy 173.827422 -19.298414)
			(xy 173.917354 -19.204271) (xy 174.012858 -19.115786) (xy 174.113578 -19.033287) (xy 174.21914 -18.957082)
			(xy 174.329152 -18.887455) (xy 174.443204 -18.824664) (xy 174.560872 -18.768942) (xy 174.681718 -18.720498)
			(xy 174.805293 -18.679511) (xy 174.931136 -18.646134) (xy 175.058781 -18.620491) (xy 175.187751 -18.602677)
			(xy 175.317567 -18.592759) (xy 175.447746 -18.590774) (xy 175.577805 -18.596728) (xy 175.707258 -18.610601)
			(xy 175.835625 -18.632339) (xy 175.962428 -18.661863) (xy 176.087195 -18.699062) (xy 176.209462 -18.743798)
			(xy 176.328775 -18.795906) (xy 176.444688 -18.855189) (xy 176.556773 -18.92143) (xy 176.66461 -18.99438)
			(xy 176.767799 -19.073768) (xy 176.865957 -19.1593) (xy 176.958718 -19.250657) (xy 177.045737 -19.347499)
			(xy 177.12669 -19.449466) (xy 177.201276 -19.556178) (xy 177.269217 -19.667239) (xy 177.330262 -19.782235)
			(xy 177.384183 -19.900739) (xy 177.430778 -20.02231) (xy 177.469876 -20.146495) (xy 177.50133 -20.272833)
			(xy 177.525024 -20.400854) (xy 177.540868 -20.53008) (xy 177.548806 -20.660033) (xy 177.549302 -20.72513)
			(xy 177.548806 -20.790227) (xy 177.540868 -20.92018) (xy 177.525024 -21.049406) (xy 177.50133 -21.177427)
			(xy 177.469876 -21.303765) (xy 177.430778 -21.42795) (xy 177.384183 -21.549521) (xy 177.330262 -21.668025)
			(xy 177.292938 -21.738336) (xy 179.516786 -21.738336) (xy 179.517275 -21.709596) (xy 179.525906 -21.652767)
			(xy 179.542965 -21.597876) (xy 179.568064 -21.546165) (xy 179.600636 -21.498804) (xy 179.61991 -21.477478)
			(xy 179.626514 -21.470366) (xy 179.633626 -21.45284) (xy 179.633626 -21.363432) (xy 179.626514 -21.345906)
			(xy 179.61991 -21.338794) (xy 179.600675 -21.317436) (xy 179.56811 -21.270078) (xy 179.543018 -21.218372)
			(xy 179.525966 -21.163486) (xy 179.51734 -21.106663) (xy 179.517336 -21.049189) (xy 179.525954 -20.992365)
			(xy 179.542998 -20.937477) (xy 179.568084 -20.885767) (xy 179.600643 -20.838405) (xy 179.61991 -20.817078)
			(xy 179.626514 -20.809966) (xy 179.633626 -20.79244) (xy 179.633626 -20.703032) (xy 179.626514 -20.685506)
			(xy 179.61991 -20.678394) (xy 179.600675 -20.657036) (xy 179.56811 -20.609678) (xy 179.543018 -20.557972)
			(xy 179.525966 -20.503086) (xy 179.51734 -20.446263) (xy 179.517336 -20.388789) (xy 179.525954 -20.331965)
			(xy 179.542998 -20.277077) (xy 179.568084 -20.225367) (xy 179.600643 -20.178005) (xy 179.61991 -20.156678)
			(xy 179.626514 -20.149566) (xy 179.633626 -20.13204) (xy 179.633626 -20.042632) (xy 179.626514 -20.025106)
			(xy 179.61991 -20.017994) (xy 179.600675 -19.996636) (xy 179.56811 -19.949278) (xy 179.543018 -19.897572)
			(xy 179.525966 -19.842686) (xy 179.51734 -19.785863) (xy 179.517336 -19.728389) (xy 179.525954 -19.671565)
			(xy 179.542998 -19.616677) (xy 179.568084 -19.564967) (xy 179.600643 -19.517605) (xy 179.61991 -19.496278)
			(xy 179.626514 -19.489166) (xy 179.633626 -19.47164) (xy 179.633626 -19.382232) (xy 179.626514 -19.364706)
			(xy 179.61991 -19.357594) (xy 179.600652 -19.336256) (xy 179.568085 -19.288897) (xy 179.54299 -19.237188)
			(xy 179.525937 -19.182299) (xy 179.51731 -19.125474) (xy 179.516786 -19.096736) (xy 179.517272 -19.069485)
			(xy 179.525028 -19.015537) (xy 179.540383 -18.963242) (xy 179.563025 -18.913665) (xy 179.592491 -18.867815)
			(xy 179.628182 -18.826624) (xy 179.669373 -18.790933) (xy 179.715223 -18.761467) (xy 179.7648 -18.738825)
			(xy 179.817095 -18.72347) (xy 179.871043 -18.715714) (xy 179.925545 -18.715714) (xy 179.979493 -18.72347)
			(xy 180.031788 -18.738825) (xy 180.081365 -18.761467) (xy 180.127215 -18.790933) (xy 180.168406 -18.826624)
			(xy 180.204097 -18.867815) (xy 180.233563 -18.913665) (xy 180.256205 -18.963242) (xy 180.27156 -19.015537)
			(xy 180.279316 -19.069485) (xy 180.279802 -19.096736) (xy 180.2793 -19.125476) (xy 180.270672 -19.182304)
			(xy 180.253617 -19.237195) (xy 180.22852 -19.288906) (xy 180.195951 -19.336268) (xy 180.176678 -19.357594)
			(xy 180.170074 -19.364706) (xy 180.162962 -19.382232) (xy 180.162962 -19.47164) (xy 180.170074 -19.489166)
			(xy 180.176678 -19.496278) (xy 180.195984 -19.517574) (xy 180.228548 -19.564942) (xy 180.253638 -19.616659)
			(xy 180.270685 -19.671554) (xy 180.279304 -19.728386) (xy 180.2793 -19.785867) (xy 180.270673 -19.842697)
			(xy 180.253618 -19.89759) (xy 180.228522 -19.949304) (xy 180.195951 -19.996667) (xy 180.176678 -20.017994)
			(xy 180.170074 -20.025106) (xy 180.162962 -20.042632) (xy 180.162962 -20.13204) (xy 180.170074 -20.149566)
			(xy 180.176678 -20.156678) (xy 180.195984 -20.177974) (xy 180.228548 -20.225342) (xy 180.253638 -20.277059)
			(xy 180.270685 -20.331954) (xy 180.279304 -20.388786) (xy 180.2793 -20.446267) (xy 180.270673 -20.503097)
			(xy 180.253618 -20.55799) (xy 180.228522 -20.609704) (xy 180.195951 -20.657067) (xy 180.176678 -20.678394)
			(xy 180.170074 -20.685506) (xy 180.162962 -20.703032) (xy 180.162962 -20.79244) (xy 180.170074 -20.809966)
			(xy 180.176678 -20.817078) (xy 180.195984 -20.838374) (xy 180.228548 -20.885742) (xy 180.253638 -20.937459)
			(xy 180.270685 -20.992354) (xy 180.279304 -21.049186) (xy 180.2793 -21.106667) (xy 180.270673 -21.163497)
			(xy 180.253618 -21.21839) (xy 180.228522 -21.270104) (xy 180.195951 -21.317467) (xy 180.176678 -21.338794)
			(xy 180.170074 -21.345906) (xy 180.162962 -21.363432) (xy 180.162962 -21.45284) (xy 180.170074 -21.470366)
			(xy 180.176678 -21.477478) (xy 180.195968 -21.498788) (xy 180.228531 -21.546155) (xy 180.25362 -21.597871)
			(xy 180.266398 -21.639022) (xy 184.173876 -21.639022) (xy 184.17442 -21.610284) (xy 184.183038 -21.553458)
			(xy 184.200084 -21.498567) (xy 184.225171 -21.446855) (xy 184.257732 -21.399492) (xy 184.277 -21.378164)
			(xy 184.283604 -21.371052) (xy 184.290716 -21.353526) (xy 184.290716 -21.264118) (xy 184.283604 -21.246592)
			(xy 184.277 -21.23948) (xy 184.257752 -21.218134) (xy 184.225188 -21.170774) (xy 184.200097 -21.119065)
			(xy 184.183046 -21.064178) (xy 184.174422 -21.007353) (xy 184.17442 -20.949879) (xy 184.183039 -20.893054)
			(xy 184.200085 -20.838165) (xy 184.225172 -20.786454) (xy 184.257732 -20.739091) (xy 184.277 -20.717764)
			(xy 184.283604 -20.710652) (xy 184.290716 -20.693126) (xy 184.290716 -20.603718) (xy 184.283604 -20.586192)
			(xy 184.277 -20.57908) (xy 184.257752 -20.557734) (xy 184.225188 -20.510374) (xy 184.200097 -20.458665)
			(xy 184.183046 -20.403778) (xy 184.174422 -20.346953) (xy 184.17442 -20.289479) (xy 184.183039 -20.232654)
			(xy 184.200085 -20.177765) (xy 184.225172 -20.126054) (xy 184.257732 -20.078691) (xy 184.277 -20.057364)
			(xy 184.283604 -20.050252) (xy 184.290716 -20.032726) (xy 184.290716 -19.943318) (xy 184.283604 -19.925792)
			(xy 184.277 -19.91868) (xy 184.257752 -19.897334) (xy 184.225188 -19.849974) (xy 184.200097 -19.798265)
			(xy 184.183046 -19.743378) (xy 184.174422 -19.686553) (xy 184.17442 -19.629079) (xy 184.183039 -19.572254)
			(xy 184.200085 -19.517365) (xy 184.225172 -19.465654) (xy 184.257732 -19.418291) (xy 184.277 -19.396964)
			(xy 184.283604 -19.389852) (xy 184.290716 -19.372326) (xy 184.290716 -19.282918) (xy 184.283604 -19.265392)
			(xy 184.277 -19.25828) (xy 184.25775 -19.236935) (xy 184.225179 -19.189579) (xy 184.200081 -19.137872)
			(xy 184.183026 -19.082985) (xy 184.174399 -19.02616) (xy 184.173876 -18.997422) (xy 184.174362 -18.970171)
			(xy 184.182118 -18.916223) (xy 184.197473 -18.863928) (xy 184.220115 -18.814351) (xy 184.249581 -18.768501)
			(xy 184.285272 -18.72731) (xy 184.326463 -18.691619) (xy 184.372313 -18.662153) (xy 184.42189 -18.639511)
			(xy 184.474185 -18.624156) (xy 184.528133 -18.6164) (xy 184.582635 -18.6164) (xy 184.636583 -18.624156)
			(xy 184.688878 -18.639511) (xy 184.738455 -18.662153) (xy 184.784305 -18.691619) (xy 184.825496 -18.72731)
			(xy 184.861187 -18.768501) (xy 184.890653 -18.814351) (xy 184.913295 -18.863928) (xy 184.92865 -18.916223)
			(xy 184.936406 -18.970171) (xy 184.936892 -18.997422) (xy 184.936384 -19.026162) (xy 184.927758 -19.08299)
			(xy 184.910704 -19.137881) (xy 184.885609 -19.189592) (xy 184.85304 -19.236954) (xy 184.833768 -19.25828)
			(xy 184.827164 -19.265392) (xy 184.820052 -19.282918) (xy 184.820052 -19.366857) (xy 189.679215 -19.366857)
			(xy 189.679215 -19.312343) (xy 189.686973 -19.258384) (xy 189.702332 -19.206079) (xy 189.724979 -19.156492)
			(xy 189.754453 -19.110632) (xy 189.790153 -19.069435) (xy 189.831353 -19.033737) (xy 189.877214 -19.004267)
			(xy 189.926803 -18.981623) (xy 189.97911 -18.966268) (xy 190.033069 -18.958513) (xy 190.060326 -18.958052)
			(xy 190.087097 -18.958508) (xy 190.140113 -18.966009) (xy 190.191559 -18.980846) (xy 190.240427 -19.002729)
			(xy 190.285756 -19.031227) (xy 190.326657 -19.065781) (xy 190.362327 -19.105712) (xy 190.377572 -19.127724)
			(xy 190.383668 -19.136614) (xy 190.401194 -19.148044) (xy 190.495682 -19.163284) (xy 190.516002 -19.158204)
			(xy 190.524384 -19.1516) (xy 190.544539 -19.136486) (xy 190.58806 -19.111112) (xy 190.634546 -19.091694)
			(xy 190.683185 -19.078573) (xy 190.733129 -19.071975) (xy 190.758318 -19.07159) (xy 190.785568 -19.072081)
			(xy 190.839514 -19.07984) (xy 190.891806 -19.095196) (xy 190.941381 -19.117838) (xy 190.987229 -19.147305)
			(xy 191.028417 -19.182996) (xy 191.064106 -19.224186) (xy 191.09357 -19.270035) (xy 191.11621 -19.319611)
			(xy 191.131564 -19.371904) (xy 191.13932 -19.42585) (xy 191.13932 -19.48035) (xy 191.131564 -19.534296)
			(xy 191.11621 -19.586589) (xy 191.09357 -19.636165) (xy 191.064106 -19.682014) (xy 191.028417 -19.723204)
			(xy 190.987229 -19.758895) (xy 190.941381 -19.788362) (xy 190.891806 -19.811004) (xy 190.839514 -19.82636)
			(xy 190.785568 -19.834119) (xy 190.758318 -19.834606) (xy 190.731547 -19.834136) (xy 190.678531 -19.826639)
			(xy 190.627085 -19.811806) (xy 190.578216 -19.789926) (xy 190.532887 -19.76143) (xy 190.491986 -19.726877)
			(xy 190.456316 -19.686946) (xy 190.441072 -19.664934) (xy 190.434976 -19.656044) (xy 190.41745 -19.644614)
			(xy 190.322962 -19.629374) (xy 190.302642 -19.634454) (xy 190.29426 -19.641058) (xy 190.274119 -19.656192)
			(xy 190.230595 -19.681564) (xy 190.184106 -19.700978) (xy 190.135463 -19.714095) (xy 190.085516 -19.720686)
			(xy 190.060326 -19.721068) (xy 190.033069 -19.720687) (xy 189.97911 -19.712932) (xy 189.926803 -19.697577)
			(xy 189.877214 -19.674933) (xy 189.831353 -19.645463) (xy 189.790153 -19.609765) (xy 189.754453 -19.568568)
			(xy 189.724979 -19.522708) (xy 189.702332 -19.473121) (xy 189.686973 -19.420816) (xy 189.679215 -19.366857)
			(xy 184.820052 -19.366857) (xy 184.820052 -19.372326) (xy 184.827164 -19.389852) (xy 184.833768 -19.396964)
			(xy 184.853061 -19.418272) (xy 184.885626 -19.465637) (xy 184.910717 -19.517352) (xy 184.927766 -19.572246)
			(xy 184.936387 -19.629076) (xy 184.936384 -19.686556) (xy 184.927759 -19.743386) (xy 184.910705 -19.798278)
			(xy 184.88561 -19.849991) (xy 184.853041 -19.897353) (xy 184.833768 -19.91868) (xy 184.827164 -19.925792)
			(xy 184.820052 -19.943318) (xy 184.820052 -20.032726) (xy 184.827164 -20.050252) (xy 184.833768 -20.057364)
			(xy 184.853061 -20.078672) (xy 184.885626 -20.126037) (xy 184.910717 -20.177752) (xy 184.927766 -20.232646)
			(xy 184.936387 -20.289476) (xy 184.936384 -20.346956) (xy 184.935078 -20.35556) (xy 189.678308 -20.35556)
			(xy 189.682379 -20.299938) (xy 189.694505 -20.245501) (xy 189.714428 -20.19341) (xy 189.741724 -20.144775)
			(xy 189.77581 -20.100632) (xy 189.815959 -20.061923) (xy 189.861317 -20.029472) (xy 189.910917 -20.003971)
			(xy 189.963701 -19.985964) (xy 190.018544 -19.975834) (xy 190.074278 -19.973797) (xy 190.129715 -19.979897)
			(xy 190.183672 -19.994003) (xy 190.235001 -20.015815) (xy 190.282607 -20.044869) (xy 190.325475 -20.080544)
			(xy 190.362692 -20.122081) (xy 190.393465 -20.168594) (xy 190.417137 -20.219091) (xy 190.433205 -20.272498)
			(xy 190.441325 -20.327674) (xy 190.441834 -20.35556) (xy 190.441325 -20.383446) (xy 190.433205 -20.438622)
			(xy 190.417137 -20.492029) (xy 190.393465 -20.542526) (xy 190.362692 -20.589039) (xy 190.325475 -20.630576)
			(xy 190.282607 -20.666251) (xy 190.235001 -20.695305) (xy 190.183672 -20.717117) (xy 190.129715 -20.731223)
			(xy 190.074278 -20.737323) (xy 190.018544 -20.735286) (xy 189.963701 -20.725156) (xy 189.910917 -20.707149)
			(xy 189.861317 -20.681648) (xy 189.815959 -20.649197) (xy 189.77581 -20.610488) (xy 189.741724 -20.566345)
			(xy 189.714428 -20.51771) (xy 189.694505 -20.465619) (xy 189.682379 -20.411182) (xy 189.678308 -20.35556)
			(xy 184.935078 -20.35556) (xy 184.927759 -20.403786) (xy 184.910705 -20.458678) (xy 184.88561 -20.510391)
			(xy 184.853041 -20.557753) (xy 184.833768 -20.57908) (xy 184.827164 -20.586192) (xy 184.820052 -20.603718)
			(xy 184.820052 -20.693126) (xy 184.827164 -20.710652) (xy 184.833768 -20.717764) (xy 184.853061 -20.739072)
			(xy 184.885626 -20.786437) (xy 184.910717 -20.838152) (xy 184.927766 -20.893046) (xy 184.936387 -20.949876)
			(xy 184.936384 -21.007356) (xy 184.927759 -21.064186) (xy 184.910705 -21.119078) (xy 184.88561 -21.170791)
			(xy 184.853041 -21.218153) (xy 184.833768 -21.23948) (xy 184.827164 -21.246592) (xy 184.820052 -21.264118)
			(xy 184.820052 -21.353526) (xy 184.827164 -21.371052) (xy 184.827636 -21.37156) (xy 189.678308 -21.37156)
			(xy 189.682379 -21.315938) (xy 189.694505 -21.261501) (xy 189.714428 -21.20941) (xy 189.741724 -21.160775)
			(xy 189.77581 -21.116632) (xy 189.815959 -21.077923) (xy 189.861317 -21.045472) (xy 189.910917 -21.019971)
			(xy 189.963701 -21.001964) (xy 190.018544 -20.991834) (xy 190.074278 -20.989797) (xy 190.129715 -20.995897)
			(xy 190.183672 -21.010003) (xy 190.235001 -21.031815) (xy 190.282607 -21.060869) (xy 190.325475 -21.096544)
			(xy 190.362692 -21.138081) (xy 190.393465 -21.184594) (xy 190.417137 -21.235091) (xy 190.433205 -21.288498)
			(xy 190.441325 -21.343674) (xy 190.441834 -21.37156) (xy 190.441325 -21.399446) (xy 190.433205 -21.454622)
			(xy 190.417137 -21.508029) (xy 190.393465 -21.558526) (xy 190.362692 -21.605039) (xy 190.325475 -21.646576)
			(xy 190.282607 -21.682251) (xy 190.235001 -21.711305) (xy 190.183672 -21.733117) (xy 190.129715 -21.747223)
			(xy 190.074278 -21.753323) (xy 190.018544 -21.751286) (xy 189.963701 -21.741156) (xy 189.910917 -21.723149)
			(xy 189.861317 -21.697648) (xy 189.815959 -21.665197) (xy 189.77581 -21.626488) (xy 189.741724 -21.582345)
			(xy 189.714428 -21.53371) (xy 189.694505 -21.481619) (xy 189.682379 -21.427182) (xy 189.678308 -21.37156)
			(xy 184.827636 -21.37156) (xy 184.833768 -21.378164) (xy 184.85305 -21.399481) (xy 184.885615 -21.446846)
			(xy 184.910705 -21.49856) (xy 184.927753 -21.553453) (xy 184.936373 -21.610282) (xy 184.936892 -21.639022)
			(xy 184.936406 -21.666273) (xy 184.92865 -21.720221) (xy 184.913295 -21.772516) (xy 184.911853 -21.775674)
			(xy 194.035932 -21.775674) (xy 194.040003 -21.720052) (xy 194.052129 -21.665615) (xy 194.072052 -21.613524)
			(xy 194.099348 -21.564889) (xy 194.133434 -21.520746) (xy 194.173583 -21.482037) (xy 194.218941 -21.449586)
			(xy 194.268541 -21.424085) (xy 194.321325 -21.406078) (xy 194.376168 -21.395948) (xy 194.431902 -21.393911)
			(xy 194.487339 -21.400011) (xy 194.541296 -21.414117) (xy 194.592625 -21.435929) (xy 194.640231 -21.464983)
			(xy 194.683099 -21.500658) (xy 194.720316 -21.542195) (xy 194.751089 -21.588708) (xy 194.774761 -21.639205)
			(xy 194.790829 -21.692612) (xy 194.798949 -21.747788) (xy 194.799458 -21.775674) (xy 194.798949 -21.80356)
			(xy 194.790829 -21.858736) (xy 194.774761 -21.912143) (xy 194.751089 -21.96264) (xy 194.720316 -22.009153)
			(xy 194.683099 -22.05069) (xy 194.640231 -22.086365) (xy 194.592625 -22.115419) (xy 194.541296 -22.137231)
			(xy 194.487339 -22.151337) (xy 194.431902 -22.157437) (xy 194.376168 -22.1554) (xy 194.321325 -22.14527)
			(xy 194.268541 -22.127263) (xy 194.218941 -22.101762) (xy 194.173583 -22.069311) (xy 194.133434 -22.030602)
			(xy 194.099348 -21.986459) (xy 194.072052 -21.937824) (xy 194.052129 -21.885733) (xy 194.040003 -21.831296)
			(xy 194.035932 -21.775674) (xy 184.911853 -21.775674) (xy 184.890653 -21.822093) (xy 184.861187 -21.867943)
			(xy 184.825496 -21.909134) (xy 184.784305 -21.944825) (xy 184.738455 -21.974291) (xy 184.688878 -21.996933)
			(xy 184.636583 -22.012288) (xy 184.582635 -22.020044) (xy 184.528133 -22.020044) (xy 184.474185 -22.012288)
			(xy 184.42189 -21.996933) (xy 184.372313 -21.974291) (xy 184.326463 -21.944825) (xy 184.285272 -21.909134)
			(xy 184.249581 -21.867943) (xy 184.220115 -21.822093) (xy 184.197473 -21.772516) (xy 184.182118 -21.720221)
			(xy 184.174362 -21.666273) (xy 184.173876 -21.639022) (xy 180.266398 -21.639022) (xy 180.270666 -21.652765)
			(xy 180.279284 -21.709596) (xy 180.279802 -21.738336) (xy 180.279316 -21.765587) (xy 180.27156 -21.819535)
			(xy 180.256205 -21.87183) (xy 180.233563 -21.921407) (xy 180.204097 -21.967257) (xy 180.168406 -22.008448)
			(xy 180.127215 -22.044139) (xy 180.081365 -22.073605) (xy 180.031788 -22.096247) (xy 179.979493 -22.111602)
			(xy 179.925545 -22.119358) (xy 179.871043 -22.119358) (xy 179.817095 -22.111602) (xy 179.7648 -22.096247)
			(xy 179.715223 -22.073605) (xy 179.669373 -22.044139) (xy 179.628182 -22.008448) (xy 179.592491 -21.967257)
			(xy 179.563025 -21.921407) (xy 179.540383 -21.87183) (xy 179.525028 -21.819535) (xy 179.517272 -21.765587)
			(xy 179.516786 -21.738336) (xy 177.292938 -21.738336) (xy 177.269217 -21.783021) (xy 177.201276 -21.894082)
			(xy 177.12669 -22.000794) (xy 177.045737 -22.102761) (xy 176.958718 -22.199603) (xy 176.865957 -22.29096)
			(xy 176.767799 -22.376492) (xy 176.66461 -22.45588) (xy 176.556773 -22.52883) (xy 176.444688 -22.595071)
			(xy 176.328775 -22.654354) (xy 176.209462 -22.706462) (xy 176.087195 -22.751198) (xy 175.962428 -22.788397)
			(xy 175.835625 -22.817921) (xy 175.707258 -22.839659) (xy 175.577805 -22.853532) (xy 175.447746 -22.859486)
			(xy 175.317567 -22.857501) (xy 175.187751 -22.847583) (xy 175.058781 -22.829769) (xy 174.931136 -22.804126)
			(xy 174.805293 -22.770749) (xy 174.681718 -22.729762) (xy 174.560872 -22.681318) (xy 174.443204 -22.625596)
			(xy 174.329152 -22.562805) (xy 174.21914 -22.493178) (xy 174.113578 -22.416973) (xy 174.012858 -22.334474)
			(xy 173.917354 -22.245989) (xy 173.827422 -22.151846) (xy 173.743397 -22.052395) (xy 173.665592 -21.948007)
			(xy 173.594295 -21.83907) (xy 173.529771 -21.725988) (xy 173.472262 -21.609184) (xy 173.42198 -21.489091)
			(xy 173.379114 -21.366155) (xy 173.343821 -21.240836) (xy 173.316235 -21.113597) (xy 173.296456 -20.984914)
			(xy 173.28456 -20.855264) (xy 173.28059 -20.72513) (xy 169.516044 -20.72513) (xy 169.516044 -21.494496)
			(xy 169.517568 -21.500592) (xy 169.519092 -21.507196) (xy 169.532046 -21.531326) (xy 169.538904 -21.540978)
			(xy 169.542968 -21.54555) (xy 169.547286 -21.548598) (xy 169.567959 -21.564397) (xy 169.605241 -21.60069)
			(xy 169.637246 -21.641712) (xy 169.663379 -21.686703) (xy 169.683154 -21.734829) (xy 169.696206 -21.785195)
			(xy 169.699686 -21.81098) (xy 169.70121 -21.824696) (xy 169.702126 -21.847048) (xy 170.172886 -21.847048)
			(xy 170.176957 -21.791426) (xy 170.189083 -21.736989) (xy 170.209006 -21.684898) (xy 170.236302 -21.636263)
			(xy 170.270388 -21.59212) (xy 170.310537 -21.553411) (xy 170.355895 -21.52096) (xy 170.405495 -21.495459)
			(xy 170.458279 -21.477452) (xy 170.513122 -21.467322) (xy 170.568856 -21.465285) (xy 170.624293 -21.471385)
			(xy 170.67825 -21.485491) (xy 170.729579 -21.507303) (xy 170.777185 -21.536357) (xy 170.820053 -21.572032)
			(xy 170.85727 -21.613569) (xy 170.888043 -21.660082) (xy 170.911715 -21.710579) (xy 170.927783 -21.763986)
			(xy 170.935903 -21.819162) (xy 170.936412 -21.847048) (xy 170.935903 -21.874934) (xy 170.927783 -21.93011)
			(xy 170.911715 -21.983517) (xy 170.888043 -22.034014) (xy 170.85727 -22.080527) (xy 170.820053 -22.122064)
			(xy 170.777185 -22.157739) (xy 170.729579 -22.186793) (xy 170.67825 -22.208605) (xy 170.624293 -22.222711)
			(xy 170.568856 -22.228811) (xy 170.513122 -22.226774) (xy 170.458279 -22.216644) (xy 170.405495 -22.198637)
			(xy 170.355895 -22.173136) (xy 170.310537 -22.140685) (xy 170.270388 -22.101976) (xy 170.236302 -22.057833)
			(xy 170.209006 -22.009198) (xy 170.189083 -21.957107) (xy 170.176957 -21.90267) (xy 170.172886 -21.847048)
			(xy 169.702126 -21.847048) (xy 169.70248 -21.855684) (xy 169.701937 -21.885117) (xy 169.692904 -21.943286)
			(xy 169.67505 -21.999378) (xy 169.648797 -22.052066) (xy 169.614768 -22.1001) (xy 169.57377 -22.142341)
			(xy 169.550588 -22.160484) (xy 169.54754 -22.162516) (xy 169.540428 -22.169628) (xy 169.535094 -22.174962)
			(xy 169.521886 -22.199346) (xy 169.51915 -22.204931) (xy 169.516186 -22.217005) (xy 169.516044 -22.223222)
			(xy 169.516044 -23.0251) (xy 179.462428 -23.0251) (xy 179.466499 -22.969478) (xy 179.478625 -22.915041)
			(xy 179.498548 -22.86295) (xy 179.525844 -22.814315) (xy 179.55993 -22.770172) (xy 179.600079 -22.731463)
			(xy 179.645437 -22.699012) (xy 179.695037 -22.673511) (xy 179.747821 -22.655504) (xy 179.802664 -22.645374)
			(xy 179.858398 -22.643337) (xy 179.913835 -22.649437) (xy 179.967792 -22.663543) (xy 180.019121 -22.685355)
			(xy 180.066727 -22.714409) (xy 180.109595 -22.750084) (xy 180.146812 -22.791621) (xy 180.177585 -22.838134)
			(xy 180.201257 -22.888631) (xy 180.217325 -22.942038) (xy 180.225445 -22.997214) (xy 180.225954 -23.0251)
			(xy 180.225445 -23.052986) (xy 180.217325 -23.108162) (xy 180.201257 -23.161569) (xy 180.177585 -23.212066)
			(xy 180.146812 -23.258579) (xy 180.109595 -23.300116) (xy 180.066727 -23.335791) (xy 180.019121 -23.364845)
			(xy 179.967792 -23.386657) (xy 179.913835 -23.400763) (xy 179.858398 -23.406863) (xy 179.802664 -23.404826)
			(xy 179.747821 -23.394696) (xy 179.695037 -23.376689) (xy 179.645437 -23.351188) (xy 179.600079 -23.318737)
			(xy 179.55993 -23.280028) (xy 179.525844 -23.235885) (xy 179.498548 -23.18725) (xy 179.478625 -23.135159)
			(xy 179.466499 -23.080722) (xy 179.462428 -23.0251) (xy 169.516044 -23.0251) (xy 169.516044 -23.49373)
			(xy 169.516505 -23.503607) (xy 169.523945 -23.521908) (xy 169.530522 -23.52929) (xy 169.55135 -23.550626)
			(xy 169.55459 -23.553807) (xy 169.562001 -23.559051) (xy 169.566082 -23.56104) (xy 169.57548 -23.565358)
			(xy 169.585132 -23.56612) (xy 169.613893 -23.568359) (xy 169.670306 -23.58041) (xy 169.724262 -23.600816)
			(xy 169.774532 -23.629111) (xy 169.819969 -23.664652) (xy 169.859538 -23.706628) (xy 169.892338 -23.754081)
			(xy 169.91762 -23.805932) (xy 169.934809 -23.860998) (xy 169.943513 -23.918023) (xy 169.944034 -23.946866)
			(xy 169.943601 -23.970996) (xy 170.172886 -23.970996) (xy 170.176957 -23.915374) (xy 170.189083 -23.860937)
			(xy 170.209006 -23.808846) (xy 170.236302 -23.760211) (xy 170.270388 -23.716068) (xy 170.310537 -23.677359)
			(xy 170.355895 -23.644908) (xy 170.405495 -23.619407) (xy 170.458279 -23.6014) (xy 170.513122 -23.59127)
			(xy 170.568856 -23.589233) (xy 170.624293 -23.595333) (xy 170.67825 -23.609439) (xy 170.681512 -23.610825)
			(xy 180.166023 -23.610825) (xy 180.166026 -23.556331) (xy 180.173784 -23.502391) (xy 180.18914 -23.450104)
			(xy 180.21178 -23.400535) (xy 180.241244 -23.354693) (xy 180.276933 -23.31351) (xy 180.318118 -23.277825)
			(xy 180.363963 -23.248365) (xy 180.413534 -23.225729) (xy 180.465822 -23.210377) (xy 180.519763 -23.202623)
			(xy 180.54701 -23.202138) (xy 180.571039 -23.202512) (xy 180.618717 -23.208552) (xy 180.665258 -23.220534)
			(xy 180.687726 -23.229062) (xy 180.700882 -23.233833) (xy 180.728708 -23.236736) (xy 180.756278 -23.231985)
			(xy 180.781526 -23.219935) (xy 180.802561 -23.20149) (xy 180.817805 -23.178031) (xy 180.826117 -23.151318)
			(xy 180.826872 -23.123351) (xy 180.82387 -23.109682) (xy 180.81842 -23.086699) (xy 180.812558 -23.039828)
			(xy 180.812186 -23.01621) (xy 180.812644 -22.988956) (xy 180.8204 -22.935003) (xy 180.835755 -22.882703)
			(xy 180.858398 -22.833121) (xy 180.887866 -22.787265) (xy 180.92356 -22.74607) (xy 180.964753 -22.710375)
			(xy 181.010608 -22.680905) (xy 181.060189 -22.658261) (xy 181.112489 -22.642903) (xy 181.166441 -22.635145)
			(xy 181.220949 -22.635145) (xy 181.274902 -22.642901) (xy 181.327202 -22.658257) (xy 181.376784 -22.6809)
			(xy 181.422639 -22.710369) (xy 181.463834 -22.746064) (xy 181.499529 -22.787258) (xy 181.528998 -22.833112)
			(xy 181.551641 -22.882694) (xy 181.566998 -22.934994) (xy 181.574755 -22.988947) (xy 181.574755 -23.043455)
			(xy 181.566998 -23.097407) (xy 181.551641 -23.149707) (xy 181.528997 -23.199289) (xy 181.499528 -23.245143)
			(xy 181.463833 -23.286337) (xy 181.422638 -23.322032) (xy 181.376783 -23.3515) (xy 181.327201 -23.374143)
			(xy 181.274901 -23.389499) (xy 181.220948 -23.397256) (xy 181.193694 -23.397718) (xy 181.169665 -23.397339)
			(xy 181.121987 -23.391301) (xy 181.075446 -23.379321) (xy 181.052978 -23.370794) (xy 181.039805 -23.366079)
			(xy 181.01199 -23.363178) (xy 180.984431 -23.367928) (xy 180.959191 -23.379971) (xy 180.938162 -23.398406)
			(xy 180.922919 -23.421853) (xy 180.914603 -23.448553) (xy 180.913838 -23.476509) (xy 180.916834 -23.490174)
			(xy 180.922295 -23.513155) (xy 180.92815 -23.560028) (xy 180.928518 -23.583646) (xy 180.928391 -23.589996)
			(xy 184.184542 -23.589996) (xy 184.188613 -23.534374) (xy 184.200739 -23.479937) (xy 184.220662 -23.427846)
			(xy 184.247958 -23.379211) (xy 184.282044 -23.335068) (xy 184.322193 -23.296359) (xy 184.367551 -23.263908)
			(xy 184.417151 -23.238407) (xy 184.469935 -23.2204) (xy 184.524778 -23.21027) (xy 184.580512 -23.208233)
			(xy 184.635949 -23.214333) (xy 184.689906 -23.228439) (xy 184.741235 -23.250251) (xy 184.788841 -23.279305)
			(xy 184.831709 -23.31498) (xy 184.868063 -23.355554) (xy 193.430652 -23.355554) (xy 193.431141 -23.328744)
			(xy 193.438648 -23.275651) (xy 193.45352 -23.224134) (xy 193.475465 -23.17521) (xy 193.504049 -23.129844)
			(xy 193.538708 -23.08893) (xy 193.578759 -23.053278) (xy 193.600832 -23.038054) (xy 193.612371 -23.029765)
			(xy 193.630769 -23.008134) (xy 193.642503 -22.982274) (xy 193.646665 -22.954184) (xy 193.642934 -22.926033)
			(xy 193.631599 -22.899996) (xy 193.613535 -22.878085) (xy 193.602102 -22.869652) (xy 193.58066 -22.854279)
			(xy 193.541746 -22.818656) (xy 193.508112 -22.778011) (xy 193.480399 -22.733119) (xy 193.459136 -22.684837)
			(xy 193.444728 -22.634085) (xy 193.437452 -22.581832) (xy 193.437002 -22.555454) (xy 193.437488 -22.528203)
			(xy 193.445244 -22.474255) (xy 193.460599 -22.42196) (xy 193.483241 -22.372383) (xy 193.512707 -22.326533)
			(xy 193.548398 -22.285342) (xy 193.589589 -22.249651) (xy 193.635439 -22.220185) (xy 193.685016 -22.197543)
			(xy 193.737311 -22.182188) (xy 193.791259 -22.174432) (xy 193.845761 -22.174432) (xy 193.899709 -22.182188)
			(xy 193.952004 -22.197543) (xy 194.001581 -22.220185) (xy 194.047431 -22.249651) (xy 194.088622 -22.285342)
			(xy 194.124313 -22.326533) (xy 194.153779 -22.372383) (xy 194.176421 -22.42196) (xy 194.191776 -22.474255)
			(xy 194.199532 -22.528203) (xy 194.200018 -22.555454) (xy 194.199548 -22.582265) (xy 194.19204 -22.635359)
			(xy 194.177165 -22.686877) (xy 194.155218 -22.735802) (xy 194.12663 -22.781168) (xy 194.091968 -22.82208)
			(xy 194.051913 -22.857731) (xy 194.029838 -22.872954) (xy 194.018285 -22.881229) (xy 193.999874 -22.902859)
			(xy 193.988133 -22.928723) (xy 193.983968 -22.956821) (xy 193.987704 -22.984979) (xy 193.999049 -23.011019)
			(xy 194.017127 -23.032928) (xy 194.028568 -23.041356) (xy 194.050029 -23.056702) (xy 194.088939 -23.092332)
			(xy 194.12257 -23.132983) (xy 194.15028 -23.177879) (xy 194.171539 -23.226165) (xy 194.185944 -23.27692)
			(xy 194.193219 -23.329175) (xy 194.193668 -23.355554) (xy 194.193182 -23.382805) (xy 194.185426 -23.436753)
			(xy 194.170071 -23.489048) (xy 194.147429 -23.538625) (xy 194.117963 -23.584475) (xy 194.082272 -23.625666)
			(xy 194.041081 -23.661357) (xy 193.995231 -23.690823) (xy 193.945654 -23.713465) (xy 193.893359 -23.72882)
			(xy 193.839411 -23.736576) (xy 193.784909 -23.736576) (xy 193.730961 -23.72882) (xy 193.678666 -23.713465)
			(xy 193.629089 -23.690823) (xy 193.583239 -23.661357) (xy 193.542048 -23.625666) (xy 193.506357 -23.584475)
			(xy 193.476891 -23.538625) (xy 193.454249 -23.489048) (xy 193.438894 -23.436753) (xy 193.431138 -23.382805)
			(xy 193.430652 -23.355554) (xy 184.868063 -23.355554) (xy 184.868926 -23.356517) (xy 184.899699 -23.40303)
			(xy 184.923371 -23.453527) (xy 184.939439 -23.506934) (xy 184.947559 -23.56211) (xy 184.948068 -23.589996)
			(xy 184.947559 -23.617882) (xy 184.939439 -23.673058) (xy 184.923371 -23.726465) (xy 184.899699 -23.776962)
			(xy 184.868926 -23.823475) (xy 184.831709 -23.865012) (xy 184.813317 -23.880318) (xy 185.34075 -23.880318)
			(xy 185.344821 -23.824696) (xy 185.356947 -23.770259) (xy 185.37687 -23.718168) (xy 185.404166 -23.669533)
			(xy 185.438252 -23.62539) (xy 185.478401 -23.586681) (xy 185.523759 -23.55423) (xy 185.573359 -23.528729)
			(xy 185.626143 -23.510722) (xy 185.680986 -23.500592) (xy 185.73672 -23.498555) (xy 185.792157 -23.504655)
			(xy 185.846114 -23.518761) (xy 185.897443 -23.540573) (xy 185.945049 -23.569627) (xy 185.987917 -23.605302)
			(xy 186.025134 -23.646839) (xy 186.055907 -23.693352) (xy 186.079579 -23.743849) (xy 186.095647 -23.797256)
			(xy 186.103767 -23.852432) (xy 186.104276 -23.880318) (xy 186.35675 -23.880318) (xy 186.360821 -23.824696)
			(xy 186.372947 -23.770259) (xy 186.39287 -23.718168) (xy 186.420166 -23.669533) (xy 186.454252 -23.62539)
			(xy 186.494401 -23.586681) (xy 186.539759 -23.55423) (xy 186.589359 -23.528729) (xy 186.642143 -23.510722)
			(xy 186.696986 -23.500592) (xy 186.75272 -23.498555) (xy 186.808157 -23.504655) (xy 186.862114 -23.518761)
			(xy 186.913443 -23.540573) (xy 186.961049 -23.569627) (xy 187.003917 -23.605302) (xy 187.041134 -23.646839)
			(xy 187.071907 -23.693352) (xy 187.095579 -23.743849) (xy 187.111647 -23.797256) (xy 187.119767 -23.852432)
			(xy 187.120276 -23.880318) (xy 187.37275 -23.880318) (xy 187.376821 -23.824696) (xy 187.388947 -23.770259)
			(xy 187.40887 -23.718168) (xy 187.436166 -23.669533) (xy 187.470252 -23.62539) (xy 187.510401 -23.586681)
			(xy 187.555759 -23.55423) (xy 187.605359 -23.528729) (xy 187.658143 -23.510722) (xy 187.712986 -23.500592)
			(xy 187.76872 -23.498555) (xy 187.824157 -23.504655) (xy 187.878114 -23.518761) (xy 187.929443 -23.540573)
			(xy 187.977049 -23.569627) (xy 188.019917 -23.605302) (xy 188.057134 -23.646839) (xy 188.087907 -23.693352)
			(xy 188.111579 -23.743849) (xy 188.127647 -23.797256) (xy 188.135767 -23.852432) (xy 188.136276 -23.880318)
			(xy 188.391036 -23.880318) (xy 188.395107 -23.824696) (xy 188.407233 -23.770259) (xy 188.427156 -23.718168)
			(xy 188.454452 -23.669533) (xy 188.488538 -23.62539) (xy 188.528687 -23.586681) (xy 188.574045 -23.55423)
			(xy 188.623645 -23.528729) (xy 188.676429 -23.510722) (xy 188.731272 -23.500592) (xy 188.787006 -23.498555)
			(xy 188.842443 -23.504655) (xy 188.8964 -23.518761) (xy 188.947729 -23.540573) (xy 188.995335 -23.569627)
			(xy 189.038203 -23.605302) (xy 189.07542 -23.646839) (xy 189.106193 -23.693352) (xy 189.129865 -23.743849)
			(xy 189.145933 -23.797256) (xy 189.154053 -23.852432) (xy 189.154562 -23.880318) (xy 189.154053 -23.908204)
			(xy 189.145933 -23.96338) (xy 189.129865 -24.016787) (xy 189.106193 -24.067284) (xy 189.07542 -24.113797)
			(xy 189.038203 -24.155334) (xy 188.995335 -24.191009) (xy 188.947729 -24.220063) (xy 188.8964 -24.241875)
			(xy 188.842443 -24.255981) (xy 188.787006 -24.262081) (xy 188.731272 -24.260044) (xy 188.676429 -24.249914)
			(xy 188.623645 -24.231907) (xy 188.574045 -24.206406) (xy 188.528687 -24.173955) (xy 188.488538 -24.135246)
			(xy 188.454452 -24.091103) (xy 188.427156 -24.042468) (xy 188.407233 -23.990377) (xy 188.395107 -23.93594)
			(xy 188.391036 -23.880318) (xy 188.136276 -23.880318) (xy 188.135767 -23.908204) (xy 188.127647 -23.96338)
			(xy 188.111579 -24.016787) (xy 188.087907 -24.067284) (xy 188.057134 -24.113797) (xy 188.019917 -24.155334)
			(xy 187.977049 -24.191009) (xy 187.929443 -24.220063) (xy 187.878114 -24.241875) (xy 187.824157 -24.255981)
			(xy 187.76872 -24.262081) (xy 187.712986 -24.260044) (xy 187.658143 -24.249914) (xy 187.605359 -24.231907)
			(xy 187.555759 -24.206406) (xy 187.510401 -24.173955) (xy 187.470252 -24.135246) (xy 187.436166 -24.091103)
			(xy 187.40887 -24.042468) (xy 187.388947 -23.990377) (xy 187.376821 -23.93594) (xy 187.37275 -23.880318)
			(xy 187.120276 -23.880318) (xy 187.119767 -23.908204) (xy 187.111647 -23.96338) (xy 187.095579 -24.016787)
			(xy 187.071907 -24.067284) (xy 187.041134 -24.113797) (xy 187.003917 -24.155334) (xy 186.961049 -24.191009)
			(xy 186.913443 -24.220063) (xy 186.862114 -24.241875) (xy 186.808157 -24.255981) (xy 186.75272 -24.262081)
			(xy 186.696986 -24.260044) (xy 186.642143 -24.249914) (xy 186.589359 -24.231907) (xy 186.539759 -24.206406)
			(xy 186.494401 -24.173955) (xy 186.454252 -24.135246) (xy 186.420166 -24.091103) (xy 186.39287 -24.042468)
			(xy 186.372947 -23.990377) (xy 186.360821 -23.93594) (xy 186.35675 -23.880318) (xy 186.104276 -23.880318)
			(xy 186.103767 -23.908204) (xy 186.095647 -23.96338) (xy 186.079579 -24.016787) (xy 186.055907 -24.067284)
			(xy 186.025134 -24.113797) (xy 185.987917 -24.155334) (xy 185.945049 -24.191009) (xy 185.897443 -24.220063)
			(xy 185.846114 -24.241875) (xy 185.792157 -24.255981) (xy 185.73672 -24.262081) (xy 185.680986 -24.260044)
			(xy 185.626143 -24.249914) (xy 185.573359 -24.231907) (xy 185.523759 -24.206406) (xy 185.478401 -24.173955)
			(xy 185.438252 -24.135246) (xy 185.404166 -24.091103) (xy 185.37687 -24.042468) (xy 185.356947 -23.990377)
			(xy 185.344821 -23.93594) (xy 185.34075 -23.880318) (xy 184.813317 -23.880318) (xy 184.788841 -23.900687)
			(xy 184.741235 -23.929741) (xy 184.689906 -23.951553) (xy 184.635949 -23.965659) (xy 184.580512 -23.971759)
			(xy 184.524778 -23.969722) (xy 184.469935 -23.959592) (xy 184.417151 -23.941585) (xy 184.367551 -23.916084)
			(xy 184.322193 -23.883633) (xy 184.282044 -23.844924) (xy 184.247958 -23.800781) (xy 184.220662 -23.752146)
			(xy 184.200739 -23.700055) (xy 184.188613 -23.645618) (xy 184.184542 -23.589996) (xy 180.928391 -23.589996)
			(xy 180.927973 -23.610893) (xy 180.920211 -23.664832) (xy 180.904852 -23.717118) (xy 180.882208 -23.766686)
			(xy 180.852741 -23.812526) (xy 180.81705 -23.853707) (xy 180.775862 -23.889389) (xy 180.730015 -23.918847)
			(xy 180.680443 -23.94148) (xy 180.628154 -23.956828) (xy 180.574213 -23.964578) (xy 180.519719 -23.964573)
			(xy 180.465779 -23.956813) (xy 180.413493 -23.941456) (xy 180.363925 -23.918814) (xy 180.318083 -23.889348)
			(xy 180.276901 -23.853659) (xy 180.241218 -23.812472) (xy 180.211759 -23.766626) (xy 180.189124 -23.717054)
			(xy 180.173775 -23.664766) (xy 180.166023 -23.610825) (xy 170.681512 -23.610825) (xy 170.729579 -23.631251)
			(xy 170.777185 -23.660305) (xy 170.820053 -23.69598) (xy 170.85727 -23.737517) (xy 170.888043 -23.78403)
			(xy 170.911715 -23.834527) (xy 170.927783 -23.887934) (xy 170.935903 -23.94311) (xy 170.936412 -23.970996)
			(xy 170.935903 -23.998882) (xy 170.927783 -24.054058) (xy 170.911715 -24.107465) (xy 170.888043 -24.157962)
			(xy 170.88789 -24.158194) (xy 175.550828 -24.158194) (xy 175.554899 -24.102572) (xy 175.567025 -24.048135)
			(xy 175.586948 -23.996044) (xy 175.614244 -23.947409) (xy 175.64833 -23.903266) (xy 175.688479 -23.864557)
			(xy 175.733837 -23.832106) (xy 175.783437 -23.806605) (xy 175.836221 -23.788598) (xy 175.891064 -23.778468)
			(xy 175.946798 -23.776431) (xy 176.002235 -23.782531) (xy 176.056192 -23.796637) (xy 176.107521 -23.818449)
			(xy 176.155127 -23.847503) (xy 176.197995 -23.883178) (xy 176.235212 -23.924715) (xy 176.265985 -23.971228)
			(xy 176.289657 -24.021725) (xy 176.305725 -24.075132) (xy 176.313845 -24.130308) (xy 176.314354 -24.158194)
			(xy 176.313845 -24.18608) (xy 176.313276 -24.189944) (xy 179.398928 -24.189944) (xy 179.402999 -24.134322)
			(xy 179.415125 -24.079885) (xy 179.435048 -24.027794) (xy 179.462344 -23.979159) (xy 179.49643 -23.935016)
			(xy 179.536579 -23.896307) (xy 179.581937 -23.863856) (xy 179.631537 -23.838355) (xy 179.684321 -23.820348)
			(xy 179.739164 -23.810218) (xy 179.794898 -23.808181) (xy 179.850335 -23.814281) (xy 179.904292 -23.828387)
			(xy 179.955621 -23.850199) (xy 180.003227 -23.879253) (xy 180.046095 -23.914928) (xy 180.083312 -23.956465)
			(xy 180.114085 -24.002978) (xy 180.137757 -24.053475) (xy 180.153825 -24.106882) (xy 180.161945 -24.162058)
			(xy 180.162454 -24.189944) (xy 181.92191 -24.189944) (xy 181.925981 -24.134322) (xy 181.938107 -24.079885)
			(xy 181.95803 -24.027794) (xy 181.985326 -23.979159) (xy 182.019412 -23.935016) (xy 182.059561 -23.896307)
			(xy 182.104919 -23.863856) (xy 182.154519 -23.838355) (xy 182.207303 -23.820348) (xy 182.262146 -23.810218)
			(xy 182.31788 -23.808181) (xy 182.373317 -23.814281) (xy 182.427274 -23.828387) (xy 182.478603 -23.850199)
			(xy 182.526209 -23.879253) (xy 182.569077 -23.914928) (xy 182.606294 -23.956465) (xy 182.637067 -24.002978)
			(xy 182.660739 -24.053475) (xy 182.676807 -24.106882) (xy 182.684927 -24.162058) (xy 182.685436 -24.189944)
			(xy 182.684927 -24.21783) (xy 182.676807 -24.273006) (xy 182.660739 -24.326413) (xy 182.637067 -24.37691)
			(xy 182.606294 -24.423423) (xy 182.569077 -24.46496) (xy 182.526209 -24.500635) (xy 182.478603 -24.529689)
			(xy 182.427274 -24.551501) (xy 182.373317 -24.565607) (xy 182.31788 -24.571707) (xy 182.262146 -24.56967)
			(xy 182.207303 -24.55954) (xy 182.154519 -24.541533) (xy 182.104919 -24.516032) (xy 182.059561 -24.483581)
			(xy 182.019412 -24.444872) (xy 181.985326 -24.400729) (xy 181.95803 -24.352094) (xy 181.938107 -24.300003)
			(xy 181.925981 -24.245566) (xy 181.92191 -24.189944) (xy 180.162454 -24.189944) (xy 180.161945 -24.21783)
			(xy 180.153825 -24.273006) (xy 180.137757 -24.326413) (xy 180.114085 -24.37691) (xy 180.083312 -24.423423)
			(xy 180.046095 -24.46496) (xy 180.003227 -24.500635) (xy 179.955621 -24.529689) (xy 179.904292 -24.551501)
			(xy 179.850335 -24.565607) (xy 179.794898 -24.571707) (xy 179.739164 -24.56967) (xy 179.684321 -24.55954)
			(xy 179.631537 -24.541533) (xy 179.581937 -24.516032) (xy 179.536579 -24.483581) (xy 179.49643 -24.444872)
			(xy 179.462344 -24.400729) (xy 179.435048 -24.352094) (xy 179.415125 -24.300003) (xy 179.402999 -24.245566)
			(xy 179.398928 -24.189944) (xy 176.313276 -24.189944) (xy 176.305725 -24.241256) (xy 176.289657 -24.294663)
			(xy 176.265985 -24.34516) (xy 176.235212 -24.391673) (xy 176.197995 -24.43321) (xy 176.155127 -24.468885)
			(xy 176.107521 -24.497939) (xy 176.056192 -24.519751) (xy 176.002235 -24.533857) (xy 175.946798 -24.539957)
			(xy 175.891064 -24.53792) (xy 175.836221 -24.52779) (xy 175.783437 -24.509783) (xy 175.733837 -24.484282)
			(xy 175.688479 -24.451831) (xy 175.64833 -24.413122) (xy 175.614244 -24.368979) (xy 175.586948 -24.320344)
			(xy 175.567025 -24.268253) (xy 175.554899 -24.213816) (xy 175.550828 -24.158194) (xy 170.88789 -24.158194)
			(xy 170.85727 -24.204475) (xy 170.820053 -24.246012) (xy 170.777185 -24.281687) (xy 170.729579 -24.310741)
			(xy 170.67825 -24.332553) (xy 170.624293 -24.346659) (xy 170.568856 -24.352759) (xy 170.513122 -24.350722)
			(xy 170.458279 -24.340592) (xy 170.405495 -24.322585) (xy 170.355895 -24.297084) (xy 170.310537 -24.264633)
			(xy 170.270388 -24.225924) (xy 170.236302 -24.181781) (xy 170.209006 -24.133146) (xy 170.189083 -24.081055)
			(xy 170.176957 -24.026618) (xy 170.172886 -23.970996) (xy 169.943601 -23.970996) (xy 169.943525 -23.975223)
			(xy 169.93515 -24.031315) (xy 169.918563 -24.085549) (xy 169.894131 -24.136731) (xy 169.862392 -24.183731)
			(xy 169.824045 -24.225516) (xy 169.779935 -24.261164) (xy 169.731034 -24.289889) (xy 169.678419 -24.31106)
			(xy 169.623251 -24.324208) (xy 169.595038 -24.327104) (xy 169.584624 -24.327866) (xy 169.57548 -24.332692)
			(xy 169.571534 -24.334797) (xy 169.564376 -24.340157) (xy 169.561256 -24.34336) (xy 169.51452 -24.39416)
			(xy 169.508337 -24.401419) (xy 169.501427 -24.419175) (xy 169.501058 -24.428704) (xy 169.501058 -24.807418)
			(xy 176.720244 -24.807418) (xy 176.724315 -24.751796) (xy 176.736441 -24.697359) (xy 176.756364 -24.645268)
			(xy 176.78366 -24.596633) (xy 176.817746 -24.55249) (xy 176.857895 -24.513781) (xy 176.903253 -24.48133)
			(xy 176.952853 -24.455829) (xy 177.005637 -24.437822) (xy 177.06048 -24.427692) (xy 177.116214 -24.425655)
			(xy 177.171651 -24.431755) (xy 177.225608 -24.445861) (xy 177.276937 -24.467673) (xy 177.324543 -24.496727)
			(xy 177.367411 -24.532402) (xy 177.404628 -24.573939) (xy 177.435401 -24.620452) (xy 177.459073 -24.670949)
			(xy 177.475141 -24.724356) (xy 177.480188 -24.75865) (xy 188.968632 -24.75865) (xy 188.972703 -24.703028)
			(xy 188.984829 -24.648591) (xy 189.004752 -24.5965) (xy 189.032048 -24.547865) (xy 189.066134 -24.503722)
			(xy 189.106283 -24.465013) (xy 189.151641 -24.432562) (xy 189.201241 -24.407061) (xy 189.254025 -24.389054)
			(xy 189.308868 -24.378924) (xy 189.364602 -24.376887) (xy 189.420039 -24.382987) (xy 189.473996 -24.397093)
			(xy 189.525325 -24.418905) (xy 189.572931 -24.447959) (xy 189.615799 -24.483634) (xy 189.653016 -24.525171)
			(xy 189.683789 -24.571684) (xy 189.707461 -24.622181) (xy 189.723529 -24.675588) (xy 189.731649 -24.730764)
			(xy 189.732158 -24.75865) (xy 189.731649 -24.786536) (xy 189.723529 -24.841712) (xy 189.707461 -24.895119)
			(xy 189.683789 -24.945616) (xy 189.653016 -24.992129) (xy 189.615799 -25.033666) (xy 189.572931 -25.069341)
			(xy 189.525325 -25.098395) (xy 189.473996 -25.120207) (xy 189.420039 -25.134313) (xy 189.364602 -25.140413)
			(xy 189.308868 -25.138376) (xy 189.254025 -25.128246) (xy 189.201241 -25.110239) (xy 189.151641 -25.084738)
			(xy 189.106283 -25.052287) (xy 189.066134 -25.013578) (xy 189.032048 -24.969435) (xy 189.004752 -24.9208)
			(xy 188.984829 -24.868709) (xy 188.972703 -24.814272) (xy 188.968632 -24.75865) (xy 177.480188 -24.75865)
			(xy 177.483261 -24.779532) (xy 177.48377 -24.807418) (xy 177.483261 -24.835304) (xy 177.475141 -24.89048)
			(xy 177.459073 -24.943887) (xy 177.435401 -24.994384) (xy 177.404628 -25.040897) (xy 177.367411 -25.082434)
			(xy 177.324543 -25.118109) (xy 177.276937 -25.147163) (xy 177.225608 -25.168975) (xy 177.171651 -25.183081)
			(xy 177.116214 -25.189181) (xy 177.06048 -25.187144) (xy 177.005637 -25.177014) (xy 176.952853 -25.159007)
			(xy 176.903253 -25.133506) (xy 176.857895 -25.101055) (xy 176.817746 -25.062346) (xy 176.78366 -25.018203)
			(xy 176.756364 -24.969568) (xy 176.736441 -24.917477) (xy 176.724315 -24.86304) (xy 176.720244 -24.807418)
			(xy 169.501058 -24.807418) (xy 169.501058 -25.390094) (xy 181.90972 -25.390094) (xy 181.910206 -25.362843)
			(xy 181.917962 -25.308895) (xy 181.933317 -25.2566) (xy 181.955959 -25.207023) (xy 181.985425 -25.161173)
			(xy 182.021116 -25.119982) (xy 182.062307 -25.084291) (xy 182.108157 -25.054825) (xy 182.157734 -25.032183)
			(xy 182.210029 -25.016828) (xy 182.263977 -25.009072) (xy 182.318479 -25.009072) (xy 182.372427 -25.016828)
			(xy 182.424722 -25.032183) (xy 182.474299 -25.054825) (xy 182.520149 -25.084291) (xy 182.56134 -25.119982)
			(xy 182.597031 -25.161173) (xy 182.626497 -25.207023) (xy 182.649139 -25.2566) (xy 182.664494 -25.308895)
			(xy 182.67225 -25.362843) (xy 182.672736 -25.390094) (xy 182.67217 -25.419114) (xy 182.66338 -25.476485)
			(xy 182.646001 -25.531862) (xy 182.620435 -25.583968) (xy 182.587271 -25.6316) (xy 182.547275 -25.673659)
			(xy 182.524654 -25.691846) (xy 182.514114 -25.700619) (xy 182.49768 -25.722555) (xy 182.487679 -25.748075)
			(xy 182.484833 -25.775336) (xy 182.489349 -25.802371) (xy 182.500899 -25.827227) (xy 182.51865 -25.848112)
			(xy 182.529734 -25.856184) (xy 182.55138 -25.871496) (xy 182.590635 -25.907136) (xy 182.624576 -25.947869)
			(xy 182.652549 -25.99291) (xy 182.674015 -26.041391) (xy 182.688559 -26.092378) (xy 182.695902 -26.144888)
			(xy 182.696358 -26.171398) (xy 182.695872 -26.198649) (xy 182.688116 -26.252597) (xy 182.672761 -26.304892)
			(xy 182.650119 -26.354469) (xy 182.620653 -26.400319) (xy 182.584962 -26.44151) (xy 182.543771 -26.477201)
			(xy 182.497921 -26.506667) (xy 182.448344 -26.529309) (xy 182.396049 -26.544664) (xy 182.342101 -26.55242)
			(xy 182.287599 -26.55242) (xy 182.233651 -26.544664) (xy 182.181356 -26.529309) (xy 182.131779 -26.506667)
			(xy 182.085929 -26.477201) (xy 182.044738 -26.44151) (xy 182.009047 -26.400319) (xy 181.979581 -26.354469)
			(xy 181.956939 -26.304892) (xy 181.941584 -26.252597) (xy 181.933828 -26.198649) (xy 181.933342 -26.171398)
			(xy 181.93391 -26.142378) (xy 181.942702 -26.085008) (xy 181.96008 -26.029631) (xy 181.985646 -25.977526)
			(xy 182.018809 -25.929893) (xy 182.058804 -25.887833) (xy 182.081424 -25.869646) (xy 182.091975 -25.860884)
			(xy 182.108413 -25.838947) (xy 182.118416 -25.813424) (xy 182.121261 -25.786159) (xy 182.116743 -25.759121)
			(xy 182.105188 -25.734263) (xy 182.087431 -25.713379) (xy 182.076344 -25.705308) (xy 182.054689 -25.690009)
			(xy 182.015435 -25.654366) (xy 181.981495 -25.61363) (xy 181.953524 -25.568587) (xy 181.93206 -25.520104)
			(xy 181.917517 -25.469116) (xy 181.910175 -25.416605) (xy 181.90972 -25.390094) (xy 169.501058 -25.390094)
			(xy 169.501058 -25.971246) (xy 172.091856 -25.971246) (xy 172.095927 -25.915624) (xy 172.108053 -25.861187)
			(xy 172.127976 -25.809096) (xy 172.155272 -25.760461) (xy 172.189358 -25.716318) (xy 172.229507 -25.677609)
			(xy 172.274865 -25.645158) (xy 172.324465 -25.619657) (xy 172.377249 -25.60165) (xy 172.432092 -25.59152)
			(xy 172.487826 -25.589483) (xy 172.543263 -25.595583) (xy 172.59722 -25.609689) (xy 172.648549 -25.631501)
			(xy 172.696155 -25.660555) (xy 172.739023 -25.69623) (xy 172.77624 -25.737767) (xy 172.807013 -25.78428)
			(xy 172.830685 -25.834777) (xy 172.846753 -25.888184) (xy 172.854873 -25.94336) (xy 172.855382 -25.971246)
			(xy 172.854873 -25.999132) (xy 172.849781 -26.03373) (xy 173.367952 -26.03373) (xy 173.372023 -25.978108)
			(xy 173.384149 -25.923671) (xy 173.404072 -25.87158) (xy 173.431368 -25.822945) (xy 173.465454 -25.778802)
			(xy 173.505603 -25.740093) (xy 173.550961 -25.707642) (xy 173.600561 -25.682141) (xy 173.653345 -25.664134)
			(xy 173.708188 -25.654004) (xy 173.763922 -25.651967) (xy 173.819359 -25.658067) (xy 173.873316 -25.672173)
			(xy 173.924645 -25.693985) (xy 173.972251 -25.723039) (xy 174.015119 -25.758714) (xy 174.052336 -25.800251)
			(xy 174.083109 -25.846764) (xy 174.106781 -25.897261) (xy 174.122849 -25.950668) (xy 174.130969 -26.005844)
			(xy 174.131478 -26.03373) (xy 174.130969 -26.061616) (xy 174.122849 -26.116792) (xy 174.106781 -26.170199)
			(xy 174.083109 -26.220696) (xy 174.052875 -26.266394) (xy 176.620678 -26.266394) (xy 176.621172 -26.239143)
			(xy 176.628929 -26.185197) (xy 176.644284 -26.132903) (xy 176.666925 -26.083326) (xy 176.696391 -26.037477)
			(xy 176.732081 -25.996287) (xy 176.77327 -25.960596) (xy 176.819119 -25.931129) (xy 176.868695 -25.908487)
			(xy 176.920989 -25.893131) (xy 176.974935 -25.885373) (xy 177.002186 -25.884886) (xy 177.031511 -25.885421)
			(xy 177.089469 -25.894402) (xy 177.145367 -25.912153) (xy 177.197888 -25.938256) (xy 177.22215 -25.954736)
			(xy 177.232564 -25.961848) (xy 177.256948 -25.96515) (xy 177.35931 -25.927304) (xy 177.376074 -25.908762)
			(xy 177.379122 -25.89657) (xy 177.386479 -25.869488) (xy 177.408038 -25.817676) (xy 177.436957 -25.769584)
			(xy 177.472611 -25.726248) (xy 177.514231 -25.688605) (xy 177.560918 -25.657468) (xy 177.611665 -25.633509)
			(xy 177.665374 -25.617245) (xy 177.720887 -25.609028) (xy 177.748946 -25.608534) (xy 177.776198 -25.608939)
			(xy 177.830147 -25.616702) (xy 177.882442 -25.632063) (xy 177.932019 -25.654709) (xy 177.977868 -25.68418)
			(xy 178.019058 -25.719875) (xy 178.054748 -25.761069) (xy 178.084213 -25.806922) (xy 178.106854 -25.856501)
			(xy 178.122208 -25.908798) (xy 178.129964 -25.962748) (xy 178.129964 -25.990042) (xy 179.398928 -25.990042)
			(xy 179.402999 -25.93442) (xy 179.415125 -25.879983) (xy 179.435048 -25.827892) (xy 179.462344 -25.779257)
			(xy 179.49643 -25.735114) (xy 179.536579 -25.696405) (xy 179.581937 -25.663954) (xy 179.631537 -25.638453)
			(xy 179.684321 -25.620446) (xy 179.739164 -25.610316) (xy 179.794898 -25.608279) (xy 179.850335 -25.614379)
			(xy 179.904292 -25.628485) (xy 179.955621 -25.650297) (xy 180.003227 -25.679351) (xy 180.046095 -25.715026)
			(xy 180.083312 -25.756563) (xy 180.114085 -25.803076) (xy 180.137757 -25.853573) (xy 180.153825 -25.90698)
			(xy 180.161945 -25.962156) (xy 180.162454 -25.990042) (xy 180.161945 -26.017928) (xy 180.153825 -26.073104)
			(xy 180.137757 -26.126511) (xy 180.114085 -26.177008) (xy 180.083312 -26.223521) (xy 180.046095 -26.265058)
			(xy 180.003227 -26.300733) (xy 179.955621 -26.329787) (xy 179.904292 -26.351599) (xy 179.850335 -26.365705)
			(xy 179.794898 -26.371805) (xy 179.739164 -26.369768) (xy 179.684321 -26.359638) (xy 179.631537 -26.341631)
			(xy 179.581937 -26.31613) (xy 179.536579 -26.283679) (xy 179.49643 -26.24497) (xy 179.462344 -26.200827)
			(xy 179.435048 -26.152192) (xy 179.415125 -26.100101) (xy 179.402999 -26.045664) (xy 179.398928 -25.990042)
			(xy 178.129964 -25.990042) (xy 178.129964 -26.017252) (xy 178.122208 -26.071202) (xy 178.106854 -26.123499)
			(xy 178.084213 -26.173078) (xy 178.054748 -26.218931) (xy 178.019058 -26.260125) (xy 177.977868 -26.29582)
			(xy 177.932019 -26.325291) (xy 177.882442 -26.347937) (xy 177.830147 -26.363298) (xy 177.776198 -26.371061)
			(xy 177.748946 -26.37155) (xy 177.719622 -26.370992) (xy 177.661665 -26.362017) (xy 177.605767 -26.344273)
			(xy 177.553245 -26.318176) (xy 177.528982 -26.3017) (xy 177.518568 -26.294588) (xy 177.494184 -26.291286)
			(xy 177.391822 -26.329132) (xy 177.375058 -26.347674) (xy 177.37201 -26.359866) (xy 177.365242 -26.384903)
			(xy 177.345824 -26.432994) (xy 177.320064 -26.478007) (xy 177.288439 -26.519113) (xy 177.251532 -26.55555)
			(xy 177.23104 -26.571448) (xy 177.22088 -26.579322) (xy 177.210212 -26.601928) (xy 177.2158 -26.711656)
			(xy 177.228754 -26.733246) (xy 177.239676 -26.73985) (xy 177.263407 -26.754763) (xy 177.306643 -26.790427)
			(xy 177.344196 -26.832032) (xy 177.375257 -26.878685) (xy 177.399158 -26.92938) (xy 177.415384 -26.983027)
			(xy 177.423585 -27.038471) (xy 177.42408 -27.066494) (xy 177.423594 -27.093745) (xy 177.415838 -27.147693)
			(xy 177.400483 -27.199988) (xy 177.377841 -27.249565) (xy 177.348375 -27.295415) (xy 177.312684 -27.336606)
			(xy 177.271493 -27.372297) (xy 177.225643 -27.401763) (xy 177.176066 -27.424405) (xy 177.123771 -27.43976)
			(xy 177.069823 -27.447516) (xy 177.015321 -27.447516) (xy 176.961373 -27.43976) (xy 176.909078 -27.424405)
			(xy 176.859501 -27.401763) (xy 176.813651 -27.372297) (xy 176.77246 -27.336606) (xy 176.736769 -27.295415)
			(xy 176.707303 -27.249565) (xy 176.684661 -27.199988) (xy 176.669306 -27.147693) (xy 176.66155 -27.093745)
			(xy 176.661064 -27.066494) (xy 176.661622 -27.037007) (xy 176.670717 -26.978737) (xy 176.688675 -26.922563)
			(xy 176.715067 -26.869822) (xy 176.749265 -26.821774) (xy 176.790451 -26.779564) (xy 176.813718 -26.76144)
			(xy 176.823878 -26.753566) (xy 176.834546 -26.73096) (xy 176.828958 -26.621232) (xy 176.816004 -26.599642)
			(xy 176.805082 -26.593038) (xy 176.781336 -26.578148) (xy 176.738102 -26.542479) (xy 176.700551 -26.500869)
			(xy 176.669493 -26.454212) (xy 176.645595 -26.403514) (xy 176.629371 -26.349864) (xy 176.621172 -26.294418)
			(xy 176.620678 -26.266394) (xy 174.052875 -26.266394) (xy 174.052336 -26.267209) (xy 174.015119 -26.308746)
			(xy 173.972251 -26.344421) (xy 173.924645 -26.373475) (xy 173.873316 -26.395287) (xy 173.819359 -26.409393)
			(xy 173.763922 -26.415493) (xy 173.708188 -26.413456) (xy 173.653345 -26.403326) (xy 173.600561 -26.385319)
			(xy 173.550961 -26.359818) (xy 173.505603 -26.327367) (xy 173.465454 -26.288658) (xy 173.431368 -26.244515)
			(xy 173.404072 -26.19588) (xy 173.384149 -26.143789) (xy 173.372023 -26.089352) (xy 173.367952 -26.03373)
			(xy 172.849781 -26.03373) (xy 172.846753 -26.054308) (xy 172.830685 -26.107715) (xy 172.807013 -26.158212)
			(xy 172.77624 -26.204725) (xy 172.739023 -26.246262) (xy 172.696155 -26.281937) (xy 172.648549 -26.310991)
			(xy 172.59722 -26.332803) (xy 172.543263 -26.346909) (xy 172.487826 -26.353009) (xy 172.432092 -26.350972)
			(xy 172.377249 -26.340842) (xy 172.324465 -26.322835) (xy 172.274865 -26.297334) (xy 172.229507 -26.264883)
			(xy 172.189358 -26.226174) (xy 172.155272 -26.182031) (xy 172.127976 -26.133396) (xy 172.108053 -26.081305)
			(xy 172.095927 -26.026868) (xy 172.091856 -25.971246) (xy 169.501058 -25.971246) (xy 169.501058 -27.66949)
			(xy 169.516552 -27.694382) (xy 169.530014 -27.700732) (xy 169.556717 -27.714144) (xy 169.605941 -27.748015)
			(xy 169.615356 -27.756952) (xy 172.859166 -27.756952) (xy 172.859166 -27.702448) (xy 172.866922 -27.6485)
			(xy 172.882278 -27.596204) (xy 172.904919 -27.546626) (xy 172.934385 -27.500774) (xy 172.970077 -27.459583)
			(xy 173.011268 -27.42389) (xy 173.057118 -27.394423) (xy 173.106696 -27.37178) (xy 173.158992 -27.356424)
			(xy 173.21294 -27.348666) (xy 173.240192 -27.34818) (xy 173.254277 -27.348285) (xy 173.282373 -27.350316)
			(xy 173.296326 -27.352244) (xy 173.310042 -27.354276) (xy 173.33595 -27.343862) (xy 173.406308 -27.249882)
			(xy 173.409356 -27.221942) (xy 173.403514 -27.209242) (xy 173.392475 -27.184111) (xy 173.37687 -27.131489)
			(xy 173.368962 -27.077173) (xy 173.368462 -27.04973) (xy 173.368948 -27.022479) (xy 173.376704 -26.968531)
			(xy 173.392059 -26.916236) (xy 173.414701 -26.866659) (xy 173.444167 -26.820809) (xy 173.479858 -26.779618)
			(xy 173.521049 -26.743927) (xy 173.566899 -26.714461) (xy 173.616476 -26.691819) (xy 173.668771 -26.676464)
			(xy 173.722719 -26.668708) (xy 173.777221 -26.668708) (xy 173.831169 -26.676464) (xy 173.883464 -26.691819)
			(xy 173.933041 -26.714461) (xy 173.978891 -26.743927) (xy 174.020082 -26.779618) (xy 174.055773 -26.820809)
			(xy 174.085239 -26.866659) (xy 174.107881 -26.916236) (xy 174.123236 -26.968531) (xy 174.130992 -27.022479)
			(xy 174.131478 -27.04973) (xy 174.13086 -27.081146) (xy 174.120597 -27.143133) (xy 174.10032 -27.202603)
			(xy 174.086012 -27.230578) (xy 174.080678 -27.24023) (xy 174.079154 -27.262074) (xy 174.113444 -27.354022)
			(xy 174.128684 -27.369516) (xy 174.138844 -27.37358) (xy 174.165498 -27.384322) (xy 174.215464 -27.412706)
			(xy 174.260605 -27.448267) (xy 174.299898 -27.4902) (xy 174.332455 -27.537554) (xy 174.357536 -27.589257)
			(xy 174.374575 -27.644138) (xy 174.383185 -27.700955) (xy 174.3837 -27.729688) (xy 174.383233 -27.756941)
			(xy 174.375478 -27.810892) (xy 174.360123 -27.86319) (xy 174.337481 -27.912771) (xy 174.308014 -27.958625)
			(xy 174.27232 -27.999818) (xy 174.231128 -28.035511) (xy 174.185275 -28.064979) (xy 174.135694 -28.087622)
			(xy 174.083396 -28.102977) (xy 174.029445 -28.110733) (xy 174.002192 -28.111196) (xy 173.973277 -28.110613)
			(xy 173.916109 -28.101898) (xy 173.860912 -28.084653) (xy 173.808949 -28.059273) (xy 173.761414 -28.026341)
			(xy 173.719394 -27.986611) (xy 173.701202 -27.96413) (xy 173.693647 -27.955362) (xy 173.672883 -27.945185)
			(xy 173.661324 -27.944572) (xy 173.58106 -27.944572) (xy 173.569493 -27.945152) (xy 173.54872 -27.955337)
			(xy 173.541182 -27.96413) (xy 173.523009 -27.986628) (xy 173.480984 -28.026361) (xy 173.433446 -28.059298)
			(xy 173.381481 -28.084683) (xy 173.326281 -28.101937) (xy 173.269109 -28.110663) (xy 173.240192 -28.111196)
			(xy 173.21294 -28.110734) (xy 173.158992 -28.102976) (xy 173.106696 -28.08762) (xy 173.057118 -28.064977)
			(xy 173.011268 -28.03551) (xy 172.970077 -27.999817) (xy 172.934385 -27.958626) (xy 172.904919 -27.912774)
			(xy 172.882278 -27.863196) (xy 172.866922 -27.8109) (xy 172.859166 -27.756952) (xy 169.615356 -27.756952)
			(xy 169.649278 -27.789152) (xy 169.667936 -27.812492) (xy 169.669968 -27.815286) (xy 169.676318 -27.821636)
			(xy 169.68228 -27.827139) (xy 169.696787 -27.834388) (xy 169.704766 -27.83586) (xy 169.78376 -27.847544)
			(xy 169.803318 -27.842464) (xy 169.811446 -27.836114) (xy 169.831495 -27.821287) (xy 169.87471 -27.796406)
			(xy 169.920798 -27.777367) (xy 169.968973 -27.764493) (xy 170.018415 -27.758003) (xy 170.043348 -27.757628)
			(xy 170.071413 -27.758122) (xy 170.126936 -27.766342) (xy 170.180656 -27.782611) (xy 170.231411 -27.806578)
			(xy 170.278104 -27.837725) (xy 170.319728 -27.87538) (xy 170.355383 -27.91873) (xy 170.370246 -27.94254)
			(xy 170.373548 -27.947874) (xy 170.377866 -27.952192) (xy 170.382692 -27.957018) (xy 170.408346 -27.972004)
			(xy 170.414283 -27.975168) (xy 170.427276 -27.978638) (xy 170.434 -27.978862) (xy 170.49496 -27.978862)
			(xy 170.503413 -27.978511) (xy 170.519377 -27.972938) (xy 170.526202 -27.96794) (xy 170.54449 -27.953716)
			(xy 170.549316 -27.945842) (xy 170.55833 -27.931421) (xy 170.578551 -27.904073) (xy 170.589702 -27.891232)
			(xy 170.59021 -27.890724) (xy 170.591988 -27.888946) (xy 170.593258 -27.887676) (xy 170.611447 -27.867635)
			(xy 170.652509 -27.832379) (xy 170.698144 -27.803283) (xy 170.747433 -27.780931) (xy 170.799388 -27.765772)
			(xy 170.852964 -27.75811) (xy 170.880024 -27.757628) (xy 170.907275 -27.758093) (xy 170.961221 -27.765853)
			(xy 171.013514 -27.781211) (xy 171.063089 -27.803856) (xy 171.108936 -27.833325) (xy 171.150123 -27.869019)
			(xy 171.185811 -27.910212) (xy 171.215273 -27.956064) (xy 171.23791 -28.005642) (xy 171.25326 -28.057938)
			(xy 171.261011 -28.111885) (xy 171.261532 -28.139136) (xy 171.768006 -28.139136) (xy 171.772077 -28.083514)
			(xy 171.784203 -28.029077) (xy 171.804126 -27.976986) (xy 171.831422 -27.928351) (xy 171.865508 -27.884208)
			(xy 171.905657 -27.845499) (xy 171.951015 -27.813048) (xy 172.000615 -27.787547) (xy 172.053399 -27.76954)
			(xy 172.108242 -27.75941) (xy 172.163976 -27.757373) (xy 172.219413 -27.763473) (xy 172.27337 -27.777579)
			(xy 172.324699 -27.799391) (xy 172.372305 -27.828445) (xy 172.415173 -27.86412) (xy 172.45239 -27.905657)
			(xy 172.483163 -27.95217) (xy 172.506835 -28.002667) (xy 172.522903 -28.056074) (xy 172.531023 -28.11125)
			(xy 172.531532 -28.139136) (xy 172.531023 -28.167022) (xy 172.522903 -28.222198) (xy 172.506835 -28.275605)
			(xy 172.483163 -28.326102) (xy 172.45239 -28.372615) (xy 172.415173 -28.414152) (xy 172.372305 -28.449827)
			(xy 172.324699 -28.478881) (xy 172.27337 -28.500693) (xy 172.219413 -28.514799) (xy 172.163976 -28.520899)
			(xy 172.108242 -28.518862) (xy 172.053399 -28.508732) (xy 172.000615 -28.490725) (xy 171.951015 -28.465224)
			(xy 171.905657 -28.432773) (xy 171.865508 -28.394064) (xy 171.831422 -28.349921) (xy 171.804126 -28.301286)
			(xy 171.784203 -28.249195) (xy 171.772077 -28.194758) (xy 171.768006 -28.139136) (xy 171.261532 -28.139136)
			(xy 171.260982 -28.168327) (xy 171.2521 -28.226028) (xy 171.234533 -28.281703) (xy 171.208692 -28.334054)
			(xy 171.175178 -28.381858) (xy 171.15536 -28.403296) (xy 171.153074 -28.405582) (xy 171.15282 -28.405836)
			(xy 171.150788 -28.407868) (xy 171.15028 -28.408376) (xy 171.132273 -28.426546) (xy 171.092239 -28.458391)
			(xy 171.048308 -28.484601) (xy 171.00127 -28.504706) (xy 170.951966 -28.518345) (xy 170.901283 -28.525275)
			(xy 170.875706 -28.525724) (xy 170.875198 -28.525724) (xy 170.846643 -28.525191) (xy 170.790171 -28.516682)
			(xy 170.735596 -28.499855) (xy 170.684138 -28.475085) (xy 170.636944 -28.442925) (xy 170.595068 -28.404092)
			(xy 170.559445 -28.359455) (xy 170.544744 -28.33497) (xy 170.539962 -28.327481) (xy 170.526357 -28.316076)
			(xy 170.509678 -28.309991) (xy 170.500802 -28.30957) (xy 170.41495 -28.30957) (xy 170.406156 -28.309932)
			(xy 170.389605 -28.315875) (xy 170.376047 -28.327076) (xy 170.371262 -28.334462) (xy 170.364635 -28.34535)
			(xy 170.350144 -28.366321) (xy 170.342306 -28.376372) (xy 170.33748 -28.382214) (xy 170.324272 -28.3972)
			(xy 170.322748 -28.398978) (xy 170.321986 -28.39974) (xy 170.303827 -28.419202) (xy 170.263044 -28.453405)
			(xy 170.217898 -28.481601) (xy 170.169268 -28.503242) (xy 170.1181 -28.517906) (xy 170.06539 -28.525308)
			(xy 170.038776 -28.525724) (xy 170.038522 -28.525724) (xy 170.009363 -28.525173) (xy 169.951724 -28.516304)
			(xy 169.896106 -28.498768) (xy 169.843803 -28.472975) (xy 169.796033 -28.439524) (xy 169.753909 -28.399195)
			(xy 169.735754 -28.376372) (xy 169.733722 -28.373578) (xy 169.72788 -28.367736) (xy 169.721993 -28.36234)
			(xy 169.707766 -28.355105) (xy 169.69994 -28.353512) (xy 169.699432 -28.353512) (xy 169.620692 -28.341828)
			(xy 169.611294 -28.34386) (xy 169.59961 -28.3464) (xy 169.590974 -28.353004) (xy 169.589196 -28.354274)
			(xy 169.587926 -28.355036) (xy 169.579798 -28.361132) (xy 169.568114 -28.373578) (xy 169.563288 -28.378658)
			(xy 169.551858 -28.399994) (xy 169.549124 -28.405579) (xy 169.546168 -28.417654) (xy 169.546016 -28.42387)
			(xy 169.546016 -28.429204) (xy 169.54627 -28.442666) (xy 169.553636 -28.45562) (xy 169.556938 -28.461716)
			(xy 169.567352 -28.47213) (xy 169.569892 -28.474924) (xy 169.578528 -28.482036) (xy 169.580814 -28.48356)
			(xy 169.603001 -28.498805) (xy 169.643268 -28.534531) (xy 169.678124 -28.575555) (xy 169.706878 -28.621064)
			(xy 169.728961 -28.670157) (xy 169.743936 -28.721864) (xy 169.751507 -28.77516) (xy 169.75201 -28.802076)
			(xy 169.75201 -28.80233) (xy 169.751448 -28.832319) (xy 169.742046 -28.891556) (xy 169.723479 -28.948588)
			(xy 169.710354 -28.975558) (xy 169.698518 -28.99785) (xy 169.66985 -29.039391) (xy 169.653204 -29.058362)
			(xy 169.652696 -29.05887) (xy 169.65168 -29.059886) (xy 169.634428 -29.078768) (xy 169.595731 -29.112213)
			(xy 169.552919 -29.140199) (xy 169.530014 -29.15158) (xy 169.516552 -29.15793) (xy 169.501058 -29.182568)
			(xy 169.501058 -29.237432) (xy 169.51706 -29.262324) (xy 169.530522 -29.268674) (xy 169.554964 -29.280481)
			(xy 169.600526 -29.309985) (xy 169.641441 -29.345655) (xy 169.676883 -29.386767) (xy 169.706135 -29.432492)
			(xy 169.728605 -29.481903) (xy 169.743838 -29.534002) (xy 169.751527 -29.587736) (xy 169.75201 -29.614876)
			(xy 169.751795 -29.635807) (xy 169.747335 -29.67743) (xy 169.74312 -29.697934) (xy 169.737013 -29.723287)
			(xy 169.7188 -29.772153) (xy 169.694098 -29.818082) (xy 169.663367 -29.860215) (xy 169.645584 -29.87929)
			(xy 169.640758 -29.88437) (xy 169.640504 -29.88437) (xy 169.636948 -29.887926) (xy 169.629784 -29.895135)
			(xy 169.61479 -29.908859) (xy 169.606976 -29.915358) (xy 169.602404 -29.919168) (xy 169.5958 -29.927804)
			(xy 169.585386 -29.950664) (xy 169.583181 -29.955723) (xy 169.580753 -29.966485) (xy 169.58056 -29.972)
			(xy 169.58056 -30.022038) (xy 169.581576 -30.033722) (xy 169.5958 -30.062932) (xy 169.598594 -30.066742)
			(xy 169.604944 -30.075632) (xy 169.609262 -30.079188) (xy 169.609516 -30.079442) (xy 169.63134 -30.097673)
			(xy 169.669869 -30.139495) (xy 169.701771 -30.186568) (xy 169.726341 -30.237851) (xy 169.743035 -30.29221)
			(xy 169.751485 -30.348444) (xy 169.75201 -30.376876) (xy 169.75201 -30.37713) (xy 169.751448 -30.407119)
			(xy 169.742046 -30.466356) (xy 169.723479 -30.523388) (xy 169.710354 -30.550358) (xy 169.698518 -30.57265)
			(xy 169.66985 -30.614191) (xy 169.653204 -30.633162) (xy 169.652696 -30.63367) (xy 169.65168 -30.634686)
			(xy 169.634428 -30.653568) (xy 169.595731 -30.687013) (xy 169.552919 -30.714999) (xy 169.530014 -30.72638)
			(xy 169.516552 -30.73273) (xy 169.501058 -30.757368) (xy 169.501058 -31.159958) (xy 169.525188 -31.188406)
			(xy 169.543476 -31.191454) (xy 169.570167 -31.196382) (xy 169.621904 -31.212792) (xy 169.670793 -31.236366)
			(xy 169.715849 -31.266629) (xy 169.756163 -31.302971) (xy 169.790921 -31.344658) (xy 169.819422 -31.390848)
			(xy 169.841091 -31.440612) (xy 169.855491 -31.492943) (xy 169.862332 -31.546786) (xy 169.861474 -31.601056)
			(xy 169.852936 -31.654656) (xy 169.83689 -31.706507) (xy 169.830848 -31.719266) (xy 170.385484 -31.719266)
			(xy 170.389555 -31.663644) (xy 170.401681 -31.609207) (xy 170.421604 -31.557116) (xy 170.4489 -31.508481)
			(xy 170.482986 -31.464338) (xy 170.523135 -31.425629) (xy 170.568493 -31.393178) (xy 170.618093 -31.367677)
			(xy 170.670877 -31.34967) (xy 170.72572 -31.33954) (xy 170.781454 -31.337503) (xy 170.836891 -31.343603)
			(xy 170.890848 -31.357709) (xy 170.942177 -31.379521) (xy 170.989783 -31.408575) (xy 171.032651 -31.44425)
			(xy 171.069868 -31.485787) (xy 171.100641 -31.5323) (xy 171.124313 -31.582797) (xy 171.140381 -31.636204)
			(xy 171.144531 -31.664402) (xy 171.661072 -31.664402) (xy 171.665143 -31.60878) (xy 171.677269 -31.554343)
			(xy 171.697192 -31.502252) (xy 171.724488 -31.453617) (xy 171.758574 -31.409474) (xy 171.798723 -31.370765)
			(xy 171.844081 -31.338314) (xy 171.893681 -31.312813) (xy 171.946465 -31.294806) (xy 172.001308 -31.284676)
			(xy 172.057042 -31.282639) (xy 172.112479 -31.288739) (xy 172.166436 -31.302845) (xy 172.217765 -31.324657)
			(xy 172.265371 -31.353711) (xy 172.308239 -31.389386) (xy 172.345456 -31.430923) (xy 172.376229 -31.477436)
			(xy 172.399901 -31.527933) (xy 172.415969 -31.58134) (xy 172.424089 -31.636516) (xy 172.424598 -31.664402)
			(xy 172.424089 -31.692288) (xy 172.415969 -31.747464) (xy 172.407029 -31.777178) (xy 172.926246 -31.777178)
			(xy 172.930317 -31.721556) (xy 172.942443 -31.667119) (xy 172.962366 -31.615028) (xy 172.989662 -31.566393)
			(xy 173.023748 -31.52225) (xy 173.063897 -31.483541) (xy 173.109255 -31.45109) (xy 173.158855 -31.425589)
			(xy 173.211639 -31.407582) (xy 173.266482 -31.397452) (xy 173.322216 -31.395415) (xy 173.377653 -31.401515)
			(xy 173.43161 -31.415621) (xy 173.482939 -31.437433) (xy 173.530545 -31.466487) (xy 173.573413 -31.502162)
			(xy 173.61063 -31.543699) (xy 173.641403 -31.590212) (xy 173.665075 -31.640709) (xy 173.681143 -31.694116)
			(xy 173.689263 -31.749292) (xy 173.689772 -31.777178) (xy 173.689263 -31.805064) (xy 173.681143 -31.86024)
			(xy 173.665075 -31.913647) (xy 173.641403 -31.964144) (xy 173.61063 -32.010657) (xy 173.573413 -32.052194)
			(xy 173.530545 -32.087869) (xy 173.482939 -32.116923) (xy 173.43161 -32.138735) (xy 173.377653 -32.152841)
			(xy 173.322216 -32.158941) (xy 173.266482 -32.156904) (xy 173.211639 -32.146774) (xy 173.158855 -32.128767)
			(xy 173.109255 -32.103266) (xy 173.063897 -32.070815) (xy 173.023748 -32.032106) (xy 172.989662 -31.987963)
			(xy 172.962366 -31.939328) (xy 172.942443 -31.887237) (xy 172.930317 -31.8328) (xy 172.926246 -31.777178)
			(xy 172.407029 -31.777178) (xy 172.399901 -31.800871) (xy 172.376229 -31.851368) (xy 172.345456 -31.897881)
			(xy 172.308239 -31.939418) (xy 172.265371 -31.975093) (xy 172.217765 -32.004147) (xy 172.166436 -32.025959)
			(xy 172.112479 -32.040065) (xy 172.057042 -32.046165) (xy 172.001308 -32.044128) (xy 171.946465 -32.033998)
			(xy 171.893681 -32.015991) (xy 171.844081 -31.99049) (xy 171.798723 -31.958039) (xy 171.758574 -31.91933)
			(xy 171.724488 -31.875187) (xy 171.697192 -31.826552) (xy 171.677269 -31.774461) (xy 171.665143 -31.720024)
			(xy 171.661072 -31.664402) (xy 171.144531 -31.664402) (xy 171.148501 -31.69138) (xy 171.14901 -31.719266)
			(xy 171.148501 -31.747152) (xy 171.140381 -31.802328) (xy 171.124313 -31.855735) (xy 171.100641 -31.906232)
			(xy 171.069868 -31.952745) (xy 171.032651 -31.994282) (xy 170.989783 -32.029957) (xy 170.942177 -32.059011)
			(xy 170.890848 -32.080823) (xy 170.836891 -32.094929) (xy 170.781454 -32.101029) (xy 170.72572 -32.098992)
			(xy 170.670877 -32.088862) (xy 170.618093 -32.070855) (xy 170.568493 -32.045354) (xy 170.523135 -32.012903)
			(xy 170.482986 -31.974194) (xy 170.4489 -31.930051) (xy 170.421604 -31.881416) (xy 170.401681 -31.829325)
			(xy 170.389555 -31.774888) (xy 170.385484 -31.719266) (xy 169.830848 -31.719266) (xy 169.81366 -31.75556)
			(xy 169.783714 -31.800828) (xy 169.76598 -31.821374) (xy 169.76471 -31.822644) (xy 169.763948 -31.823406)
			(xy 169.761916 -31.825692) (xy 169.761408 -31.826454) (xy 169.744132 -31.845225) (xy 169.705444 -31.878477)
			(xy 169.662676 -31.906286) (xy 169.616588 -31.928157) (xy 169.567999 -31.943701) (xy 169.542968 -31.948628)
			(xy 169.52468 -31.95193) (xy 169.501058 -31.97987) (xy 169.501058 -33.512506) (xy 169.50142 -33.521584)
			(xy 169.507763 -33.538595) (xy 169.519674 -33.552296) (xy 169.527474 -33.556956) (xy 169.531792 -33.559496)
			(xy 169.63136 -33.602168) (xy 169.661586 -33.59658) (xy 169.672762 -33.585658) (xy 169.694304 -33.565269)
			(xy 169.742523 -33.530733) (xy 169.795505 -33.504073) (xy 169.851973 -33.485931) (xy 169.910568 -33.476743)
			(xy 169.940224 -33.476184) (xy 169.967329 -33.476655) (xy 170.020995 -33.484322) (xy 170.073033 -33.499512)
			(xy 170.122396 -33.521919) (xy 170.168088 -33.551092) (xy 170.209188 -33.586441) (xy 170.244867 -33.627255)
			(xy 170.274405 -33.672711) (xy 170.297209 -33.721892) (xy 170.305476 -33.74771) (xy 170.30827 -33.756854)
			(xy 170.3197 -33.771586) (xy 170.38574 -33.81121) (xy 170.393868 -33.812734) (xy 170.416429 -33.8075)
			(xy 170.462404 -33.801893) (xy 170.485562 -33.801558) (xy 170.513299 -33.80206) (xy 170.568186 -33.8101)
			(xy 170.621332 -33.826002) (xy 170.671615 -33.849431) (xy 170.684188 -33.857692) (xy 171.590206 -33.857692)
			(xy 171.594277 -33.80207) (xy 171.606403 -33.747633) (xy 171.626326 -33.695542) (xy 171.653622 -33.646907)
			(xy 171.687708 -33.602764) (xy 171.727857 -33.564055) (xy 171.773215 -33.531604) (xy 171.822815 -33.506103)
			(xy 171.875599 -33.488096) (xy 171.930442 -33.477966) (xy 171.986176 -33.475929) (xy 172.041613 -33.482029)
			(xy 172.09557 -33.496135) (xy 172.146899 -33.517947) (xy 172.194505 -33.547001) (xy 172.237373 -33.582676)
			(xy 172.27459 -33.624213) (xy 172.305363 -33.670726) (xy 172.329035 -33.721223) (xy 172.345103 -33.77463)
			(xy 172.353223 -33.829806) (xy 172.353732 -33.857692) (xy 172.353223 -33.885578) (xy 172.345103 -33.940754)
			(xy 172.329035 -33.994161) (xy 172.305363 -34.044658) (xy 172.27459 -34.091171) (xy 172.237373 -34.132708)
			(xy 172.194505 -34.168383) (xy 172.146899 -34.197437) (xy 172.09557 -34.219249) (xy 172.041613 -34.233355)
			(xy 171.986176 -34.239455) (xy 171.930442 -34.237418) (xy 171.875599 -34.227288) (xy 171.822815 -34.209281)
			(xy 171.773215 -34.18378) (xy 171.727857 -34.151329) (xy 171.687708 -34.11262) (xy 171.653622 -34.068477)
			(xy 171.626326 -34.019842) (xy 171.606403 -33.967751) (xy 171.594277 -33.913314) (xy 171.590206 -33.857692)
			(xy 170.684188 -33.857692) (xy 170.717977 -33.879893) (xy 170.759439 -33.916746) (xy 170.79513 -33.959214)
			(xy 170.824296 -34.006401) (xy 170.846323 -34.057314) (xy 170.860747 -34.110879) (xy 170.86453 -34.138362)
			(xy 170.866054 -34.152078) (xy 170.867781 -34.178936) (xy 170.864577 -34.232661) (xy 170.853858 -34.285403)
			(xy 170.835837 -34.336116) (xy 170.810871 -34.383795) (xy 170.779456 -34.427495) (xy 170.761152 -34.447226)
			(xy 170.75912 -34.449004) (xy 170.758104 -34.450274) (xy 170.740043 -34.468759) (xy 170.699796 -34.50118)
			(xy 170.655536 -34.527865) (xy 170.608077 -34.548324) (xy 170.558289 -34.562182) (xy 170.507084 -34.569185)
			(xy 170.481244 -34.569654) (xy 170.480736 -34.569654) (xy 170.454331 -34.569209) (xy 170.402024 -34.561935)
			(xy 170.351218 -34.54752) (xy 170.302885 -34.52624) (xy 170.257946 -34.498501) (xy 170.21726 -34.464832)
			(xy 170.181603 -34.425877) (xy 170.151656 -34.382379) (xy 170.12799 -34.335167) (xy 170.11904 -34.31032)
			(xy 170.118786 -34.309558) (xy 170.114976 -34.298128) (xy 170.09999 -34.283142) (xy 170.095418 -34.278316)
			(xy 170.03014 -34.239708) (xy 170.01236 -34.23666) (xy 170.003216 -34.238184) (xy 169.986468 -34.241012)
			(xy 169.952636 -34.244062) (xy 169.935652 -34.24428) (xy 169.935398 -34.24428) (xy 169.906449 -34.243722)
			(xy 169.84922 -34.234939) (xy 169.793972 -34.217619) (xy 169.741971 -34.19216) (xy 169.694408 -34.159145)
			(xy 169.673016 -34.139632) (xy 169.667682 -34.134552) (xy 169.660062 -34.130742) (xy 169.649857 -34.126234)
			(xy 169.627583 -34.12556) (xy 169.617136 -34.129472) (xy 169.531792 -34.166302) (xy 169.522862 -34.170631)
			(xy 169.50896 -34.184766) (xy 169.501474 -34.203124) (xy 169.501058 -34.213038) (xy 169.501058 -35.264852)
			(xy 172.002448 -35.264852) (xy 172.006519 -35.20923) (xy 172.018645 -35.154793) (xy 172.038568 -35.102702)
			(xy 172.065864 -35.054067) (xy 172.09995 -35.009924) (xy 172.140099 -34.971215) (xy 172.185457 -34.938764)
			(xy 172.235057 -34.913263) (xy 172.287841 -34.895256) (xy 172.342684 -34.885126) (xy 172.398418 -34.883089)
			(xy 172.453855 -34.889189) (xy 172.507812 -34.903295) (xy 172.559141 -34.925107) (xy 172.606747 -34.954161)
			(xy 172.649615 -34.989836) (xy 172.674453 -35.017557) (xy 174.319833 -35.017557) (xy 174.319833 -34.963043)
			(xy 174.327592 -34.909085) (xy 174.342951 -34.856781) (xy 174.365598 -34.807195) (xy 174.395072 -34.761337)
			(xy 174.430773 -34.72014) (xy 174.471973 -34.684445) (xy 174.517835 -34.654976) (xy 174.567424 -34.632335)
			(xy 174.61973 -34.616982) (xy 174.673689 -34.60923) (xy 174.700946 -34.60877) (xy 174.718058 -34.608963)
			(xy 174.752145 -34.612014) (xy 174.769018 -34.614866) (xy 174.780284 -34.616265) (xy 174.802167 -34.610334)
			(xy 174.811182 -34.603436) (xy 174.835566 -34.582354) (xy 174.843955 -34.574429) (xy 174.853078 -34.553255)
			(xy 174.853092 -34.541714) (xy 174.852584 -34.52241) (xy 174.852584 -33.65881) (xy 174.853092 -33.638744)
			(xy 174.852935 -33.627233) (xy 174.843824 -33.606126) (xy 174.835566 -33.598104) (xy 174.811182 -33.577022)
			(xy 174.802194 -33.570071) (xy 174.780289 -33.564144) (xy 174.769018 -33.565592) (xy 174.752147 -33.568461)
			(xy 174.718059 -33.571514) (xy 174.700946 -33.571688) (xy 174.67369 -33.571268) (xy 174.619731 -33.563516)
			(xy 174.567425 -33.548163) (xy 174.517836 -33.525522) (xy 174.471975 -33.496054) (xy 174.430774 -33.460358)
			(xy 174.395074 -33.419162) (xy 174.3656 -33.373304) (xy 174.342953 -33.323719) (xy 174.327594 -33.271414)
			(xy 174.319835 -33.217456) (xy 174.319835 -33.162944) (xy 174.327594 -33.108986) (xy 174.342953 -33.056681)
			(xy 174.3656 -33.007096) (xy 174.395074 -32.961238) (xy 174.430774 -32.920042) (xy 174.471975 -32.884346)
			(xy 174.517836 -32.854878) (xy 174.567425 -32.832237) (xy 174.619731 -32.816884) (xy 174.67369 -32.809132)
			(xy 174.700946 -32.808672) (xy 174.727956 -32.809077) (xy 174.781436 -32.81669) (xy 174.833307 -32.831771)
			(xy 174.882532 -32.854018) (xy 174.928127 -32.882987) (xy 174.969179 -32.918098) (xy 175.004867 -32.958649)
			(xy 175.034479 -33.003829) (xy 175.057421 -33.052735) (xy 175.073234 -33.104387) (xy 175.077882 -33.130998)
			(xy 175.079406 -33.141666) (xy 175.090836 -33.159446) (xy 175.1711 -33.212786) (xy 175.191674 -33.216596)
			(xy 175.202342 -33.214056) (xy 175.228974 -33.20793) (xy 175.283222 -33.201306) (xy 175.310546 -33.200848)
			(xy 175.337871 -33.201302) (xy 175.392119 -33.207924) (xy 175.41875 -33.214056) (xy 175.429418 -33.216596)
			(xy 175.449992 -33.212786) (xy 175.530256 -33.159446) (xy 175.541686 -33.141666) (xy 175.54321 -33.130998)
			(xy 175.547866 -33.104393) (xy 175.563698 -33.052756) (xy 175.586652 -33.003866) (xy 175.616269 -32.958701)
			(xy 175.651959 -32.918162) (xy 175.693007 -32.883061) (xy 175.738595 -32.854098) (xy 175.787811 -32.831851)
			(xy 175.839671 -32.816766) (xy 175.893141 -32.809144) (xy 175.920146 -32.808672) (xy 175.947516 -32.809152)
			(xy 176.001695 -32.816964) (xy 176.054199 -32.832449) (xy 176.103946 -32.855288) (xy 176.149913 -32.885011)
			(xy 176.170844 -32.902652) (xy 176.177956 -32.908748) (xy 176.194974 -32.915098) (xy 176.280318 -32.915098)
			(xy 176.297336 -32.908748) (xy 176.304448 -32.902652) (xy 176.325396 -32.885032) (xy 176.371363 -32.855315)
			(xy 176.421107 -32.832475) (xy 176.473604 -32.81698) (xy 176.527778 -32.809148) (xy 176.555146 -32.808672)
			(xy 176.572258 -32.808865) (xy 176.606345 -32.811916) (xy 176.623218 -32.814768) (xy 176.634484 -32.816166)
			(xy 176.656366 -32.810236) (xy 176.665382 -32.803338) (xy 176.689766 -32.782256) (xy 176.698154 -32.77433)
			(xy 176.707278 -32.753157) (xy 176.707292 -32.741616) (xy 176.706784 -32.722312) (xy 176.706784 -31.858712)
			(xy 176.707292 -31.838646) (xy 176.707134 -31.827135) (xy 176.698024 -31.806028) (xy 176.689766 -31.798006)
			(xy 176.665382 -31.776924) (xy 176.656394 -31.769973) (xy 176.634489 -31.764046) (xy 176.623218 -31.765494)
			(xy 176.606347 -31.768363) (xy 176.572259 -31.771416) (xy 176.555146 -31.77159) (xy 176.527777 -31.771099)
			(xy 176.473598 -31.763288) (xy 176.421096 -31.747805) (xy 176.371348 -31.724968) (xy 176.32538 -31.695249)
			(xy 176.304448 -31.67761) (xy 176.297336 -31.671514) (xy 176.280572 -31.665164) (xy 176.194974 -31.665164)
			(xy 176.177956 -31.671514) (xy 176.171098 -31.677864) (xy 176.150127 -31.695496) (xy 176.104116 -31.725241)
			(xy 176.054322 -31.748093) (xy 176.001769 -31.763582) (xy 175.94754 -31.771388) (xy 175.920146 -31.771844)
			(xy 175.893167 -31.771424) (xy 175.839746 -31.763835) (xy 175.787929 -31.748789) (xy 175.738751 -31.726586)
			(xy 175.693196 -31.69767) (xy 175.652174 -31.662619) (xy 175.616505 -31.622133) (xy 175.586901 -31.577021)
			(xy 175.563955 -31.528186) (xy 175.548125 -31.476603) (xy 175.543464 -31.450026) (xy 175.541686 -31.439358)
			(xy 175.530256 -31.421832) (xy 175.449992 -31.368238) (xy 175.429418 -31.364682) (xy 175.419004 -31.367222)
			(xy 175.392302 -31.373292) (xy 175.337927 -31.379788) (xy 175.310546 -31.380176) (xy 175.283164 -31.379807)
			(xy 175.228788 -31.373308) (xy 175.202088 -31.367222) (xy 175.191674 -31.364682) (xy 175.1711 -31.368238)
			(xy 175.090836 -31.421832) (xy 175.079406 -31.439358) (xy 175.077628 -31.450026) (xy 175.072976 -31.4766)
			(xy 175.057119 -31.528166) (xy 175.034154 -31.576982) (xy 175.00454 -31.622077) (xy 174.968868 -31.662548)
			(xy 174.927849 -31.69759) (xy 174.882301 -31.726502) (xy 174.833135 -31.748709) (xy 174.78133 -31.763766)
			(xy 174.72792 -31.771374) (xy 174.700946 -31.771844) (xy 174.673694 -31.771312) (xy 174.619743 -31.763561)
			(xy 174.567444 -31.74821) (xy 174.517863 -31.725573) (xy 174.472009 -31.696109) (xy 174.430814 -31.660418)
			(xy 174.395119 -31.619228) (xy 174.365649 -31.573377) (xy 174.343006 -31.523799) (xy 174.327649 -31.471502)
			(xy 174.319891 -31.417552) (xy 174.319891 -31.363048) (xy 174.327649 -31.309098) (xy 174.343006 -31.256801)
			(xy 174.365649 -31.207223) (xy 174.395119 -31.161372) (xy 174.430814 -31.120182) (xy 174.472009 -31.084491)
			(xy 174.517863 -31.055027) (xy 174.567444 -31.03239) (xy 174.619743 -31.017039) (xy 174.673694 -31.009288)
			(xy 174.700946 -31.008828) (xy 174.718058 -31.009022) (xy 174.752145 -31.012072) (xy 174.769018 -31.014924)
			(xy 174.780283 -31.016332) (xy 174.802168 -31.010397) (xy 174.811182 -31.003494) (xy 174.835566 -30.982412)
			(xy 174.843927 -30.974462) (xy 174.853066 -30.953308) (xy 174.853092 -30.941772) (xy 174.852584 -30.922468)
			(xy 174.852584 -30.058868) (xy 174.853092 -30.038802) (xy 174.852902 -30.027294) (xy 174.843814 -30.006187)
			(xy 174.835566 -29.998162) (xy 174.811182 -29.97708) (xy 174.802197 -29.970126) (xy 174.780289 -29.964202)
			(xy 174.769018 -29.96565) (xy 174.752147 -29.968519) (xy 174.718059 -29.971572) (xy 174.700946 -29.971746)
			(xy 174.673694 -29.97121) (xy 174.619743 -29.963459) (xy 174.567445 -29.948108) (xy 174.517864 -29.925471)
			(xy 174.47201 -29.896007) (xy 174.430816 -29.860317) (xy 174.395121 -29.819127) (xy 174.365651 -29.773276)
			(xy 174.343008 -29.723698) (xy 174.327651 -29.671402) (xy 174.319893 -29.617452) (xy 174.319893 -29.562948)
			(xy 174.327651 -29.508998) (xy 174.343008 -29.456702) (xy 174.365651 -29.407124) (xy 174.395121 -29.361273)
			(xy 174.430816 -29.320083) (xy 174.47201 -29.284393) (xy 174.517864 -29.254929) (xy 174.567445 -29.232292)
			(xy 174.619743 -29.216941) (xy 174.673694 -29.20919) (xy 174.700946 -29.20873) (xy 174.727954 -29.209171)
			(xy 174.781431 -29.216782) (xy 174.833299 -29.231861) (xy 174.882522 -29.254106) (xy 174.928116 -29.283071)
			(xy 174.969167 -29.318177) (xy 175.004856 -29.358724) (xy 175.034469 -29.403899) (xy 175.057414 -29.452799)
			(xy 175.073232 -29.504447) (xy 175.077882 -29.531056) (xy 175.079406 -29.541724) (xy 175.090836 -29.559504)
			(xy 175.1711 -29.612844) (xy 175.191674 -29.616654) (xy 175.202342 -29.614114) (xy 175.22898 -29.608047)
			(xy 175.283228 -29.601556) (xy 175.310546 -29.60116) (xy 175.337864 -29.60155) (xy 175.392113 -29.608042)
			(xy 175.41875 -29.614114) (xy 175.429418 -29.616654) (xy 175.449992 -29.612844) (xy 175.530256 -29.559504)
			(xy 175.541686 -29.541724) (xy 175.54321 -29.531056) (xy 175.547911 -29.504459) (xy 175.563734 -29.452822)
			(xy 175.586681 -29.403932) (xy 175.616293 -29.358765) (xy 175.651977 -29.318226) (xy 175.693021 -29.283123)
			(xy 175.738605 -29.254158) (xy 175.787817 -29.231911) (xy 175.839675 -29.216825) (xy 175.893142 -29.209202)
			(xy 175.920146 -29.20873) (xy 175.947515 -29.20922) (xy 176.001694 -29.217031) (xy 176.054197 -29.232514)
			(xy 176.103944 -29.255351) (xy 176.149912 -29.285071) (xy 176.170844 -29.30271) (xy 176.177956 -29.308806)
			(xy 176.194974 -29.315156) (xy 176.280318 -29.315156) (xy 176.297336 -29.308806) (xy 176.304448 -29.30271)
			(xy 176.32539 -29.285083) (xy 176.37136 -29.255369) (xy 176.421105 -29.232531) (xy 176.473603 -29.217037)
			(xy 176.527777 -29.209206) (xy 176.555146 -29.20873) (xy 176.572258 -29.208924) (xy 176.606345 -29.211974)
			(xy 176.623218 -29.214826) (xy 176.634483 -29.216234) (xy 176.656368 -29.210299) (xy 176.665382 -29.203396)
			(xy 176.689766 -29.182314) (xy 176.698126 -29.174363) (xy 176.707266 -29.153209) (xy 176.707292 -29.141674)
			(xy 176.706784 -29.12237) (xy 176.706784 -28.25877) (xy 176.707292 -28.238704) (xy 176.7071 -28.227196)
			(xy 176.698014 -28.206089) (xy 176.689766 -28.198064) (xy 176.665382 -28.176982) (xy 176.656396 -28.170028)
			(xy 176.634489 -28.164104) (xy 176.623218 -28.165552) (xy 176.606347 -28.168421) (xy 176.572259 -28.171474)
			(xy 176.555146 -28.171648) (xy 176.527894 -28.171108) (xy 176.473944 -28.163357) (xy 176.421646 -28.148007)
			(xy 176.372065 -28.125369) (xy 176.326211 -28.095905) (xy 176.285017 -28.060216) (xy 176.249322 -28.019026)
			(xy 176.219853 -27.973175) (xy 176.197209 -27.923597) (xy 176.181853 -27.871301) (xy 176.174095 -27.817352)
			(xy 176.174095 -27.762848) (xy 176.181853 -27.708899) (xy 176.197209 -27.656603) (xy 176.219853 -27.607025)
			(xy 176.249322 -27.561174) (xy 176.285017 -27.519984) (xy 176.326211 -27.484295) (xy 176.372065 -27.454831)
			(xy 176.421646 -27.432193) (xy 176.473944 -27.416843) (xy 176.527894 -27.409092) (xy 176.555146 -27.408632)
			(xy 176.582154 -27.409071) (xy 176.635631 -27.416683) (xy 176.6875 -27.431762) (xy 176.736723 -27.454006)
			(xy 176.782316 -27.482972) (xy 176.823368 -27.518078) (xy 176.859057 -27.558625) (xy 176.88867 -27.6038)
			(xy 176.911614 -27.652701) (xy 176.927432 -27.704349) (xy 176.932082 -27.730958) (xy 176.933606 -27.741626)
			(xy 176.945036 -27.759406) (xy 177.0253 -27.812746) (xy 177.045874 -27.816556) (xy 177.056542 -27.814016)
			(xy 177.083174 -27.807889) (xy 177.137422 -27.801266) (xy 177.164746 -27.800808) (xy 177.186924 -27.801103)
			(xy 177.23107 -27.805429) (xy 177.252884 -27.809444) (xy 177.263298 -27.811476) (xy 177.28311 -27.807412)
			(xy 177.360072 -27.754072) (xy 177.370994 -27.737054) (xy 177.372772 -27.72664) (xy 177.377652 -27.700298)
			(xy 177.393869 -27.649237) (xy 177.41707 -27.600948) (xy 177.446799 -27.55638) (xy 177.482472 -27.51641)
			(xy 177.523387 -27.481825) (xy 177.568738 -27.453304) (xy 177.617633 -27.43141) (xy 177.669111 -27.416572)
			(xy 177.722159 -27.409082) (xy 177.748946 -27.408632) (xy 177.776198 -27.409041) (xy 177.830146 -27.416804)
			(xy 177.882441 -27.432164) (xy 177.932018 -27.454811) (xy 177.977867 -27.484281) (xy 178.019056 -27.519976)
			(xy 178.054746 -27.56117) (xy 178.084212 -27.607023) (xy 178.106852 -27.656602) (xy 178.122206 -27.708899)
			(xy 178.129962 -27.762848) (xy 178.129962 -27.817352) (xy 178.122206 -27.871301) (xy 178.106852 -27.923598)
			(xy 178.084212 -27.973177) (xy 178.054746 -28.01903) (xy 178.019056 -28.060224) (xy 177.977867 -28.095919)
			(xy 177.932018 -28.125389) (xy 177.882441 -28.148036) (xy 177.830146 -28.163396) (xy 177.776198 -28.171159)
			(xy 177.748946 -28.171648) (xy 177.737424 -28.171556) (xy 177.714421 -28.170157) (xy 177.702972 -28.168854)
			(xy 177.692058 -28.168132) (xy 177.671263 -28.174832) (xy 177.66284 -28.181808) (xy 177.638964 -28.203398)
			(xy 177.63111 -28.21125) (xy 177.622423 -28.231664) (xy 177.6222 -28.242768) (xy 177.622708 -28.25877)
			(xy 177.622708 -29.12237) (xy 177.622454 -29.137356) (xy 177.622583 -29.148441) (xy 177.631149 -29.168862)
			(xy 177.638964 -29.176726) (xy 177.66284 -29.198316) (xy 177.671248 -29.205316) (xy 177.692055 -29.212017)
			(xy 177.702972 -29.21127) (xy 177.71442 -29.209955) (xy 177.737423 -29.208559) (xy 177.748946 -29.208476)
			(xy 177.776194 -29.208997) (xy 177.830134 -29.216759) (xy 177.882421 -29.232117) (xy 177.931991 -29.25476)
			(xy 177.977833 -29.284226) (xy 178.019016 -29.319916) (xy 178.054701 -29.361104) (xy 178.084162 -29.40695)
			(xy 178.106799 -29.456522) (xy 178.122151 -29.508811) (xy 178.129906 -29.562752) (xy 178.129906 -29.617248)
			(xy 178.122151 -29.671189) (xy 178.106799 -29.723478) (xy 178.084162 -29.77305) (xy 178.054701 -29.818896)
			(xy 178.019016 -29.860084) (xy 177.977833 -29.895774) (xy 177.931991 -29.92524) (xy 177.882421 -29.947883)
			(xy 177.830134 -29.963241) (xy 177.776194 -29.971003) (xy 177.748946 -29.971492) (xy 177.7222 -29.97098)
			(xy 177.669234 -29.963493) (xy 177.617831 -29.948686) (xy 177.568999 -29.92685) (xy 177.523691 -29.898413)
			(xy 177.482797 -29.86393) (xy 177.447115 -29.824077) (xy 177.417345 -29.779634) (xy 177.394069 -29.73147)
			(xy 177.377743 -29.68053) (xy 177.372772 -29.654246) (xy 177.370994 -29.643832) (xy 177.360326 -29.626814)
			(xy 177.28311 -29.573728) (xy 177.263298 -29.569664) (xy 177.253138 -29.571696) (xy 177.231265 -29.575747)
			(xy 177.186989 -29.580071) (xy 177.164746 -29.580332) (xy 177.137358 -29.579884) (xy 177.082982 -29.573266)
			(xy 177.056288 -29.567124) (xy 177.045874 -29.564584) (xy 177.0253 -29.56814) (xy 176.945036 -29.621734)
			(xy 176.933606 -29.63926) (xy 176.931828 -29.649928) (xy 176.927178 -29.676502) (xy 176.91132 -29.728068)
			(xy 176.888355 -29.776885) (xy 176.858741 -29.821979) (xy 176.823068 -29.86245) (xy 176.782049 -29.897492)
			(xy 176.736502 -29.926404) (xy 176.687335 -29.948611) (xy 176.63553 -29.963668) (xy 176.58212 -29.971276)
			(xy 176.555146 -29.971746) (xy 176.527776 -29.971266) (xy 176.473597 -29.963454) (xy 176.421094 -29.947969)
			(xy 176.371346 -29.92513) (xy 176.32538 -29.895407) (xy 176.304448 -29.877766) (xy 176.297336 -29.87167)
			(xy 176.280318 -29.86532) (xy 176.194974 -29.86532) (xy 176.177956 -29.87167) (xy 176.170844 -29.877766)
			(xy 176.149902 -29.895393) (xy 176.103932 -29.925108) (xy 176.054187 -29.947946) (xy 176.001689 -29.96344)
			(xy 175.947515 -29.971271) (xy 175.920146 -29.971746) (xy 175.903034 -29.971554) (xy 175.868947 -29.968502)
			(xy 175.852074 -29.96565) (xy 175.840809 -29.964243) (xy 175.818925 -29.970179) (xy 175.80991 -29.97708)
			(xy 175.785526 -29.998162) (xy 175.777128 -30.006079) (xy 175.76801 -30.027259) (xy 175.768 -30.038802)
			(xy 175.768508 -30.058868) (xy 175.768508 -30.922468) (xy 175.768 -30.941772) (xy 175.76815 -30.953283)
			(xy 175.777266 -30.974391) (xy 175.785526 -30.982412) (xy 175.80991 -31.003494) (xy 175.8189 -31.010442)
			(xy 175.840804 -31.01637) (xy 175.852074 -31.014924) (xy 175.868945 -31.012055) (xy 175.903033 -31.009002)
			(xy 175.920146 -31.008828) (xy 175.947515 -31.009319) (xy 176.001694 -31.01713) (xy 176.054197 -31.032613)
			(xy 176.103944 -31.055449) (xy 176.149912 -31.085169) (xy 176.170844 -31.102808) (xy 176.177956 -31.108904)
			(xy 176.19472 -31.115254) (xy 176.280318 -31.115254) (xy 176.297336 -31.108904) (xy 176.304194 -31.102554)
			(xy 176.325133 -31.084881) (xy 176.371152 -31.055142) (xy 176.420954 -31.032298) (xy 176.473515 -31.016819)
			(xy 176.52775 -31.009023) (xy 176.555146 -31.008574) (xy 176.582156 -31.008978) (xy 176.635636 -31.01659)
			(xy 176.687507 -31.031671) (xy 176.736733 -31.053919) (xy 176.782327 -31.082888) (xy 176.823379 -31.117999)
			(xy 176.859068 -31.15855) (xy 176.888679 -31.203731) (xy 176.911621 -31.252636) (xy 176.927434 -31.304289)
			(xy 176.932082 -31.3309) (xy 176.933606 -31.341568) (xy 176.945036 -31.359348) (xy 177.0253 -31.412688)
			(xy 177.045874 -31.416498) (xy 177.056542 -31.413958) (xy 177.08318 -31.407891) (xy 177.137428 -31.4014)
			(xy 177.164746 -31.401004) (xy 177.186919 -31.401226) (xy 177.231065 -31.405429) (xy 177.252884 -31.409386)
			(xy 177.263298 -31.411418) (xy 177.28311 -31.407354) (xy 177.360072 -31.354014) (xy 177.370994 -31.336996)
			(xy 177.372772 -31.326582) (xy 177.377608 -31.300231) (xy 177.393832 -31.249171) (xy 177.41704 -31.200882)
			(xy 177.446776 -31.156315) (xy 177.482454 -31.116347) (xy 177.523373 -31.081763) (xy 177.568728 -31.053243)
			(xy 177.617627 -31.03135) (xy 177.669108 -31.016513) (xy 177.722158 -31.009024) (xy 177.748946 -31.008574)
			(xy 177.776194 -31.009099) (xy 177.830134 -31.016861) (xy 177.882421 -31.032219) (xy 177.93199 -31.054862)
			(xy 177.977832 -31.084328) (xy 178.019015 -31.120018) (xy 178.0547 -31.161205) (xy 178.08416 -31.207051)
			(xy 178.106797 -31.256623) (xy 178.122149 -31.308911) (xy 178.129904 -31.362852) (xy 178.129904 -31.417348)
			(xy 178.122149 -31.471289) (xy 178.106797 -31.523577) (xy 178.08416 -31.573149) (xy 178.0547 -31.618995)
			(xy 178.019015 -31.660182) (xy 177.977832 -31.695872) (xy 177.93199 -31.725338) (xy 177.882421 -31.747981)
			(xy 177.830134 -31.763339) (xy 177.776194 -31.771101) (xy 177.748946 -31.77159) (xy 177.737424 -31.771496)
			(xy 177.714421 -31.770096) (xy 177.702972 -31.768796) (xy 177.692058 -31.768063) (xy 177.671261 -31.77477)
			(xy 177.66284 -31.78175) (xy 177.638964 -31.80334) (xy 177.631137 -31.811214) (xy 177.622435 -31.831611)
			(xy 177.6222 -31.84271) (xy 177.622708 -31.858712) (xy 177.622708 -32.722312) (xy 177.6222 -32.737552)
			(xy 177.622381 -32.748665) (xy 177.631079 -32.769089) (xy 177.638964 -32.776922) (xy 177.66284 -32.798512)
			(xy 177.671249 -32.805511) (xy 177.692056 -32.812213) (xy 177.702972 -32.811466) (xy 177.71442 -32.810151)
			(xy 177.737423 -32.808755) (xy 177.748946 -32.808672) (xy 177.776194 -32.809201) (xy 177.830133 -32.816963)
			(xy 177.88242 -32.832321) (xy 177.931989 -32.854964) (xy 177.977831 -32.88443) (xy 178.019013 -32.920119)
			(xy 178.054698 -32.961306) (xy 178.084158 -33.007152) (xy 178.106795 -33.056723) (xy 178.122147 -33.109012)
			(xy 178.129902 -33.162952) (xy 178.129902 -33.217448) (xy 178.122147 -33.271388) (xy 178.106795 -33.323677)
			(xy 178.084158 -33.373248) (xy 178.054698 -33.419094) (xy 178.019013 -33.460281) (xy 177.977831 -33.49597)
			(xy 177.931989 -33.525436) (xy 177.88242 -33.548079) (xy 177.830133 -33.563437) (xy 177.776194 -33.571199)
			(xy 177.748946 -33.571688) (xy 177.722179 -33.571275) (xy 177.66917 -33.56381) (xy 177.617725 -33.549006)
			(xy 177.568855 -33.527154) (xy 177.523521 -33.498683) (xy 177.482614 -33.464153) (xy 177.446936 -33.424242)
			(xy 177.41719 -33.379734) (xy 177.39396 -33.331505) (xy 177.377701 -33.2805) (xy 177.372772 -33.254188)
			(xy 177.370994 -33.243774) (xy 177.360326 -33.226756) (xy 177.28311 -33.17367) (xy 177.263298 -33.169606)
			(xy 177.253138 -33.171638) (xy 177.231259 -33.175622) (xy 177.186984 -33.179819) (xy 177.164746 -33.18002)
			(xy 177.137364 -33.179653) (xy 177.082988 -33.173153) (xy 177.056288 -33.167066) (xy 177.045874 -33.164526)
			(xy 177.0253 -33.168082) (xy 176.945036 -33.221676) (xy 176.933606 -33.239202) (xy 176.931828 -33.24987)
			(xy 176.927134 -33.276436) (xy 176.911284 -33.328001) (xy 176.888325 -33.376819) (xy 176.858717 -33.421914)
			(xy 176.82305 -33.462387) (xy 176.782035 -33.49743) (xy 176.736492 -33.526344) (xy 176.687329 -33.548551)
			(xy 176.635526 -33.56361) (xy 176.582119 -33.571218) (xy 176.555146 -33.571688) (xy 176.527777 -33.571198)
			(xy 176.473598 -33.563386) (xy 176.421095 -33.547903) (xy 176.371348 -33.525067) (xy 176.32538 -33.495347)
			(xy 176.304448 -33.477708) (xy 176.297336 -33.471612) (xy 176.280318 -33.465262) (xy 176.194974 -33.465262)
			(xy 176.177956 -33.471612) (xy 176.170844 -33.477708) (xy 176.149907 -33.495341) (xy 176.103936 -33.525054)
			(xy 176.054189 -33.547891) (xy 176.00169 -33.563383) (xy 175.947515 -33.571213) (xy 175.920146 -33.571688)
			(xy 175.903034 -33.571495) (xy 175.868947 -33.568444) (xy 175.852074 -33.565592) (xy 175.840809 -33.564175)
			(xy 175.818923 -33.570116) (xy 175.80991 -33.577022) (xy 175.785526 -33.598104) (xy 175.777156 -33.606046)
			(xy 175.768022 -33.627207) (xy 175.768 -33.638744) (xy 175.768508 -33.65881) (xy 175.768508 -34.52241)
			(xy 175.768 -34.541714) (xy 175.768183 -34.553222) (xy 175.777276 -34.57433) (xy 175.785526 -34.582354)
			(xy 175.80991 -34.603436) (xy 175.818904 -34.610379) (xy 175.840804 -34.616313) (xy 175.852074 -34.614866)
			(xy 175.868945 -34.611998) (xy 175.903033 -34.608944) (xy 175.920146 -34.60877) (xy 175.947393 -34.609303)
			(xy 176.001333 -34.617065) (xy 176.053619 -34.632423) (xy 176.103188 -34.655065) (xy 176.14903 -34.684531)
			(xy 176.190212 -34.720221) (xy 176.225896 -34.761407) (xy 176.255357 -34.807253) (xy 176.277993 -34.856824)
			(xy 176.293345 -34.909112) (xy 176.3011 -34.963052) (xy 176.3011 -34.990024) (xy 177.366928 -34.990024)
			(xy 177.370999 -34.934402) (xy 177.383125 -34.879965) (xy 177.403048 -34.827874) (xy 177.430344 -34.779239)
			(xy 177.46443 -34.735096) (xy 177.504579 -34.696387) (xy 177.549937 -34.663936) (xy 177.599537 -34.638435)
			(xy 177.652321 -34.620428) (xy 177.707164 -34.610298) (xy 177.762898 -34.608261) (xy 177.818335 -34.614361)
			(xy 177.872292 -34.628467) (xy 177.923621 -34.650279) (xy 177.971227 -34.679333) (xy 178.014095 -34.715008)
			(xy 178.051312 -34.756545) (xy 178.082085 -34.803058) (xy 178.105757 -34.853555) (xy 178.121825 -34.906962)
			(xy 178.129945 -34.962138) (xy 178.130454 -34.990024) (xy 178.129945 -35.01791) (xy 178.121825 -35.073086)
			(xy 178.105757 -35.126493) (xy 178.082085 -35.17699) (xy 178.051312 -35.223503) (xy 178.014095 -35.26504)
			(xy 177.971227 -35.300715) (xy 177.923621 -35.329769) (xy 177.872292 -35.351581) (xy 177.818335 -35.365687)
			(xy 177.762898 -35.371787) (xy 177.707164 -35.36975) (xy 177.652321 -35.35962) (xy 177.599537 -35.341613)
			(xy 177.549937 -35.316112) (xy 177.504579 -35.283661) (xy 177.46443 -35.244952) (xy 177.430344 -35.200809)
			(xy 177.403048 -35.152174) (xy 177.383125 -35.100083) (xy 177.370999 -35.045646) (xy 177.366928 -34.990024)
			(xy 176.3011 -34.990024) (xy 176.3011 -35.017548) (xy 176.293345 -35.071488) (xy 176.277993 -35.123776)
			(xy 176.255357 -35.173347) (xy 176.225896 -35.219193) (xy 176.190212 -35.260379) (xy 176.14903 -35.296069)
			(xy 176.103188 -35.325535) (xy 176.053619 -35.348177) (xy 176.001333 -35.363535) (xy 175.947393 -35.371297)
			(xy 175.920146 -35.371786) (xy 175.893169 -35.37133) (xy 175.839751 -35.363743) (xy 175.787936 -35.348699)
			(xy 175.738761 -35.326499) (xy 175.693207 -35.297586) (xy 175.652186 -35.262539) (xy 175.616516 -35.222058)
			(xy 175.586911 -35.176952) (xy 175.563962 -35.128121) (xy 175.548127 -35.076543) (xy 175.543464 -35.049968)
			(xy 175.541686 -35.0393) (xy 175.530256 -35.021774) (xy 175.449992 -34.96818) (xy 175.429418 -34.964624)
			(xy 175.419004 -34.967164) (xy 175.392311 -34.973311) (xy 175.337934 -34.979928) (xy 175.310546 -34.980372)
			(xy 175.283158 -34.979923) (xy 175.228782 -34.973305) (xy 175.202088 -34.967164) (xy 175.191674 -34.964624)
			(xy 175.1711 -34.96818) (xy 175.090836 -35.021774) (xy 175.079406 -35.0393) (xy 175.077628 -35.049968)
			(xy 175.073008 -35.076548) (xy 175.057145 -35.128114) (xy 175.034175 -35.17693) (xy 175.004557 -35.222024)
			(xy 174.968881 -35.262494) (xy 174.927859 -35.297535) (xy 174.882309 -35.326446) (xy 174.83314 -35.348652)
			(xy 174.781333 -35.363709) (xy 174.727921 -35.371316) (xy 174.700946 -35.371786) (xy 174.673689 -35.37137)
			(xy 174.61973 -35.363618) (xy 174.567424 -35.348265) (xy 174.517835 -35.325624) (xy 174.471973 -35.296155)
			(xy 174.430773 -35.26046) (xy 174.395072 -35.219263) (xy 174.365598 -35.173405) (xy 174.342951 -35.123819)
			(xy 174.327592 -35.071515) (xy 174.319833 -35.017557) (xy 172.674453 -35.017557) (xy 172.686832 -35.031373)
			(xy 172.717605 -35.077886) (xy 172.741277 -35.128383) (xy 172.757345 -35.18179) (xy 172.765465 -35.236966)
			(xy 172.765974 -35.264852) (xy 172.765465 -35.292738) (xy 172.757345 -35.347914) (xy 172.741277 -35.401321)
			(xy 172.717605 -35.451818) (xy 172.686832 -35.498331) (xy 172.649615 -35.539868) (xy 172.606747 -35.575543)
			(xy 172.559141 -35.604597) (xy 172.507812 -35.626409) (xy 172.453855 -35.640515) (xy 172.398418 -35.646615)
			(xy 172.342684 -35.644578) (xy 172.287841 -35.634448) (xy 172.235057 -35.616441) (xy 172.185457 -35.59094)
			(xy 172.140099 -35.558489) (xy 172.09995 -35.51978) (xy 172.065864 -35.475637) (xy 172.038568 -35.427002)
			(xy 172.018645 -35.374911) (xy 172.006519 -35.320474) (xy 172.002448 -35.264852) (xy 169.501058 -35.264852)
			(xy 169.501058 -37.087048) (xy 173.300898 -37.087048) (xy 173.301384 -37.060445) (xy 173.308759 -37.007754)
			(xy 173.323387 -36.956599) (xy 173.344984 -36.907974) (xy 173.373129 -36.862823) (xy 173.407278 -36.822023)
			(xy 173.446766 -36.786366) (xy 173.468538 -36.771072) (xy 173.478471 -36.763552) (xy 173.490192 -36.7416)
			(xy 173.49089 -36.729162) (xy 173.49089 -36.644834) (xy 173.490237 -36.632381) (xy 173.478516 -36.610404)
			(xy 173.468538 -36.602924) (xy 173.44677 -36.587627) (xy 173.407291 -36.551961) (xy 173.373147 -36.511157)
			(xy 173.345002 -36.466008) (xy 173.323399 -36.417387) (xy 173.308758 -36.366237) (xy 173.301362 -36.31355)
			(xy 173.300898 -36.286948) (xy 173.3014 -36.259696) (xy 173.309151 -36.205746) (xy 173.324501 -36.153449)
			(xy 173.347138 -36.103868) (xy 173.376602 -36.058015) (xy 173.412292 -36.016821) (xy 173.453481 -35.981127)
			(xy 173.499331 -35.951658) (xy 173.548909 -35.929016) (xy 173.601205 -35.91366) (xy 173.655154 -35.905903)
			(xy 173.682406 -35.90544) (xy 173.686978 -35.90544) (xy 173.69663 -35.905694) (xy 173.713394 -35.899344)
			(xy 173.778926 -35.843464) (xy 173.787562 -35.827462) (xy 173.788832 -35.818064) (xy 173.793132 -35.791125)
			(xy 173.808445 -35.738765) (xy 173.83106 -35.689121) (xy 173.860516 -35.643204) (xy 173.896212 -35.60195)
			(xy 173.93742 -35.566203) (xy 173.9833 -35.536689) (xy 174.032916 -35.514012) (xy 174.085256 -35.498633)
			(xy 174.139254 -35.490867) (xy 174.16653 -35.490404) (xy 174.193781 -35.490868) (xy 174.247727 -35.498628)
			(xy 174.30002 -35.513986) (xy 174.349595 -35.53663) (xy 174.395443 -35.566098) (xy 174.436631 -35.601791)
			(xy 174.47232 -35.642981) (xy 174.501785 -35.688832) (xy 174.524424 -35.738408) (xy 174.539778 -35.790702)
			(xy 174.547534 -35.844649) (xy 174.547534 -35.899151) (xy 174.539778 -35.953098) (xy 174.524424 -36.005392)
			(xy 174.501785 -36.054968) (xy 174.47232 -36.100819) (xy 174.436631 -36.142009) (xy 174.395443 -36.177702)
			(xy 174.349595 -36.20717) (xy 174.30002 -36.229814) (xy 174.247727 -36.245172) (xy 174.193781 -36.252932)
			(xy 174.16653 -36.25342) (xy 174.161958 -36.25342) (xy 174.152306 -36.253166) (xy 174.135542 -36.259516)
			(xy 174.07001 -36.315396) (xy 174.061374 -36.331398) (xy 174.060104 -36.340796) (xy 174.055885 -36.366995)
			(xy 174.041203 -36.417988) (xy 174.019593 -36.466453) (xy 173.991473 -36.511455) (xy 173.988042 -36.515548)
			(xy 175.114202 -36.515548) (xy 175.118273 -36.459926) (xy 175.130399 -36.405489) (xy 175.150322 -36.353398)
			(xy 175.177618 -36.304763) (xy 175.211704 -36.26062) (xy 175.251853 -36.221911) (xy 175.297211 -36.18946)
			(xy 175.346811 -36.163959) (xy 175.399595 -36.145952) (xy 175.454438 -36.135822) (xy 175.510172 -36.133785)
			(xy 175.565609 -36.139885) (xy 175.619566 -36.153991) (xy 175.670895 -36.175803) (xy 175.718501 -36.204857)
			(xy 175.761369 -36.240532) (xy 175.798586 -36.282069) (xy 175.829359 -36.328582) (xy 175.853031 -36.379079)
			(xy 175.869099 -36.432486) (xy 175.877219 -36.487662) (xy 175.877728 -36.515548) (xy 175.877219 -36.543434)
			(xy 175.869099 -36.59861) (xy 175.853031 -36.652017) (xy 175.829359 -36.702514) (xy 175.798586 -36.749027)
			(xy 175.761369 -36.790564) (xy 175.718501 -36.826239) (xy 175.670895 -36.855293) (xy 175.619566 -36.877105)
			(xy 175.565609 -36.891211) (xy 175.510172 -36.897311) (xy 175.454438 -36.895274) (xy 175.399595 -36.885144)
			(xy 175.346811 -36.867137) (xy 175.297211 -36.841636) (xy 175.251853 -36.809185) (xy 175.211704 -36.770476)
			(xy 175.177618 -36.726333) (xy 175.150322 -36.677698) (xy 175.130399 -36.625607) (xy 175.118273 -36.57117)
			(xy 175.114202 -36.515548) (xy 173.988042 -36.515548) (xy 173.957386 -36.552123) (xy 173.91799 -36.587673)
			(xy 173.896274 -36.602924) (xy 173.886344 -36.610448) (xy 173.874621 -36.632397) (xy 173.873922 -36.644834)
			(xy 173.873922 -36.729162) (xy 173.874573 -36.741615) (xy 173.886295 -36.763593) (xy 173.896274 -36.771072)
			(xy 173.918043 -36.786368) (xy 173.957522 -36.822035) (xy 173.991665 -36.862838) (xy 174.01981 -36.907988)
			(xy 174.041413 -36.956609) (xy 174.056054 -37.007759) (xy 174.063449 -37.060446) (xy 174.063914 -37.087048)
			(xy 174.063308 -37.118807) (xy 174.052822 -37.181453) (xy 174.032082 -37.241489) (xy 174.017432 -37.269674)
			(xy 174.012098 -37.27958) (xy 174.010574 -37.301678) (xy 174.046388 -37.394896) (xy 174.06239 -37.41039)
			(xy 174.073058 -37.4142) (xy 174.097582 -37.42329) (xy 174.144113 -37.447168) (xy 174.186946 -37.47718)
			(xy 174.225276 -37.512763) (xy 174.258385 -37.553248) (xy 174.285653 -37.597878) (xy 174.306566 -37.645815)
			(xy 174.320735 -37.69616) (xy 174.327892 -37.747968) (xy 174.328328 -37.774118) (xy 174.327842 -37.801369)
			(xy 174.320086 -37.855317) (xy 174.304731 -37.907612) (xy 174.282089 -37.957189) (xy 174.252623 -38.003039)
			(xy 174.216932 -38.04423) (xy 174.175741 -38.079921) (xy 174.129891 -38.109387) (xy 174.080314 -38.132029)
			(xy 174.028019 -38.147384) (xy 173.974071 -38.15514) (xy 173.919569 -38.15514) (xy 173.865621 -38.147384)
			(xy 173.813326 -38.132029) (xy 173.763749 -38.109387) (xy 173.717899 -38.079921) (xy 173.676708 -38.04423)
			(xy 173.641017 -38.003039) (xy 173.611551 -37.957189) (xy 173.588909 -37.907612) (xy 173.573554 -37.855317)
			(xy 173.565798 -37.801369) (xy 173.565312 -37.774118) (xy 173.565902 -37.742358) (xy 173.576394 -37.679712)
			(xy 173.597141 -37.619676) (xy 173.611794 -37.591492) (xy 173.617128 -37.581586) (xy 173.618652 -37.559488)
			(xy 173.582838 -37.46627) (xy 173.566836 -37.450776) (xy 173.556168 -37.446966) (xy 173.531617 -37.437947)
			(xy 173.485086 -37.414057) (xy 173.442255 -37.384035) (xy 173.403927 -37.348443) (xy 173.370821 -37.307948)
			(xy 173.343557 -37.26331) (xy 173.322648 -37.215366) (xy 173.308484 -37.165015) (xy 173.301332 -37.113201)
			(xy 173.300898 -37.087048) (xy 169.501058 -37.087048) (xy 169.501058 -38.315138) (xy 174.518064 -38.315138)
			(xy 174.522135 -38.259516) (xy 174.534261 -38.205079) (xy 174.554184 -38.152988) (xy 174.58148 -38.104353)
			(xy 174.615566 -38.06021) (xy 174.655715 -38.021501) (xy 174.701073 -37.98905) (xy 174.750673 -37.963549)
			(xy 174.803457 -37.945542) (xy 174.8583 -37.935412) (xy 174.914034 -37.933375) (xy 174.969471 -37.939475)
			(xy 175.023428 -37.953581) (xy 175.074757 -37.975393) (xy 175.122363 -38.004447) (xy 175.165231 -38.040122)
			(xy 175.202448 -38.081659) (xy 175.233221 -38.128172) (xy 175.256893 -38.178669) (xy 175.272961 -38.232076)
			(xy 175.281081 -38.287252) (xy 175.28159 -38.315138) (xy 175.281081 -38.343024) (xy 175.272961 -38.3982)
			(xy 175.256893 -38.451607) (xy 175.233221 -38.502104) (xy 175.202448 -38.548617) (xy 175.165231 -38.590154)
			(xy 175.122363 -38.625829) (xy 175.074757 -38.654883) (xy 175.023428 -38.676695) (xy 174.969471 -38.690801)
			(xy 174.914034 -38.696901) (xy 174.8583 -38.694864) (xy 174.803457 -38.684734) (xy 174.750673 -38.666727)
			(xy 174.701073 -38.641226) (xy 174.655715 -38.608775) (xy 174.615566 -38.570066) (xy 174.58148 -38.525923)
			(xy 174.554184 -38.477288) (xy 174.534261 -38.425197) (xy 174.522135 -38.37076) (xy 174.518064 -38.315138)
			(xy 169.501058 -38.315138) (xy 169.501058 -42.426636) (xy 169.501224 -42.43279) (xy 169.504172 -42.44474)
			(xy 169.5069 -42.450258) (xy 169.514012 -42.463466) (xy 169.52849 -42.476166) (xy 169.537888 -42.479214)
			(xy 169.562749 -42.48812) (xy 169.609946 -42.511813) (xy 169.653431 -42.541778) (xy 169.692375 -42.577446)
			(xy 169.726037 -42.618136) (xy 169.753776 -42.663074) (xy 169.775064 -42.711403) (xy 169.789493 -42.762203)
			(xy 169.796791 -42.814505) (xy 169.797222 -42.84091) (xy 169.796742 -42.86843) (xy 169.788849 -42.9229)
			(xy 169.773225 -42.975675) (xy 169.750196 -43.025665) (xy 169.720236 -43.071836) (xy 169.683965 -43.113233)
			(xy 169.663364 -43.131486) (xy 169.66311 -43.13174) (xy 169.644209 -43.147906) (xy 169.602974 -43.175717)
			(xy 169.558473 -43.19793) (xy 169.535094 -43.206416) (xy 169.519854 -43.21175) (xy 169.501058 -43.238166)
			(xy 169.501058 -43.442636) (xy 169.501224 -43.44879) (xy 169.504172 -43.46074) (xy 169.5069 -43.466258)
			(xy 169.514012 -43.479466) (xy 169.52849 -43.492166) (xy 169.537888 -43.495214) (xy 169.562749 -43.50412)
			(xy 169.609946 -43.527813) (xy 169.653431 -43.557778) (xy 169.692375 -43.593446) (xy 169.726037 -43.634136)
			(xy 169.753776 -43.679074) (xy 169.775064 -43.727403) (xy 169.789493 -43.778203) (xy 169.796791 -43.830505)
			(xy 169.797222 -43.85691) (xy 169.796742 -43.88443) (xy 169.788849 -43.9389) (xy 169.773225 -43.991675)
			(xy 169.750196 -44.041665) (xy 169.720236 -44.087836) (xy 169.683965 -44.129233) (xy 169.663364 -44.147486)
			(xy 169.66311 -44.14774) (xy 169.644209 -44.163906) (xy 169.602974 -44.191717) (xy 169.558473 -44.21393)
			(xy 169.535094 -44.222416) (xy 169.519854 -44.22775) (xy 169.501058 -44.254166) (xy 169.501058 -44.458636)
			(xy 169.501224 -44.46479) (xy 169.504172 -44.47674) (xy 169.5069 -44.482258) (xy 169.514012 -44.495466)
			(xy 169.52849 -44.508166) (xy 169.537888 -44.511214) (xy 169.562749 -44.52012) (xy 169.609946 -44.543813)
			(xy 169.653431 -44.573778) (xy 169.692375 -44.609446) (xy 169.726037 -44.650136) (xy 169.753776 -44.695074)
			(xy 169.775064 -44.743403) (xy 169.789493 -44.794203) (xy 169.796791 -44.846505) (xy 169.797222 -44.87291)
			(xy 169.796742 -44.90043) (xy 169.788849 -44.9549) (xy 169.773225 -45.007675) (xy 169.750196 -45.057665)
			(xy 169.720236 -45.103836) (xy 169.683965 -45.145233) (xy 169.663364 -45.163486) (xy 169.66311 -45.16374)
			(xy 169.644209 -45.179906) (xy 169.602974 -45.207717) (xy 169.558473 -45.22993) (xy 169.535094 -45.238416)
			(xy 169.519854 -45.24375) (xy 169.501058 -45.270166) (xy 169.501058 -45.474636) (xy 169.501224 -45.48079)
			(xy 169.504172 -45.49274) (xy 169.5069 -45.498258) (xy 169.514012 -45.511466) (xy 169.52849 -45.524166)
			(xy 169.537888 -45.527214) (xy 169.562749 -45.53612) (xy 169.609946 -45.559813) (xy 169.653431 -45.589778)
			(xy 169.692375 -45.625446) (xy 169.726037 -45.666136) (xy 169.753776 -45.711074) (xy 169.775064 -45.759403)
			(xy 169.789493 -45.810203) (xy 169.796791 -45.862505) (xy 169.797222 -45.88891) (xy 169.796742 -45.91643)
			(xy 169.788849 -45.9709) (xy 169.773225 -46.023675) (xy 169.750196 -46.073665) (xy 169.720236 -46.119836)
			(xy 169.683965 -46.161233) (xy 169.663364 -46.179486) (xy 169.66311 -46.17974) (xy 169.644209 -46.195906)
			(xy 169.602974 -46.223717) (xy 169.558473 -46.24593) (xy 169.535094 -46.254416) (xy 169.519854 -46.25975)
			(xy 169.501058 -46.286166) (xy 169.501058 -47.021496) (xy 169.501701 -47.03405) (xy 169.513562 -47.056178)
			(xy 169.523664 -47.06366) (xy 169.527474 -47.0662) (xy 169.53611 -47.07128) (xy 169.542714 -47.073058)
			(xy 169.569397 -47.080725) (xy 169.620373 -47.102714) (xy 169.667623 -47.131861) (xy 169.710148 -47.16755)
			(xy 169.74705 -47.209026) (xy 169.77755 -47.255414) (xy 169.801002 -47.305734) (xy 169.816913 -47.358921)
			(xy 169.824945 -47.413854) (xy 169.825416 -47.441612) (xy 169.825416 -47.441866) (xy 169.824912 -47.469468)
			(xy 169.816934 -47.524093) (xy 169.801182 -47.577003) (xy 169.777984 -47.627098) (xy 169.747823 -47.673335)
			(xy 169.729912 -47.694342) (xy 169.729404 -47.69485) (xy 169.728134 -47.69612) (xy 169.709233 -47.717173)
			(xy 169.666299 -47.754018) (xy 169.618397 -47.784123) (xy 169.566577 -47.806827) (xy 169.539412 -47.814738)
			(xy 169.53865 -47.814992) (xy 169.53738 -47.8155) (xy 169.527099 -47.819086) (xy 169.510678 -47.833353)
			(xy 169.501638 -47.853138) (xy 169.501058 -47.864014) (xy 169.501058 -48.522636) (xy 169.501224 -48.52879)
			(xy 169.504172 -48.54074) (xy 169.5069 -48.546258) (xy 169.514012 -48.559466) (xy 169.52849 -48.572166)
			(xy 169.537888 -48.575214) (xy 169.562749 -48.58412) (xy 169.609946 -48.607813) (xy 169.653431 -48.637778)
			(xy 169.692375 -48.673446) (xy 169.726037 -48.714136) (xy 169.753776 -48.759074) (xy 169.775064 -48.807403)
			(xy 169.789493 -48.858203) (xy 169.796791 -48.910505) (xy 169.797222 -48.93691) (xy 169.796742 -48.96443)
			(xy 169.788849 -49.0189) (xy 169.773225 -49.071675) (xy 169.750196 -49.121665) (xy 169.720236 -49.167836)
			(xy 169.683965 -49.209233) (xy 169.663364 -49.227486) (xy 169.66311 -49.22774) (xy 169.644209 -49.243906)
			(xy 169.602974 -49.271717) (xy 169.558473 -49.29393) (xy 169.535094 -49.302416) (xy 169.519854 -49.30775)
			(xy 169.501058 -49.334166) (xy 169.501058 -49.538636) (xy 169.501224 -49.54479) (xy 169.504172 -49.55674)
			(xy 169.5069 -49.562258) (xy 169.514012 -49.575466) (xy 169.52849 -49.588166) (xy 169.537888 -49.591214)
			(xy 169.562749 -49.60012) (xy 169.566394 -49.60195) (xy 170.391082 -49.60195) (xy 170.391082 -49.54745)
			(xy 170.398837 -49.493505) (xy 170.414191 -49.441213) (xy 170.43683 -49.391638) (xy 170.466294 -49.34579)
			(xy 170.501982 -49.3046) (xy 170.543169 -49.268909) (xy 170.589015 -49.239443) (xy 170.638589 -49.2168)
			(xy 170.69088 -49.201443) (xy 170.744824 -49.193684) (xy 170.772074 -49.193196) (xy 170.799444 -49.193678)
			(xy 170.853622 -49.201492) (xy 170.906125 -49.216978) (xy 170.955872 -49.239816) (xy 171.00184 -49.269537)
			(xy 171.022772 -49.287176) (xy 171.029884 -49.293272) (xy 171.046902 -49.299622) (xy 171.132246 -49.299622)
			(xy 171.149264 -49.293272) (xy 171.156376 -49.287176) (xy 171.177309 -49.269535) (xy 171.223277 -49.239811)
			(xy 171.273023 -49.216965) (xy 171.325525 -49.201469) (xy 171.379703 -49.19364) (xy 171.434445 -49.19364)
			(xy 171.488623 -49.201469) (xy 171.541125 -49.216965) (xy 171.590871 -49.239811) (xy 171.636839 -49.269535)
			(xy 171.657772 -49.287176) (xy 171.664884 -49.293272) (xy 171.681902 -49.299622) (xy 171.767246 -49.299622)
			(xy 171.784264 -49.293272) (xy 171.791376 -49.287176) (xy 171.812303 -49.269531) (xy 171.858278 -49.239821)
			(xy 171.908027 -49.216986) (xy 171.960528 -49.201497) (xy 172.014705 -49.19367) (xy 172.042074 -49.193196)
			(xy 172.068391 -49.193621) (xy 172.120526 -49.200847) (xy 172.171175 -49.215166) (xy 172.219377 -49.236305)
			(xy 172.264218 -49.263866) (xy 172.304849 -49.297324) (xy 172.322998 -49.316386) (xy 172.33052 -49.323787)
			(xy 172.3498 -49.332312) (xy 172.360336 -49.332896) (xy 172.435012 -49.332896) (xy 172.445564 -49.332388)
			(xy 172.464859 -49.323838) (xy 172.47235 -49.316386) (xy 172.490457 -49.29728) (xy 172.531084 -49.263805)
			(xy 172.57593 -49.236238) (xy 172.624143 -49.215104) (xy 172.674805 -49.200805) (xy 172.726953 -49.193613)
			(xy 172.753274 -49.193196) (xy 172.780528 -49.19365) (xy 172.834483 -49.201404) (xy 172.886784 -49.216758)
			(xy 172.936368 -49.239399) (xy 172.982225 -49.268866) (xy 173.023421 -49.30456) (xy 173.059118 -49.345754)
			(xy 173.088589 -49.391609) (xy 173.111233 -49.441191) (xy 173.126591 -49.493492) (xy 173.134349 -49.547446)
			(xy 173.134349 -49.601954) (xy 173.126591 -49.655908) (xy 173.111233 -49.708209) (xy 173.088589 -49.757791)
			(xy 173.059118 -49.803646) (xy 173.023421 -49.84484) (xy 172.982225 -49.880534) (xy 172.936368 -49.910001)
			(xy 172.886784 -49.932642) (xy 172.834483 -49.947996) (xy 172.780528 -49.95575) (xy 172.753274 -49.956212)
			(xy 172.726958 -49.955752) (xy 172.674825 -49.948533) (xy 172.624177 -49.934221) (xy 172.575975 -49.913088)
			(xy 172.531133 -49.885534) (xy 172.4905 -49.852082) (xy 172.47235 -49.833022) (xy 172.464846 -49.8256)
			(xy 172.445553 -49.817086) (xy 172.435012 -49.816512) (xy 172.360336 -49.816512) (xy 172.349786 -49.817043)
			(xy 172.330491 -49.825577) (xy 172.322998 -49.833022) (xy 172.304849 -49.852087) (xy 172.264233 -49.88557)
			(xy 172.219396 -49.913144) (xy 172.171191 -49.934286) (xy 172.120536 -49.948592) (xy 172.068393 -49.955791)
			(xy 172.042074 -49.956212) (xy 172.014703 -49.955758) (xy 171.960524 -49.947937) (xy 171.908021 -49.932445)
			(xy 171.858274 -49.909601) (xy 171.812308 -49.879874) (xy 171.791376 -49.862232) (xy 171.784264 -49.856136)
			(xy 171.767246 -49.849786) (xy 171.681902 -49.849786) (xy 171.664884 -49.856136) (xy 171.657772 -49.862232)
			(xy 171.636839 -49.879873) (xy 171.590871 -49.909597) (xy 171.541125 -49.932443) (xy 171.488623 -49.947939)
			(xy 171.434445 -49.955768) (xy 171.379703 -49.955768) (xy 171.325525 -49.947939) (xy 171.273023 -49.932443)
			(xy 171.223277 -49.909597) (xy 171.177309 -49.879873) (xy 171.156376 -49.862232) (xy 171.149264 -49.856136)
			(xy 171.132246 -49.849786) (xy 171.046902 -49.849786) (xy 171.029884 -49.856136) (xy 171.022772 -49.862232)
			(xy 171.001828 -49.879856) (xy 170.955858 -49.909569) (xy 170.906113 -49.932407) (xy 170.853616 -49.947902)
			(xy 170.799442 -49.955735) (xy 170.772074 -49.956212) (xy 170.744824 -49.955716) (xy 170.69088 -49.947957)
			(xy 170.638589 -49.9326) (xy 170.589015 -49.909957) (xy 170.543169 -49.880491) (xy 170.501982 -49.8448)
			(xy 170.466294 -49.80361) (xy 170.43683 -49.757762) (xy 170.414191 -49.708187) (xy 170.398837 -49.655895)
			(xy 170.391082 -49.60195) (xy 169.566394 -49.60195) (xy 169.609946 -49.623813) (xy 169.653431 -49.653778)
			(xy 169.692375 -49.689446) (xy 169.726037 -49.730136) (xy 169.753776 -49.775074) (xy 169.775064 -49.823403)
			(xy 169.789493 -49.874203) (xy 169.796791 -49.926505) (xy 169.797222 -49.95291) (xy 169.796742 -49.98043)
			(xy 169.788849 -50.0349) (xy 169.773225 -50.087675) (xy 169.750196 -50.137665) (xy 169.720236 -50.183836)
			(xy 169.683965 -50.225233) (xy 169.663364 -50.243486) (xy 169.66311 -50.24374) (xy 169.644209 -50.259906)
			(xy 169.602974 -50.287717) (xy 169.558473 -50.30993) (xy 169.535094 -50.318416) (xy 169.519854 -50.32375)
			(xy 169.501058 -50.350166) (xy 169.501058 -50.606706) (xy 169.501558 -50.617522) (xy 169.510461 -50.637236)
			(xy 169.526688 -50.651541) (xy 169.536872 -50.65522) (xy 169.538904 -50.655982) (xy 169.564294 -50.664509)
			(xy 169.61258 -50.687686) (xy 169.657146 -50.717395) (xy 169.697113 -50.753051) (xy 169.731695 -50.79395)
			(xy 169.760211 -50.839289) (xy 169.782098 -50.888173) (xy 169.796926 -50.93964) (xy 169.804403 -50.992676)
			(xy 169.804842 -51.019456) (xy 169.804312 -51.048017) (xy 169.795807 -51.104501) (xy 169.77898 -51.159088)
			(xy 169.754208 -51.210558) (xy 169.722042 -51.257763) (xy 169.702988 -51.279044) (xy 169.69994 -51.282346)
			(xy 169.699686 -51.2826) (xy 169.692574 -51.29022) (xy 169.670554 -51.312041) (xy 169.620761 -51.348963)
			(xy 169.565658 -51.377357) (xy 169.536364 -51.387502) (xy 169.52849 -51.390042) (xy 169.515536 -51.399186)
			(xy 169.510964 -51.40579) (xy 169.506404 -51.41243) (xy 169.501346 -51.427713) (xy 169.501058 -51.435762)
			(xy 169.501058 -51.622706) (xy 169.501558 -51.633522) (xy 169.510461 -51.653236) (xy 169.526688 -51.667541)
			(xy 169.536872 -51.67122) (xy 169.538904 -51.671982) (xy 169.564294 -51.680509) (xy 169.582092 -51.689052)
			(xy 170.355477 -51.689052) (xy 170.355477 -51.634548) (xy 170.363234 -51.580599) (xy 170.37859 -51.528303)
			(xy 170.401232 -51.478725) (xy 170.4307 -51.432874) (xy 170.466393 -51.391683) (xy 170.507585 -51.355991)
			(xy 170.553437 -51.326526) (xy 170.603016 -51.303885) (xy 170.655313 -51.288531) (xy 170.709262 -51.280776)
			(xy 170.736514 -51.280314) (xy 170.763885 -51.280768) (xy 170.818064 -51.288589) (xy 170.870568 -51.30408)
			(xy 170.920314 -51.326925) (xy 170.966281 -51.356652) (xy 170.987212 -51.374294) (xy 170.994324 -51.38039)
			(xy 171.011342 -51.38674) (xy 171.096686 -51.38674) (xy 171.113704 -51.38039) (xy 171.120816 -51.374294)
			(xy 171.141768 -51.35668) (xy 171.187736 -51.326965) (xy 171.237478 -51.304124) (xy 171.289974 -51.288627)
			(xy 171.344146 -51.280792) (xy 171.371514 -51.280314) (xy 171.389857 -51.280541) (xy 171.42637 -51.284108)
			(xy 171.444412 -51.287426) (xy 171.455334 -51.289458) (xy 171.475908 -51.284632) (xy 171.553886 -51.225704)
			(xy 171.5643 -51.206908) (xy 171.565062 -51.195986) (xy 171.567948 -51.167701) (xy 171.580986 -51.112363)
			(xy 171.602084 -51.059569) (xy 171.630775 -51.010486) (xy 171.666425 -50.966199) (xy 171.686982 -50.946558)
			(xy 171.694401 -50.939052) (xy 171.702916 -50.91976) (xy 171.703492 -50.90922) (xy 171.703492 -50.834544)
			(xy 171.702955 -50.823995) (xy 171.694426 -50.804699) (xy 171.686982 -50.797206) (xy 171.667921 -50.779052)
			(xy 171.634438 -50.738438) (xy 171.606863 -50.693602) (xy 171.585721 -50.645398) (xy 171.571414 -50.594743)
			(xy 171.564213 -50.542601) (xy 171.563792 -50.516282) (xy 171.564278 -50.489031) (xy 171.572034 -50.435083)
			(xy 171.587389 -50.382788) (xy 171.610031 -50.333211) (xy 171.639497 -50.287361) (xy 171.675188 -50.24617)
			(xy 171.716379 -50.210479) (xy 171.762229 -50.181013) (xy 171.811806 -50.158371) (xy 171.864101 -50.143016)
			(xy 171.918049 -50.13526) (xy 171.972551 -50.13526) (xy 172.026499 -50.143016) (xy 172.078794 -50.158371)
			(xy 172.128371 -50.181013) (xy 172.174221 -50.210479) (xy 172.215412 -50.24617) (xy 172.251103 -50.287361)
			(xy 172.280569 -50.333211) (xy 172.303211 -50.382788) (xy 172.318566 -50.435083) (xy 172.326322 -50.489031)
			(xy 172.326808 -50.516282) (xy 172.326387 -50.542599) (xy 172.31916 -50.594734) (xy 172.30484 -50.645383)
			(xy 172.2837 -50.693585) (xy 172.256139 -50.738426) (xy 172.222681 -50.779057) (xy 172.203618 -50.797206)
			(xy 172.196214 -50.804726) (xy 172.187691 -50.824007) (xy 172.187108 -50.834544) (xy 172.187108 -50.90922)
			(xy 172.187665 -50.919767) (xy 172.19618 -50.939062) (xy 172.203618 -50.946558) (xy 172.222661 -50.964729)
			(xy 172.256146 -51.00534) (xy 172.283723 -51.050172) (xy 172.304868 -51.098373) (xy 172.31918 -51.149025)
			(xy 172.326384 -51.201164) (xy 172.326808 -51.227482) (xy 172.326328 -51.254734) (xy 172.318573 -51.308685)
			(xy 172.30322 -51.360982) (xy 172.280579 -51.410562) (xy 172.251113 -51.456416) (xy 172.215421 -51.497608)
			(xy 172.17423 -51.533302) (xy 172.128378 -51.562771) (xy 172.078799 -51.585413) (xy 172.026502 -51.60077)
			(xy 171.972552 -51.608527) (xy 171.9453 -51.60899) (xy 171.926957 -51.608761) (xy 171.890444 -51.605196)
			(xy 171.872402 -51.601878) (xy 171.86148 -51.599846) (xy 171.840906 -51.604672) (xy 171.762928 -51.6636)
			(xy 171.752514 -51.682396) (xy 171.751752 -51.693318) (xy 171.74886 -51.721576) (xy 171.735827 -51.776862)
			(xy 171.714742 -51.829605) (xy 171.686071 -51.878639) (xy 171.650446 -51.92288) (xy 171.608656 -51.96135)
			(xy 171.561625 -51.9932) (xy 171.510391 -52.017725) (xy 171.456088 -52.034384) (xy 171.399915 -52.042807)
			(xy 171.371514 -52.04333) (xy 171.344143 -52.042873) (xy 171.289963 -52.035055) (xy 171.237459 -52.019565)
			(xy 171.187712 -51.996721) (xy 171.141747 -51.966993) (xy 171.120816 -51.94935) (xy 171.113704 -51.943254)
			(xy 171.096686 -51.936904) (xy 171.011342 -51.936904) (xy 170.994324 -51.943254) (xy 170.987212 -51.94935)
			(xy 170.96628 -51.966989) (xy 170.920308 -51.996703) (xy 170.87056 -52.019539) (xy 170.818059 -52.03503)
			(xy 170.763883 -52.042857) (xy 170.736514 -52.04333) (xy 170.709262 -52.042824) (xy 170.655313 -52.035069)
			(xy 170.603016 -52.019715) (xy 170.553437 -51.997074) (xy 170.507585 -51.967609) (xy 170.466393 -51.931917)
			(xy 170.4307 -51.890726) (xy 170.401232 -51.844875) (xy 170.37859 -51.795297) (xy 170.363234 -51.743001)
			(xy 170.355477 -51.689052) (xy 169.582092 -51.689052) (xy 169.61258 -51.703686) (xy 169.657146 -51.733395)
			(xy 169.697113 -51.769051) (xy 169.731695 -51.80995) (xy 169.760211 -51.855289) (xy 169.782098 -51.904173)
			(xy 169.796926 -51.95564) (xy 169.804403 -52.008676) (xy 169.804842 -52.035456) (xy 169.804312 -52.064017)
			(xy 169.795807 -52.120501) (xy 169.77898 -52.175088) (xy 169.754208 -52.226558) (xy 169.722042 -52.273763)
			(xy 169.702988 -52.295044) (xy 169.69994 -52.298346) (xy 169.699686 -52.2986) (xy 169.692574 -52.30622)
			(xy 169.670554 -52.328041) (xy 169.620761 -52.364963) (xy 169.565658 -52.393357) (xy 169.536364 -52.403502)
			(xy 169.52849 -52.406042) (xy 169.515536 -52.415186) (xy 169.510964 -52.42179) (xy 169.506404 -52.42843)
			(xy 169.501346 -52.443713) (xy 169.501058 -52.451762) (xy 169.501058 -52.564153) (xy 171.92723 -52.564153)
			(xy 171.92723 -52.509647) (xy 171.934986 -52.455695) (xy 171.950342 -52.403397) (xy 171.972983 -52.353816)
			(xy 172.00245 -52.307961) (xy 172.038142 -52.266766) (xy 172.079334 -52.23107) (xy 172.125186 -52.2016)
			(xy 172.174765 -52.178954) (xy 172.227062 -52.163594) (xy 172.281013 -52.155832) (xy 172.308266 -52.155344)
			(xy 172.335636 -52.155819) (xy 172.389815 -52.163633) (xy 172.442319 -52.17912) (xy 172.492066 -52.20196)
			(xy 172.538032 -52.231683) (xy 172.558964 -52.249324) (xy 172.566076 -52.25542) (xy 172.583094 -52.26177)
			(xy 172.668438 -52.26177) (xy 172.685456 -52.25542) (xy 172.692568 -52.249324) (xy 172.713504 -52.23169)
			(xy 172.759476 -52.201977) (xy 172.809222 -52.179139) (xy 172.861722 -52.163647) (xy 172.915897 -52.155818)
			(xy 172.943266 -52.155344) (xy 172.970517 -52.155901) (xy 173.024465 -52.163653) (xy 173.07676 -52.179004)
			(xy 173.126338 -52.201642) (xy 173.17219 -52.231105) (xy 173.213382 -52.266794) (xy 173.249074 -52.307983)
			(xy 173.278542 -52.353832) (xy 173.301184 -52.403408) (xy 173.31654 -52.455702) (xy 173.324297 -52.509649)
			(xy 173.324297 -52.564151) (xy 173.31654 -52.618098) (xy 173.301184 -52.670392) (xy 173.278542 -52.719968)
			(xy 173.249074 -52.765817) (xy 173.213382 -52.807006) (xy 173.17219 -52.842695) (xy 173.126338 -52.872158)
			(xy 173.07676 -52.894796) (xy 173.024465 -52.910147) (xy 172.970517 -52.917899) (xy 172.943266 -52.91836)
			(xy 172.915895 -52.917924) (xy 172.861714 -52.9101) (xy 172.80921 -52.894605) (xy 172.759464 -52.871756)
			(xy 172.713498 -52.842025) (xy 172.692568 -52.82438) (xy 172.685456 -52.818284) (xy 172.668438 -52.811934)
			(xy 172.583094 -52.811934) (xy 172.566076 -52.818284) (xy 172.558964 -52.82438) (xy 172.538016 -52.841999)
			(xy 172.492048 -52.871715) (xy 172.442304 -52.894555) (xy 172.389807 -52.910051) (xy 172.335634 -52.917884)
			(xy 172.308266 -52.91836) (xy 172.281013 -52.917968) (xy 172.227062 -52.910206) (xy 172.174765 -52.894846)
			(xy 172.125186 -52.8722) (xy 172.079334 -52.84273) (xy 172.038142 -52.807034) (xy 172.00245 -52.765839)
			(xy 171.972983 -52.719984) (xy 171.950342 -52.670403) (xy 171.934986 -52.618105) (xy 171.92723 -52.564153)
			(xy 169.501058 -52.564153) (xy 169.501058 -52.638706) (xy 169.501558 -52.649522) (xy 169.510461 -52.669236)
			(xy 169.526688 -52.683541) (xy 169.536872 -52.68722) (xy 169.538904 -52.687982) (xy 169.564294 -52.696509)
			(xy 169.61258 -52.719686) (xy 169.657146 -52.749395) (xy 169.697113 -52.785051) (xy 169.731695 -52.82595)
			(xy 169.760211 -52.871289) (xy 169.782098 -52.920173) (xy 169.796926 -52.97164) (xy 169.804403 -53.024676)
			(xy 169.804842 -53.051456) (xy 169.804312 -53.080017) (xy 169.795807 -53.136501) (xy 169.77898 -53.191088)
			(xy 169.754208 -53.242558) (xy 169.722042 -53.289763) (xy 169.702988 -53.311044) (xy 169.69994 -53.314346)
			(xy 169.699686 -53.3146) (xy 169.692574 -53.32222) (xy 169.670554 -53.344041) (xy 169.620761 -53.380963)
			(xy 169.565658 -53.409357) (xy 169.536364 -53.419502) (xy 169.52849 -53.422042) (xy 169.515536 -53.431186)
			(xy 169.510964 -53.43779) (xy 169.506404 -53.44443) (xy 169.501346 -53.459713) (xy 169.501058 -53.467762)
			(xy 169.501058 -53.654706) (xy 169.501558 -53.665522) (xy 169.510461 -53.685236) (xy 169.526688 -53.699541)
			(xy 169.536872 -53.70322) (xy 169.538904 -53.703982) (xy 169.564294 -53.712509) (xy 169.61258 -53.735686)
			(xy 169.657146 -53.765395) (xy 169.697113 -53.801051) (xy 169.731695 -53.84195) (xy 169.760211 -53.887289)
			(xy 169.782098 -53.936173) (xy 169.796926 -53.98764) (xy 169.804403 -54.040676) (xy 169.804842 -54.067456)
			(xy 169.804312 -54.096017) (xy 169.795807 -54.152501) (xy 169.77898 -54.207088) (xy 169.763666 -54.238906)
			(xy 176.486056 -54.238906) (xy 176.490127 -54.183284) (xy 176.502253 -54.128847) (xy 176.522176 -54.076756)
			(xy 176.549472 -54.028121) (xy 176.583558 -53.983978) (xy 176.623707 -53.945269) (xy 176.669065 -53.912818)
			(xy 176.718665 -53.887317) (xy 176.771449 -53.86931) (xy 176.826292 -53.85918) (xy 176.882026 -53.857143)
			(xy 176.937463 -53.863243) (xy 176.99142 -53.877349) (xy 177.042749 -53.899161) (xy 177.090355 -53.928215)
			(xy 177.133223 -53.96389) (xy 177.17044 -54.005427) (xy 177.201213 -54.05194) (xy 177.224885 -54.102437)
			(xy 177.240953 -54.155844) (xy 177.249073 -54.21102) (xy 177.249582 -54.238906) (xy 177.249073 -54.266792)
			(xy 177.240953 -54.321968) (xy 177.224885 -54.375375) (xy 177.201213 -54.425872) (xy 177.17044 -54.472385)
			(xy 177.133223 -54.513922) (xy 177.090355 -54.549597) (xy 177.042749 -54.578651) (xy 176.99142 -54.600463)
			(xy 176.937463 -54.614569) (xy 176.882026 -54.620669) (xy 176.826292 -54.618632) (xy 176.771449 -54.608502)
			(xy 176.718665 -54.590495) (xy 176.669065 -54.564994) (xy 176.623707 -54.532543) (xy 176.583558 -54.493834)
			(xy 176.549472 -54.449691) (xy 176.522176 -54.401056) (xy 176.502253 -54.348965) (xy 176.490127 -54.294528)
			(xy 176.486056 -54.238906) (xy 169.763666 -54.238906) (xy 169.754208 -54.258558) (xy 169.722042 -54.305763)
			(xy 169.702988 -54.327044) (xy 169.69994 -54.330346) (xy 169.699686 -54.3306) (xy 169.692574 -54.33822)
			(xy 169.670554 -54.360041) (xy 169.620761 -54.396963) (xy 169.565658 -54.425357) (xy 169.536364 -54.435502)
			(xy 169.52849 -54.438042) (xy 169.515536 -54.447186) (xy 169.510964 -54.45379) (xy 169.506404 -54.46043)
			(xy 169.501346 -54.475713) (xy 169.501058 -54.483762) (xy 169.501058 -54.670706) (xy 169.501558 -54.681522)
			(xy 169.510461 -54.701236) (xy 169.526688 -54.715541) (xy 169.536872 -54.71922) (xy 169.538904 -54.719982)
			(xy 169.564294 -54.728509) (xy 169.61258 -54.751686) (xy 169.657146 -54.781395) (xy 169.697113 -54.817051)
			(xy 169.731695 -54.85795) (xy 169.760211 -54.903289) (xy 169.782098 -54.952173) (xy 169.792723 -54.989051)
			(xy 172.001168 -54.989051) (xy 172.001168 -54.934549) (xy 172.008924 -54.880602) (xy 172.024278 -54.828307)
			(xy 172.046919 -54.77873) (xy 172.076384 -54.732879) (xy 172.112074 -54.691688) (xy 172.153263 -54.655996)
			(xy 172.199112 -54.626528) (xy 172.248688 -54.603885) (xy 172.300982 -54.588528) (xy 172.354929 -54.580769)
			(xy 172.38218 -54.580282) (xy 172.410271 -54.580793) (xy 172.465847 -54.589017) (xy 172.519616 -54.605305)
			(xy 172.570413 -54.629305) (xy 172.61714 -54.660498) (xy 172.658786 -54.698208) (xy 172.694449 -54.741619)
			(xy 172.709332 -54.765448) (xy 172.714666 -54.774592) (xy 172.731684 -54.786784) (xy 172.824902 -54.80685)
			(xy 172.845476 -54.802786) (xy 172.854112 -54.79669) (xy 172.87817 -54.780681) (xy 172.930104 -54.755341)
			(xy 172.985264 -54.738118) (xy 173.042389 -54.729405) (xy 173.071282 -54.728872) (xy 173.098532 -54.729395)
			(xy 173.152477 -54.737148) (xy 173.20477 -54.7525) (xy 173.254346 -54.775138) (xy 173.300195 -54.8046)
			(xy 173.341385 -54.840288) (xy 173.377077 -54.881474) (xy 173.406544 -54.927321) (xy 173.429186 -54.976894)
			(xy 173.444543 -55.029186) (xy 173.452302 -55.08313) (xy 173.45279 -55.11038) (xy 173.452315 -55.13775)
			(xy 173.444499 -55.191929) (xy 173.429013 -55.244432) (xy 173.406173 -55.294179) (xy 173.37645 -55.340146)
			(xy 173.35881 -55.361078) (xy 173.352714 -55.36819) (xy 173.346364 -55.385208) (xy 173.346364 -55.470552)
			(xy 173.352714 -55.48757) (xy 173.35881 -55.494682) (xy 173.37643 -55.515631) (xy 173.406152 -55.561597)
			(xy 173.428997 -55.611341) (xy 173.444493 -55.66384) (xy 173.452323 -55.718016) (xy 173.452325 -55.772754)
			(xy 173.444499 -55.82693) (xy 173.429007 -55.879431) (xy 173.406167 -55.929176) (xy 173.376448 -55.975145)
			(xy 173.35881 -55.996078) (xy 173.352714 -56.00319) (xy 173.346364 -56.020208) (xy 173.346364 -56.105552)
			(xy 173.352714 -56.12257) (xy 173.35881 -56.129682) (xy 173.376456 -56.150609) (xy 173.406166 -56.196583)
			(xy 173.429001 -56.246332) (xy 173.44449 -56.298834) (xy 173.452317 -56.35301) (xy 173.45279 -56.38038)
			(xy 173.452304 -56.407631) (xy 173.444548 -56.461579) (xy 173.429193 -56.513874) (xy 173.406551 -56.563451)
			(xy 173.377085 -56.609301) (xy 173.341394 -56.650492) (xy 173.300203 -56.686183) (xy 173.254353 -56.715649)
			(xy 173.204776 -56.738291) (xy 173.152481 -56.753646) (xy 173.098533 -56.761402) (xy 173.044031 -56.761402)
			(xy 172.990083 -56.753646) (xy 172.937788 -56.738291) (xy 172.888211 -56.715649) (xy 172.842361 -56.686183)
			(xy 172.80117 -56.650492) (xy 172.765479 -56.609301) (xy 172.736013 -56.563451) (xy 172.713371 -56.513874)
			(xy 172.698016 -56.461579) (xy 172.69026 -56.407631) (xy 172.689774 -56.38038) (xy 172.69021 -56.353008)
			(xy 172.698033 -56.298827) (xy 172.713528 -56.246323) (xy 172.736376 -56.196577) (xy 172.766109 -56.150612)
			(xy 172.783754 -56.129682) (xy 172.78985 -56.12257) (xy 172.7962 -56.105552) (xy 172.7962 -56.020208)
			(xy 172.78985 -56.00319) (xy 172.783754 -55.996078) (xy 172.766093 -55.975162) (xy 172.736367 -55.929192)
			(xy 172.713521 -55.879443) (xy 172.698025 -55.826938) (xy 172.690197 -55.772757) (xy 172.6902 -55.718013)
			(xy 172.698031 -55.663832) (xy 172.713531 -55.611329) (xy 172.736381 -55.561582) (xy 172.766111 -55.515614)
			(xy 172.783754 -55.494682) (xy 172.78985 -55.48757) (xy 172.7962 -55.470552) (xy 172.7962 -55.385208)
			(xy 172.78985 -55.36819) (xy 172.783754 -55.361078) (xy 172.772799 -55.348285) (xy 172.752961 -55.321064)
			(xy 172.74413 -55.306722) (xy 172.738796 -55.297578) (xy 172.721778 -55.285386) (xy 172.62856 -55.26532)
			(xy 172.607986 -55.269384) (xy 172.59935 -55.27548) (xy 172.575273 -55.291459) (xy 172.523346 -55.316807)
			(xy 172.468192 -55.334038) (xy 172.411071 -55.34276) (xy 172.38218 -55.343298) (xy 172.354929 -55.342831)
			(xy 172.300982 -55.335072) (xy 172.248688 -55.319715) (xy 172.199112 -55.297072) (xy 172.153263 -55.267604)
			(xy 172.112074 -55.231912) (xy 172.076384 -55.190721) (xy 172.046919 -55.14487) (xy 172.024278 -55.095293)
			(xy 172.008924 -55.042998) (xy 172.001168 -54.989051) (xy 169.792723 -54.989051) (xy 169.796926 -55.00364)
			(xy 169.804403 -55.056676) (xy 169.804842 -55.083456) (xy 169.804312 -55.112017) (xy 169.795807 -55.168501)
			(xy 169.77898 -55.223088) (xy 169.754208 -55.274558) (xy 169.722042 -55.321763) (xy 169.702988 -55.343044)
			(xy 169.69994 -55.346346) (xy 169.699686 -55.3466) (xy 169.692574 -55.35422) (xy 169.670554 -55.376041)
			(xy 169.620761 -55.412963) (xy 169.605453 -55.420851) (xy 170.324768 -55.420851) (xy 170.324768 -55.366349)
			(xy 170.332524 -55.312402) (xy 170.347878 -55.260107) (xy 170.370519 -55.21053) (xy 170.399984 -55.164679)
			(xy 170.435674 -55.123488) (xy 170.476863 -55.087796) (xy 170.522712 -55.058328) (xy 170.572288 -55.035685)
			(xy 170.624582 -55.020328) (xy 170.678529 -55.012569) (xy 170.70578 -55.012082) (xy 170.732097 -55.012508)
			(xy 170.784232 -55.019734) (xy 170.83488 -55.034053) (xy 170.883082 -55.055193) (xy 170.927923 -55.082752)
			(xy 170.968554 -55.11621) (xy 170.986704 -55.135272) (xy 170.994226 -55.142673) (xy 171.013506 -55.151199)
			(xy 171.024042 -55.151782) (xy 171.098718 -55.151782) (xy 171.109265 -55.151227) (xy 171.128561 -55.142711)
			(xy 171.136056 -55.135272) (xy 171.154226 -55.116228) (xy 171.194838 -55.082744) (xy 171.23967 -55.055167)
			(xy 171.287871 -55.034022) (xy 171.338523 -55.019711) (xy 171.390662 -55.012506) (xy 171.41698 -55.012082)
			(xy 171.444233 -55.012564) (xy 171.498185 -55.020318) (xy 171.550484 -55.035672) (xy 171.600065 -55.058313)
			(xy 171.645919 -55.08778) (xy 171.687113 -55.123472) (xy 171.722808 -55.164665) (xy 171.752277 -55.210517)
			(xy 171.774921 -55.260098) (xy 171.790277 -55.312396) (xy 171.798035 -55.366347) (xy 171.798035 -55.420853)
			(xy 171.790277 -55.474804) (xy 171.774921 -55.527102) (xy 171.752277 -55.576683) (xy 171.722808 -55.622535)
			(xy 171.687113 -55.663728) (xy 171.645919 -55.69942) (xy 171.600065 -55.728887) (xy 171.550484 -55.751528)
			(xy 171.498185 -55.766882) (xy 171.444233 -55.774636) (xy 171.41698 -55.775098) (xy 171.390664 -55.774639)
			(xy 171.33853 -55.76742) (xy 171.287882 -55.753108) (xy 171.23968 -55.731975) (xy 171.194838 -55.704421)
			(xy 171.154206 -55.670968) (xy 171.136056 -55.651908) (xy 171.128552 -55.644486) (xy 171.109259 -55.635973)
			(xy 171.098718 -55.635398) (xy 171.024042 -55.635398) (xy 171.013493 -55.635937) (xy 170.994198 -55.644465)
			(xy 170.986704 -55.651908) (xy 170.968569 -55.670987) (xy 170.927948 -55.704465) (xy 170.883108 -55.732035)
			(xy 170.834901 -55.753174) (xy 170.784243 -55.767478) (xy 170.7321 -55.774677) (xy 170.70578 -55.775098)
			(xy 170.678529 -55.774631) (xy 170.624582 -55.766872) (xy 170.572288 -55.751515) (xy 170.522712 -55.728872)
			(xy 170.476863 -55.699404) (xy 170.435674 -55.663712) (xy 170.399984 -55.622521) (xy 170.370519 -55.57667)
			(xy 170.347878 -55.527093) (xy 170.332524 -55.474798) (xy 170.324768 -55.420851) (xy 169.605453 -55.420851)
			(xy 169.565658 -55.441357) (xy 169.536364 -55.451502) (xy 169.52849 -55.454042) (xy 169.515536 -55.463186)
			(xy 169.510964 -55.46979) (xy 169.506404 -55.47643) (xy 169.501346 -55.491713) (xy 169.501058 -55.499762)
			(xy 169.501058 -55.940706) (xy 169.501558 -55.951522) (xy 169.510461 -55.971236) (xy 169.526688 -55.985541)
			(xy 169.536872 -55.98922) (xy 169.538904 -55.989982) (xy 169.564294 -55.998509) (xy 169.61258 -56.021686)
			(xy 169.657146 -56.051395) (xy 169.697113 -56.087051) (xy 169.731695 -56.12795) (xy 169.760211 -56.173289)
			(xy 169.782098 -56.222173) (xy 169.796926 -56.27364) (xy 169.804403 -56.326676) (xy 169.804842 -56.353456)
			(xy 169.804312 -56.382017) (xy 169.795807 -56.438501) (xy 169.77898 -56.493088) (xy 169.754208 -56.544558)
			(xy 169.722042 -56.591763) (xy 169.702988 -56.613044) (xy 169.69994 -56.616346) (xy 169.699686 -56.6166)
			(xy 169.692574 -56.62422) (xy 169.670554 -56.646041) (xy 169.620761 -56.682963) (xy 169.565658 -56.711357)
			(xy 169.536364 -56.721502) (xy 169.52849 -56.724042) (xy 169.515536 -56.733186) (xy 169.510964 -56.73979)
			(xy 169.506404 -56.74643) (xy 169.501346 -56.761713) (xy 169.501058 -56.769762) (xy 169.501058 -57.48528)
			(xy 172.706028 -57.48528) (xy 172.710099 -57.429658) (xy 172.722225 -57.375221) (xy 172.742148 -57.32313)
			(xy 172.769444 -57.274495) (xy 172.80353 -57.230352) (xy 172.843679 -57.191643) (xy 172.889037 -57.159192)
			(xy 172.938637 -57.133691) (xy 172.991421 -57.115684) (xy 173.046264 -57.105554) (xy 173.101998 -57.103517)
			(xy 173.157435 -57.109617) (xy 173.211392 -57.123723) (xy 173.262721 -57.145535) (xy 173.310327 -57.174589)
			(xy 173.353195 -57.210264) (xy 173.390412 -57.251801) (xy 173.421185 -57.298314) (xy 173.444857 -57.348811)
			(xy 173.460925 -57.402218) (xy 173.469045 -57.457394) (xy 173.469554 -57.48528) (xy 173.469045 -57.513166)
			(xy 173.460925 -57.568342) (xy 173.444857 -57.621749) (xy 173.421185 -57.672246) (xy 173.390412 -57.718759)
			(xy 173.353195 -57.760296) (xy 173.310327 -57.795971) (xy 173.262721 -57.825025) (xy 173.211392 -57.846837)
			(xy 173.157435 -57.860943) (xy 173.101998 -57.867043) (xy 173.046264 -57.865006) (xy 172.991421 -57.854876)
			(xy 172.938637 -57.836869) (xy 172.889037 -57.811368) (xy 172.843679 -57.778917) (xy 172.80353 -57.740208)
			(xy 172.769444 -57.696065) (xy 172.742148 -57.64743) (xy 172.722225 -57.595339) (xy 172.710099 -57.540902)
			(xy 172.706028 -57.48528) (xy 169.501058 -57.48528) (xy 169.501058 -58.076084) (xy 173.458122 -58.076084)
			(xy 173.462193 -58.020462) (xy 173.474319 -57.966025) (xy 173.494242 -57.913934) (xy 173.521538 -57.865299)
			(xy 173.555624 -57.821156) (xy 173.595773 -57.782447) (xy 173.641131 -57.749996) (xy 173.690731 -57.724495)
			(xy 173.743515 -57.706488) (xy 173.798358 -57.696358) (xy 173.854092 -57.694321) (xy 173.909529 -57.700421)
			(xy 173.963486 -57.714527) (xy 174.014815 -57.736339) (xy 174.062421 -57.765393) (xy 174.105289 -57.801068)
			(xy 174.142506 -57.842605) (xy 174.158842 -57.867296) (xy 175.742852 -57.867296) (xy 175.746925 -57.811637)
			(xy 175.75906 -57.757164) (xy 175.778996 -57.705038) (xy 175.80631 -57.65637) (xy 175.840418 -57.612198)
			(xy 175.880595 -57.573463) (xy 175.925983 -57.540991) (xy 175.975615 -57.515473) (xy 176.028435 -57.497454)
			(xy 176.083314 -57.487317) (xy 176.139085 -57.485279) (xy 176.194559 -57.491382) (xy 176.248552 -57.505498)
			(xy 176.299915 -57.527325) (xy 176.347553 -57.556398) (xy 176.390449 -57.592097) (xy 176.427691 -57.633661)
			(xy 176.458485 -57.680205) (xy 176.482173 -57.730736) (xy 176.498251 -57.784178) (xy 176.506377 -57.839392)
			(xy 176.506886 -57.867296) (xy 176.506377 -57.8952) (xy 176.498251 -57.950414) (xy 176.482173 -58.003856)
			(xy 176.458485 -58.054387) (xy 176.427691 -58.100931) (xy 176.390449 -58.142495) (xy 176.347553 -58.178194)
			(xy 176.299915 -58.207267) (xy 176.248552 -58.229094) (xy 176.194559 -58.24321) (xy 176.139085 -58.249313)
			(xy 176.083314 -58.247275) (xy 176.028435 -58.237138) (xy 175.975615 -58.219119) (xy 175.925983 -58.193601)
			(xy 175.880595 -58.161129) (xy 175.840418 -58.122394) (xy 175.80631 -58.078222) (xy 175.778996 -58.029554)
			(xy 175.75906 -57.977428) (xy 175.746925 -57.922955) (xy 175.742852 -57.867296) (xy 174.158842 -57.867296)
			(xy 174.173279 -57.889118) (xy 174.196951 -57.939615) (xy 174.213019 -57.993022) (xy 174.221139 -58.048198)
			(xy 174.221648 -58.076084) (xy 174.221139 -58.10397) (xy 174.213019 -58.159146) (xy 174.196951 -58.212553)
			(xy 174.173279 -58.26305) (xy 174.142506 -58.309563) (xy 174.105289 -58.3511) (xy 174.062421 -58.386775)
			(xy 174.014815 -58.415829) (xy 173.963486 -58.437641) (xy 173.909529 -58.451747) (xy 173.854092 -58.457847)
			(xy 173.798358 -58.45581) (xy 173.743515 -58.44568) (xy 173.690731 -58.427673) (xy 173.641131 -58.402172)
			(xy 173.595773 -58.369721) (xy 173.555624 -58.331012) (xy 173.521538 -58.286869) (xy 173.494242 -58.238234)
			(xy 173.474319 -58.186143) (xy 173.462193 -58.131706) (xy 173.458122 -58.076084) (xy 169.501058 -58.076084)
			(xy 169.501058 -58.561224) (xy 174.662336 -58.561224) (xy 174.666407 -58.505602) (xy 174.678533 -58.451165)
			(xy 174.698456 -58.399074) (xy 174.725752 -58.350439) (xy 174.759838 -58.306296) (xy 174.799987 -58.267587)
			(xy 174.845345 -58.235136) (xy 174.894945 -58.209635) (xy 174.947729 -58.191628) (xy 175.002572 -58.181498)
			(xy 175.058306 -58.179461) (xy 175.113743 -58.185561) (xy 175.1677 -58.199667) (xy 175.219029 -58.221479)
			(xy 175.266635 -58.250533) (xy 175.309503 -58.286208) (xy 175.34672 -58.327745) (xy 175.377493 -58.374258)
			(xy 175.401165 -58.424755) (xy 175.408675 -58.449718) (xy 176.908966 -58.449718) (xy 176.913037 -58.394096)
			(xy 176.925163 -58.339659) (xy 176.945086 -58.287568) (xy 176.972382 -58.238933) (xy 177.006468 -58.19479)
			(xy 177.046617 -58.156081) (xy 177.091975 -58.12363) (xy 177.141575 -58.098129) (xy 177.194359 -58.080122)
			(xy 177.249202 -58.069992) (xy 177.304936 -58.067955) (xy 177.360373 -58.074055) (xy 177.41433 -58.088161)
			(xy 177.465659 -58.109973) (xy 177.513265 -58.139027) (xy 177.556133 -58.174702) (xy 177.59335 -58.216239)
			(xy 177.624123 -58.262752) (xy 177.647795 -58.313249) (xy 177.663863 -58.366656) (xy 177.671983 -58.421832)
			(xy 177.672492 -58.449718) (xy 177.671983 -58.477604) (xy 177.663863 -58.53278) (xy 177.647795 -58.586187)
			(xy 177.624123 -58.636684) (xy 177.59335 -58.683197) (xy 177.556133 -58.724734) (xy 177.513265 -58.760409)
			(xy 177.465659 -58.789463) (xy 177.41433 -58.811275) (xy 177.360373 -58.825381) (xy 177.304936 -58.831481)
			(xy 177.249202 -58.829444) (xy 177.194359 -58.819314) (xy 177.141575 -58.801307) (xy 177.091975 -58.775806)
			(xy 177.046617 -58.743355) (xy 177.006468 -58.704646) (xy 176.972382 -58.660503) (xy 176.945086 -58.611868)
			(xy 176.925163 -58.559777) (xy 176.913037 -58.50534) (xy 176.908966 -58.449718) (xy 175.408675 -58.449718)
			(xy 175.417233 -58.478162) (xy 175.425353 -58.533338) (xy 175.425862 -58.561224) (xy 175.425353 -58.58911)
			(xy 175.417233 -58.644286) (xy 175.401165 -58.697693) (xy 175.377493 -58.74819) (xy 175.34672 -58.794703)
			(xy 175.309503 -58.83624) (xy 175.266635 -58.871915) (xy 175.219029 -58.900969) (xy 175.1677 -58.922781)
			(xy 175.113743 -58.936887) (xy 175.058306 -58.942987) (xy 175.002572 -58.94095) (xy 174.947729 -58.93082)
			(xy 174.894945 -58.912813) (xy 174.845345 -58.887312) (xy 174.799987 -58.854861) (xy 174.759838 -58.816152)
			(xy 174.725752 -58.772009) (xy 174.698456 -58.723374) (xy 174.678533 -58.671283) (xy 174.666407 -58.616846)
			(xy 174.662336 -58.561224) (xy 169.501058 -58.561224) (xy 169.501058 -59.974734) (xy 173.187106 -59.974734)
			(xy 173.187535 -59.947907) (xy 173.195056 -59.894782) (xy 173.209939 -59.843234) (xy 173.231893 -59.794276)
			(xy 173.260484 -59.748874) (xy 173.29515 -59.707922) (xy 173.335208 -59.672227) (xy 173.357286 -59.65698)
			(xy 173.368855 -59.648764) (xy 173.387266 -59.627186) (xy 173.399023 -59.601372) (xy 173.403219 -59.573319)
			(xy 173.399529 -59.545195) (xy 173.388239 -59.519174) (xy 173.370221 -59.497267) (xy 173.35881 -59.488832)
			(xy 173.337361 -59.473469) (xy 173.298446 -59.437845) (xy 173.264812 -59.397198) (xy 173.2371 -59.352304)
			(xy 173.215838 -59.30402) (xy 173.201433 -59.253267) (xy 173.194158 -59.201013) (xy 173.19371 -59.174634)
			(xy 173.194196 -59.147383) (xy 173.201952 -59.093435) (xy 173.217307 -59.04114) (xy 173.239949 -58.991563)
			(xy 173.269415 -58.945713) (xy 173.305106 -58.904522) (xy 173.346297 -58.868831) (xy 173.392147 -58.839365)
			(xy 173.441724 -58.816723) (xy 173.494019 -58.801368) (xy 173.547967 -58.793612) (xy 173.602469 -58.793612)
			(xy 173.656417 -58.801368) (xy 173.708712 -58.816723) (xy 173.758289 -58.839365) (xy 173.804139 -58.868831)
			(xy 173.84533 -58.904522) (xy 173.881021 -58.945713) (xy 173.910487 -58.991563) (xy 173.933129 -59.04114)
			(xy 173.948484 -59.093435) (xy 173.95624 -59.147383) (xy 173.956726 -59.174634) (xy 173.956259 -59.20146)
			(xy 173.948743 -59.254582) (xy 173.933865 -59.306129) (xy 173.911917 -59.355086) (xy 173.883332 -59.400488)
			(xy 173.848672 -59.441441) (xy 173.808621 -59.47714) (xy 173.786546 -59.492388) (xy 173.775013 -59.500647)
			(xy 173.756616 -59.52222) (xy 173.744865 -59.548023) (xy 173.740669 -59.576063) (xy 173.74435 -59.604175)
			(xy 173.755624 -59.630189) (xy 173.773622 -59.652097) (xy 173.785022 -59.660536) (xy 173.80651 -59.675846)
			(xy 173.845422 -59.711481) (xy 173.879052 -59.752137) (xy 173.906759 -59.79704) (xy 173.928014 -59.845332)
			(xy 173.942412 -59.896092) (xy 173.949678 -59.948353) (xy 173.950122 -59.974734) (xy 173.949636 -60.001985)
			(xy 173.94188 -60.055933) (xy 173.926525 -60.108228) (xy 173.903883 -60.157805) (xy 173.874417 -60.203655)
			(xy 173.838726 -60.244846) (xy 173.797535 -60.280537) (xy 173.751685 -60.310003) (xy 173.702108 -60.332645)
			(xy 173.649813 -60.348) (xy 173.595865 -60.355756) (xy 173.541363 -60.355756) (xy 173.487415 -60.348)
			(xy 173.43512 -60.332645) (xy 173.385543 -60.310003) (xy 173.339693 -60.280537) (xy 173.298502 -60.244846)
			(xy 173.262811 -60.203655) (xy 173.233345 -60.157805) (xy 173.210703 -60.108228) (xy 173.195348 -60.055933)
			(xy 173.187592 -60.001985) (xy 173.187106 -59.974734) (xy 169.501058 -59.974734) (xy 169.501058 -60.601606)
			(xy 172.433232 -60.601606) (xy 172.437303 -60.545984) (xy 172.449429 -60.491547) (xy 172.469352 -60.439456)
			(xy 172.496648 -60.390821) (xy 172.530734 -60.346678) (xy 172.570883 -60.307969) (xy 172.616241 -60.275518)
			(xy 172.665841 -60.250017) (xy 172.718625 -60.23201) (xy 172.773468 -60.22188) (xy 172.829202 -60.219843)
			(xy 172.884639 -60.225943) (xy 172.938596 -60.240049) (xy 172.989925 -60.261861) (xy 173.037531 -60.290915)
			(xy 173.080399 -60.32659) (xy 173.117616 -60.368127) (xy 173.148389 -60.41464) (xy 173.172061 -60.465137)
			(xy 173.188129 -60.518544) (xy 173.196249 -60.57372) (xy 173.196758 -60.601606) (xy 173.196294 -60.627006)
			(xy 174.82134 -60.627006) (xy 174.825411 -60.571384) (xy 174.837537 -60.516947) (xy 174.85746 -60.464856)
			(xy 174.884756 -60.416221) (xy 174.918842 -60.372078) (xy 174.958991 -60.333369) (xy 175.004349 -60.300918)
			(xy 175.053949 -60.275417) (xy 175.106733 -60.25741) (xy 175.161576 -60.24728) (xy 175.21731 -60.245243)
			(xy 175.272747 -60.251343) (xy 175.326704 -60.265449) (xy 175.378033 -60.287261) (xy 175.425639 -60.316315)
			(xy 175.468507 -60.35199) (xy 175.505724 -60.393527) (xy 175.536497 -60.44004) (xy 175.560169 -60.490537)
			(xy 175.576237 -60.543944) (xy 175.584357 -60.59912) (xy 175.584866 -60.627006) (xy 175.58475 -60.633356)
			(xy 176.91303 -60.633356) (xy 176.917101 -60.577734) (xy 176.929227 -60.523297) (xy 176.94915 -60.471206)
			(xy 176.976446 -60.422571) (xy 177.010532 -60.378428) (xy 177.050681 -60.339719) (xy 177.096039 -60.307268)
			(xy 177.145639 -60.281767) (xy 177.198423 -60.26376) (xy 177.253266 -60.25363) (xy 177.309 -60.251593)
			(xy 177.364437 -60.257693) (xy 177.418394 -60.271799) (xy 177.469723 -60.293611) (xy 177.517329 -60.322665)
			(xy 177.560197 -60.35834) (xy 177.597414 -60.399877) (xy 177.628187 -60.44639) (xy 177.651859 -60.496887)
			(xy 177.667927 -60.550294) (xy 177.676047 -60.60547) (xy 177.676556 -60.633356) (xy 177.676047 -60.661242)
			(xy 177.667927 -60.716418) (xy 177.651859 -60.769825) (xy 177.628187 -60.820322) (xy 177.597414 -60.866835)
			(xy 177.560197 -60.908372) (xy 177.517329 -60.944047) (xy 177.469723 -60.973101) (xy 177.418394 -60.994913)
			(xy 177.364437 -61.009019) (xy 177.309 -61.015119) (xy 177.253266 -61.013082) (xy 177.198423 -61.002952)
			(xy 177.145639 -60.984945) (xy 177.096039 -60.959444) (xy 177.050681 -60.926993) (xy 177.010532 -60.888284)
			(xy 176.976446 -60.844141) (xy 176.94915 -60.795506) (xy 176.929227 -60.743415) (xy 176.917101 -60.688978)
			(xy 176.91303 -60.633356) (xy 175.58475 -60.633356) (xy 175.584357 -60.654892) (xy 175.576237 -60.710068)
			(xy 175.560169 -60.763475) (xy 175.536497 -60.813972) (xy 175.505724 -60.860485) (xy 175.468507 -60.902022)
			(xy 175.425639 -60.937697) (xy 175.378033 -60.966751) (xy 175.326704 -60.988563) (xy 175.272747 -61.002669)
			(xy 175.21731 -61.008769) (xy 175.161576 -61.006732) (xy 175.106733 -60.996602) (xy 175.053949 -60.978595)
			(xy 175.004349 -60.953094) (xy 174.958991 -60.920643) (xy 174.918842 -60.881934) (xy 174.884756 -60.837791)
			(xy 174.85746 -60.789156) (xy 174.837537 -60.737065) (xy 174.825411 -60.682628) (xy 174.82134 -60.627006)
			(xy 173.196294 -60.627006) (xy 173.196249 -60.629492) (xy 173.188129 -60.684668) (xy 173.172061 -60.738075)
			(xy 173.148389 -60.788572) (xy 173.117616 -60.835085) (xy 173.080399 -60.876622) (xy 173.037531 -60.912297)
			(xy 172.989925 -60.941351) (xy 172.938596 -60.963163) (xy 172.884639 -60.977269) (xy 172.829202 -60.983369)
			(xy 172.773468 -60.981332) (xy 172.718625 -60.971202) (xy 172.665841 -60.953195) (xy 172.616241 -60.927694)
			(xy 172.570883 -60.895243) (xy 172.530734 -60.856534) (xy 172.496648 -60.812391) (xy 172.469352 -60.763756)
			(xy 172.449429 -60.711665) (xy 172.437303 -60.657228) (xy 172.433232 -60.601606) (xy 169.501058 -60.601606)
			(xy 169.501058 -61.333126) (xy 169.501487 -61.343193) (xy 169.509215 -61.361785) (xy 169.516044 -61.369194)
			(xy 169.706544 -61.559694) (xy 169.713945 -61.566534) (xy 169.732543 -61.574254) (xy 169.742612 -61.57468)
			(xy 172.285152 -61.57468) (xy 172.31995 -61.576712) (xy 172.322998 -61.576966) (xy 173.125638 -61.576966)
		)
		(stroke
			(width 0)
			(type solid)
		)
		(fill yes)
		(layer "In9.Cu")
		(net "P3V3_SSD6")
	)
	(gr_poly
		(pts
			(xy 263.227312 -61.576458) (xy 263.236421 -61.575415) (xy 263.254721 -61.574274) (xy 263.263888 -61.574172)
			(xy 264.397998 -61.574172) (xy 264.407904 -61.573156) (xy 264.411206 -61.572648) (xy 264.418282 -61.570976)
			(xy 264.431182 -61.564281) (xy 264.436606 -61.55944) (xy 264.491724 -61.506608) (xy 264.499598 -61.488574)
			(xy 264.500106 -61.478668) (xy 264.50119 -61.457323) (xy 264.50756 -61.415059) (xy 264.512806 -61.39434)
			(xy 264.52009 -61.368819) (xy 264.540743 -61.31993) (xy 264.567962 -61.27437) (xy 264.601225 -61.233015)
			(xy 264.620248 -61.214508) (xy 264.620756 -61.214) (xy 264.621518 -61.213238) (xy 264.642973 -61.193277)
			(xy 264.690868 -61.159514) (xy 264.743365 -61.133476) (xy 264.799227 -61.115777) (xy 264.85714 -61.106833)
			(xy 264.88644 -61.106304) (xy 264.913449 -61.106775) (xy 264.966928 -61.114399) (xy 265.018797 -61.129488)
			(xy 265.068019 -61.151742) (xy 265.113611 -61.180715) (xy 265.154662 -61.215828) (xy 265.19035 -61.256379)
			(xy 265.219963 -61.301558) (xy 265.242909 -61.350461) (xy 265.258728 -61.402112) (xy 265.267105 -61.455478)
			(xy 265.267948 -61.482478) (xy 265.268202 -61.492892) (xy 265.276076 -61.51118) (xy 265.326114 -61.559186)
			(xy 265.331498 -61.564126) (xy 265.344404 -61.570965) (xy 265.351514 -61.572648) (xy 265.359642 -61.574172)
			(xy 266.34313 -61.574172) (xy 266.377674 -61.576204) (xy 266.380722 -61.576458) (xy 267.241274 -61.576458)
			(xy 267.244322 -61.576204) (xy 267.278866 -61.574172) (xy 268.953488 -61.574172) (xy 268.963559 -61.57375)
			(xy 268.982164 -61.566036) (xy 268.989556 -61.559186) (xy 269.625064 -60.923678) (xy 269.627994 -60.918012)
			(xy 269.631198 -60.905669) (xy 269.631414 -60.899294) (xy 269.631414 -38.906196) (xy 269.630652 -38.897052)
			(xy 269.629382 -38.890702) (xy 269.62775 -38.883212) (xy 269.620636 -38.869642) (xy 269.615412 -38.864032)
			(xy 269.613888 -38.862508) (xy 269.612618 -38.861492) (xy 269.580666 -38.83282) (xy 269.521563 -38.770546)
			(xy 269.468385 -38.703143) (xy 269.421576 -38.631171) (xy 269.381524 -38.55523) (xy 269.348564 -38.475953)
			(xy 269.322971 -38.394001) (xy 269.304958 -38.310057) (xy 269.294674 -38.224819) (xy 269.292206 -38.139)
			(xy 269.297574 -38.053312) (xy 269.310733 -37.968471) (xy 269.331574 -37.885184) (xy 269.359923 -37.804144)
			(xy 269.395545 -37.726027) (xy 269.438141 -37.651484) (xy 269.487357 -37.581135) (xy 269.542783 -37.515568)
			(xy 269.572994 -37.485066) (xy 269.573248 -37.484812) (xy 269.60322 -37.45611) (xy 269.607538 -37.4523)
			(xy 269.611856 -37.44849) (xy 269.618206 -37.4396) (xy 269.62735 -37.41801) (xy 269.629223 -37.413271)
			(xy 269.631272 -37.403291) (xy 269.631414 -37.398198) (xy 269.631414 -31.77667) (xy 269.62862 -31.768542)
			(xy 269.618581 -31.737951) (xy 269.607735 -31.674493) (xy 269.60703 -31.642304) (xy 269.607717 -31.610114)
			(xy 269.618565 -31.546653) (xy 269.62862 -31.516066) (xy 269.631414 -31.507938) (xy 269.631414 -31.23819)
			(xy 269.631534 -31.233236) (xy 269.633455 -31.223515) (xy 269.635224 -31.218886) (xy 269.640304 -31.206948)
			(xy 269.642107 -31.202262) (xy 269.644034 -31.19241) (xy 269.644114 -31.18739) (xy 269.644114 -29.841698)
			(xy 269.643844 -29.833762) (xy 269.639047 -29.818636) (xy 269.634716 -29.81198) (xy 269.617904 -29.787563)
			(xy 269.591241 -29.734619) (xy 269.573096 -29.678186) (xy 269.563906 -29.619623) (xy 269.563342 -29.589984)
			(xy 269.563926 -29.560347) (xy 269.573131 -29.501791) (xy 269.591272 -29.44536) (xy 269.617913 -29.392408)
			(xy 269.634716 -29.367988) (xy 269.639075 -29.361346) (xy 269.643864 -29.34621) (xy 269.644114 -29.33827)
			(xy 269.644114 -28.11272) (xy 269.644143 -28.108117) (xy 269.645678 -28.099043) (xy 269.647162 -28.094686)
			(xy 269.650972 -28.084526) (xy 269.648686 -28.051506) (xy 269.648389 -28.047866) (xy 269.646854 -28.040726)
			(xy 269.645638 -28.037282) (xy 269.638272 -28.01747) (xy 269.634208 -28.011882) (xy 269.617484 -27.987469)
			(xy 269.590979 -27.934563) (xy 269.572962 -27.878198) (xy 269.563864 -27.819727) (xy 269.563342 -27.79014)
			(xy 269.564612 -27.759152) (xy 269.565374 -27.751786) (xy 269.568691 -27.723928) (xy 269.582452 -27.66954)
			(xy 269.604027 -27.617754) (xy 269.632953 -27.569685) (xy 269.668606 -27.526369) (xy 269.710217 -27.488742)
			(xy 269.75689 -27.457612) (xy 269.807617 -27.433653) (xy 269.861306 -27.417379) (xy 269.9168 -27.409142)
			(xy 269.94485 -27.408632) (xy 269.970371 -27.409075) (xy 270.020953 -27.415909) (xy 270.070174 -27.429423)
			(xy 270.117155 -27.449375) (xy 270.161059 -27.47541) (xy 270.181324 -27.490928) (xy 270.196818 -27.502866)
			(xy 270.234918 -27.500834) (xy 270.388334 -27.347418) (xy 270.395733 -27.340575) (xy 270.414332 -27.33285)
			(xy 270.424402 -27.332432) (xy 270.572484 -27.332432) (xy 270.576802 -27.33167) (xy 270.589344 -27.32968)
			(xy 270.61465 -27.32752) (xy 270.627348 -27.327352) (xy 274.672806 -27.327352) (xy 274.682763 -27.326865)
			(xy 274.701161 -27.319243) (xy 274.715243 -27.305161) (xy 274.722865 -27.286763) (xy 274.723352 -27.276806)
			(xy 274.723352 -26.479246) (xy 274.723574 -26.461259) (xy 274.726499 -26.425403) (xy 274.729194 -26.407618)
			(xy 274.73148 -26.39441) (xy 274.73275 -26.387044) (xy 274.731226 -26.372566) (xy 274.728178 -26.365454)
			(xy 274.725187 -26.358741) (xy 274.716021 -26.347261) (xy 274.710144 -26.342848) (xy 274.69084 -26.329386)
			(xy 274.6629 -26.327608) (xy 274.650454 -26.334212) (xy 274.62335 -26.347495) (xy 274.565991 -26.366283)
			(xy 274.506389 -26.375805) (xy 274.47621 -26.376376) (xy 274.475702 -26.376376) (xy 274.44845 -26.375913)
			(xy 274.3945 -26.368156) (xy 274.342204 -26.3528) (xy 274.292626 -26.330157) (xy 274.246775 -26.300688)
			(xy 274.205584 -26.264994) (xy 274.169894 -26.223801) (xy 274.140429 -26.177948) (xy 274.11779 -26.128368)
			(xy 274.102438 -26.07607) (xy 274.094685 -26.02212) (xy 274.094194 -25.994868) (xy 274.094629 -25.968884)
			(xy 274.101676 -25.917396) (xy 274.115649 -25.867342) (xy 274.136288 -25.819648) (xy 274.163212 -25.775199)
			(xy 274.195923 -25.734817) (xy 274.21459 -25.716738) (xy 274.215098 -25.71623) (xy 274.21586 -25.715468)
			(xy 274.237313 -25.695502) (xy 274.285206 -25.661729) (xy 274.337702 -25.635682) (xy 274.393565 -25.617972)
			(xy 274.45148 -25.609019) (xy 274.480782 -25.608534) (xy 274.509729 -25.609077) (xy 274.566956 -25.617835)
			(xy 274.622204 -25.635138) (xy 274.674204 -25.660589) (xy 274.721762 -25.693603) (xy 274.763787 -25.733422)
			(xy 274.799314 -25.779134) (xy 274.827527 -25.829688) (xy 274.828411 -25.832054) (xy 276.387812 -25.832054)
			(xy 276.391883 -25.776432) (xy 276.404009 -25.721995) (xy 276.423932 -25.669904) (xy 276.451228 -25.621269)
			(xy 276.485314 -25.577126) (xy 276.525463 -25.538417) (xy 276.570821 -25.505966) (xy 276.620421 -25.480465)
			(xy 276.673205 -25.462458) (xy 276.728048 -25.452328) (xy 276.783782 -25.450291) (xy 276.839219 -25.456391)
			(xy 276.893176 -25.470497) (xy 276.944505 -25.492309) (xy 276.992111 -25.521363) (xy 277.034979 -25.557038)
			(xy 277.036513 -25.55875) (xy 280.842212 -25.55875) (xy 280.842698 -25.531499) (xy 280.850454 -25.477551)
			(xy 280.865809 -25.425256) (xy 280.888451 -25.375679) (xy 280.917917 -25.329829) (xy 280.953608 -25.288638)
			(xy 280.994799 -25.252947) (xy 281.040649 -25.223481) (xy 281.090226 -25.200839) (xy 281.142521 -25.185484)
			(xy 281.196469 -25.177728) (xy 281.250971 -25.177728) (xy 281.304919 -25.185484) (xy 281.357214 -25.200839)
			(xy 281.406791 -25.223481) (xy 281.452641 -25.252947) (xy 281.493832 -25.288638) (xy 281.529523 -25.329829)
			(xy 281.558989 -25.375679) (xy 281.581631 -25.425256) (xy 281.596986 -25.477551) (xy 281.604742 -25.531499)
			(xy 281.605228 -25.55875) (xy 281.604674 -25.589013) (xy 281.595121 -25.648779) (xy 281.576248 -25.706287)
			(xy 281.548528 -25.760091) (xy 281.53106 -25.78481) (xy 281.522786 -25.796959) (xy 281.512838 -25.824601)
			(xy 281.511171 -25.853932) (xy 281.517923 -25.882524) (xy 281.532536 -25.90801) (xy 281.5538 -25.928281)
			(xy 281.579955 -25.94166) (xy 281.594306 -25.94483) (xy 281.6202 -25.95017) (xy 281.670322 -25.966987)
			(xy 281.717642 -25.990566) (xy 281.76125 -26.020455) (xy 281.800312 -26.056082) (xy 281.834078 -26.096763)
			(xy 281.861902 -26.141718) (xy 281.883248 -26.190085) (xy 281.89771 -26.240937) (xy 281.905008 -26.2933)
			(xy 281.905456 -26.319734) (xy 283.04185 -26.319734) (xy 283.045921 -26.264112) (xy 283.058047 -26.209675)
			(xy 283.07797 -26.157584) (xy 283.105266 -26.108949) (xy 283.139352 -26.064806) (xy 283.179501 -26.026097)
			(xy 283.224859 -25.993646) (xy 283.274459 -25.968145) (xy 283.327243 -25.950138) (xy 283.382086 -25.940008)
			(xy 283.43782 -25.937971) (xy 283.493257 -25.944071) (xy 283.547214 -25.958177) (xy 283.598543 -25.979989)
			(xy 283.646149 -26.009043) (xy 283.689017 -26.044718) (xy 283.726234 -26.086255) (xy 283.757007 -26.132768)
			(xy 283.780679 -26.183265) (xy 283.796747 -26.236672) (xy 283.804867 -26.291848) (xy 283.805376 -26.319734)
			(xy 283.804867 -26.34762) (xy 283.796747 -26.402796) (xy 283.780679 -26.456203) (xy 283.757007 -26.5067)
			(xy 283.726234 -26.553213) (xy 283.689017 -26.59475) (xy 283.646149 -26.630425) (xy 283.598543 -26.659479)
			(xy 283.547214 -26.681291) (xy 283.493257 -26.695397) (xy 283.43782 -26.701497) (xy 283.382086 -26.69946)
			(xy 283.327243 -26.68933) (xy 283.274459 -26.671323) (xy 283.224859 -26.645822) (xy 283.179501 -26.613371)
			(xy 283.139352 -26.574662) (xy 283.105266 -26.530519) (xy 283.07797 -26.481884) (xy 283.058047 -26.429793)
			(xy 283.045921 -26.375356) (xy 283.04185 -26.319734) (xy 281.905456 -26.319734) (xy 281.90497 -26.346985)
			(xy 281.897214 -26.400933) (xy 281.881859 -26.453228) (xy 281.859217 -26.502805) (xy 281.829751 -26.548655)
			(xy 281.79406 -26.589846) (xy 281.752869 -26.625537) (xy 281.707019 -26.655003) (xy 281.657442 -26.677645)
			(xy 281.605147 -26.693) (xy 281.551199 -26.700756) (xy 281.496697 -26.700756) (xy 281.442749 -26.693)
			(xy 281.390454 -26.677645) (xy 281.340877 -26.655003) (xy 281.295027 -26.625537) (xy 281.253836 -26.589846)
			(xy 281.218145 -26.548655) (xy 281.188679 -26.502805) (xy 281.166037 -26.453228) (xy 281.150682 -26.400933)
			(xy 281.142926 -26.346985) (xy 281.14244 -26.319734) (xy 281.142992 -26.289471) (xy 281.152546 -26.229705)
			(xy 281.17142 -26.172198) (xy 281.19914 -26.118393) (xy 281.216608 -26.093674) (xy 281.224922 -26.081549)
			(xy 281.234872 -26.053898) (xy 281.236538 -26.024559) (xy 281.229781 -25.99596) (xy 281.215159 -25.970468)
			(xy 281.193885 -25.950196) (xy 281.167718 -25.93682) (xy 281.153362 -25.933654) (xy 281.12746 -25.928353)
			(xy 281.077336 -25.911531) (xy 281.030016 -25.887947) (xy 280.986408 -25.858052) (xy 280.947347 -25.822421)
			(xy 280.913581 -25.781736) (xy 280.88576 -25.736777) (xy 280.864414 -25.688407) (xy 280.849955 -25.637551)
			(xy 280.842659 -25.585186) (xy 280.842212 -25.55875) (xy 277.036513 -25.55875) (xy 277.072196 -25.598575)
			(xy 277.102969 -25.645088) (xy 277.126641 -25.695585) (xy 277.142709 -25.748992) (xy 277.150829 -25.804168)
			(xy 277.151338 -25.832054) (xy 277.150829 -25.85994) (xy 277.142709 -25.915116) (xy 277.126641 -25.968523)
			(xy 277.102969 -26.01902) (xy 277.072196 -26.065533) (xy 277.034979 -26.10707) (xy 276.992111 -26.142745)
			(xy 276.944505 -26.171799) (xy 276.893176 -26.193611) (xy 276.839219 -26.207717) (xy 276.783782 -26.213817)
			(xy 276.728048 -26.21178) (xy 276.673205 -26.20165) (xy 276.620421 -26.183643) (xy 276.570821 -26.158142)
			(xy 276.525463 -26.125691) (xy 276.485314 -26.086982) (xy 276.451228 -26.042839) (xy 276.423932 -25.994204)
			(xy 276.404009 -25.942113) (xy 276.391883 -25.887676) (xy 276.387812 -25.832054) (xy 274.828411 -25.832054)
			(xy 274.84778 -25.883923) (xy 274.859607 -25.940596) (xy 274.861782 -25.969468) (xy 274.861782 -25.969976)
			(xy 274.863214 -25.982104) (xy 274.875685 -26.003058) (xy 274.885658 -26.010108) (xy 274.920964 -26.031952)
			(xy 274.966684 -26.0604) (xy 274.991322 -26.062432) (xy 275.002752 -26.057606) (xy 275.030668 -26.046286)
			(xy 275.088734 -26.030245) (xy 275.148403 -26.021964) (xy 275.17852 -26.021284) (xy 275.181314 -26.021284)
			(xy 275.211298 -26.021754) (xy 275.270753 -26.029584) (xy 275.328677 -26.045107) (xy 275.384079 -26.068058)
			(xy 275.436011 -26.098045) (xy 275.483584 -26.134554) (xy 275.525985 -26.176961) (xy 275.562488 -26.224539)
			(xy 275.592468 -26.276475) (xy 275.615412 -26.33188) (xy 275.62318 -26.360882) (xy 278.305512 -26.360882)
			(xy 278.309583 -26.30526) (xy 278.321709 -26.250823) (xy 278.341632 -26.198732) (xy 278.368928 -26.150097)
			(xy 278.403014 -26.105954) (xy 278.443163 -26.067245) (xy 278.488521 -26.034794) (xy 278.538121 -26.009293)
			(xy 278.590905 -25.991286) (xy 278.645748 -25.981156) (xy 278.701482 -25.979119) (xy 278.756919 -25.985219)
			(xy 278.810876 -25.999325) (xy 278.862205 -26.021137) (xy 278.909811 -26.050191) (xy 278.952679 -26.085866)
			(xy 278.989896 -26.127403) (xy 279.020669 -26.173916) (xy 279.044341 -26.224413) (xy 279.060409 -26.27782)
			(xy 279.068529 -26.332996) (xy 279.069038 -26.360882) (xy 279.068529 -26.388768) (xy 279.060409 -26.443944)
			(xy 279.044341 -26.497351) (xy 279.020669 -26.547848) (xy 278.989896 -26.594361) (xy 278.952679 -26.635898)
			(xy 278.909811 -26.671573) (xy 278.862205 -26.700627) (xy 278.810876 -26.722439) (xy 278.756919 -26.736545)
			(xy 278.701482 -26.742645) (xy 278.645748 -26.740608) (xy 278.590905 -26.730478) (xy 278.538121 -26.712471)
			(xy 278.488521 -26.68697) (xy 278.443163 -26.654519) (xy 278.403014 -26.61581) (xy 278.368928 -26.571667)
			(xy 278.341632 -26.523032) (xy 278.321709 -26.470941) (xy 278.309583 -26.416504) (xy 278.305512 -26.360882)
			(xy 275.62318 -26.360882) (xy 275.630928 -26.389806) (xy 275.63875 -26.449262) (xy 275.639276 -26.479246)
			(xy 275.639276 -27.276806) (xy 275.639664 -27.286787) (xy 275.647268 -27.305239) (xy 275.661384 -27.319347)
			(xy 275.679841 -27.326942) (xy 275.689822 -27.327352) (xy 284.89529 -27.327352) (xy 284.90536 -27.326929)
			(xy 284.923962 -27.319212) (xy 284.931358 -27.312366) (xy 285.290514 -26.95321) (xy 285.29641 -26.946869)
			(xy 285.303941 -26.93129) (xy 285.305246 -26.92273) (xy 285.3055 -26.919936) (xy 285.3055 -25.127966)
			(xy 285.305002 -25.117127) (xy 285.29605 -25.097385) (xy 285.288228 -25.089866) (xy 285.222696 -25.032208)
			(xy 285.201868 -25.025858) (xy 285.1912 -25.027128) (xy 285.179375 -25.028534) (xy 285.155609 -25.03006)
			(xy 285.143702 -25.030176) (xy 285.116703 -25.029708) (xy 285.063243 -25.022096) (xy 285.011391 -25.007023)
			(xy 284.962181 -24.98479) (xy 284.916598 -24.955841) (xy 284.875551 -24.920755) (xy 284.83986 -24.880233)
			(xy 284.810239 -24.835084) (xy 284.787279 -24.78621) (xy 284.771438 -24.734587) (xy 284.763034 -24.681246)
			(xy 284.762194 -24.654256) (xy 284.762194 -24.648414) (xy 284.762691 -24.62097) (xy 284.770593 -24.566653)
			(xy 284.786195 -24.514028) (xy 284.797246 -24.488902) (xy 284.797246 -24.488648) (xy 284.800639 -24.480384)
			(xy 284.802148 -24.462598) (xy 284.797501 -24.445364) (xy 284.792674 -24.437848) (xy 284.734 -24.355044)
			(xy 284.709108 -24.343614) (xy 284.695646 -24.344884) (xy 284.659324 -24.346662) (xy 284.632073 -24.3462)
			(xy 284.578126 -24.338447) (xy 284.525832 -24.323095) (xy 284.476255 -24.300457) (xy 284.430404 -24.270993)
			(xy 284.389214 -24.235303) (xy 284.353522 -24.194115) (xy 284.324055 -24.148266) (xy 284.301413 -24.098691)
			(xy 284.286058 -24.046397) (xy 284.278301 -23.992451) (xy 284.278301 -23.937949) (xy 284.286058 -23.884003)
			(xy 284.301413 -23.831709) (xy 284.324055 -23.782134) (xy 284.353522 -23.736285) (xy 284.389214 -23.695097)
			(xy 284.430404 -23.659407) (xy 284.476255 -23.629943) (xy 284.525832 -23.607305) (xy 284.578126 -23.591953)
			(xy 284.632073 -23.5842) (xy 284.659324 -23.583646) (xy 284.686322 -23.584115) (xy 284.739777 -23.591731)
			(xy 284.791625 -23.606807) (xy 284.84083 -23.629041) (xy 284.886409 -23.657991) (xy 284.927451 -23.693077)
			(xy 284.963137 -23.733599) (xy 284.992753 -23.778747) (xy 285.015709 -23.82762) (xy 285.031545 -23.879241)
			(xy 285.039946 -23.932578) (xy 285.040832 -23.959566) (xy 285.040832 -23.965408) (xy 285.040334 -23.992852)
			(xy 285.032429 -24.047168) (xy 285.016825 -24.099792) (xy 285.00578 -24.12492) (xy 285.00578 -24.125174)
			(xy 285.002394 -24.133438) (xy 285.000895 -24.15122) (xy 285.005541 -24.16845) (xy 285.010352 -24.175974)
			(xy 285.069026 -24.258778) (xy 285.093918 -24.270208) (xy 285.10738 -24.268938) (xy 285.143702 -24.26716)
			(xy 285.15561 -24.267265) (xy 285.179376 -24.268792) (xy 285.1912 -24.270208) (xy 285.201868 -24.271478)
			(xy 285.222696 -24.265128) (xy 285.288228 -24.20747) (xy 285.296031 -24.199937) (xy 285.304982 -24.180203)
			(xy 285.3055 -24.16937) (xy 285.3055 -24.081994) (xy 285.302706 -24.073866) (xy 285.292543 -24.043102)
			(xy 285.281553 -23.979257) (xy 285.280862 -23.946866) (xy 285.281566 -23.914475) (xy 285.292543 -23.850629)
			(xy 285.302706 -23.819866) (xy 285.3055 -23.811738) (xy 285.3055 -22.254972) (xy 285.304998 -22.24498)
			(xy 285.297357 -22.226511) (xy 285.28327 -22.212331) (xy 285.274258 -22.207982) (xy 285.248519 -22.19675)
			(xy 285.200379 -22.167837) (xy 285.156997 -22.132179) (xy 285.119312 -22.090546) (xy 285.088137 -22.043837)
			(xy 285.064148 -21.993064) (xy 285.047861 -21.939321) (xy 285.039629 -21.883772) (xy 285.03963 -21.827616)
			(xy 285.047863 -21.772067) (xy 285.064152 -21.718325) (xy 285.088143 -21.667552) (xy 285.119319 -21.620845)
			(xy 285.157006 -21.579213) (xy 285.200389 -21.543556) (xy 285.24853 -21.514644) (xy 285.274258 -21.503386)
			(xy 285.288736 -21.49729) (xy 285.3055 -21.472144) (xy 285.3055 -15.832328) (xy 285.305246 -15.829534)
			(xy 285.304484 -15.820644) (xy 285.297118 -15.804642) (xy 285.278322 -15.785592) (xy 285.241238 -15.748)
			(xy 285.234035 -15.741297) (xy 285.216001 -15.733469) (xy 285.206186 -15.73276) (xy 285.204916 -15.73276)
			(xy 285.179264 -15.731861) (xy 285.128536 -15.724028) (xy 285.079315 -15.709471) (xy 285.032488 -15.68845)
			(xy 284.988899 -15.661346) (xy 284.949334 -15.628646) (xy 284.931612 -15.610078) (xy 284.923992 -15.60195)
			(xy 284.903926 -15.593568) (xy 284.867604 -15.594584) (xy 284.805374 -15.596108) (xy 284.785816 -15.605506)
			(xy 284.778704 -15.614142) (xy 284.760494 -15.635293) (xy 284.718948 -15.672562) (xy 284.672417 -15.703383)
			(xy 284.621893 -15.727098) (xy 284.568454 -15.743201) (xy 284.51324 -15.751349) (xy 284.485334 -15.75181)
			(xy 284.458079 -15.751349) (xy 284.404125 -15.743596) (xy 284.351822 -15.728243) (xy 284.302238 -15.705602)
			(xy 284.25638 -15.676135) (xy 284.215183 -15.640441) (xy 284.179486 -15.599247) (xy 284.150014 -15.553392)
			(xy 284.127369 -15.50381) (xy 284.112011 -15.451509) (xy 284.104253 -15.397555) (xy 284.104253 -15.343045)
			(xy 284.112011 -15.289091) (xy 284.127369 -15.23679) (xy 284.150014 -15.187208) (xy 284.179486 -15.141353)
			(xy 284.215183 -15.100159) (xy 284.25638 -15.064465) (xy 284.302238 -15.034998) (xy 284.351822 -15.012357)
			(xy 284.404125 -14.997004) (xy 284.458079 -14.989251) (xy 284.485334 -14.988794) (xy 284.51157 -14.989234)
			(xy 284.563544 -14.996435) (xy 284.61404 -15.010696) (xy 284.662103 -15.031749) (xy 284.706824 -15.059194)
			(xy 284.747358 -15.092514) (xy 284.765496 -15.111476) (xy 284.773116 -15.119604) (xy 284.793182 -15.127986)
			(xy 284.829504 -15.12697) (xy 284.891734 -15.125446) (xy 284.911292 -15.116048) (xy 284.918404 -15.107412)
			(xy 284.933586 -15.089628) (xy 284.96759 -15.057532) (xy 284.986222 -15.043404) (xy 284.99562 -15.0368)
			(xy 285.006288 -15.016988) (xy 285.01213 -14.915896) (xy 285.003748 -14.895068) (xy 284.995366 -14.887194)
			(xy 284.976531 -14.869073) (xy 284.943493 -14.828572) (xy 284.916287 -14.783944) (xy 284.895422 -14.736023)
			(xy 284.881287 -14.685704) (xy 284.874146 -14.633927) (xy 284.8737 -14.607794) (xy 284.874241 -14.578795)
			(xy 284.883021 -14.521464) (xy 284.900378 -14.466123) (xy 284.925912 -14.414047) (xy 284.959034 -14.366436)
			(xy 284.998981 -14.324387) (xy 285.044833 -14.28887) (xy 285.095532 -14.260702) (xy 285.149911 -14.240533)
			(xy 285.206717 -14.228827) (xy 285.23565 -14.226794) (xy 285.245028 -14.226) (xy 285.262245 -14.218428)
			(xy 285.269178 -14.212062) (xy 285.290768 -14.190472) (xy 285.297545 -14.183047) (xy 285.305133 -14.16445)
			(xy 285.3055 -14.154404) (xy 285.3055 -13.730986) (xy 285.305074 -13.720917) (xy 285.297356 -13.702316)
			(xy 285.290514 -13.694918) (xy 284.985206 -13.38961) (xy 284.977808 -13.382761) (xy 284.95921 -13.375023)
			(xy 284.949138 -13.374624) (xy 280.242518 -13.374624) (xy 280.232455 -13.375063) (xy 280.213874 -13.382801)
			(xy 280.20645 -13.38961) (xy 278.900636 -14.695424) (xy 278.895425 -14.700337) (xy 278.882922 -14.707312)
			(xy 278.875998 -14.70914) (xy 278.866346 -14.711426) (xy 278.850852 -14.722094) (xy 278.802338 -14.793976)
			(xy 278.793956 -14.806422) (xy 278.791416 -14.831314) (xy 278.796242 -14.843252) (xy 278.821752 -14.907255)
			(xy 278.865453 -15.037937) (xy 278.900627 -15.171167) (xy 278.927128 -15.306389) (xy 278.944845 -15.443041)
			(xy 278.953704 -15.58055) (xy 278.95423 -15.649448) (xy 278.95423 -15.680182) (xy 278.952799 -15.745971)
			(xy 278.942827 -15.877197) (xy 278.924788 -16.00756) (xy 278.898751 -16.136563) (xy 278.864816 -16.263717)
			(xy 278.823109 -16.388538) (xy 278.773791 -16.510553) (xy 278.717049 -16.629297) (xy 278.653098 -16.744319)
			(xy 278.582181 -16.855182) (xy 278.504568 -16.961464) (xy 278.420553 -17.062763) (xy 278.330457 -17.158692)
			(xy 278.282908 -17.204182) (xy 278.268176 -17.217644) (xy 278.267922 -17.217898) (xy 278.218785 -17.262865)
			(xy 278.115743 -17.347287) (xy 278.007638 -17.425119) (xy 277.894889 -17.49606) (xy 277.777937 -17.559831)
			(xy 277.657235 -17.616186) (xy 277.533254 -17.664905) (xy 277.406477 -17.705798) (xy 277.277397 -17.738707)
			(xy 277.146515 -17.763502) (xy 277.014342 -17.780088) (xy 276.881393 -17.7884) (xy 276.814788 -17.78889)
			(xy 276.750317 -17.788412) (xy 276.62161 -17.780626) (xy 276.493608 -17.765083) (xy 276.366778 -17.74184)
			(xy 276.241583 -17.710981) (xy 276.118479 -17.67262) (xy 275.997917 -17.626896) (xy 275.880335 -17.573975)
			(xy 275.766162 -17.514052) (xy 275.655817 -17.447345) (xy 275.5497 -17.374097) (xy 275.448199 -17.294575)
			(xy 275.351685 -17.20907) (xy 275.26051 -17.117893) (xy 275.175006 -17.021378) (xy 275.095486 -16.919876)
			(xy 275.022239 -16.813758) (xy 274.955533 -16.703411) (xy 274.895612 -16.589238) (xy 274.842693 -16.471656)
			(xy 274.79697 -16.351092) (xy 274.758611 -16.227988) (xy 274.727754 -16.102793) (xy 274.704512 -15.975962)
			(xy 274.688971 -15.84796) (xy 274.681187 -15.719253) (xy 274.68068 -15.654782) (xy 274.68123 -15.586451)
			(xy 274.689987 -15.45007) (xy 274.707457 -15.31453) (xy 274.733568 -15.180386) (xy 274.768214 -15.048188)
			(xy 274.811252 -14.91848) (xy 274.836382 -14.854936) (xy 274.839176 -14.845538) (xy 274.840192 -14.839696)
			(xy 274.841623 -14.829851) (xy 274.837718 -14.810363) (xy 274.832572 -14.80185) (xy 274.822412 -14.78661)
			(xy 274.78609 -14.732762) (xy 274.778563 -14.722738) (xy 274.756446 -14.711008) (xy 274.743926 -14.71041)
			(xy 272.929096 -14.71041) (xy 272.91967 -14.71079) (xy 272.902096 -14.717616) (xy 272.888186 -14.730341)
			(xy 272.88363 -14.738604) (xy 272.880836 -14.744192) (xy 272.840196 -14.82471) (xy 272.842482 -14.853158)
			(xy 272.851118 -14.864588) (xy 272.87576 -14.899105) (xy 272.919431 -14.971814) (xy 272.956378 -15.04816)
			(xy 272.9863 -15.127522) (xy 273.008956 -15.209256) (xy 273.02416 -15.292698) (xy 273.03179 -15.37717)
			(xy 273.03222 -15.419578) (xy 273.03222 -15.425674) (xy 273.031377 -15.471623) (xy 273.021838 -15.563035)
			(xy 273.003425 -15.653079) (xy 272.976314 -15.740897) (xy 272.940764 -15.825651) (xy 272.919444 -15.866364)
			(xy 272.913348 -15.877794) (xy 272.913348 -15.903194) (xy 272.961608 -15.992602) (xy 272.982944 -16.006572)
			(xy 272.995898 -16.007588) (xy 273.040216 -16.011834) (xy 273.127872 -16.027444) (xy 273.21372 -16.051056)
			(xy 273.29703 -16.082469) (xy 273.377096 -16.121417) (xy 273.453236 -16.167568) (xy 273.524806 -16.220531)
			(xy 273.591197 -16.279857) (xy 273.651847 -16.345042) (xy 273.706239 -16.415532) (xy 273.753912 -16.490729)
			(xy 273.794463 -16.569994) (xy 273.827545 -16.652656) (xy 273.852879 -16.738011) (xy 273.870249 -16.825336)
			(xy 273.879508 -16.913889) (xy 273.880578 -17.002918) (xy 273.873449 -17.091668) (xy 273.858181 -17.179385)
			(xy 273.834906 -17.265324) (xy 273.803819 -17.348757) (xy 273.765185 -17.428974) (xy 273.719331 -17.505294)
			(xy 273.666648 -17.577071) (xy 273.607583 -17.643694) (xy 273.575526 -17.67459) (xy 273.575018 -17.675098)
			(xy 273.57451 -17.675606) (xy 273.542255 -17.705497) (xy 273.473196 -17.759953) (xy 273.399472 -17.807904)
			(xy 273.321693 -17.848954) (xy 273.240505 -17.882762) (xy 273.156579 -17.90905) (xy 273.070611 -17.927598)
			(xy 272.983313 -17.938254) (xy 272.895407 -17.940929) (xy 272.807623 -17.9356) (xy 272.720686 -17.922313)
			(xy 272.635317 -17.901177) (xy 272.552224 -17.872367) (xy 272.472094 -17.836122) (xy 272.39559 -17.792743)
			(xy 272.323348 -17.742587) (xy 272.255965 -17.686071) (xy 272.193999 -17.623663) (xy 272.137963 -17.55588)
			(xy 272.088322 -17.483283) (xy 272.045487 -17.406473) (xy 272.009812 -17.326088) (xy 271.981594 -17.242791)
			(xy 271.961065 -17.157275) (xy 271.948396 -17.070246) (xy 271.943692 -16.982425) (xy 271.946992 -16.894541)
			(xy 271.958267 -16.80732) (xy 271.977426 -16.721486) (xy 272.00431 -16.63775) (xy 272.038694 -16.556804)
			(xy 272.059146 -16.517874) (xy 272.0594 -16.517112) (xy 272.060924 -16.514064) (xy 272.062448 -16.510254)
			(xy 272.066578 -16.498627) (xy 272.064592 -16.474071) (xy 272.058638 -16.463264) (xy 272.057876 -16.462248)
			(xy 272.014696 -16.389858) (xy 272.009893 -16.382489) (xy 271.996337 -16.371299) (xy 271.979797 -16.365353)
			(xy 271.971008 -16.364966) (xy 270.232632 -16.364966) (xy 270.189192 -16.364481) (xy 270.102682 -16.356467)
			(xy 270.017281 -16.340506) (xy 269.933717 -16.316733) (xy 269.852703 -16.28535) (xy 269.77493 -16.246627)
			(xy 269.701062 -16.200892) (xy 269.631729 -16.148537) (xy 269.567523 -16.090008) (xy 269.508991 -16.025804)
			(xy 269.456633 -15.956474) (xy 269.410895 -15.882608) (xy 269.372167 -15.804837) (xy 269.340781 -15.723824)
			(xy 269.317004 -15.640262) (xy 269.301039 -15.554861) (xy 269.293021 -15.468352) (xy 269.292578 -15.424912)
			(xy 269.292578 -15.424404) (xy 269.29306 -15.382207) (xy 269.300669 -15.298157) (xy 269.315783 -15.215127)
			(xy 269.338278 -15.133786) (xy 269.367975 -15.054789) (xy 269.404633 -14.978772) (xy 269.447959 -14.906348)
			(xy 269.47241 -14.871954) (xy 269.480792 -14.86027) (xy 269.483078 -14.831568) (xy 269.470886 -14.807946)
			(xy 269.435834 -14.738858) (xy 269.432238 -14.732282) (xy 269.421907 -14.721434) (xy 269.415514 -14.717522)
			(xy 269.414498 -14.717014) (xy 269.408683 -14.713912) (xy 269.395941 -14.710556) (xy 269.389352 -14.71041)
			(xy 260.06933 -14.71041) (xy 260.059266 -14.710846) (xy 260.040681 -14.71858) (xy 260.033262 -14.725396)
			(xy 259.838952 -14.919706) (xy 259.832001 -14.927266) (xy 259.824252 -14.946266) (xy 259.824547 -14.966783)
			(xy 259.828284 -14.976348) (xy 259.845048 -15.01394) (xy 259.867146 -15.063216) (xy 259.870547 -15.070122)
			(xy 259.880755 -15.081633) (xy 259.887212 -15.085822) (xy 259.89407 -15.089886) (xy 259.908548 -15.093442)
			(xy 259.916168 -15.093188) (xy 259.936742 -15.09268) (xy 259.963992 -15.093169) (xy 260.017937 -15.10093)
			(xy 260.070228 -15.11629) (xy 260.119802 -15.138934) (xy 260.165648 -15.168402) (xy 260.206835 -15.204095)
			(xy 260.242523 -15.245285) (xy 260.271986 -15.291135) (xy 260.294625 -15.340711) (xy 260.309979 -15.393004)
			(xy 260.317734 -15.44695) (xy 260.317734 -15.50145) (xy 260.309979 -15.555396) (xy 260.294625 -15.607689)
			(xy 260.271986 -15.657265) (xy 260.242523 -15.703115) (xy 260.206835 -15.744305) (xy 260.165648 -15.779998)
			(xy 260.119802 -15.809466) (xy 260.070228 -15.83211) (xy 260.017937 -15.84747) (xy 259.963992 -15.855231)
			(xy 259.936742 -15.855696) (xy 259.906751 -15.855145) (xy 259.847508 -15.845758) (xy 259.790471 -15.827195)
			(xy 259.763514 -15.81404) (xy 259.751576 -15.807944) (xy 259.725414 -15.80896) (xy 259.679948 -15.836646)
			(xy 259.664708 -15.846044) (xy 259.651246 -15.854426) (xy 259.639562 -15.861792) (xy 259.632456 -15.866601)
			(xy 259.621719 -15.879969) (xy 259.61603 -15.896145) (xy 259.615686 -15.904718) (xy 259.615686 -18.44421)
			(xy 280.476196 -18.44421) (xy 280.480267 -18.388588) (xy 280.492393 -18.334151) (xy 280.512316 -18.28206)
			(xy 280.539612 -18.233425) (xy 280.573698 -18.189282) (xy 280.613847 -18.150573) (xy 280.659205 -18.118122)
			(xy 280.708805 -18.092621) (xy 280.761589 -18.074614) (xy 280.816432 -18.064484) (xy 280.872166 -18.062447)
			(xy 280.927603 -18.068547) (xy 280.98156 -18.082653) (xy 281.032889 -18.104465) (xy 281.080495 -18.133519)
			(xy 281.123363 -18.169194) (xy 281.16058 -18.210731) (xy 281.191353 -18.257244) (xy 281.215025 -18.307741)
			(xy 281.231093 -18.361148) (xy 281.239213 -18.416324) (xy 281.239722 -18.44421) (xy 281.239213 -18.472096)
			(xy 281.231093 -18.527272) (xy 281.215025 -18.580679) (xy 281.191353 -18.631176) (xy 281.16058 -18.677689)
			(xy 281.123363 -18.719226) (xy 281.080495 -18.754901) (xy 281.032889 -18.783955) (xy 280.98156 -18.805767)
			(xy 280.927603 -18.819873) (xy 280.872166 -18.825973) (xy 280.816432 -18.823936) (xy 280.761589 -18.813806)
			(xy 280.708805 -18.795799) (xy 280.659205 -18.770298) (xy 280.613847 -18.737847) (xy 280.573698 -18.699138)
			(xy 280.539612 -18.654995) (xy 280.512316 -18.60636) (xy 280.492393 -18.554269) (xy 280.480267 -18.499832)
			(xy 280.476196 -18.44421) (xy 259.615686 -18.44421) (xy 259.615686 -20.72513) (xy 263.380486 -20.72513)
			(xy 263.384456 -20.594996) (xy 263.396352 -20.465346) (xy 263.416131 -20.336663) (xy 263.443717 -20.209424)
			(xy 263.47901 -20.084105) (xy 263.521876 -19.961169) (xy 263.572158 -19.841076) (xy 263.629667 -19.724272)
			(xy 263.694191 -19.61119) (xy 263.765488 -19.502253) (xy 263.843293 -19.397865) (xy 263.927318 -19.298414)
			(xy 264.01725 -19.204271) (xy 264.112754 -19.115786) (xy 264.213474 -19.033287) (xy 264.319036 -18.957082)
			(xy 264.429048 -18.887455) (xy 264.5431 -18.824664) (xy 264.660768 -18.768942) (xy 264.781614 -18.720498)
			(xy 264.905189 -18.679511) (xy 265.031032 -18.646134) (xy 265.158677 -18.620491) (xy 265.287647 -18.602677)
			(xy 265.417463 -18.592759) (xy 265.547642 -18.590774) (xy 265.677701 -18.596728) (xy 265.807154 -18.610601)
			(xy 265.935521 -18.632339) (xy 266.062324 -18.661863) (xy 266.187091 -18.699062) (xy 266.309358 -18.743798)
			(xy 266.428671 -18.795906) (xy 266.544584 -18.855189) (xy 266.656669 -18.92143) (xy 266.764506 -18.99438)
			(xy 266.867695 -19.073768) (xy 266.965853 -19.1593) (xy 267.058614 -19.250657) (xy 267.145633 -19.347499)
			(xy 267.226586 -19.449466) (xy 267.301172 -19.556178) (xy 267.369113 -19.667239) (xy 267.430158 -19.782235)
			(xy 267.484079 -19.900739) (xy 267.530674 -20.02231) (xy 267.569772 -20.146495) (xy 267.601226 -20.272833)
			(xy 267.62492 -20.400854) (xy 267.640764 -20.53008) (xy 267.648702 -20.660033) (xy 267.649198 -20.72513)
			(xy 267.648702 -20.790227) (xy 267.640764 -20.92018) (xy 267.62492 -21.049406) (xy 267.601226 -21.177427)
			(xy 267.569772 -21.303765) (xy 267.530674 -21.42795) (xy 267.484079 -21.549521) (xy 267.430158 -21.668025)
			(xy 267.392834 -21.738336) (xy 269.616682 -21.738336) (xy 269.617172 -21.709596) (xy 269.625803 -21.652767)
			(xy 269.642862 -21.597876) (xy 269.667961 -21.546165) (xy 269.700532 -21.498804) (xy 269.719806 -21.477478)
			(xy 269.72641 -21.470366) (xy 269.733522 -21.45284) (xy 269.733522 -21.363432) (xy 269.72641 -21.345906)
			(xy 269.719806 -21.338794) (xy 269.700572 -21.317436) (xy 269.668007 -21.270078) (xy 269.642914 -21.218371)
			(xy 269.625863 -21.163486) (xy 269.617237 -21.106663) (xy 269.617233 -21.049189) (xy 269.625851 -20.992366)
			(xy 269.642895 -20.937477) (xy 269.66798 -20.885767) (xy 269.700539 -20.838405) (xy 269.719806 -20.817078)
			(xy 269.72641 -20.809966) (xy 269.733522 -20.79244) (xy 269.733522 -20.703032) (xy 269.72641 -20.685506)
			(xy 269.719806 -20.678394) (xy 269.700572 -20.657036) (xy 269.668007 -20.609678) (xy 269.642914 -20.557971)
			(xy 269.625863 -20.503086) (xy 269.617237 -20.446263) (xy 269.617233 -20.388789) (xy 269.625851 -20.331966)
			(xy 269.642895 -20.277077) (xy 269.66798 -20.225367) (xy 269.700539 -20.178005) (xy 269.719806 -20.156678)
			(xy 269.72641 -20.149566) (xy 269.733522 -20.13204) (xy 269.733522 -20.042632) (xy 269.72641 -20.025106)
			(xy 269.719806 -20.017994) (xy 269.700572 -19.996636) (xy 269.668007 -19.949278) (xy 269.642914 -19.897571)
			(xy 269.625863 -19.842686) (xy 269.617237 -19.785863) (xy 269.617233 -19.728389) (xy 269.625851 -19.671566)
			(xy 269.642895 -19.616677) (xy 269.66798 -19.564967) (xy 269.700539 -19.517605) (xy 269.719806 -19.496278)
			(xy 269.72641 -19.489166) (xy 269.733522 -19.47164) (xy 269.733522 -19.382232) (xy 269.72641 -19.364706)
			(xy 269.719806 -19.357594) (xy 269.700564 -19.336242) (xy 269.667991 -19.288888) (xy 269.642892 -19.237183)
			(xy 269.625835 -19.182297) (xy 269.617206 -19.125473) (xy 269.616682 -19.096736) (xy 269.617168 -19.069485)
			(xy 269.624924 -19.015537) (xy 269.640279 -18.963242) (xy 269.662921 -18.913665) (xy 269.692387 -18.867815)
			(xy 269.728078 -18.826624) (xy 269.769269 -18.790933) (xy 269.815119 -18.761467) (xy 269.864696 -18.738825)
			(xy 269.916991 -18.72347) (xy 269.970939 -18.715714) (xy 270.025441 -18.715714) (xy 270.079389 -18.72347)
			(xy 270.131684 -18.738825) (xy 270.181261 -18.761467) (xy 270.227111 -18.790933) (xy 270.268302 -18.826624)
			(xy 270.303993 -18.867815) (xy 270.333459 -18.913665) (xy 270.356101 -18.963242) (xy 270.371456 -19.015537)
			(xy 270.379212 -19.069485) (xy 270.379698 -19.096736) (xy 270.379197 -19.125476) (xy 270.370569 -19.182304)
			(xy 270.353513 -19.237195) (xy 270.328417 -19.288907) (xy 270.295847 -19.336268) (xy 270.276574 -19.357594)
			(xy 270.26997 -19.364706) (xy 270.262858 -19.382232) (xy 270.262858 -19.47164) (xy 270.26997 -19.489166)
			(xy 270.276574 -19.496278) (xy 270.295881 -19.517574) (xy 270.328445 -19.564941) (xy 270.353535 -19.616658)
			(xy 270.370582 -19.671554) (xy 270.379201 -19.728385) (xy 270.379197 -19.785867) (xy 270.37057 -19.842697)
			(xy 270.353515 -19.897591) (xy 270.328418 -19.949304) (xy 270.295848 -19.996667) (xy 270.276574 -20.017994)
			(xy 270.26997 -20.025106) (xy 270.262858 -20.042632) (xy 270.262858 -20.13204) (xy 270.26997 -20.149566)
			(xy 270.276574 -20.156678) (xy 270.295881 -20.177974) (xy 270.328445 -20.225341) (xy 270.353535 -20.277058)
			(xy 270.370582 -20.331954) (xy 270.379201 -20.388785) (xy 270.379197 -20.446267) (xy 270.37057 -20.503097)
			(xy 270.353515 -20.557991) (xy 270.328418 -20.609704) (xy 270.295848 -20.657067) (xy 270.276574 -20.678394)
			(xy 270.26997 -20.685506) (xy 270.262858 -20.703032) (xy 270.262858 -20.79244) (xy 270.26997 -20.809966)
			(xy 270.276574 -20.817078) (xy 270.295881 -20.838374) (xy 270.328445 -20.885741) (xy 270.353535 -20.937458)
			(xy 270.370582 -20.992354) (xy 270.379201 -21.049185) (xy 270.379197 -21.106667) (xy 270.37057 -21.163497)
			(xy 270.353515 -21.218391) (xy 270.328418 -21.270104) (xy 270.295848 -21.317467) (xy 270.276574 -21.338794)
			(xy 270.26997 -21.345906) (xy 270.262858 -21.363432) (xy 270.262858 -21.45284) (xy 270.26997 -21.470366)
			(xy 270.276574 -21.477478) (xy 270.295864 -21.498789) (xy 270.328427 -21.546155) (xy 270.353516 -21.597871)
			(xy 270.366294 -21.639022) (xy 274.273772 -21.639022) (xy 274.274317 -21.610284) (xy 274.282935 -21.553458)
			(xy 274.299981 -21.498568) (xy 274.325068 -21.446856) (xy 274.357628 -21.399492) (xy 274.376896 -21.378164)
			(xy 274.3835 -21.371052) (xy 274.390612 -21.353526) (xy 274.390612 -21.264118) (xy 274.3835 -21.246592)
			(xy 274.376896 -21.23948) (xy 274.357648 -21.218134) (xy 274.325085 -21.170774) (xy 274.299994 -21.119065)
			(xy 274.282943 -21.064178) (xy 274.274319 -21.007353) (xy 274.274317 -20.949879) (xy 274.282936 -20.893054)
			(xy 274.299982 -20.838165) (xy 274.325068 -20.786454) (xy 274.357628 -20.739091) (xy 274.376896 -20.717764)
			(xy 274.3835 -20.710652) (xy 274.390612 -20.693126) (xy 274.390612 -20.603718) (xy 274.3835 -20.586192)
			(xy 274.376896 -20.57908) (xy 274.357648 -20.557734) (xy 274.325085 -20.510374) (xy 274.299994 -20.458665)
			(xy 274.282943 -20.403778) (xy 274.274319 -20.346953) (xy 274.274317 -20.289479) (xy 274.282936 -20.232654)
			(xy 274.299982 -20.177765) (xy 274.325068 -20.126054) (xy 274.357628 -20.078691) (xy 274.376896 -20.057364)
			(xy 274.3835 -20.050252) (xy 274.390612 -20.032726) (xy 274.390612 -19.943318) (xy 274.3835 -19.925792)
			(xy 274.376896 -19.91868) (xy 274.357648 -19.897334) (xy 274.325085 -19.849974) (xy 274.299994 -19.798265)
			(xy 274.282943 -19.743378) (xy 274.274319 -19.686553) (xy 274.274317 -19.629079) (xy 274.282936 -19.572254)
			(xy 274.299982 -19.517365) (xy 274.325068 -19.465654) (xy 274.357628 -19.418291) (xy 274.376896 -19.396964)
			(xy 274.3835 -19.389852) (xy 274.390612 -19.372326) (xy 274.390612 -19.282918) (xy 274.3835 -19.265392)
			(xy 274.376896 -19.25828) (xy 274.357646 -19.236935) (xy 274.325075 -19.189579) (xy 274.299977 -19.137872)
			(xy 274.282922 -19.082985) (xy 274.274295 -19.02616) (xy 274.273772 -18.997422) (xy 274.274258 -18.970171)
			(xy 274.282014 -18.916223) (xy 274.297369 -18.863928) (xy 274.320011 -18.814351) (xy 274.349477 -18.768501)
			(xy 274.385168 -18.72731) (xy 274.426359 -18.691619) (xy 274.472209 -18.662153) (xy 274.521786 -18.639511)
			(xy 274.574081 -18.624156) (xy 274.628029 -18.6164) (xy 274.682531 -18.6164) (xy 274.736479 -18.624156)
			(xy 274.788774 -18.639511) (xy 274.838351 -18.662153) (xy 274.884201 -18.691619) (xy 274.925392 -18.72731)
			(xy 274.961083 -18.768501) (xy 274.990549 -18.814351) (xy 275.013191 -18.863928) (xy 275.028546 -18.916223)
			(xy 275.036302 -18.970171) (xy 275.036788 -18.997422) (xy 275.036281 -19.026162) (xy 275.027655 -19.08299)
			(xy 275.010601 -19.137881) (xy 274.985506 -19.189592) (xy 274.952937 -19.236954) (xy 274.933664 -19.25828)
			(xy 274.92706 -19.265392) (xy 274.919948 -19.282918) (xy 274.919948 -19.366857) (xy 279.779115 -19.366857)
			(xy 279.779115 -19.312343) (xy 279.786873 -19.258385) (xy 279.802232 -19.20608) (xy 279.824879 -19.156493)
			(xy 279.854352 -19.110634) (xy 279.890052 -19.069436) (xy 279.931251 -19.033739) (xy 279.977112 -19.004268)
			(xy 280.0267 -18.981624) (xy 280.079006 -18.966269) (xy 280.132965 -18.958513) (xy 280.160222 -18.958052)
			(xy 280.186993 -18.958511) (xy 280.240008 -18.966011) (xy 280.291455 -18.980848) (xy 280.340322 -19.00273)
			(xy 280.385652 -19.031228) (xy 280.426553 -19.065781) (xy 280.462223 -19.105712) (xy 280.477468 -19.127724)
			(xy 280.483564 -19.136614) (xy 280.50109 -19.148044) (xy 280.595578 -19.163284) (xy 280.615898 -19.158204)
			(xy 280.62428 -19.1516) (xy 280.644436 -19.136488) (xy 280.687957 -19.111113) (xy 280.734442 -19.091695)
			(xy 280.783081 -19.078573) (xy 280.833025 -19.071975) (xy 280.858214 -19.07159) (xy 280.885464 -19.072081)
			(xy 280.93941 -19.079839) (xy 280.991703 -19.095195) (xy 281.041278 -19.117837) (xy 281.087127 -19.147303)
			(xy 281.128315 -19.182995) (xy 281.164005 -19.224184) (xy 281.19347 -19.270034) (xy 281.21611 -19.31961)
			(xy 281.231464 -19.371903) (xy 281.23922 -19.42585) (xy 281.23922 -19.48035) (xy 281.231464 -19.534297)
			(xy 281.21611 -19.58659) (xy 281.19347 -19.636166) (xy 281.164005 -19.682016) (xy 281.128315 -19.723205)
			(xy 281.087127 -19.758897) (xy 281.041278 -19.788363) (xy 280.991703 -19.811005) (xy 280.93941 -19.826361)
			(xy 280.885464 -19.834119) (xy 280.858214 -19.834606) (xy 280.831443 -19.834139) (xy 280.778427 -19.826642)
			(xy 280.72698 -19.811808) (xy 280.678112 -19.789928) (xy 280.632782 -19.761431) (xy 280.591881 -19.726878)
			(xy 280.556212 -19.686946) (xy 280.540968 -19.664934) (xy 280.534872 -19.656044) (xy 280.517346 -19.644614)
			(xy 280.422858 -19.629374) (xy 280.402538 -19.634454) (xy 280.394156 -19.641058) (xy 280.374017 -19.656194)
			(xy 280.330492 -19.681566) (xy 280.284002 -19.700979) (xy 280.23536 -19.714096) (xy 280.185412 -19.720687)
			(xy 280.160222 -19.721068) (xy 280.132965 -19.720687) (xy 280.079006 -19.712931) (xy 280.0267 -19.697576)
			(xy 279.977112 -19.674932) (xy 279.931251 -19.645461) (xy 279.890052 -19.609764) (xy 279.854352 -19.568566)
			(xy 279.824879 -19.522707) (xy 279.802232 -19.47312) (xy 279.786873 -19.420815) (xy 279.779115 -19.366857)
			(xy 274.919948 -19.366857) (xy 274.919948 -19.372326) (xy 274.92706 -19.389852) (xy 274.933664 -19.396964)
			(xy 274.952957 -19.418272) (xy 274.985523 -19.465637) (xy 275.010614 -19.517352) (xy 275.027663 -19.572246)
			(xy 275.036284 -19.629076) (xy 275.036281 -19.686556) (xy 275.027656 -19.743386) (xy 275.010602 -19.798278)
			(xy 274.985506 -19.849991) (xy 274.952937 -19.897353) (xy 274.933664 -19.91868) (xy 274.92706 -19.925792)
			(xy 274.919948 -19.943318) (xy 274.919948 -20.032726) (xy 274.92706 -20.050252) (xy 274.933664 -20.057364)
			(xy 274.952957 -20.078672) (xy 274.985523 -20.126037) (xy 275.010614 -20.177752) (xy 275.027663 -20.232646)
			(xy 275.036284 -20.289476) (xy 275.036281 -20.346956) (xy 275.034975 -20.35556) (xy 279.778204 -20.35556)
			(xy 279.782275 -20.299938) (xy 279.794401 -20.245501) (xy 279.814324 -20.19341) (xy 279.84162 -20.144775)
			(xy 279.875706 -20.100632) (xy 279.915855 -20.061923) (xy 279.961213 -20.029472) (xy 280.010813 -20.003971)
			(xy 280.063597 -19.985964) (xy 280.11844 -19.975834) (xy 280.174174 -19.973797) (xy 280.229611 -19.979897)
			(xy 280.283568 -19.994003) (xy 280.334897 -20.015815) (xy 280.382503 -20.044869) (xy 280.425371 -20.080544)
			(xy 280.462588 -20.122081) (xy 280.493361 -20.168594) (xy 280.517033 -20.219091) (xy 280.533101 -20.272498)
			(xy 280.541221 -20.327674) (xy 280.54173 -20.35556) (xy 280.541221 -20.383446) (xy 280.533101 -20.438622)
			(xy 280.517033 -20.492029) (xy 280.493361 -20.542526) (xy 280.462588 -20.589039) (xy 280.425371 -20.630576)
			(xy 280.382503 -20.666251) (xy 280.334897 -20.695305) (xy 280.283568 -20.717117) (xy 280.229611 -20.731223)
			(xy 280.174174 -20.737323) (xy 280.11844 -20.735286) (xy 280.063597 -20.725156) (xy 280.010813 -20.707149)
			(xy 279.961213 -20.681648) (xy 279.915855 -20.649197) (xy 279.875706 -20.610488) (xy 279.84162 -20.566345)
			(xy 279.814324 -20.51771) (xy 279.794401 -20.465619) (xy 279.782275 -20.411182) (xy 279.778204 -20.35556)
			(xy 275.034975 -20.35556) (xy 275.027656 -20.403786) (xy 275.010602 -20.458678) (xy 274.985506 -20.510391)
			(xy 274.952937 -20.557753) (xy 274.933664 -20.57908) (xy 274.92706 -20.586192) (xy 274.919948 -20.603718)
			(xy 274.919948 -20.693126) (xy 274.92706 -20.710652) (xy 274.933664 -20.717764) (xy 274.952957 -20.739072)
			(xy 274.985523 -20.786437) (xy 275.010614 -20.838152) (xy 275.027663 -20.893046) (xy 275.036284 -20.949876)
			(xy 275.036281 -21.007356) (xy 275.027656 -21.064186) (xy 275.010602 -21.119078) (xy 274.985506 -21.170791)
			(xy 274.952937 -21.218153) (xy 274.933664 -21.23948) (xy 274.92706 -21.246592) (xy 274.919948 -21.264118)
			(xy 274.919948 -21.353526) (xy 274.92706 -21.371052) (xy 274.927532 -21.37156) (xy 279.778204 -21.37156)
			(xy 279.782275 -21.315938) (xy 279.794401 -21.261501) (xy 279.814324 -21.20941) (xy 279.84162 -21.160775)
			(xy 279.875706 -21.116632) (xy 279.915855 -21.077923) (xy 279.961213 -21.045472) (xy 280.010813 -21.019971)
			(xy 280.063597 -21.001964) (xy 280.11844 -20.991834) (xy 280.174174 -20.989797) (xy 280.229611 -20.995897)
			(xy 280.283568 -21.010003) (xy 280.334897 -21.031815) (xy 280.382503 -21.060869) (xy 280.425371 -21.096544)
			(xy 280.462588 -21.138081) (xy 280.493361 -21.184594) (xy 280.517033 -21.235091) (xy 280.533101 -21.288498)
			(xy 280.541221 -21.343674) (xy 280.54173 -21.37156) (xy 280.541221 -21.399446) (xy 280.533101 -21.454622)
			(xy 280.517033 -21.508029) (xy 280.493361 -21.558526) (xy 280.462588 -21.605039) (xy 280.425371 -21.646576)
			(xy 280.382503 -21.682251) (xy 280.334897 -21.711305) (xy 280.283568 -21.733117) (xy 280.229611 -21.747223)
			(xy 280.174174 -21.753323) (xy 280.11844 -21.751286) (xy 280.063597 -21.741156) (xy 280.010813 -21.723149)
			(xy 279.961213 -21.697648) (xy 279.915855 -21.665197) (xy 279.875706 -21.626488) (xy 279.84162 -21.582345)
			(xy 279.814324 -21.53371) (xy 279.794401 -21.481619) (xy 279.782275 -21.427182) (xy 279.778204 -21.37156)
			(xy 274.927532 -21.37156) (xy 274.933664 -21.378164) (xy 274.952945 -21.399482) (xy 274.98551 -21.446846)
			(xy 275.010601 -21.49856) (xy 275.027649 -21.553453) (xy 275.036269 -21.610282) (xy 275.036788 -21.639022)
			(xy 275.036302 -21.666273) (xy 275.028546 -21.720221) (xy 275.013191 -21.772516) (xy 275.011749 -21.775674)
			(xy 284.135828 -21.775674) (xy 284.139899 -21.720052) (xy 284.152025 -21.665615) (xy 284.171948 -21.613524)
			(xy 284.199244 -21.564889) (xy 284.23333 -21.520746) (xy 284.273479 -21.482037) (xy 284.318837 -21.449586)
			(xy 284.368437 -21.424085) (xy 284.421221 -21.406078) (xy 284.476064 -21.395948) (xy 284.531798 -21.393911)
			(xy 284.587235 -21.400011) (xy 284.641192 -21.414117) (xy 284.692521 -21.435929) (xy 284.740127 -21.464983)
			(xy 284.782995 -21.500658) (xy 284.820212 -21.542195) (xy 284.850985 -21.588708) (xy 284.874657 -21.639205)
			(xy 284.890725 -21.692612) (xy 284.898845 -21.747788) (xy 284.899354 -21.775674) (xy 284.898845 -21.80356)
			(xy 284.890725 -21.858736) (xy 284.874657 -21.912143) (xy 284.850985 -21.96264) (xy 284.820212 -22.009153)
			(xy 284.782995 -22.05069) (xy 284.740127 -22.086365) (xy 284.692521 -22.115419) (xy 284.641192 -22.137231)
			(xy 284.587235 -22.151337) (xy 284.531798 -22.157437) (xy 284.476064 -22.1554) (xy 284.421221 -22.14527)
			(xy 284.368437 -22.127263) (xy 284.318837 -22.101762) (xy 284.273479 -22.069311) (xy 284.23333 -22.030602)
			(xy 284.199244 -21.986459) (xy 284.171948 -21.937824) (xy 284.152025 -21.885733) (xy 284.139899 -21.831296)
			(xy 284.135828 -21.775674) (xy 275.011749 -21.775674) (xy 274.990549 -21.822093) (xy 274.961083 -21.867943)
			(xy 274.925392 -21.909134) (xy 274.884201 -21.944825) (xy 274.838351 -21.974291) (xy 274.788774 -21.996933)
			(xy 274.736479 -22.012288) (xy 274.682531 -22.020044) (xy 274.628029 -22.020044) (xy 274.574081 -22.012288)
			(xy 274.521786 -21.996933) (xy 274.472209 -21.974291) (xy 274.426359 -21.944825) (xy 274.385168 -21.909134)
			(xy 274.349477 -21.867943) (xy 274.320011 -21.822093) (xy 274.297369 -21.772516) (xy 274.282014 -21.720221)
			(xy 274.274258 -21.666273) (xy 274.273772 -21.639022) (xy 270.366294 -21.639022) (xy 270.370562 -21.652765)
			(xy 270.37918 -21.709596) (xy 270.379698 -21.738336) (xy 270.379212 -21.765587) (xy 270.371456 -21.819535)
			(xy 270.356101 -21.87183) (xy 270.333459 -21.921407) (xy 270.303993 -21.967257) (xy 270.268302 -22.008448)
			(xy 270.227111 -22.044139) (xy 270.181261 -22.073605) (xy 270.131684 -22.096247) (xy 270.079389 -22.111602)
			(xy 270.025441 -22.119358) (xy 269.970939 -22.119358) (xy 269.916991 -22.111602) (xy 269.864696 -22.096247)
			(xy 269.815119 -22.073605) (xy 269.769269 -22.044139) (xy 269.728078 -22.008448) (xy 269.692387 -21.967257)
			(xy 269.662921 -21.921407) (xy 269.640279 -21.87183) (xy 269.624924 -21.819535) (xy 269.617168 -21.765587)
			(xy 269.616682 -21.738336) (xy 267.392834 -21.738336) (xy 267.369113 -21.783021) (xy 267.301172 -21.894082)
			(xy 267.226586 -22.000794) (xy 267.145633 -22.102761) (xy 267.058614 -22.199603) (xy 266.965853 -22.29096)
			(xy 266.867695 -22.376492) (xy 266.764506 -22.45588) (xy 266.656669 -22.52883) (xy 266.544584 -22.595071)
			(xy 266.428671 -22.654354) (xy 266.309358 -22.706462) (xy 266.187091 -22.751198) (xy 266.062324 -22.788397)
			(xy 265.935521 -22.817921) (xy 265.807154 -22.839659) (xy 265.677701 -22.853532) (xy 265.547642 -22.859486)
			(xy 265.417463 -22.857501) (xy 265.287647 -22.847583) (xy 265.158677 -22.829769) (xy 265.031032 -22.804126)
			(xy 264.905189 -22.770749) (xy 264.781614 -22.729762) (xy 264.660768 -22.681318) (xy 264.5431 -22.625596)
			(xy 264.429048 -22.562805) (xy 264.319036 -22.493178) (xy 264.213474 -22.416973) (xy 264.112754 -22.334474)
			(xy 264.01725 -22.245989) (xy 263.927318 -22.151846) (xy 263.843293 -22.052395) (xy 263.765488 -21.948007)
			(xy 263.694191 -21.83907) (xy 263.629667 -21.725988) (xy 263.572158 -21.609184) (xy 263.521876 -21.489091)
			(xy 263.47901 -21.366155) (xy 263.443717 -21.240836) (xy 263.416131 -21.113597) (xy 263.396352 -20.984914)
			(xy 263.384456 -20.855264) (xy 263.380486 -20.72513) (xy 259.615686 -20.72513) (xy 259.615686 -21.500084)
			(xy 259.616268 -21.512417) (xy 259.627704 -21.534267) (xy 259.63753 -21.54174) (xy 259.660579 -21.558297)
			(xy 259.701976 -21.597116) (xy 259.737167 -21.641636) (xy 259.765378 -21.690877) (xy 259.785985 -21.743753)
			(xy 259.798534 -21.799098) (xy 259.802105 -21.847048) (xy 260.272782 -21.847048) (xy 260.276853 -21.791426)
			(xy 260.288979 -21.736989) (xy 260.308902 -21.684898) (xy 260.336198 -21.636263) (xy 260.370284 -21.59212)
			(xy 260.410433 -21.553411) (xy 260.455791 -21.52096) (xy 260.505391 -21.495459) (xy 260.558175 -21.477452)
			(xy 260.613018 -21.467322) (xy 260.668752 -21.465285) (xy 260.724189 -21.471385) (xy 260.778146 -21.485491)
			(xy 260.829475 -21.507303) (xy 260.877081 -21.536357) (xy 260.919949 -21.572032) (xy 260.957166 -21.613569)
			(xy 260.987939 -21.660082) (xy 261.011611 -21.710579) (xy 261.027679 -21.763986) (xy 261.035799 -21.819162)
			(xy 261.036308 -21.847048) (xy 261.035799 -21.874934) (xy 261.027679 -21.93011) (xy 261.011611 -21.983517)
			(xy 260.987939 -22.034014) (xy 260.957166 -22.080527) (xy 260.919949 -22.122064) (xy 260.877081 -22.157739)
			(xy 260.829475 -22.186793) (xy 260.778146 -22.208605) (xy 260.724189 -22.222711) (xy 260.668752 -22.228811)
			(xy 260.613018 -22.226774) (xy 260.558175 -22.216644) (xy 260.505391 -22.198637) (xy 260.455791 -22.173136)
			(xy 260.410433 -22.140685) (xy 260.370284 -22.101976) (xy 260.336198 -22.057833) (xy 260.308902 -22.009198)
			(xy 260.288979 -21.957107) (xy 260.276853 -21.90267) (xy 260.272782 -21.847048) (xy 259.802105 -21.847048)
			(xy 259.802749 -21.855691) (xy 259.798537 -21.912284) (xy 259.78599 -21.967629) (xy 259.765385 -22.020506)
			(xy 259.737177 -22.069749) (xy 259.701988 -22.114271) (xy 259.660593 -22.153091) (xy 259.63753 -22.169628)
			(xy 259.627857 -22.177239) (xy 259.616437 -22.198999) (xy 259.615686 -22.211284) (xy 259.615686 -23.0251)
			(xy 269.562324 -23.0251) (xy 269.566395 -22.969478) (xy 269.578521 -22.915041) (xy 269.598444 -22.86295)
			(xy 269.62574 -22.814315) (xy 269.659826 -22.770172) (xy 269.699975 -22.731463) (xy 269.745333 -22.699012)
			(xy 269.794933 -22.673511) (xy 269.847717 -22.655504) (xy 269.90256 -22.645374) (xy 269.958294 -22.643337)
			(xy 270.013731 -22.649437) (xy 270.067688 -22.663543) (xy 270.119017 -22.685355) (xy 270.166623 -22.714409)
			(xy 270.209491 -22.750084) (xy 270.246708 -22.791621) (xy 270.277481 -22.838134) (xy 270.301153 -22.888631)
			(xy 270.317221 -22.942038) (xy 270.325341 -22.997214) (xy 270.32585 -23.0251) (xy 270.325341 -23.052986)
			(xy 270.317221 -23.108162) (xy 270.301153 -23.161569) (xy 270.277481 -23.212066) (xy 270.246708 -23.258579)
			(xy 270.209491 -23.300116) (xy 270.166623 -23.335791) (xy 270.119017 -23.364845) (xy 270.067688 -23.386657)
			(xy 270.013731 -23.400763) (xy 269.958294 -23.406863) (xy 269.90256 -23.404826) (xy 269.847717 -23.394696)
			(xy 269.794933 -23.376689) (xy 269.745333 -23.351188) (xy 269.699975 -23.318737) (xy 269.659826 -23.280028)
			(xy 269.62574 -23.235885) (xy 269.598444 -23.18725) (xy 269.578521 -23.135159) (xy 269.566395 -23.080722)
			(xy 269.562324 -23.0251) (xy 259.615686 -23.0251) (xy 259.615686 -23.515066) (xy 259.645404 -23.544784)
			(xy 259.658358 -23.557738) (xy 259.675122 -23.565358) (xy 259.684774 -23.56612) (xy 259.713546 -23.568347)
			(xy 259.769983 -23.580379) (xy 259.823966 -23.600771) (xy 259.874264 -23.629058) (xy 259.91973 -23.664594)
			(xy 259.959328 -23.706571) (xy 259.992154 -23.75403) (xy 260.017461 -23.805891) (xy 260.034673 -23.86097)
			(xy 260.043395 -23.918013) (xy 260.04393 -23.946866) (xy 260.043482 -23.970996) (xy 260.272782 -23.970996)
			(xy 260.276853 -23.915374) (xy 260.288979 -23.860937) (xy 260.308902 -23.808846) (xy 260.336198 -23.760211)
			(xy 260.370284 -23.716068) (xy 260.410433 -23.677359) (xy 260.455791 -23.644908) (xy 260.505391 -23.619407)
			(xy 260.558175 -23.6014) (xy 260.613018 -23.59127) (xy 260.668752 -23.589233) (xy 260.724189 -23.595333)
			(xy 260.778146 -23.609439) (xy 260.781415 -23.610828) (xy 270.265923 -23.610828) (xy 270.265926 -23.556333)
			(xy 270.273683 -23.502394) (xy 270.289039 -23.450107) (xy 270.311679 -23.400538) (xy 270.341142 -23.354695)
			(xy 270.37683 -23.313512) (xy 270.418016 -23.277827) (xy 270.46386 -23.248366) (xy 270.513431 -23.22573)
			(xy 270.565719 -23.210378) (xy 270.619659 -23.202624) (xy 270.646906 -23.202138) (xy 270.670935 -23.202513)
			(xy 270.718613 -23.208552) (xy 270.765154 -23.220534) (xy 270.787622 -23.229062) (xy 270.80078 -23.233829)
			(xy 270.828605 -23.236733) (xy 270.856175 -23.231982) (xy 270.881423 -23.219933) (xy 270.902457 -23.201488)
			(xy 270.917701 -23.17803) (xy 270.926013 -23.151317) (xy 270.926768 -23.123351) (xy 270.923766 -23.109682)
			(xy 270.918316 -23.086699) (xy 270.912454 -23.039828) (xy 270.912082 -23.01621) (xy 270.912544 -22.988956)
			(xy 270.9203 -22.935003) (xy 270.935656 -22.882703) (xy 270.958298 -22.83312) (xy 270.987766 -22.787265)
			(xy 271.02346 -22.74607) (xy 271.064654 -22.710374) (xy 271.110508 -22.680904) (xy 271.16009 -22.65826)
			(xy 271.21239 -22.642903) (xy 271.266343 -22.635145) (xy 271.320851 -22.635145) (xy 271.374804 -22.642902)
			(xy 271.427104 -22.658258) (xy 271.476686 -22.680901) (xy 271.522541 -22.71037) (xy 271.563735 -22.746065)
			(xy 271.59943 -22.787259) (xy 271.628899 -22.833114) (xy 271.651542 -22.882696) (xy 271.666898 -22.934996)
			(xy 271.674655 -22.988949) (xy 271.674655 -23.043457) (xy 271.666897 -23.09741) (xy 271.65154 -23.14971)
			(xy 271.628896 -23.199292) (xy 271.599426 -23.245146) (xy 271.56373 -23.28634) (xy 271.522535 -23.322034)
			(xy 271.47668 -23.351502) (xy 271.427097 -23.374144) (xy 271.374797 -23.3895) (xy 271.320844 -23.397256)
			(xy 271.29359 -23.397718) (xy 271.269561 -23.39734) (xy 271.221883 -23.391301) (xy 271.175342 -23.379321)
			(xy 271.152874 -23.370794) (xy 271.139703 -23.366074) (xy 271.111887 -23.363174) (xy 271.084327 -23.367925)
			(xy 271.059088 -23.379969) (xy 271.038058 -23.398405) (xy 271.022815 -23.421851) (xy 271.014499 -23.448553)
			(xy 271.013734 -23.476509) (xy 271.01673 -23.490174) (xy 271.02219 -23.513155) (xy 271.028046 -23.560028)
			(xy 271.028414 -23.583646) (xy 271.028288 -23.589996) (xy 274.284438 -23.589996) (xy 274.288509 -23.534374)
			(xy 274.300635 -23.479937) (xy 274.320558 -23.427846) (xy 274.347854 -23.379211) (xy 274.38194 -23.335068)
			(xy 274.422089 -23.296359) (xy 274.467447 -23.263908) (xy 274.517047 -23.238407) (xy 274.569831 -23.2204)
			(xy 274.624674 -23.21027) (xy 274.680408 -23.208233) (xy 274.735845 -23.214333) (xy 274.789802 -23.228439)
			(xy 274.841131 -23.250251) (xy 274.888737 -23.279305) (xy 274.931605 -23.31498) (xy 274.967959 -23.355554)
			(xy 283.530548 -23.355554) (xy 283.531039 -23.328744) (xy 283.538545 -23.275651) (xy 283.553417 -23.224135)
			(xy 283.575362 -23.175211) (xy 283.603946 -23.129844) (xy 283.638605 -23.088931) (xy 283.678655 -23.053278)
			(xy 283.700728 -23.038054) (xy 283.712268 -23.029766) (xy 283.730666 -23.008134) (xy 283.7424 -22.982274)
			(xy 283.746562 -22.954184) (xy 283.742831 -22.926032) (xy 283.731496 -22.899995) (xy 283.713431 -22.878084)
			(xy 283.701998 -22.869652) (xy 283.680555 -22.85428) (xy 283.641641 -22.818657) (xy 283.608007 -22.778012)
			(xy 283.580294 -22.733119) (xy 283.559032 -22.684837) (xy 283.544624 -22.634085) (xy 283.537348 -22.581832)
			(xy 283.536898 -22.555454) (xy 283.537384 -22.528203) (xy 283.54514 -22.474255) (xy 283.560495 -22.42196)
			(xy 283.583137 -22.372383) (xy 283.612603 -22.326533) (xy 283.648294 -22.285342) (xy 283.689485 -22.249651)
			(xy 283.735335 -22.220185) (xy 283.784912 -22.197543) (xy 283.837207 -22.182188) (xy 283.891155 -22.174432)
			(xy 283.945657 -22.174432) (xy 283.999605 -22.182188) (xy 284.0519 -22.197543) (xy 284.101477 -22.220185)
			(xy 284.147327 -22.249651) (xy 284.188518 -22.285342) (xy 284.224209 -22.326533) (xy 284.253675 -22.372383)
			(xy 284.276317 -22.42196) (xy 284.291672 -22.474255) (xy 284.299428 -22.528203) (xy 284.299914 -22.555454)
			(xy 284.299446 -22.582265) (xy 284.291938 -22.635359) (xy 284.277063 -22.686877) (xy 284.255115 -22.735802)
			(xy 284.226527 -22.781168) (xy 284.191864 -22.822081) (xy 284.151809 -22.857732) (xy 284.129734 -22.872954)
			(xy 284.118181 -22.881229) (xy 284.099771 -22.902859) (xy 284.08803 -22.928724) (xy 284.083866 -22.956821)
			(xy 284.087601 -22.984978) (xy 284.098946 -23.011019) (xy 284.117024 -23.032927) (xy 284.128464 -23.041356)
			(xy 284.149924 -23.056704) (xy 284.188835 -23.092333) (xy 284.222466 -23.132984) (xy 284.250175 -23.17788)
			(xy 284.271435 -23.226166) (xy 284.28584 -23.27692) (xy 284.293115 -23.329175) (xy 284.293564 -23.355554)
			(xy 284.293078 -23.382805) (xy 284.285322 -23.436753) (xy 284.269967 -23.489048) (xy 284.247325 -23.538625)
			(xy 284.217859 -23.584475) (xy 284.182168 -23.625666) (xy 284.140977 -23.661357) (xy 284.095127 -23.690823)
			(xy 284.04555 -23.713465) (xy 283.993255 -23.72882) (xy 283.939307 -23.736576) (xy 283.884805 -23.736576)
			(xy 283.830857 -23.72882) (xy 283.778562 -23.713465) (xy 283.728985 -23.690823) (xy 283.683135 -23.661357)
			(xy 283.641944 -23.625666) (xy 283.606253 -23.584475) (xy 283.576787 -23.538625) (xy 283.554145 -23.489048)
			(xy 283.53879 -23.436753) (xy 283.531034 -23.382805) (xy 283.530548 -23.355554) (xy 274.967959 -23.355554)
			(xy 274.968822 -23.356517) (xy 274.999595 -23.40303) (xy 275.023267 -23.453527) (xy 275.039335 -23.506934)
			(xy 275.047455 -23.56211) (xy 275.047964 -23.589996) (xy 275.047455 -23.617882) (xy 275.039335 -23.673058)
			(xy 275.023267 -23.726465) (xy 274.999595 -23.776962) (xy 274.968822 -23.823475) (xy 274.931605 -23.865012)
			(xy 274.913213 -23.880318) (xy 275.440646 -23.880318) (xy 275.444717 -23.824696) (xy 275.456843 -23.770259)
			(xy 275.476766 -23.718168) (xy 275.504062 -23.669533) (xy 275.538148 -23.62539) (xy 275.578297 -23.586681)
			(xy 275.623655 -23.55423) (xy 275.673255 -23.528729) (xy 275.726039 -23.510722) (xy 275.780882 -23.500592)
			(xy 275.836616 -23.498555) (xy 275.892053 -23.504655) (xy 275.94601 -23.518761) (xy 275.997339 -23.540573)
			(xy 276.044945 -23.569627) (xy 276.087813 -23.605302) (xy 276.12503 -23.646839) (xy 276.155803 -23.693352)
			(xy 276.179475 -23.743849) (xy 276.195543 -23.797256) (xy 276.203663 -23.852432) (xy 276.204172 -23.880318)
			(xy 276.456646 -23.880318) (xy 276.460717 -23.824696) (xy 276.472843 -23.770259) (xy 276.492766 -23.718168)
			(xy 276.520062 -23.669533) (xy 276.554148 -23.62539) (xy 276.594297 -23.586681) (xy 276.639655 -23.55423)
			(xy 276.689255 -23.528729) (xy 276.742039 -23.510722) (xy 276.796882 -23.500592) (xy 276.852616 -23.498555)
			(xy 276.908053 -23.504655) (xy 276.96201 -23.518761) (xy 277.013339 -23.540573) (xy 277.060945 -23.569627)
			(xy 277.103813 -23.605302) (xy 277.14103 -23.646839) (xy 277.171803 -23.693352) (xy 277.195475 -23.743849)
			(xy 277.211543 -23.797256) (xy 277.219663 -23.852432) (xy 277.220172 -23.880318) (xy 277.472646 -23.880318)
			(xy 277.476717 -23.824696) (xy 277.488843 -23.770259) (xy 277.508766 -23.718168) (xy 277.536062 -23.669533)
			(xy 277.570148 -23.62539) (xy 277.610297 -23.586681) (xy 277.655655 -23.55423) (xy 277.705255 -23.528729)
			(xy 277.758039 -23.510722) (xy 277.812882 -23.500592) (xy 277.868616 -23.498555) (xy 277.924053 -23.504655)
			(xy 277.97801 -23.518761) (xy 278.029339 -23.540573) (xy 278.076945 -23.569627) (xy 278.119813 -23.605302)
			(xy 278.15703 -23.646839) (xy 278.187803 -23.693352) (xy 278.211475 -23.743849) (xy 278.227543 -23.797256)
			(xy 278.235663 -23.852432) (xy 278.236172 -23.880318) (xy 278.490932 -23.880318) (xy 278.495003 -23.824696)
			(xy 278.507129 -23.770259) (xy 278.527052 -23.718168) (xy 278.554348 -23.669533) (xy 278.588434 -23.62539)
			(xy 278.628583 -23.586681) (xy 278.673941 -23.55423) (xy 278.723541 -23.528729) (xy 278.776325 -23.510722)
			(xy 278.831168 -23.500592) (xy 278.886902 -23.498555) (xy 278.942339 -23.504655) (xy 278.996296 -23.518761)
			(xy 279.047625 -23.540573) (xy 279.095231 -23.569627) (xy 279.138099 -23.605302) (xy 279.175316 -23.646839)
			(xy 279.206089 -23.693352) (xy 279.229761 -23.743849) (xy 279.245829 -23.797256) (xy 279.253949 -23.852432)
			(xy 279.254458 -23.880318) (xy 279.253949 -23.908204) (xy 279.245829 -23.96338) (xy 279.229761 -24.016787)
			(xy 279.206089 -24.067284) (xy 279.175316 -24.113797) (xy 279.138099 -24.155334) (xy 279.095231 -24.191009)
			(xy 279.047625 -24.220063) (xy 278.996296 -24.241875) (xy 278.942339 -24.255981) (xy 278.886902 -24.262081)
			(xy 278.831168 -24.260044) (xy 278.776325 -24.249914) (xy 278.723541 -24.231907) (xy 278.673941 -24.206406)
			(xy 278.628583 -24.173955) (xy 278.588434 -24.135246) (xy 278.554348 -24.091103) (xy 278.527052 -24.042468)
			(xy 278.507129 -23.990377) (xy 278.495003 -23.93594) (xy 278.490932 -23.880318) (xy 278.236172 -23.880318)
			(xy 278.235663 -23.908204) (xy 278.227543 -23.96338) (xy 278.211475 -24.016787) (xy 278.187803 -24.067284)
			(xy 278.15703 -24.113797) (xy 278.119813 -24.155334) (xy 278.076945 -24.191009) (xy 278.029339 -24.220063)
			(xy 277.97801 -24.241875) (xy 277.924053 -24.255981) (xy 277.868616 -24.262081) (xy 277.812882 -24.260044)
			(xy 277.758039 -24.249914) (xy 277.705255 -24.231907) (xy 277.655655 -24.206406) (xy 277.610297 -24.173955)
			(xy 277.570148 -24.135246) (xy 277.536062 -24.091103) (xy 277.508766 -24.042468) (xy 277.488843 -23.990377)
			(xy 277.476717 -23.93594) (xy 277.472646 -23.880318) (xy 277.220172 -23.880318) (xy 277.219663 -23.908204)
			(xy 277.211543 -23.96338) (xy 277.195475 -24.016787) (xy 277.171803 -24.067284) (xy 277.14103 -24.113797)
			(xy 277.103813 -24.155334) (xy 277.060945 -24.191009) (xy 277.013339 -24.220063) (xy 276.96201 -24.241875)
			(xy 276.908053 -24.255981) (xy 276.852616 -24.262081) (xy 276.796882 -24.260044) (xy 276.742039 -24.249914)
			(xy 276.689255 -24.231907) (xy 276.639655 -24.206406) (xy 276.594297 -24.173955) (xy 276.554148 -24.135246)
			(xy 276.520062 -24.091103) (xy 276.492766 -24.042468) (xy 276.472843 -23.990377) (xy 276.460717 -23.93594)
			(xy 276.456646 -23.880318) (xy 276.204172 -23.880318) (xy 276.203663 -23.908204) (xy 276.195543 -23.96338)
			(xy 276.179475 -24.016787) (xy 276.155803 -24.067284) (xy 276.12503 -24.113797) (xy 276.087813 -24.155334)
			(xy 276.044945 -24.191009) (xy 275.997339 -24.220063) (xy 275.94601 -24.241875) (xy 275.892053 -24.255981)
			(xy 275.836616 -24.262081) (xy 275.780882 -24.260044) (xy 275.726039 -24.249914) (xy 275.673255 -24.231907)
			(xy 275.623655 -24.206406) (xy 275.578297 -24.173955) (xy 275.538148 -24.135246) (xy 275.504062 -24.091103)
			(xy 275.476766 -24.042468) (xy 275.456843 -23.990377) (xy 275.444717 -23.93594) (xy 275.440646 -23.880318)
			(xy 274.913213 -23.880318) (xy 274.888737 -23.900687) (xy 274.841131 -23.929741) (xy 274.789802 -23.951553)
			(xy 274.735845 -23.965659) (xy 274.680408 -23.971759) (xy 274.624674 -23.969722) (xy 274.569831 -23.959592)
			(xy 274.517047 -23.941585) (xy 274.467447 -23.916084) (xy 274.422089 -23.883633) (xy 274.38194 -23.844924)
			(xy 274.347854 -23.800781) (xy 274.320558 -23.752146) (xy 274.300635 -23.700055) (xy 274.288509 -23.645618)
			(xy 274.284438 -23.589996) (xy 271.028288 -23.589996) (xy 271.027873 -23.610893) (xy 271.020111 -23.664832)
			(xy 271.004752 -23.717118) (xy 270.982109 -23.766685) (xy 270.952642 -23.812526) (xy 270.916951 -23.853707)
			(xy 270.875763 -23.889389) (xy 270.829916 -23.918846) (xy 270.780344 -23.941479) (xy 270.728055 -23.956828)
			(xy 270.674115 -23.964578) (xy 270.61962 -23.964574) (xy 270.565681 -23.956814) (xy 270.513395 -23.941457)
			(xy 270.463826 -23.918815) (xy 270.417985 -23.88935) (xy 270.376803 -23.85366) (xy 270.341119 -23.812474)
			(xy 270.31166 -23.766628) (xy 270.289025 -23.717057) (xy 270.273675 -23.664768) (xy 270.265923 -23.610828)
			(xy 260.781415 -23.610828) (xy 260.829475 -23.631251) (xy 260.877081 -23.660305) (xy 260.919949 -23.69598)
			(xy 260.957166 -23.737517) (xy 260.987939 -23.78403) (xy 261.011611 -23.834527) (xy 261.027679 -23.887934)
			(xy 261.035799 -23.94311) (xy 261.036308 -23.970996) (xy 261.035799 -23.998882) (xy 261.027679 -24.054058)
			(xy 261.011611 -24.107465) (xy 260.987939 -24.157962) (xy 260.987786 -24.158194) (xy 265.650724 -24.158194)
			(xy 265.654795 -24.102572) (xy 265.666921 -24.048135) (xy 265.686844 -23.996044) (xy 265.71414 -23.947409)
			(xy 265.748226 -23.903266) (xy 265.788375 -23.864557) (xy 265.833733 -23.832106) (xy 265.883333 -23.806605)
			(xy 265.936117 -23.788598) (xy 265.99096 -23.778468) (xy 266.046694 -23.776431) (xy 266.102131 -23.782531)
			(xy 266.156088 -23.796637) (xy 266.207417 -23.818449) (xy 266.255023 -23.847503) (xy 266.297891 -23.883178)
			(xy 266.335108 -23.924715) (xy 266.365881 -23.971228) (xy 266.389553 -24.021725) (xy 266.405621 -24.075132)
			(xy 266.413741 -24.130308) (xy 266.41425 -24.158194) (xy 266.413741 -24.18608) (xy 266.413172 -24.189944)
			(xy 269.498824 -24.189944) (xy 269.502895 -24.134322) (xy 269.515021 -24.079885) (xy 269.534944 -24.027794)
			(xy 269.56224 -23.979159) (xy 269.596326 -23.935016) (xy 269.636475 -23.896307) (xy 269.681833 -23.863856)
			(xy 269.731433 -23.838355) (xy 269.784217 -23.820348) (xy 269.83906 -23.810218) (xy 269.894794 -23.808181)
			(xy 269.950231 -23.814281) (xy 270.004188 -23.828387) (xy 270.055517 -23.850199) (xy 270.103123 -23.879253)
			(xy 270.145991 -23.914928) (xy 270.183208 -23.956465) (xy 270.213981 -24.002978) (xy 270.237653 -24.053475)
			(xy 270.253721 -24.106882) (xy 270.261841 -24.162058) (xy 270.26235 -24.189944) (xy 272.021806 -24.189944)
			(xy 272.025877 -24.134322) (xy 272.038003 -24.079885) (xy 272.057926 -24.027794) (xy 272.085222 -23.979159)
			(xy 272.119308 -23.935016) (xy 272.159457 -23.896307) (xy 272.204815 -23.863856) (xy 272.254415 -23.838355)
			(xy 272.307199 -23.820348) (xy 272.362042 -23.810218) (xy 272.417776 -23.808181) (xy 272.473213 -23.814281)
			(xy 272.52717 -23.828387) (xy 272.578499 -23.850199) (xy 272.626105 -23.879253) (xy 272.668973 -23.914928)
			(xy 272.70619 -23.956465) (xy 272.736963 -24.002978) (xy 272.760635 -24.053475) (xy 272.776703 -24.106882)
			(xy 272.784823 -24.162058) (xy 272.785332 -24.189944) (xy 272.784823 -24.21783) (xy 272.776703 -24.273006)
			(xy 272.760635 -24.326413) (xy 272.736963 -24.37691) (xy 272.70619 -24.423423) (xy 272.668973 -24.46496)
			(xy 272.626105 -24.500635) (xy 272.578499 -24.529689) (xy 272.52717 -24.551501) (xy 272.473213 -24.565607)
			(xy 272.417776 -24.571707) (xy 272.362042 -24.56967) (xy 272.307199 -24.55954) (xy 272.254415 -24.541533)
			(xy 272.204815 -24.516032) (xy 272.159457 -24.483581) (xy 272.119308 -24.444872) (xy 272.085222 -24.400729)
			(xy 272.057926 -24.352094) (xy 272.038003 -24.300003) (xy 272.025877 -24.245566) (xy 272.021806 -24.189944)
			(xy 270.26235 -24.189944) (xy 270.261841 -24.21783) (xy 270.253721 -24.273006) (xy 270.237653 -24.326413)
			(xy 270.213981 -24.37691) (xy 270.183208 -24.423423) (xy 270.145991 -24.46496) (xy 270.103123 -24.500635)
			(xy 270.055517 -24.529689) (xy 270.004188 -24.551501) (xy 269.950231 -24.565607) (xy 269.894794 -24.571707)
			(xy 269.83906 -24.56967) (xy 269.784217 -24.55954) (xy 269.731433 -24.541533) (xy 269.681833 -24.516032)
			(xy 269.636475 -24.483581) (xy 269.596326 -24.444872) (xy 269.56224 -24.400729) (xy 269.534944 -24.352094)
			(xy 269.515021 -24.300003) (xy 269.502895 -24.245566) (xy 269.498824 -24.189944) (xy 266.413172 -24.189944)
			(xy 266.405621 -24.241256) (xy 266.389553 -24.294663) (xy 266.365881 -24.34516) (xy 266.335108 -24.391673)
			(xy 266.297891 -24.43321) (xy 266.255023 -24.468885) (xy 266.207417 -24.497939) (xy 266.156088 -24.519751)
			(xy 266.102131 -24.533857) (xy 266.046694 -24.539957) (xy 265.99096 -24.53792) (xy 265.936117 -24.52779)
			(xy 265.883333 -24.509783) (xy 265.833733 -24.484282) (xy 265.788375 -24.451831) (xy 265.748226 -24.413122)
			(xy 265.71414 -24.368979) (xy 265.686844 -24.320344) (xy 265.666921 -24.268253) (xy 265.654795 -24.213816)
			(xy 265.650724 -24.158194) (xy 260.987786 -24.158194) (xy 260.957166 -24.204475) (xy 260.919949 -24.246012)
			(xy 260.877081 -24.281687) (xy 260.829475 -24.310741) (xy 260.778146 -24.332553) (xy 260.724189 -24.346659)
			(xy 260.668752 -24.352759) (xy 260.613018 -24.350722) (xy 260.558175 -24.340592) (xy 260.505391 -24.322585)
			(xy 260.455791 -24.297084) (xy 260.410433 -24.264633) (xy 260.370284 -24.225924) (xy 260.336198 -24.181781)
			(xy 260.308902 -24.133146) (xy 260.288979 -24.081055) (xy 260.276853 -24.026618) (xy 260.272782 -23.970996)
			(xy 260.043482 -23.970996) (xy 260.043403 -23.975264) (xy 260.034974 -24.031432) (xy 260.018311 -24.085729)
			(xy 259.993783 -24.136956) (xy 259.961931 -24.18398) (xy 259.923461 -24.225764) (xy 259.879221 -24.261383)
			(xy 259.83019 -24.290049) (xy 259.777451 -24.311131) (xy 259.72217 -24.324161) (xy 259.693918 -24.327104)
			(xy 259.684266 -24.327866) (xy 259.667248 -24.336248) (xy 259.629402 -24.377142) (xy 259.614162 -24.393906)
			(xy 259.608011 -24.401111) (xy 259.601092 -24.418731) (xy 259.6007 -24.428196) (xy 259.6007 -24.807418)
			(xy 266.82014 -24.807418) (xy 266.824211 -24.751796) (xy 266.836337 -24.697359) (xy 266.85626 -24.645268)
			(xy 266.883556 -24.596633) (xy 266.917642 -24.55249) (xy 266.957791 -24.513781) (xy 267.003149 -24.48133)
			(xy 267.052749 -24.455829) (xy 267.105533 -24.437822) (xy 267.160376 -24.427692) (xy 267.21611 -24.425655)
			(xy 267.271547 -24.431755) (xy 267.325504 -24.445861) (xy 267.376833 -24.467673) (xy 267.424439 -24.496727)
			(xy 267.467307 -24.532402) (xy 267.504524 -24.573939) (xy 267.535297 -24.620452) (xy 267.558969 -24.670949)
			(xy 267.575037 -24.724356) (xy 267.580084 -24.75865) (xy 279.068528 -24.75865) (xy 279.072599 -24.703028)
			(xy 279.084725 -24.648591) (xy 279.104648 -24.5965) (xy 279.131944 -24.547865) (xy 279.16603 -24.503722)
			(xy 279.206179 -24.465013) (xy 279.251537 -24.432562) (xy 279.301137 -24.407061) (xy 279.353921 -24.389054)
			(xy 279.408764 -24.378924) (xy 279.464498 -24.376887) (xy 279.519935 -24.382987) (xy 279.573892 -24.397093)
			(xy 279.625221 -24.418905) (xy 279.672827 -24.447959) (xy 279.715695 -24.483634) (xy 279.752912 -24.525171)
			(xy 279.783685 -24.571684) (xy 279.807357 -24.622181) (xy 279.823425 -24.675588) (xy 279.831545 -24.730764)
			(xy 279.832054 -24.75865) (xy 279.831545 -24.786536) (xy 279.823425 -24.841712) (xy 279.807357 -24.895119)
			(xy 279.783685 -24.945616) (xy 279.752912 -24.992129) (xy 279.715695 -25.033666) (xy 279.672827 -25.069341)
			(xy 279.625221 -25.098395) (xy 279.573892 -25.120207) (xy 279.519935 -25.134313) (xy 279.464498 -25.140413)
			(xy 279.408764 -25.138376) (xy 279.353921 -25.128246) (xy 279.301137 -25.110239) (xy 279.251537 -25.084738)
			(xy 279.206179 -25.052287) (xy 279.16603 -25.013578) (xy 279.131944 -24.969435) (xy 279.104648 -24.9208)
			(xy 279.084725 -24.868709) (xy 279.072599 -24.814272) (xy 279.068528 -24.75865) (xy 267.580084 -24.75865)
			(xy 267.583157 -24.779532) (xy 267.583666 -24.807418) (xy 267.583157 -24.835304) (xy 267.575037 -24.89048)
			(xy 267.558969 -24.943887) (xy 267.535297 -24.994384) (xy 267.504524 -25.040897) (xy 267.467307 -25.082434)
			(xy 267.424439 -25.118109) (xy 267.376833 -25.147163) (xy 267.325504 -25.168975) (xy 267.271547 -25.183081)
			(xy 267.21611 -25.189181) (xy 267.160376 -25.187144) (xy 267.105533 -25.177014) (xy 267.052749 -25.159007)
			(xy 267.003149 -25.133506) (xy 266.957791 -25.101055) (xy 266.917642 -25.062346) (xy 266.883556 -25.018203)
			(xy 266.85626 -24.969568) (xy 266.836337 -24.917477) (xy 266.824211 -24.86304) (xy 266.82014 -24.807418)
			(xy 259.6007 -24.807418) (xy 259.6007 -25.390094) (xy 272.009616 -25.390094) (xy 272.010102 -25.362843)
			(xy 272.017858 -25.308895) (xy 272.033213 -25.2566) (xy 272.055855 -25.207023) (xy 272.085321 -25.161173)
			(xy 272.121012 -25.119982) (xy 272.162203 -25.084291) (xy 272.208053 -25.054825) (xy 272.25763 -25.032183)
			(xy 272.309925 -25.016828) (xy 272.363873 -25.009072) (xy 272.418375 -25.009072) (xy 272.472323 -25.016828)
			(xy 272.524618 -25.032183) (xy 272.574195 -25.054825) (xy 272.620045 -25.084291) (xy 272.661236 -25.119982)
			(xy 272.696927 -25.161173) (xy 272.726393 -25.207023) (xy 272.749035 -25.2566) (xy 272.76439 -25.308895)
			(xy 272.772146 -25.362843) (xy 272.772632 -25.390094) (xy 272.772068 -25.419114) (xy 272.763277 -25.476485)
			(xy 272.745898 -25.531862) (xy 272.720332 -25.583968) (xy 272.687167 -25.6316) (xy 272.647171 -25.673659)
			(xy 272.62455 -25.691846) (xy 272.614011 -25.70062) (xy 272.597577 -25.722555) (xy 272.587576 -25.748075)
			(xy 272.584731 -25.775336) (xy 272.589246 -25.80237) (xy 272.600796 -25.827227) (xy 272.618546 -25.848112)
			(xy 272.62963 -25.856184) (xy 272.651275 -25.871497) (xy 272.690531 -25.907137) (xy 272.724472 -25.94787)
			(xy 272.752445 -25.992911) (xy 272.77391 -26.041392) (xy 272.788455 -26.092378) (xy 272.795798 -26.144888)
			(xy 272.796254 -26.171398) (xy 272.795768 -26.198649) (xy 272.788012 -26.252597) (xy 272.772657 -26.304892)
			(xy 272.750015 -26.354469) (xy 272.720549 -26.400319) (xy 272.684858 -26.44151) (xy 272.643667 -26.477201)
			(xy 272.597817 -26.506667) (xy 272.54824 -26.529309) (xy 272.495945 -26.544664) (xy 272.441997 -26.55242)
			(xy 272.387495 -26.55242) (xy 272.333547 -26.544664) (xy 272.281252 -26.529309) (xy 272.231675 -26.506667)
			(xy 272.185825 -26.477201) (xy 272.144634 -26.44151) (xy 272.108943 -26.400319) (xy 272.079477 -26.354469)
			(xy 272.056835 -26.304892) (xy 272.04148 -26.252597) (xy 272.033724 -26.198649) (xy 272.033238 -26.171398)
			(xy 272.033808 -26.142378) (xy 272.042599 -26.085008) (xy 272.059978 -26.029632) (xy 272.085543 -25.977526)
			(xy 272.118706 -25.929894) (xy 272.1587 -25.887833) (xy 272.18132 -25.869646) (xy 272.191871 -25.860884)
			(xy 272.20831 -25.838947) (xy 272.218313 -25.813424) (xy 272.221159 -25.786159) (xy 272.21664 -25.759121)
			(xy 272.205085 -25.734263) (xy 272.187328 -25.713379) (xy 272.17624 -25.705308) (xy 272.154606 -25.689978)
			(xy 272.115348 -25.654344) (xy 272.081403 -25.613615) (xy 272.053428 -25.568577) (xy 272.03196 -25.520098)
			(xy 272.017415 -25.469112) (xy 272.010071 -25.416604) (xy 272.009616 -25.390094) (xy 259.6007 -25.390094)
			(xy 259.6007 -25.971246) (xy 260.159752 -25.971246) (xy 260.163823 -25.915624) (xy 260.175949 -25.861187)
			(xy 260.195872 -25.809096) (xy 260.223168 -25.760461) (xy 260.257254 -25.716318) (xy 260.297403 -25.677609)
			(xy 260.342761 -25.645158) (xy 260.392361 -25.619657) (xy 260.445145 -25.60165) (xy 260.499988 -25.59152)
			(xy 260.555722 -25.589483) (xy 260.611159 -25.595583) (xy 260.665116 -25.609689) (xy 260.716445 -25.631501)
			(xy 260.764051 -25.660555) (xy 260.806919 -25.69623) (xy 260.844136 -25.737767) (xy 260.874909 -25.78428)
			(xy 260.898581 -25.834777) (xy 260.914649 -25.888184) (xy 260.922769 -25.94336) (xy 260.923278 -25.971246)
			(xy 261.175752 -25.971246) (xy 261.179823 -25.915624) (xy 261.191949 -25.861187) (xy 261.211872 -25.809096)
			(xy 261.239168 -25.760461) (xy 261.273254 -25.716318) (xy 261.313403 -25.677609) (xy 261.358761 -25.645158)
			(xy 261.408361 -25.619657) (xy 261.461145 -25.60165) (xy 261.515988 -25.59152) (xy 261.571722 -25.589483)
			(xy 261.627159 -25.595583) (xy 261.681116 -25.609689) (xy 261.732445 -25.631501) (xy 261.780051 -25.660555)
			(xy 261.822919 -25.69623) (xy 261.860136 -25.737767) (xy 261.890909 -25.78428) (xy 261.914581 -25.834777)
			(xy 261.930649 -25.888184) (xy 261.938769 -25.94336) (xy 261.939278 -25.971246) (xy 262.191752 -25.971246)
			(xy 262.195823 -25.915624) (xy 262.207949 -25.861187) (xy 262.227872 -25.809096) (xy 262.255168 -25.760461)
			(xy 262.289254 -25.716318) (xy 262.329403 -25.677609) (xy 262.374761 -25.645158) (xy 262.424361 -25.619657)
			(xy 262.477145 -25.60165) (xy 262.531988 -25.59152) (xy 262.587722 -25.589483) (xy 262.643159 -25.595583)
			(xy 262.697116 -25.609689) (xy 262.748445 -25.631501) (xy 262.796051 -25.660555) (xy 262.838919 -25.69623)
			(xy 262.876136 -25.737767) (xy 262.906909 -25.78428) (xy 262.930581 -25.834777) (xy 262.946649 -25.888184)
			(xy 262.954769 -25.94336) (xy 262.955278 -25.971246) (xy 262.954769 -25.999132) (xy 262.949677 -26.03373)
			(xy 263.467848 -26.03373) (xy 263.471919 -25.978108) (xy 263.484045 -25.923671) (xy 263.503968 -25.87158)
			(xy 263.531264 -25.822945) (xy 263.56535 -25.778802) (xy 263.605499 -25.740093) (xy 263.650857 -25.707642)
			(xy 263.700457 -25.682141) (xy 263.753241 -25.664134) (xy 263.808084 -25.654004) (xy 263.863818 -25.651967)
			(xy 263.919255 -25.658067) (xy 263.973212 -25.672173) (xy 264.024541 -25.693985) (xy 264.072147 -25.723039)
			(xy 264.115015 -25.758714) (xy 264.152232 -25.800251) (xy 264.183005 -25.846764) (xy 264.206677 -25.897261)
			(xy 264.222745 -25.950668) (xy 264.230865 -26.005844) (xy 264.231374 -26.03373) (xy 264.230865 -26.061616)
			(xy 264.222745 -26.116792) (xy 264.206677 -26.170199) (xy 264.183005 -26.220696) (xy 264.152771 -26.266394)
			(xy 266.720574 -26.266394) (xy 266.721072 -26.239143) (xy 266.728829 -26.185197) (xy 266.744184 -26.132904)
			(xy 266.766825 -26.083328) (xy 266.79629 -26.037478) (xy 266.83198 -25.996288) (xy 266.873168 -25.960597)
			(xy 266.919017 -25.93113) (xy 266.968592 -25.908488) (xy 267.020885 -25.893132) (xy 267.074831 -25.885373)
			(xy 267.102082 -25.884886) (xy 267.131407 -25.885423) (xy 267.189365 -25.894403) (xy 267.245263 -25.912154)
			(xy 267.297784 -25.938256) (xy 267.322046 -25.954736) (xy 267.33246 -25.961848) (xy 267.356844 -25.96515)
			(xy 267.459206 -25.927304) (xy 267.47597 -25.908762) (xy 267.479018 -25.89657) (xy 267.486379 -25.869489)
			(xy 267.507937 -25.817678) (xy 267.536856 -25.769585) (xy 267.572509 -25.72625) (xy 267.614129 -25.688607)
			(xy 267.660816 -25.65747) (xy 267.711562 -25.63351) (xy 267.765271 -25.617246) (xy 267.820783 -25.609029)
			(xy 267.848842 -25.608534) (xy 267.876094 -25.608939) (xy 267.930043 -25.616701) (xy 267.982339 -25.632061)
			(xy 268.031916 -25.654707) (xy 268.077766 -25.684178) (xy 268.118956 -25.719874) (xy 268.154647 -25.761067)
			(xy 268.184113 -25.806921) (xy 268.206753 -25.856501) (xy 268.222108 -25.908798) (xy 268.229864 -25.962748)
			(xy 268.229864 -25.990042) (xy 269.498824 -25.990042) (xy 269.502895 -25.93442) (xy 269.515021 -25.879983)
			(xy 269.534944 -25.827892) (xy 269.56224 -25.779257) (xy 269.596326 -25.735114) (xy 269.636475 -25.696405)
			(xy 269.681833 -25.663954) (xy 269.731433 -25.638453) (xy 269.784217 -25.620446) (xy 269.83906 -25.610316)
			(xy 269.894794 -25.608279) (xy 269.950231 -25.614379) (xy 270.004188 -25.628485) (xy 270.055517 -25.650297)
			(xy 270.103123 -25.679351) (xy 270.145991 -25.715026) (xy 270.183208 -25.756563) (xy 270.213981 -25.803076)
			(xy 270.237653 -25.853573) (xy 270.253721 -25.90698) (xy 270.261841 -25.962156) (xy 270.26235 -25.990042)
			(xy 270.261841 -26.017928) (xy 270.253721 -26.073104) (xy 270.237653 -26.126511) (xy 270.213981 -26.177008)
			(xy 270.183208 -26.223521) (xy 270.145991 -26.265058) (xy 270.103123 -26.300733) (xy 270.055517 -26.329787)
			(xy 270.004188 -26.351599) (xy 269.950231 -26.365705) (xy 269.894794 -26.371805) (xy 269.83906 -26.369768)
			(xy 269.784217 -26.359638) (xy 269.731433 -26.341631) (xy 269.681833 -26.31613) (xy 269.636475 -26.283679)
			(xy 269.596326 -26.24497) (xy 269.56224 -26.200827) (xy 269.534944 -26.152192) (xy 269.515021 -26.100101)
			(xy 269.502895 -26.045664) (xy 269.498824 -25.990042) (xy 268.229864 -25.990042) (xy 268.229864 -26.017252)
			(xy 268.222108 -26.071202) (xy 268.206753 -26.123499) (xy 268.184113 -26.173079) (xy 268.154647 -26.218933)
			(xy 268.118956 -26.260126) (xy 268.077766 -26.295822) (xy 268.031916 -26.325293) (xy 267.982339 -26.347939)
			(xy 267.930043 -26.363299) (xy 267.876094 -26.371061) (xy 267.848842 -26.37155) (xy 267.819518 -26.370994)
			(xy 267.761561 -26.362019) (xy 267.705663 -26.344273) (xy 267.653141 -26.318177) (xy 267.628878 -26.3017)
			(xy 267.618464 -26.294588) (xy 267.59408 -26.291286) (xy 267.491718 -26.329132) (xy 267.474954 -26.347674)
			(xy 267.471906 -26.359866) (xy 267.465139 -26.384903) (xy 267.445721 -26.432994) (xy 267.419961 -26.478008)
			(xy 267.388335 -26.519113) (xy 267.351428 -26.55555) (xy 267.330936 -26.571448) (xy 267.320776 -26.579322)
			(xy 267.310108 -26.601928) (xy 267.315696 -26.711656) (xy 267.32865 -26.733246) (xy 267.339572 -26.73985)
			(xy 267.363302 -26.754765) (xy 267.406539 -26.790428) (xy 267.444092 -26.832033) (xy 267.475153 -26.878685)
			(xy 267.499054 -26.929381) (xy 267.51528 -26.983027) (xy 267.523481 -27.038471) (xy 267.523976 -27.066494)
			(xy 267.52349 -27.093745) (xy 267.515734 -27.147693) (xy 267.500379 -27.199988) (xy 267.477737 -27.249565)
			(xy 267.448271 -27.295415) (xy 267.41258 -27.336606) (xy 267.371389 -27.372297) (xy 267.325539 -27.401763)
			(xy 267.275962 -27.424405) (xy 267.223667 -27.43976) (xy 267.169719 -27.447516) (xy 267.115217 -27.447516)
			(xy 267.061269 -27.43976) (xy 267.008974 -27.424405) (xy 266.959397 -27.401763) (xy 266.913547 -27.372297)
			(xy 266.872356 -27.336606) (xy 266.836665 -27.295415) (xy 266.807199 -27.249565) (xy 266.784557 -27.199988)
			(xy 266.769202 -27.147693) (xy 266.761446 -27.093745) (xy 266.76096 -27.066494) (xy 266.761519 -27.037007)
			(xy 266.770615 -26.978737) (xy 266.788572 -26.922563) (xy 266.814964 -26.869823) (xy 266.849161 -26.821775)
			(xy 266.890347 -26.779564) (xy 266.913614 -26.76144) (xy 266.923774 -26.753566) (xy 266.934442 -26.73096)
			(xy 266.928854 -26.621232) (xy 266.9159 -26.599642) (xy 266.904978 -26.593038) (xy 266.881231 -26.578149)
			(xy 266.837997 -26.54248) (xy 266.800447 -26.500869) (xy 266.769388 -26.454213) (xy 266.74549 -26.403514)
			(xy 266.729267 -26.349864) (xy 266.721068 -26.294418) (xy 266.720574 -26.266394) (xy 264.152771 -26.266394)
			(xy 264.152232 -26.267209) (xy 264.115015 -26.308746) (xy 264.072147 -26.344421) (xy 264.024541 -26.373475)
			(xy 263.973212 -26.395287) (xy 263.919255 -26.409393) (xy 263.863818 -26.415493) (xy 263.808084 -26.413456)
			(xy 263.753241 -26.403326) (xy 263.700457 -26.385319) (xy 263.650857 -26.359818) (xy 263.605499 -26.327367)
			(xy 263.56535 -26.288658) (xy 263.531264 -26.244515) (xy 263.503968 -26.19588) (xy 263.484045 -26.143789)
			(xy 263.471919 -26.089352) (xy 263.467848 -26.03373) (xy 262.949677 -26.03373) (xy 262.946649 -26.054308)
			(xy 262.930581 -26.107715) (xy 262.906909 -26.158212) (xy 262.876136 -26.204725) (xy 262.838919 -26.246262)
			(xy 262.796051 -26.281937) (xy 262.748445 -26.310991) (xy 262.697116 -26.332803) (xy 262.643159 -26.346909)
			(xy 262.587722 -26.353009) (xy 262.531988 -26.350972) (xy 262.477145 -26.340842) (xy 262.424361 -26.322835)
			(xy 262.374761 -26.297334) (xy 262.329403 -26.264883) (xy 262.289254 -26.226174) (xy 262.255168 -26.182031)
			(xy 262.227872 -26.133396) (xy 262.207949 -26.081305) (xy 262.195823 -26.026868) (xy 262.191752 -25.971246)
			(xy 261.939278 -25.971246) (xy 261.938769 -25.999132) (xy 261.930649 -26.054308) (xy 261.914581 -26.107715)
			(xy 261.890909 -26.158212) (xy 261.860136 -26.204725) (xy 261.822919 -26.246262) (xy 261.780051 -26.281937)
			(xy 261.732445 -26.310991) (xy 261.681116 -26.332803) (xy 261.627159 -26.346909) (xy 261.571722 -26.353009)
			(xy 261.515988 -26.350972) (xy 261.461145 -26.340842) (xy 261.408361 -26.322835) (xy 261.358761 -26.297334)
			(xy 261.313403 -26.264883) (xy 261.273254 -26.226174) (xy 261.239168 -26.182031) (xy 261.211872 -26.133396)
			(xy 261.191949 -26.081305) (xy 261.179823 -26.026868) (xy 261.175752 -25.971246) (xy 260.923278 -25.971246)
			(xy 260.922769 -25.999132) (xy 260.914649 -26.054308) (xy 260.898581 -26.107715) (xy 260.874909 -26.158212)
			(xy 260.844136 -26.204725) (xy 260.806919 -26.246262) (xy 260.764051 -26.281937) (xy 260.716445 -26.310991)
			(xy 260.665116 -26.332803) (xy 260.611159 -26.346909) (xy 260.555722 -26.353009) (xy 260.499988 -26.350972)
			(xy 260.445145 -26.340842) (xy 260.392361 -26.322835) (xy 260.342761 -26.297334) (xy 260.297403 -26.264883)
			(xy 260.257254 -26.226174) (xy 260.223168 -26.182031) (xy 260.195872 -26.133396) (xy 260.175949 -26.081305)
			(xy 260.163823 -26.026868) (xy 260.159752 -25.971246) (xy 259.6007 -25.971246) (xy 259.6007 -27.654504)
			(xy 259.601049 -27.664073) (xy 259.60797 -27.681912) (xy 259.620958 -27.695963) (xy 259.629402 -27.700478)
			(xy 259.629656 -27.700478) (xy 259.656481 -27.713866) (xy 259.705908 -27.747791) (xy 259.715571 -27.756952)
			(xy 262.959066 -27.756952) (xy 262.959066 -27.702448) (xy 262.966822 -27.6485) (xy 262.982177 -27.596205)
			(xy 263.004818 -27.546627) (xy 263.034284 -27.500775) (xy 263.069976 -27.459584) (xy 263.111166 -27.423891)
			(xy 263.157016 -27.394424) (xy 263.206593 -27.371781) (xy 263.258888 -27.356425) (xy 263.312836 -27.348667)
			(xy 263.340088 -27.34818) (xy 263.354173 -27.348286) (xy 263.382269 -27.350316) (xy 263.396222 -27.352244)
			(xy 263.409938 -27.354276) (xy 263.435846 -27.343862) (xy 263.506204 -27.249882) (xy 263.509252 -27.221942)
			(xy 263.50341 -27.209242) (xy 263.492371 -27.184111) (xy 263.476766 -27.131489) (xy 263.468858 -27.077173)
			(xy 263.468358 -27.04973) (xy 263.468844 -27.022479) (xy 263.4766 -26.968531) (xy 263.491955 -26.916236)
			(xy 263.514597 -26.866659) (xy 263.544063 -26.820809) (xy 263.579754 -26.779618) (xy 263.620945 -26.743927)
			(xy 263.666795 -26.714461) (xy 263.716372 -26.691819) (xy 263.768667 -26.676464) (xy 263.822615 -26.668708)
			(xy 263.877117 -26.668708) (xy 263.931065 -26.676464) (xy 263.98336 -26.691819) (xy 264.032937 -26.714461)
			(xy 264.078787 -26.743927) (xy 264.119978 -26.779618) (xy 264.155669 -26.820809) (xy 264.185135 -26.866659)
			(xy 264.207777 -26.916236) (xy 264.223132 -26.968531) (xy 264.230888 -27.022479) (xy 264.231374 -27.04973)
			(xy 264.230756 -27.081146) (xy 264.220493 -27.143133) (xy 264.200217 -27.202603) (xy 264.185908 -27.230578)
			(xy 264.180574 -27.24023) (xy 264.17905 -27.262074) (xy 264.21334 -27.354022) (xy 264.22858 -27.369516)
			(xy 264.23874 -27.37358) (xy 264.265393 -27.384324) (xy 264.315359 -27.412708) (xy 264.3605 -27.448269)
			(xy 264.399794 -27.490201) (xy 264.43235 -27.537554) (xy 264.457432 -27.589257) (xy 264.474471 -27.644138)
			(xy 264.483081 -27.700955) (xy 264.483596 -27.729688) (xy 264.483133 -27.756941) (xy 264.475378 -27.810893)
			(xy 264.460023 -27.863191) (xy 264.437381 -27.912772) (xy 264.407913 -27.958626) (xy 264.372219 -27.999819)
			(xy 264.331026 -28.035513) (xy 264.285172 -28.064981) (xy 264.235591 -28.087623) (xy 264.183293 -28.102978)
			(xy 264.129341 -28.110733) (xy 264.102088 -28.111196) (xy 264.073173 -28.110616) (xy 264.016005 -28.1019)
			(xy 263.960807 -28.084655) (xy 263.908845 -28.059274) (xy 263.86131 -28.026342) (xy 263.81929 -27.986611)
			(xy 263.801098 -27.96413) (xy 263.793545 -27.95536) (xy 263.772779 -27.945184) (xy 263.76122 -27.944572)
			(xy 263.680956 -27.944572) (xy 263.669388 -27.94515) (xy 263.648616 -27.955337) (xy 263.641078 -27.96413)
			(xy 263.622907 -27.98663) (xy 263.580882 -28.026363) (xy 263.533343 -28.059299) (xy 263.481378 -28.084684)
			(xy 263.426177 -28.101937) (xy 263.369005 -28.110663) (xy 263.340088 -28.111196) (xy 263.312836 -28.110733)
			(xy 263.258888 -28.102975) (xy 263.206593 -28.087619) (xy 263.157016 -28.064976) (xy 263.111166 -28.035509)
			(xy 263.069976 -27.999816) (xy 263.034284 -27.958625) (xy 263.004818 -27.912773) (xy 262.982177 -27.863195)
			(xy 262.966822 -27.8109) (xy 262.959066 -27.756952) (xy 259.715571 -27.756952) (xy 259.749413 -27.789038)
			(xy 259.768086 -27.812492) (xy 259.768086 -27.812746) (xy 259.770626 -27.816048) (xy 259.77596 -27.821382)
			(xy 259.781921 -27.826888) (xy 259.796426 -27.834146) (xy 259.804408 -27.835606) (xy 259.873242 -27.845766)
			(xy 259.883353 -27.846794) (xy 259.903002 -27.841671) (xy 259.911342 -27.83586) (xy 259.91185 -27.835606)
			(xy 259.931864 -27.820831) (xy 259.974993 -27.796041) (xy 260.020981 -27.777072) (xy 260.069046 -27.764245)
			(xy 260.118371 -27.75778) (xy 260.143244 -27.757374) (xy 260.147816 -27.757374) (xy 260.175794 -27.758218)
			(xy 260.231059 -27.767089) (xy 260.284437 -27.783935) (xy 260.334783 -27.808395) (xy 260.381017 -27.839944)
			(xy 260.422149 -27.877906) (xy 260.457297 -27.921467) (xy 260.47192 -27.945334) (xy 260.475222 -27.950668)
			(xy 260.484366 -27.959812) (xy 260.504178 -27.971496) (xy 260.510088 -27.974753) (xy 260.523089 -27.978348)
			(xy 260.529832 -27.978608) (xy 260.600444 -27.978608) (xy 260.609336 -27.978276) (xy 260.626048 -27.972193)
			(xy 260.639658 -27.960747) (xy 260.644386 -27.953208) (xy 260.652136 -27.940109) (xy 260.669429 -27.91506)
			(xy 260.67893 -27.90317) (xy 260.687294 -27.893047) (xy 260.705218 -27.873854) (xy 260.714744 -27.864816)
			(xy 260.715252 -27.864308) (xy 260.716014 -27.863546) (xy 260.737461 -27.843793) (xy 260.785232 -27.810364)
			(xy 260.83753 -27.784589) (xy 260.89314 -27.767066) (xy 260.950767 -27.758202) (xy 260.97992 -27.757628)
			(xy 261.007171 -27.758093) (xy 261.061118 -27.765852) (xy 261.113411 -27.78121) (xy 261.162987 -27.803854)
			(xy 261.208835 -27.833324) (xy 261.250022 -27.869018) (xy 261.28571 -27.91021) (xy 261.315172 -27.956063)
			(xy 261.337809 -28.005641) (xy 261.35316 -28.057937) (xy 261.360911 -28.111885) (xy 261.361428 -28.139136)
			(xy 261.867902 -28.139136) (xy 261.871973 -28.083514) (xy 261.884099 -28.029077) (xy 261.904022 -27.976986)
			(xy 261.931318 -27.928351) (xy 261.965404 -27.884208) (xy 262.005553 -27.845499) (xy 262.050911 -27.813048)
			(xy 262.100511 -27.787547) (xy 262.153295 -27.76954) (xy 262.208138 -27.75941) (xy 262.263872 -27.757373)
			(xy 262.319309 -27.763473) (xy 262.373266 -27.777579) (xy 262.424595 -27.799391) (xy 262.472201 -27.828445)
			(xy 262.515069 -27.86412) (xy 262.552286 -27.905657) (xy 262.583059 -27.95217) (xy 262.606731 -28.002667)
			(xy 262.622799 -28.056074) (xy 262.630919 -28.11125) (xy 262.631428 -28.139136) (xy 262.630919 -28.167022)
			(xy 262.622799 -28.222198) (xy 262.606731 -28.275605) (xy 262.583059 -28.326102) (xy 262.552286 -28.372615)
			(xy 262.515069 -28.414152) (xy 262.472201 -28.449827) (xy 262.424595 -28.478881) (xy 262.373266 -28.500693)
			(xy 262.319309 -28.514799) (xy 262.263872 -28.520899) (xy 262.208138 -28.518862) (xy 262.153295 -28.508732)
			(xy 262.100511 -28.490725) (xy 262.050911 -28.465224) (xy 262.005553 -28.432773) (xy 261.965404 -28.394064)
			(xy 261.931318 -28.349921) (xy 261.904022 -28.301286) (xy 261.884099 -28.249195) (xy 261.871973 -28.194758)
			(xy 261.867902 -28.139136) (xy 261.361428 -28.139136) (xy 261.360993 -28.16512) (xy 261.353946 -28.216608)
			(xy 261.339973 -28.266662) (xy 261.319334 -28.314356) (xy 261.292411 -28.358806) (xy 261.259702 -28.399189)
			(xy 261.241032 -28.417266) (xy 261.240524 -28.417774) (xy 261.239762 -28.418536) (xy 261.218307 -28.438497)
			(xy 261.170412 -28.47226) (xy 261.117915 -28.498296) (xy 261.062053 -28.515994) (xy 261.00414 -28.524936)
			(xy 260.97484 -28.52547) (xy 260.946288 -28.524933) (xy 260.889822 -28.516416) (xy 260.835256 -28.499581)
			(xy 260.783807 -28.474805) (xy 260.736623 -28.442639) (xy 260.694759 -28.403803) (xy 260.659147 -28.359163)
			(xy 260.644386 -28.334716) (xy 260.63961 -28.327217) (xy 260.626008 -28.31579) (xy 260.609325 -28.309685)
			(xy 260.600444 -28.309316) (xy 260.528308 -28.309316) (xy 260.521662 -28.309496) (xy 260.508796 -28.312832)
			(xy 260.502908 -28.31592) (xy 260.477 -28.330906) (xy 260.468364 -28.339034) (xy 260.464808 -28.344622)
			(xy 260.45786 -28.355282) (xy 260.442734 -28.375746) (xy 260.434582 -28.385516) (xy 260.419088 -28.402788)
			(xy 260.41858 -28.403296) (xy 260.418072 -28.404058) (xy 260.41477 -28.40736) (xy 260.413754 -28.408376)
			(xy 260.406134 -28.415488) (xy 260.40588 -28.415996) (xy 260.404102 -28.41752) (xy 260.40334 -28.418282)
			(xy 260.381875 -28.438282) (xy 260.333945 -28.472116) (xy 260.2814 -28.498211) (xy 260.225478 -28.515949)
			(xy 260.167498 -28.524914) (xy 260.138164 -28.52547) (xy 260.109008 -28.524915) (xy 260.051375 -28.516037)
			(xy 259.995764 -28.498494) (xy 259.94347 -28.472693) (xy 259.895711 -28.439236) (xy 259.853598 -28.398902)
			(xy 259.835396 -28.376118) (xy 259.832602 -28.372562) (xy 259.827522 -28.367482) (xy 259.821558 -28.361981)
			(xy 259.807052 -28.354734) (xy 259.799074 -28.353258) (xy 259.72897 -28.342844) (xy 259.719034 -28.341873)
			(xy 259.699685 -28.346706) (xy 259.691378 -28.352242) (xy 259.686044 -28.356052) (xy 259.685028 -28.35656)
			(xy 259.681726 -28.3591) (xy 259.679186 -28.360878) (xy 259.67436 -28.36418) (xy 259.666232 -28.37307)
			(xy 259.652008 -28.398978) (xy 259.649047 -28.404701) (xy 259.645827 -28.417174) (xy 259.645658 -28.423616)
			(xy 259.645658 -28.428442) (xy 259.645901 -28.435187) (xy 259.649509 -28.448187) (xy 259.65277 -28.454096)
			(xy 259.660644 -28.467558) (xy 259.668772 -28.47594) (xy 259.674106 -28.479242) (xy 259.696348 -28.493832)
			(xy 259.736946 -28.528202) (xy 259.772378 -28.567876) (xy 259.801959 -28.612085) (xy 259.825115 -28.659973)
			(xy 259.841398 -28.710612) (xy 259.850492 -28.763022) (xy 259.852222 -28.816186) (xy 259.846553 -28.869076)
			(xy 259.833596 -28.920667) (xy 259.813601 -28.969959) (xy 259.786956 -29.015997) (xy 259.754177 -29.05789)
			(xy 259.73532 -29.07665) (xy 259.734812 -29.077158) (xy 259.711419 -29.099504) (xy 259.658557 -29.13679)
			(xy 259.629656 -29.151326) (xy 259.616194 -29.157676) (xy 259.6007 -29.182314) (xy 259.6007 -29.237178)
			(xy 259.616702 -29.26207) (xy 259.630164 -29.26842) (xy 259.654628 -29.280232) (xy 259.700231 -29.309754)
			(xy 259.741184 -29.345446) (xy 259.776659 -29.386588) (xy 259.805939 -29.432347) (xy 259.82843 -29.481797)
			(xy 259.843678 -29.533937) (xy 259.851375 -29.587714) (xy 259.851906 -29.614876) (xy 259.851466 -29.640889)
			(xy 259.844399 -29.692434) (xy 259.830393 -29.74254) (xy 259.809707 -29.790278) (xy 259.782726 -29.834762)
			(xy 259.749951 -29.875166) (xy 259.731256 -29.89326) (xy 259.730748 -29.893768) (xy 259.723326 -29.900864)
			(xy 259.707824 -29.914334) (xy 259.69976 -29.920692) (xy 259.690938 -29.928286) (xy 259.680769 -29.949196)
			(xy 259.680202 -29.960824) (xy 259.680202 -30.031944) (xy 259.680741 -30.043772) (xy 259.691189 -30.064987)
			(xy 259.700268 -30.072584) (xy 259.720497 -30.088355) (xy 259.756948 -30.124446) (xy 259.78823 -30.165098)
			(xy 259.813778 -30.209577) (xy 259.833131 -30.257081) (xy 259.845939 -30.306751) (xy 259.849366 -30.332172)
			(xy 259.851144 -30.347412) (xy 259.85216 -30.376876) (xy 259.851737 -30.402667) (xy 259.844796 -30.453781)
			(xy 259.831037 -30.503495) (xy 259.810712 -30.550905) (xy 259.784189 -30.595146) (xy 259.751952 -30.635415)
			(xy 259.733542 -30.653482) (xy 259.733034 -30.65399) (xy 259.729224 -30.657546) (xy 259.706855 -30.678097)
			(xy 259.656831 -30.712552) (xy 259.629656 -30.726126) (xy 259.616194 -30.732476) (xy 259.6007 -30.757114)
			(xy 259.6007 -31.159958) (xy 259.62483 -31.188406) (xy 259.643118 -31.191454) (xy 259.669522 -31.196298)
			(xy 259.720723 -31.212422) (xy 259.769158 -31.235567) (xy 259.813869 -31.265275) (xy 259.853973 -31.300959)
			(xy 259.888676 -31.341914) (xy 259.917294 -31.38733) (xy 259.93926 -31.436311) (xy 259.954142 -31.487887)
			(xy 259.961644 -31.541041) (xy 259.962142 -31.567882) (xy 259.961704 -31.593865) (xy 259.954651 -31.64535)
			(xy 259.940674 -31.695401) (xy 259.930344 -31.719266) (xy 260.48538 -31.719266) (xy 260.489451 -31.663644)
			(xy 260.501577 -31.609207) (xy 260.5215 -31.557116) (xy 260.548796 -31.508481) (xy 260.582882 -31.464338)
			(xy 260.623031 -31.425629) (xy 260.668389 -31.393178) (xy 260.717989 -31.367677) (xy 260.770773 -31.34967)
			(xy 260.825616 -31.33954) (xy 260.88135 -31.337503) (xy 260.936787 -31.343603) (xy 260.990744 -31.357709)
			(xy 261.042073 -31.379521) (xy 261.089679 -31.408575) (xy 261.132547 -31.44425) (xy 261.169764 -31.485787)
			(xy 261.200537 -31.5323) (xy 261.224209 -31.582797) (xy 261.240277 -31.636204) (xy 261.244427 -31.664402)
			(xy 261.760968 -31.664402) (xy 261.765039 -31.60878) (xy 261.777165 -31.554343) (xy 261.797088 -31.502252)
			(xy 261.824384 -31.453617) (xy 261.85847 -31.409474) (xy 261.898619 -31.370765) (xy 261.943977 -31.338314)
			(xy 261.993577 -31.312813) (xy 262.046361 -31.294806) (xy 262.101204 -31.284676) (xy 262.156938 -31.282639)
			(xy 262.212375 -31.288739) (xy 262.266332 -31.302845) (xy 262.317661 -31.324657) (xy 262.365267 -31.353711)
			(xy 262.408135 -31.389386) (xy 262.445352 -31.430923) (xy 262.476125 -31.477436) (xy 262.499797 -31.527933)
			(xy 262.515865 -31.58134) (xy 262.523985 -31.636516) (xy 262.524494 -31.664402) (xy 262.523985 -31.692288)
			(xy 262.515865 -31.747464) (xy 262.506925 -31.777178) (xy 263.026142 -31.777178) (xy 263.030213 -31.721556)
			(xy 263.042339 -31.667119) (xy 263.062262 -31.615028) (xy 263.089558 -31.566393) (xy 263.123644 -31.52225)
			(xy 263.163793 -31.483541) (xy 263.209151 -31.45109) (xy 263.258751 -31.425589) (xy 263.311535 -31.407582)
			(xy 263.366378 -31.397452) (xy 263.422112 -31.395415) (xy 263.477549 -31.401515) (xy 263.531506 -31.415621)
			(xy 263.582835 -31.437433) (xy 263.630441 -31.466487) (xy 263.673309 -31.502162) (xy 263.710526 -31.543699)
			(xy 263.741299 -31.590212) (xy 263.764971 -31.640709) (xy 263.781039 -31.694116) (xy 263.789159 -31.749292)
			(xy 263.789668 -31.777178) (xy 263.789159 -31.805064) (xy 263.781039 -31.86024) (xy 263.764971 -31.913647)
			(xy 263.741299 -31.964144) (xy 263.710526 -32.010657) (xy 263.673309 -32.052194) (xy 263.630441 -32.087869)
			(xy 263.582835 -32.116923) (xy 263.531506 -32.138735) (xy 263.477549 -32.152841) (xy 263.422112 -32.158941)
			(xy 263.366378 -32.156904) (xy 263.311535 -32.146774) (xy 263.258751 -32.128767) (xy 263.209151 -32.103266)
			(xy 263.163793 -32.070815) (xy 263.123644 -32.032106) (xy 263.089558 -31.987963) (xy 263.062262 -31.939328)
			(xy 263.042339 -31.887237) (xy 263.030213 -31.8328) (xy 263.026142 -31.777178) (xy 262.506925 -31.777178)
			(xy 262.499797 -31.800871) (xy 262.476125 -31.851368) (xy 262.445352 -31.897881) (xy 262.408135 -31.939418)
			(xy 262.365267 -31.975093) (xy 262.317661 -32.004147) (xy 262.266332 -32.025959) (xy 262.212375 -32.040065)
			(xy 262.156938 -32.046165) (xy 262.101204 -32.044128) (xy 262.046361 -32.033998) (xy 261.993577 -32.015991)
			(xy 261.943977 -31.99049) (xy 261.898619 -31.958039) (xy 261.85847 -31.91933) (xy 261.824384 -31.875187)
			(xy 261.797088 -31.826552) (xy 261.777165 -31.774461) (xy 261.765039 -31.720024) (xy 261.760968 -31.664402)
			(xy 261.244427 -31.664402) (xy 261.248397 -31.69138) (xy 261.248906 -31.719266) (xy 261.248397 -31.747152)
			(xy 261.240277 -31.802328) (xy 261.224209 -31.855735) (xy 261.200537 -31.906232) (xy 261.169764 -31.952745)
			(xy 261.132547 -31.994282) (xy 261.089679 -32.029957) (xy 261.042073 -32.059011) (xy 260.990744 -32.080823)
			(xy 260.936787 -32.094929) (xy 260.88135 -32.101029) (xy 260.825616 -32.098992) (xy 260.770773 -32.088862)
			(xy 260.717989 -32.070855) (xy 260.668389 -32.045354) (xy 260.623031 -32.012903) (xy 260.582882 -31.974194)
			(xy 260.548796 -31.930051) (xy 260.5215 -31.881416) (xy 260.501577 -31.829325) (xy 260.489451 -31.774888)
			(xy 260.48538 -31.719266) (xy 259.930344 -31.719266) (xy 259.920032 -31.743091) (xy 259.893106 -31.787537)
			(xy 259.860396 -31.827916) (xy 259.841746 -31.846012) (xy 259.841238 -31.84652) (xy 259.84073 -31.847028)
			(xy 259.82027 -31.866131) (xy 259.774786 -31.898756) (xy 259.72503 -31.924399) (xy 259.672067 -31.942512)
			(xy 259.644642 -31.94812) (xy 259.64261 -31.948374) (xy 259.638038 -31.949644) (xy 259.62748 -31.953106)
			(xy 259.610529 -31.967432) (xy 259.601199 -31.987569) (xy 259.6007 -31.998666) (xy 259.6007 -33.512252)
			(xy 259.601172 -33.522155) (xy 259.608666 -33.540489) (xy 259.622525 -33.554639) (xy 259.631434 -33.558988)
			(xy 259.731256 -33.601914) (xy 259.760974 -33.59658) (xy 259.77215 -33.585912) (xy 259.780052 -33.57852)
			(xy 259.796574 -33.564544) (xy 259.80517 -33.557972) (xy 259.812282 -33.552384) (xy 259.817362 -33.54451)
			(xy 259.819704 -33.540603) (xy 259.823151 -33.532174) (xy 259.82422 -33.527746) (xy 259.840222 -33.454594)
			(xy 259.837682 -33.436814) (xy 259.833364 -33.428686) (xy 259.819073 -33.400749) (xy 259.79881 -33.341364)
			(xy 259.788533 -33.279465) (xy 259.787898 -33.248092) (xy 259.788384 -33.220841) (xy 259.796142 -33.166895)
			(xy 259.811498 -33.114601) (xy 259.834139 -33.065025) (xy 259.863606 -33.019176) (xy 259.899298 -32.977988)
			(xy 259.940488 -32.942298) (xy 259.986338 -32.912833) (xy 260.035914 -32.890193) (xy 260.088208 -32.874839)
			(xy 260.142155 -32.867083) (xy 260.169406 -32.866584) (xy 260.197142 -32.867089) (xy 260.252029 -32.875134)
			(xy 260.305173 -32.891039) (xy 260.355455 -32.914469) (xy 260.401816 -32.94493) (xy 260.44328 -32.981782)
			(xy 260.478973 -33.024247) (xy 260.508143 -33.071431) (xy 260.530176 -33.122341) (xy 260.544608 -33.175904)
			(xy 260.548374 -33.203388) (xy 260.549898 -33.217104) (xy 260.551652 -33.244494) (xy 260.548228 -33.299272)
			(xy 260.536996 -33.352994) (xy 260.518186 -33.404554) (xy 260.492186 -33.45289) (xy 260.459532 -33.497003)
			(xy 260.420898 -33.535986) (xy 260.399276 -33.552892) (xy 260.39191 -33.55848) (xy 260.382004 -33.57372)
			(xy 260.364224 -33.655762) (xy 260.366764 -33.673796) (xy 260.371082 -33.68167) (xy 260.378954 -33.696684)
			(xy 260.392309 -33.727845) (xy 260.397752 -33.7439) (xy 260.397752 -33.744154) (xy 260.400965 -33.752644)
			(xy 260.412288 -33.766818) (xy 260.41985 -33.77184) (xy 260.485382 -33.810956) (xy 260.494018 -33.812734)
			(xy 260.516517 -33.807513) (xy 260.562364 -33.801914) (xy 260.585458 -33.801558) (xy 260.612714 -33.802018)
			(xy 260.666671 -33.80977) (xy 260.718976 -33.825122) (xy 260.768564 -33.847762) (xy 260.784019 -33.857692)
			(xy 261.690102 -33.857692) (xy 261.694173 -33.80207) (xy 261.706299 -33.747633) (xy 261.726222 -33.695542)
			(xy 261.753518 -33.646907) (xy 261.787604 -33.602764) (xy 261.827753 -33.564055) (xy 261.873111 -33.531604)
			(xy 261.922711 -33.506103) (xy 261.975495 -33.488096) (xy 262.030338 -33.477966) (xy 262.086072 -33.475929)
			(xy 262.141509 -33.482029) (xy 262.195466 -33.496135) (xy 262.246795 -33.517947) (xy 262.294401 -33.547001)
			(xy 262.337269 -33.582676) (xy 262.374486 -33.624213) (xy 262.405259 -33.670726) (xy 262.428931 -33.721223)
			(xy 262.444999 -33.77463) (xy 262.453119 -33.829806) (xy 262.453628 -33.857692) (xy 262.453119 -33.885578)
			(xy 262.444999 -33.940754) (xy 262.428931 -33.994161) (xy 262.405259 -34.044658) (xy 262.374486 -34.091171)
			(xy 262.337269 -34.132708) (xy 262.294401 -34.168383) (xy 262.246795 -34.197437) (xy 262.195466 -34.219249)
			(xy 262.141509 -34.233355) (xy 262.086072 -34.239455) (xy 262.030338 -34.237418) (xy 261.975495 -34.227288)
			(xy 261.922711 -34.209281) (xy 261.873111 -34.18378) (xy 261.827753 -34.151329) (xy 261.787604 -34.11262)
			(xy 261.753518 -34.068477) (xy 261.726222 -34.019842) (xy 261.706299 -33.967751) (xy 261.694173 -33.913314)
			(xy 261.690102 -33.857692) (xy 260.784019 -33.857692) (xy 260.814424 -33.877228) (xy 260.855625 -33.912921)
			(xy 260.891326 -33.954115) (xy 260.920802 -33.99997) (xy 260.943451 -34.049553) (xy 260.958814 -34.101855)
			(xy 260.966577 -34.15581) (xy 260.966966 -34.183066) (xy 260.966529 -34.209049) (xy 260.959477 -34.260534)
			(xy 260.9455 -34.310584) (xy 260.924856 -34.358273) (xy 260.897927 -34.402717) (xy 260.865213 -34.443093)
			(xy 260.84657 -34.461196) (xy 260.846062 -34.461704) (xy 260.8453 -34.462466) (xy 260.823845 -34.482428)
			(xy 260.77595 -34.516193) (xy 260.723454 -34.542233) (xy 260.667591 -34.559934) (xy 260.609678 -34.568881)
			(xy 260.580378 -34.5694) (xy 260.553769 -34.568944) (xy 260.501065 -34.56156) (xy 260.449898 -34.546924)
			(xy 260.401262 -34.52532) (xy 260.356099 -34.497168) (xy 260.315286 -34.463013) (xy 260.279616 -34.423519)
			(xy 260.249779 -34.379451) (xy 260.226354 -34.331665) (xy 260.217666 -34.30651) (xy 260.217412 -34.306002)
			(xy 260.214247 -34.297483) (xy 260.202919 -34.28329) (xy 260.195314 -34.278316) (xy 260.166612 -34.261298)
			(xy 260.129782 -34.239454) (xy 260.112002 -34.236406) (xy 260.102858 -34.23793) (xy 260.08611 -34.24076)
			(xy 260.052278 -34.243812) (xy 260.035294 -34.244026) (xy 260.03504 -34.244026) (xy 260.005994 -34.243479)
			(xy 259.948574 -34.234673) (xy 259.89315 -34.217272) (xy 259.841 -34.191679) (xy 259.793327 -34.158483)
			(xy 259.771896 -34.13887) (xy 259.76072 -34.128202) (xy 259.731002 -34.122868) (xy 259.670042 -34.14903)
			(xy 259.670296 -34.149284) (xy 259.631434 -34.166048) (xy 259.622517 -34.170386) (xy 259.608644 -34.184526)
			(xy 259.601184 -34.202877) (xy 259.6007 -34.212784) (xy 259.6007 -35.264852) (xy 262.102344 -35.264852)
			(xy 262.106415 -35.20923) (xy 262.118541 -35.154793) (xy 262.138464 -35.102702) (xy 262.16576 -35.054067)
			(xy 262.199846 -35.009924) (xy 262.239995 -34.971215) (xy 262.285353 -34.938764) (xy 262.334953 -34.913263)
			(xy 262.387737 -34.895256) (xy 262.44258 -34.885126) (xy 262.498314 -34.883089) (xy 262.553751 -34.889189)
			(xy 262.607708 -34.903295) (xy 262.659037 -34.925107) (xy 262.706643 -34.954161) (xy 262.749511 -34.989836)
			(xy 262.774348 -35.017556) (xy 264.419733 -35.017556) (xy 264.419733 -34.963044) (xy 264.427492 -34.909086)
			(xy 264.442851 -34.856782) (xy 264.465497 -34.807196) (xy 264.494971 -34.761338) (xy 264.530671 -34.720142)
			(xy 264.571872 -34.684446) (xy 264.617733 -34.654977) (xy 264.667321 -34.632336) (xy 264.719627 -34.616983)
			(xy 264.773586 -34.60923) (xy 264.800842 -34.60877) (xy 264.817954 -34.608964) (xy 264.852041 -34.612014)
			(xy 264.868914 -34.614866) (xy 264.88018 -34.616262) (xy 264.902062 -34.610334) (xy 264.911078 -34.603436)
			(xy 264.935462 -34.582354) (xy 264.94385 -34.574428) (xy 264.952974 -34.553255) (xy 264.952988 -34.541714)
			(xy 264.95248 -34.52241) (xy 264.95248 -33.65881) (xy 264.952988 -33.638744) (xy 264.952833 -33.627233)
			(xy 264.94372 -33.606125) (xy 264.935462 -33.598104) (xy 264.911078 -33.577022) (xy 264.902091 -33.570069)
			(xy 264.880185 -33.564143) (xy 264.868914 -33.565592) (xy 264.852043 -33.568461) (xy 264.817955 -33.571514)
			(xy 264.800842 -33.571688) (xy 264.773586 -33.571268) (xy 264.719627 -33.563515) (xy 264.667322 -33.548162)
			(xy 264.617734 -33.525521) (xy 264.571873 -33.496052) (xy 264.530673 -33.460357) (xy 264.494973 -33.419161)
			(xy 264.465499 -33.373303) (xy 264.442852 -33.323718) (xy 264.427493 -33.271414) (xy 264.419735 -33.217456)
			(xy 264.419735 -33.162944) (xy 264.427493 -33.108986) (xy 264.442852 -33.056682) (xy 264.465499 -33.007097)
			(xy 264.494973 -32.961239) (xy 264.530673 -32.920043) (xy 264.571873 -32.884348) (xy 264.617734 -32.854879)
			(xy 264.667322 -32.832238) (xy 264.719627 -32.816885) (xy 264.773586 -32.809132) (xy 264.800842 -32.808672)
			(xy 264.827852 -32.809081) (xy 264.881331 -32.816693) (xy 264.933203 -32.831773) (xy 264.982428 -32.85402)
			(xy 265.028022 -32.882989) (xy 265.069075 -32.918099) (xy 265.104763 -32.95865) (xy 265.134375 -33.00383)
			(xy 265.157316 -33.052735) (xy 265.17313 -33.104387) (xy 265.177778 -33.130998) (xy 265.179302 -33.141666)
			(xy 265.190732 -33.159446) (xy 265.270996 -33.212786) (xy 265.29157 -33.216596) (xy 265.302238 -33.214056)
			(xy 265.328871 -33.20793) (xy 265.383118 -33.201307) (xy 265.410442 -33.200848) (xy 265.437766 -33.201302)
			(xy 265.492015 -33.207924) (xy 265.518646 -33.214056) (xy 265.529314 -33.216596) (xy 265.549888 -33.212786)
			(xy 265.630152 -33.159446) (xy 265.641582 -33.141666) (xy 265.643106 -33.130998) (xy 265.647766 -33.104394)
			(xy 265.663597 -33.052757) (xy 265.686551 -33.003867) (xy 265.716168 -32.958702) (xy 265.751857 -32.918164)
			(xy 265.792905 -32.883062) (xy 265.838493 -32.854099) (xy 265.887708 -32.831853) (xy 265.939568 -32.816767)
			(xy 265.993037 -32.809144) (xy 266.020042 -32.808672) (xy 266.047412 -32.809155) (xy 266.101591 -32.816966)
			(xy 266.154095 -32.83245) (xy 266.203842 -32.855288) (xy 266.249809 -32.885011) (xy 266.27074 -32.902652)
			(xy 266.277852 -32.908748) (xy 266.29487 -32.915098) (xy 266.380214 -32.915098) (xy 266.397232 -32.908748)
			(xy 266.404344 -32.902652) (xy 266.425293 -32.885034) (xy 266.47126 -32.855317) (xy 266.521003 -32.832476)
			(xy 266.573501 -32.81698) (xy 266.627674 -32.809148) (xy 266.655042 -32.808672) (xy 266.672154 -32.808866)
			(xy 266.706241 -32.811916) (xy 266.723114 -32.814768) (xy 266.73438 -32.816164) (xy 266.756262 -32.810235)
			(xy 266.765278 -32.803338) (xy 266.789662 -32.782256) (xy 266.798049 -32.774329) (xy 266.807174 -32.753157)
			(xy 266.807188 -32.741616) (xy 266.80668 -32.722312) (xy 266.80668 -31.858712) (xy 266.807188 -31.838646)
			(xy 266.807031 -31.827135) (xy 266.79792 -31.806028) (xy 266.789662 -31.798006) (xy 266.765278 -31.776924)
			(xy 266.756291 -31.769971) (xy 266.734385 -31.764045) (xy 266.723114 -31.765494) (xy 266.706243 -31.768364)
			(xy 266.672155 -31.771416) (xy 266.655042 -31.77159) (xy 266.627673 -31.771102) (xy 266.573494 -31.76329)
			(xy 266.520991 -31.747806) (xy 266.471244 -31.724969) (xy 266.425276 -31.695249) (xy 266.404344 -31.67761)
			(xy 266.397232 -31.671514) (xy 266.380468 -31.665164) (xy 266.29487 -31.665164) (xy 266.277852 -31.671514)
			(xy 266.270994 -31.677864) (xy 266.250024 -31.695498) (xy 266.204014 -31.725242) (xy 266.154219 -31.748094)
			(xy 266.101665 -31.763582) (xy 266.047436 -31.771388) (xy 266.020042 -31.771844) (xy 265.993063 -31.771427)
			(xy 265.939642 -31.763838) (xy 265.887825 -31.748791) (xy 265.838647 -31.726588) (xy 265.793092 -31.697672)
			(xy 265.75207 -31.66262) (xy 265.716401 -31.622134) (xy 265.686797 -31.577022) (xy 265.663851 -31.528187)
			(xy 265.648021 -31.476603) (xy 265.64336 -31.450026) (xy 265.641582 -31.439358) (xy 265.630152 -31.421832)
			(xy 265.549888 -31.368238) (xy 265.529314 -31.364682) (xy 265.5189 -31.367222) (xy 265.492198 -31.373292)
			(xy 265.437823 -31.379788) (xy 265.410442 -31.380176) (xy 265.38306 -31.379808) (xy 265.328684 -31.373308)
			(xy 265.301984 -31.367222) (xy 265.29157 -31.364682) (xy 265.270996 -31.368238) (xy 265.190732 -31.421832)
			(xy 265.179302 -31.439358) (xy 265.177524 -31.450026) (xy 265.172876 -31.476601) (xy 265.157019 -31.528167)
			(xy 265.134053 -31.576984) (xy 265.104439 -31.622078) (xy 265.068766 -31.66255) (xy 265.027747 -31.697591)
			(xy 264.982199 -31.726504) (xy 264.933032 -31.74871) (xy 264.881227 -31.763767) (xy 264.827817 -31.771374)
			(xy 264.800842 -31.771844) (xy 264.77359 -31.771312) (xy 264.719639 -31.76356) (xy 264.667341 -31.748209)
			(xy 264.617761 -31.725571) (xy 264.571907 -31.696107) (xy 264.530713 -31.660417) (xy 264.495018 -31.619227)
			(xy 264.465549 -31.573376) (xy 264.442905 -31.523798) (xy 264.427549 -31.471502) (xy 264.419791 -31.417552)
			(xy 264.419791 -31.363048) (xy 264.427549 -31.309098) (xy 264.442905 -31.256802) (xy 264.465549 -31.207224)
			(xy 264.495018 -31.161373) (xy 264.530713 -31.120183) (xy 264.571907 -31.084493) (xy 264.617761 -31.055029)
			(xy 264.667341 -31.032391) (xy 264.719639 -31.01704) (xy 264.77359 -31.009288) (xy 264.800842 -31.008828)
			(xy 264.817954 -31.009022) (xy 264.852041 -31.012073) (xy 264.868914 -31.014924) (xy 264.88018 -31.01633)
			(xy 264.902064 -31.010396) (xy 264.911078 -31.003494) (xy 264.935462 -30.982412) (xy 264.943822 -30.974462)
			(xy 264.952962 -30.953307) (xy 264.952988 -30.941772) (xy 264.95248 -30.922468) (xy 264.95248 -30.058868)
			(xy 264.952988 -30.038802) (xy 264.952799 -30.027294) (xy 264.94371 -30.006187) (xy 264.935462 -29.998162)
			(xy 264.911078 -29.97708) (xy 264.902094 -29.970123) (xy 264.880186 -29.964201) (xy 264.868914 -29.96565)
			(xy 264.852043 -29.96852) (xy 264.817955 -29.971572) (xy 264.800842 -29.971746) (xy 264.77359 -29.97121)
			(xy 264.71964 -29.963458) (xy 264.667342 -29.948107) (xy 264.617762 -29.92547) (xy 264.571908 -29.896006)
			(xy 264.530714 -29.860316) (xy 264.49502 -29.819126) (xy 264.465551 -29.773275) (xy 264.442907 -29.723697)
			(xy 264.427551 -29.671401) (xy 264.419793 -29.617452) (xy 264.419793 -29.562948) (xy 264.427551 -29.508999)
			(xy 264.442907 -29.456703) (xy 264.465551 -29.407125) (xy 264.49502 -29.361274) (xy 264.530714 -29.320084)
			(xy 264.571908 -29.284394) (xy 264.617762 -29.25493) (xy 264.667342 -29.232293) (xy 264.71964 -29.216942)
			(xy 264.77359 -29.20919) (xy 264.800842 -29.20873) (xy 264.82785 -29.209174) (xy 264.881327 -29.216785)
			(xy 264.933195 -29.231864) (xy 264.982418 -29.254108) (xy 265.028011 -29.283072) (xy 265.069063 -29.318179)
			(xy 265.104752 -29.358725) (xy 265.134365 -29.403899) (xy 265.15731 -29.4528) (xy 265.173128 -29.504447)
			(xy 265.177778 -29.531056) (xy 265.179302 -29.541724) (xy 265.190732 -29.559504) (xy 265.270996 -29.612844)
			(xy 265.29157 -29.616654) (xy 265.302238 -29.614114) (xy 265.328876 -29.608047) (xy 265.383124 -29.601557)
			(xy 265.410442 -29.60116) (xy 265.43776 -29.601551) (xy 265.492008 -29.608043) (xy 265.518646 -29.614114)
			(xy 265.529314 -29.616654) (xy 265.549888 -29.612844) (xy 265.630152 -29.559504) (xy 265.641582 -29.541724)
			(xy 265.643106 -29.531056) (xy 265.64781 -29.50446) (xy 265.663634 -29.452823) (xy 265.686581 -29.403933)
			(xy 265.716192 -29.358767) (xy 265.751876 -29.318227) (xy 265.792919 -29.283124) (xy 265.838502 -29.25416)
			(xy 265.887714 -29.231912) (xy 265.939572 -29.216826) (xy 265.993038 -29.209202) (xy 266.020042 -29.20873)
			(xy 266.047411 -29.209223) (xy 266.10159 -29.217033) (xy 266.154093 -29.232515) (xy 266.20384 -29.255351)
			(xy 266.249808 -29.285071) (xy 266.27074 -29.30271) (xy 266.277852 -29.308806) (xy 266.29487 -29.315156)
			(xy 266.380214 -29.315156) (xy 266.397232 -29.308806) (xy 266.404344 -29.30271) (xy 266.425288 -29.285085)
			(xy 266.471257 -29.255371) (xy 266.521002 -29.232532) (xy 266.5735 -29.217038) (xy 266.627674 -29.209206)
			(xy 266.655042 -29.20873) (xy 266.672154 -29.208924) (xy 266.706241 -29.211975) (xy 266.723114 -29.214826)
			(xy 266.73438 -29.216231) (xy 266.756264 -29.210298) (xy 266.765278 -29.203396) (xy 266.789662 -29.182314)
			(xy 266.798021 -29.174363) (xy 266.807162 -29.153209) (xy 266.807188 -29.141674) (xy 266.80668 -29.12237)
			(xy 266.80668 -28.25877) (xy 266.807188 -28.238704) (xy 266.806998 -28.227196) (xy 266.79791 -28.206089)
			(xy 266.789662 -28.198064) (xy 266.765278 -28.176982) (xy 266.756294 -28.170026) (xy 266.734386 -28.164103)
			(xy 266.723114 -28.165552) (xy 266.706243 -28.168422) (xy 266.672155 -28.171474) (xy 266.655042 -28.171648)
			(xy 266.62779 -28.171108) (xy 266.57384 -28.163356) (xy 266.521543 -28.148006) (xy 266.471963 -28.125368)
			(xy 266.426109 -28.095904) (xy 266.384916 -28.060214) (xy 266.349221 -28.019025) (xy 266.319752 -27.973174)
			(xy 266.297109 -27.923597) (xy 266.281753 -27.871301) (xy 266.273995 -27.817352) (xy 266.273995 -27.762848)
			(xy 266.281753 -27.708899) (xy 266.297109 -27.656603) (xy 266.319752 -27.607026) (xy 266.349221 -27.561175)
			(xy 266.384916 -27.519986) (xy 266.426109 -27.484296) (xy 266.471963 -27.454832) (xy 266.521543 -27.432194)
			(xy 266.57384 -27.416844) (xy 266.62779 -27.409092) (xy 266.655042 -27.408632) (xy 266.68205 -27.409075)
			(xy 266.735527 -27.416686) (xy 266.787395 -27.431764) (xy 266.836619 -27.454008) (xy 266.882212 -27.482973)
			(xy 266.923263 -27.51808) (xy 266.958953 -27.558626) (xy 266.988566 -27.603801) (xy 267.01151 -27.652701)
			(xy 267.027328 -27.704349) (xy 267.031978 -27.730958) (xy 267.033502 -27.741626) (xy 267.044932 -27.759406)
			(xy 267.125196 -27.812746) (xy 267.14577 -27.816556) (xy 267.156438 -27.814016) (xy 267.18307 -27.80789)
			(xy 267.237318 -27.801266) (xy 267.264642 -27.800808) (xy 267.28682 -27.801103) (xy 267.330966 -27.805429)
			(xy 267.35278 -27.809444) (xy 267.363194 -27.811476) (xy 267.383006 -27.807412) (xy 267.459968 -27.754072)
			(xy 267.47089 -27.737054) (xy 267.472668 -27.72664) (xy 267.477552 -27.700299) (xy 267.493768 -27.649239)
			(xy 267.516969 -27.60095) (xy 267.546698 -27.556382) (xy 267.582371 -27.516412) (xy 267.623285 -27.481827)
			(xy 267.668635 -27.453306) (xy 267.71753 -27.431411) (xy 267.769008 -27.416572) (xy 267.822055 -27.409082)
			(xy 267.848842 -27.408632) (xy 267.876094 -27.409041) (xy 267.930043 -27.416803) (xy 267.982338 -27.432163)
			(xy 268.031915 -27.454809) (xy 268.077765 -27.48428) (xy 268.118955 -27.519975) (xy 268.154645 -27.561168)
			(xy 268.184111 -27.607022) (xy 268.206751 -27.656601) (xy 268.222106 -27.708898) (xy 268.229862 -27.762848)
			(xy 268.229862 -27.817352) (xy 268.222106 -27.871302) (xy 268.206751 -27.923599) (xy 268.184111 -27.973178)
			(xy 268.154645 -28.019032) (xy 268.118955 -28.060225) (xy 268.077765 -28.09592) (xy 268.031915 -28.125391)
			(xy 267.982338 -28.148037) (xy 267.930043 -28.163397) (xy 267.876094 -28.171159) (xy 267.848842 -28.171648)
			(xy 267.83732 -28.171556) (xy 267.814317 -28.170157) (xy 267.802868 -28.168854) (xy 267.791954 -28.168129)
			(xy 267.771159 -28.174831) (xy 267.762736 -28.181808) (xy 267.73886 -28.203398) (xy 267.731005 -28.211249)
			(xy 267.722319 -28.231664) (xy 267.722096 -28.242768) (xy 267.722604 -28.25877) (xy 267.722604 -29.12237)
			(xy 267.72235 -29.137356) (xy 267.722481 -29.148441) (xy 267.731046 -29.168862) (xy 267.73886 -29.176726)
			(xy 267.762736 -29.198316) (xy 267.771146 -29.205314) (xy 267.791952 -29.212016) (xy 267.802868 -29.21127)
			(xy 267.814316 -29.209955) (xy 267.837319 -29.208559) (xy 267.848842 -29.208476) (xy 267.87609 -29.208997)
			(xy 267.930031 -29.216758) (xy 267.982318 -29.232116) (xy 268.031888 -29.254759) (xy 268.077731 -29.284225)
			(xy 268.118915 -29.319915) (xy 268.1546 -29.361102) (xy 268.184061 -29.406949) (xy 268.206698 -29.456521)
			(xy 268.222051 -29.50881) (xy 268.229806 -29.562752) (xy 268.229806 -29.617248) (xy 268.222051 -29.67119)
			(xy 268.206698 -29.723479) (xy 268.184061 -29.773051) (xy 268.1546 -29.818898) (xy 268.118915 -29.860085)
			(xy 268.077731 -29.895775) (xy 268.031888 -29.925241) (xy 267.982318 -29.947884) (xy 267.930031 -29.963242)
			(xy 267.87609 -29.971003) (xy 267.848842 -29.971492) (xy 267.822096 -29.970984) (xy 267.76913 -29.963496)
			(xy 267.717727 -29.948689) (xy 267.668894 -29.926853) (xy 267.623587 -29.898414) (xy 267.582692 -29.863931)
			(xy 267.547011 -29.824078) (xy 267.51724 -29.779634) (xy 267.493965 -29.731471) (xy 267.477639 -29.68053)
			(xy 267.472668 -29.654246) (xy 267.47089 -29.643832) (xy 267.460222 -29.626814) (xy 267.383006 -29.573728)
			(xy 267.363194 -29.569664) (xy 267.353034 -29.571696) (xy 267.331161 -29.575748) (xy 267.286885 -29.580071)
			(xy 267.264642 -29.580332) (xy 267.237254 -29.579884) (xy 267.182878 -29.573266) (xy 267.156184 -29.567124)
			(xy 267.14577 -29.564584) (xy 267.125196 -29.56814) (xy 267.044932 -29.621734) (xy 267.033502 -29.63926)
			(xy 267.031724 -29.649928) (xy 267.027078 -29.676503) (xy 267.01122 -29.728069) (xy 266.988254 -29.776886)
			(xy 266.95864 -29.82198) (xy 266.922967 -29.862452) (xy 266.881947 -29.897493) (xy 266.836399 -29.926406)
			(xy 266.787232 -29.948612) (xy 266.735427 -29.963669) (xy 266.682017 -29.971276) (xy 266.655042 -29.971746)
			(xy 266.627672 -29.971268) (xy 266.573493 -29.963455) (xy 266.520989 -29.94797) (xy 266.471242 -29.92513)
			(xy 266.425275 -29.895407) (xy 266.404344 -29.877766) (xy 266.397232 -29.87167) (xy 266.380214 -29.86532)
			(xy 266.29487 -29.86532) (xy 266.277852 -29.87167) (xy 266.27074 -29.877766) (xy 266.249799 -29.895395)
			(xy 266.203829 -29.925109) (xy 266.154084 -29.947948) (xy 266.101585 -29.963441) (xy 266.047411 -29.971271)
			(xy 266.020042 -29.971746) (xy 266.00293 -29.971554) (xy 265.968843 -29.968502) (xy 265.95197 -29.96565)
			(xy 265.940705 -29.964241) (xy 265.918821 -29.970178) (xy 265.909806 -29.97708) (xy 265.885422 -29.998162)
			(xy 265.877024 -30.006079) (xy 265.867906 -30.027259) (xy 265.867896 -30.038802) (xy 265.868404 -30.058868)
			(xy 265.868404 -30.922468) (xy 265.867896 -30.941772) (xy 265.868047 -30.953283) (xy 265.877163 -30.974391)
			(xy 265.885422 -30.982412) (xy 265.909806 -31.003494) (xy 265.918798 -31.010439) (xy 265.9407 -31.016369)
			(xy 265.95197 -31.014924) (xy 265.968841 -31.012056) (xy 266.00293 -31.009002) (xy 266.020042 -31.008828)
			(xy 266.047411 -31.009321) (xy 266.10159 -31.017131) (xy 266.154093 -31.032614) (xy 266.20384 -31.05545)
			(xy 266.249808 -31.085169) (xy 266.27074 -31.102808) (xy 266.277852 -31.108904) (xy 266.294616 -31.115254)
			(xy 266.380214 -31.115254) (xy 266.397232 -31.108904) (xy 266.40409 -31.102554) (xy 266.42503 -31.084883)
			(xy 266.471049 -31.055144) (xy 266.520851 -31.032299) (xy 266.573411 -31.016819) (xy 266.627646 -31.009024)
			(xy 266.655042 -31.008574) (xy 266.682052 -31.008981) (xy 266.735532 -31.016594) (xy 266.787403 -31.031674)
			(xy 266.836628 -31.053921) (xy 266.882223 -31.08289) (xy 266.923275 -31.118) (xy 266.958964 -31.158551)
			(xy 266.988575 -31.203731) (xy 267.011517 -31.252637) (xy 267.02733 -31.304289) (xy 267.031978 -31.3309)
			(xy 267.033502 -31.341568) (xy 267.044932 -31.359348) (xy 267.125196 -31.412688) (xy 267.14577 -31.416498)
			(xy 267.156438 -31.413958) (xy 267.183076 -31.407892) (xy 267.237324 -31.401401) (xy 267.264642 -31.401004)
			(xy 267.286815 -31.401227) (xy 267.330961 -31.405429) (xy 267.35278 -31.409386) (xy 267.363194 -31.411418)
			(xy 267.383006 -31.407354) (xy 267.459968 -31.354014) (xy 267.47089 -31.336996) (xy 267.472668 -31.326582)
			(xy 267.477508 -31.300232) (xy 267.493732 -31.249172) (xy 267.51694 -31.200883) (xy 267.546675 -31.156317)
			(xy 267.582353 -31.116348) (xy 267.623271 -31.081764) (xy 267.668626 -31.053245) (xy 267.717524 -31.031351)
			(xy 267.769004 -31.016513) (xy 267.822054 -31.009024) (xy 267.848842 -31.008574) (xy 267.87609 -31.009099)
			(xy 267.930031 -31.01686) (xy 267.982318 -31.032218) (xy 268.031887 -31.054861) (xy 268.07773 -31.084327)
			(xy 268.118913 -31.120016) (xy 268.154599 -31.161203) (xy 268.18406 -31.20705) (xy 268.206697 -31.256622)
			(xy 268.222049 -31.308911) (xy 268.229804 -31.362852) (xy 268.229804 -31.417348) (xy 268.222049 -31.471289)
			(xy 268.206697 -31.523578) (xy 268.18406 -31.57315) (xy 268.154599 -31.618997) (xy 268.118913 -31.660184)
			(xy 268.07773 -31.695873) (xy 268.031887 -31.725339) (xy 267.982318 -31.747982) (xy 267.930031 -31.76334)
			(xy 267.87609 -31.771101) (xy 267.848842 -31.77159) (xy 267.83732 -31.771496) (xy 267.814317 -31.770097)
			(xy 267.802868 -31.768796) (xy 267.791954 -31.768061) (xy 267.771157 -31.774769) (xy 267.762736 -31.78175)
			(xy 267.73886 -31.80334) (xy 267.731032 -31.811214) (xy 267.722331 -31.831611) (xy 267.722096 -31.84271)
			(xy 267.722604 -31.858712) (xy 267.722604 -32.722312) (xy 267.722096 -32.737552) (xy 267.722279 -32.748664)
			(xy 267.730976 -32.769089) (xy 267.73886 -32.776922) (xy 267.762736 -32.798512) (xy 267.771146 -32.805509)
			(xy 267.791952 -32.812212) (xy 267.802868 -32.811466) (xy 267.814316 -32.810151) (xy 267.837319 -32.808755)
			(xy 267.848842 -32.808672) (xy 267.87609 -32.809201) (xy 267.93003 -32.816962) (xy 267.982317 -32.83232)
			(xy 268.031886 -32.854962) (xy 268.077729 -32.884428) (xy 268.118912 -32.920118) (xy 268.154597 -32.961305)
			(xy 268.184058 -33.007151) (xy 268.206695 -33.056722) (xy 268.222047 -33.109011) (xy 268.229802 -33.162952)
			(xy 268.229802 -33.217448) (xy 268.222047 -33.271389) (xy 268.206695 -33.323678) (xy 268.184058 -33.373249)
			(xy 268.154597 -33.419095) (xy 268.118912 -33.460282) (xy 268.077729 -33.495972) (xy 268.031886 -33.525438)
			(xy 267.982317 -33.54808) (xy 267.93003 -33.563438) (xy 267.87609 -33.571199) (xy 267.848842 -33.571688)
			(xy 267.822075 -33.571278) (xy 267.769066 -33.563813) (xy 267.71762 -33.549008) (xy 267.668751 -33.527156)
			(xy 267.623417 -33.498684) (xy 267.582509 -33.464154) (xy 267.546832 -33.424243) (xy 267.517086 -33.379735)
			(xy 267.493855 -33.331505) (xy 267.477597 -33.280501) (xy 267.472668 -33.254188) (xy 267.47089 -33.243774)
			(xy 267.460222 -33.226756) (xy 267.383006 -33.17367) (xy 267.363194 -33.169606) (xy 267.353034 -33.171638)
			(xy 267.331155 -33.175622) (xy 267.28688 -33.179819) (xy 267.264642 -33.18002) (xy 267.23726 -33.179653)
			(xy 267.182884 -33.173153) (xy 267.156184 -33.167066) (xy 267.14577 -33.164526) (xy 267.125196 -33.168082)
			(xy 267.044932 -33.221676) (xy 267.033502 -33.239202) (xy 267.031724 -33.24987) (xy 267.027034 -33.276437)
			(xy 267.011183 -33.328003) (xy 266.988225 -33.37682) (xy 266.958616 -33.421915) (xy 266.922948 -33.462388)
			(xy 266.881933 -33.497431) (xy 266.836389 -33.526345) (xy 266.787226 -33.548553) (xy 266.735423 -33.56361)
			(xy 266.682015 -33.571218) (xy 266.655042 -33.571688) (xy 266.627673 -33.5712) (xy 266.573494 -33.563388)
			(xy 266.520991 -33.547904) (xy 266.471244 -33.525067) (xy 266.425276 -33.495347) (xy 266.404344 -33.477708)
			(xy 266.397232 -33.471612) (xy 266.380214 -33.465262) (xy 266.29487 -33.465262) (xy 266.277852 -33.471612)
			(xy 266.27074 -33.477708) (xy 266.249805 -33.495343) (xy 266.203833 -33.525055) (xy 266.154086 -33.547892)
			(xy 266.101586 -33.563384) (xy 266.047411 -33.571213) (xy 266.020042 -33.571688) (xy 266.00293 -33.571496)
			(xy 265.968843 -33.568444) (xy 265.95197 -33.565592) (xy 265.940705 -33.564173) (xy 265.918819 -33.570115)
			(xy 265.909806 -33.577022) (xy 265.885422 -33.598104) (xy 265.877052 -33.606046) (xy 265.867918 -33.627207)
			(xy 265.867896 -33.638744) (xy 265.868404 -33.65881) (xy 265.868404 -34.52241) (xy 265.867896 -34.541714)
			(xy 265.868081 -34.553222) (xy 265.877173 -34.574329) (xy 265.885422 -34.582354) (xy 265.909806 -34.603436)
			(xy 265.918802 -34.610376) (xy 265.940701 -34.616312) (xy 265.95197 -34.614866) (xy 265.968841 -34.611998)
			(xy 266.00293 -34.608944) (xy 266.020042 -34.60877) (xy 266.04729 -34.609303) (xy 266.10123 -34.617064)
			(xy 266.153516 -34.632422) (xy 266.203085 -34.655064) (xy 266.248928 -34.68453) (xy 266.290111 -34.720219)
			(xy 266.325795 -34.761406) (xy 266.355256 -34.807252) (xy 266.377893 -34.856823) (xy 266.393245 -34.909111)
			(xy 266.401 -34.963052) (xy 266.401 -34.990024) (xy 267.466824 -34.990024) (xy 267.470895 -34.934402)
			(xy 267.483021 -34.879965) (xy 267.502944 -34.827874) (xy 267.53024 -34.779239) (xy 267.564326 -34.735096)
			(xy 267.604475 -34.696387) (xy 267.649833 -34.663936) (xy 267.699433 -34.638435) (xy 267.752217 -34.620428)
			(xy 267.80706 -34.610298) (xy 267.862794 -34.608261) (xy 267.918231 -34.614361) (xy 267.972188 -34.628467)
			(xy 268.023517 -34.650279) (xy 268.071123 -34.679333) (xy 268.113991 -34.715008) (xy 268.151208 -34.756545)
			(xy 268.181981 -34.803058) (xy 268.205653 -34.853555) (xy 268.221721 -34.906962) (xy 268.229841 -34.962138)
			(xy 268.23035 -34.990024) (xy 268.229841 -35.01791) (xy 268.221721 -35.073086) (xy 268.205653 -35.126493)
			(xy 268.181981 -35.17699) (xy 268.151208 -35.223503) (xy 268.113991 -35.26504) (xy 268.071123 -35.300715)
			(xy 268.023517 -35.329769) (xy 267.972188 -35.351581) (xy 267.918231 -35.365687) (xy 267.862794 -35.371787)
			(xy 267.80706 -35.36975) (xy 267.752217 -35.35962) (xy 267.699433 -35.341613) (xy 267.649833 -35.316112)
			(xy 267.604475 -35.283661) (xy 267.564326 -35.244952) (xy 267.53024 -35.200809) (xy 267.502944 -35.152174)
			(xy 267.483021 -35.100083) (xy 267.470895 -35.045646) (xy 267.466824 -34.990024) (xy 266.401 -34.990024)
			(xy 266.401 -35.017548) (xy 266.393245 -35.071489) (xy 266.377893 -35.123777) (xy 266.355256 -35.173348)
			(xy 266.325795 -35.219194) (xy 266.290111 -35.260381) (xy 266.248928 -35.29607) (xy 266.203085 -35.325536)
			(xy 266.153516 -35.348178) (xy 266.10123 -35.363536) (xy 266.04729 -35.371297) (xy 266.020042 -35.371786)
			(xy 265.993065 -35.371334) (xy 265.939646 -35.363746) (xy 265.887832 -35.348701) (xy 265.838657 -35.326501)
			(xy 265.793103 -35.297588) (xy 265.752081 -35.262541) (xy 265.716412 -35.222059) (xy 265.686807 -35.176952)
			(xy 265.663858 -35.128122) (xy 265.648023 -35.076543) (xy 265.64336 -35.049968) (xy 265.641582 -35.0393)
			(xy 265.630152 -35.021774) (xy 265.549888 -34.96818) (xy 265.529314 -34.964624) (xy 265.5189 -34.967164)
			(xy 265.492207 -34.973312) (xy 265.43783 -34.979928) (xy 265.410442 -34.980372) (xy 265.383054 -34.979923)
			(xy 265.328678 -34.973305) (xy 265.301984 -34.967164) (xy 265.29157 -34.964624) (xy 265.270996 -34.96818)
			(xy 265.190732 -35.021774) (xy 265.179302 -35.0393) (xy 265.177524 -35.049968) (xy 265.172908 -35.076549)
			(xy 265.157045 -35.128115) (xy 265.134075 -35.176931) (xy 265.104456 -35.222025) (xy 265.068779 -35.262496)
			(xy 265.027757 -35.297536) (xy 264.982206 -35.326448) (xy 264.933037 -35.348653) (xy 264.881229 -35.363709)
			(xy 264.827817 -35.371316) (xy 264.800842 -35.371786) (xy 264.773586 -35.37137) (xy 264.719627 -35.363617)
			(xy 264.667321 -35.348264) (xy 264.617733 -35.325623) (xy 264.571872 -35.296154) (xy 264.530671 -35.260458)
			(xy 264.494971 -35.219262) (xy 264.465497 -35.173404) (xy 264.442851 -35.123818) (xy 264.427492 -35.071514)
			(xy 264.419733 -35.017556) (xy 262.774348 -35.017556) (xy 262.786728 -35.031373) (xy 262.817501 -35.077886)
			(xy 262.841173 -35.128383) (xy 262.857241 -35.18179) (xy 262.865361 -35.236966) (xy 262.86587 -35.264852)
			(xy 262.865361 -35.292738) (xy 262.857241 -35.347914) (xy 262.841173 -35.401321) (xy 262.817501 -35.451818)
			(xy 262.786728 -35.498331) (xy 262.749511 -35.539868) (xy 262.706643 -35.575543) (xy 262.659037 -35.604597)
			(xy 262.607708 -35.626409) (xy 262.553751 -35.640515) (xy 262.498314 -35.646615) (xy 262.44258 -35.644578)
			(xy 262.387737 -35.634448) (xy 262.334953 -35.616441) (xy 262.285353 -35.59094) (xy 262.239995 -35.558489)
			(xy 262.199846 -35.51978) (xy 262.16576 -35.475637) (xy 262.138464 -35.427002) (xy 262.118541 -35.374911)
			(xy 262.106415 -35.320474) (xy 262.102344 -35.264852) (xy 259.6007 -35.264852) (xy 259.6007 -37.087048)
			(xy 263.400794 -37.087048) (xy 263.401282 -37.060445) (xy 263.408657 -37.007754) (xy 263.423285 -36.956599)
			(xy 263.444881 -36.907975) (xy 263.473026 -36.862824) (xy 263.507175 -36.822024) (xy 263.546663 -36.786366)
			(xy 263.568434 -36.771072) (xy 263.578367 -36.763551) (xy 263.590088 -36.7416) (xy 263.590786 -36.729162)
			(xy 263.590786 -36.644834) (xy 263.590135 -36.632381) (xy 263.578413 -36.610403) (xy 263.568434 -36.602924)
			(xy 263.546665 -36.587628) (xy 263.507186 -36.551961) (xy 263.473043 -36.511158) (xy 263.444897 -36.466008)
			(xy 263.423295 -36.417387) (xy 263.408654 -36.366237) (xy 263.401258 -36.31355) (xy 263.400794 -36.286948)
			(xy 263.4013 -36.259696) (xy 263.40905 -36.205747) (xy 263.4244 -36.15345) (xy 263.447038 -36.103869)
			(xy 263.476501 -36.058016) (xy 263.51219 -36.016823) (xy 263.553379 -35.981128) (xy 263.599229 -35.95166)
			(xy 263.648806 -35.929017) (xy 263.701102 -35.91366) (xy 263.75505 -35.905903) (xy 263.782302 -35.90544)
			(xy 263.786874 -35.90544) (xy 263.796526 -35.905694) (xy 263.81329 -35.899344) (xy 263.878822 -35.843464)
			(xy 263.887458 -35.827462) (xy 263.888728 -35.818064) (xy 263.893031 -35.791125) (xy 263.908344 -35.738766)
			(xy 263.930959 -35.689122) (xy 263.960414 -35.643205) (xy 263.99611 -35.601952) (xy 264.037318 -35.566204)
			(xy 264.083197 -35.536691) (xy 264.132813 -35.514013) (xy 264.185153 -35.498634) (xy 264.23915 -35.490867)
			(xy 264.266426 -35.490404) (xy 264.293677 -35.490868) (xy 264.347624 -35.498627) (xy 264.399917 -35.513985)
			(xy 264.449492 -35.536629) (xy 264.495341 -35.566096) (xy 264.536529 -35.601789) (xy 264.572219 -35.64298)
			(xy 264.601684 -35.688831) (xy 264.624324 -35.738408) (xy 264.639678 -35.790702) (xy 264.647434 -35.844649)
			(xy 264.647434 -35.899151) (xy 264.639678 -35.953098) (xy 264.624324 -36.005392) (xy 264.601684 -36.054969)
			(xy 264.572219 -36.10082) (xy 264.536529 -36.142011) (xy 264.495341 -36.177704) (xy 264.449492 -36.207171)
			(xy 264.399917 -36.229815) (xy 264.347624 -36.245173) (xy 264.293677 -36.252932) (xy 264.266426 -36.25342)
			(xy 264.261854 -36.25342) (xy 264.252202 -36.253166) (xy 264.235438 -36.259516) (xy 264.169906 -36.315396)
			(xy 264.16127 -36.331398) (xy 264.16 -36.340796) (xy 264.155782 -36.366996) (xy 264.1411 -36.417989)
			(xy 264.11949 -36.466454) (xy 264.09137 -36.511455) (xy 264.087939 -36.515548) (xy 265.214098 -36.515548)
			(xy 265.218169 -36.459926) (xy 265.230295 -36.405489) (xy 265.250218 -36.353398) (xy 265.277514 -36.304763)
			(xy 265.3116 -36.26062) (xy 265.351749 -36.221911) (xy 265.397107 -36.18946) (xy 265.446707 -36.163959)
			(xy 265.499491 -36.145952) (xy 265.554334 -36.135822) (xy 265.610068 -36.133785) (xy 265.665505 -36.139885)
			(xy 265.719462 -36.153991) (xy 265.770791 -36.175803) (xy 265.818397 -36.204857) (xy 265.861265 -36.240532)
			(xy 265.898482 -36.282069) (xy 265.929255 -36.328582) (xy 265.952927 -36.379079) (xy 265.968995 -36.432486)
			(xy 265.977115 -36.487662) (xy 265.977624 -36.515548) (xy 265.977115 -36.543434) (xy 265.968995 -36.59861)
			(xy 265.952927 -36.652017) (xy 265.929255 -36.702514) (xy 265.898482 -36.749027) (xy 265.861265 -36.790564)
			(xy 265.818397 -36.826239) (xy 265.770791 -36.855293) (xy 265.719462 -36.877105) (xy 265.665505 -36.891211)
			(xy 265.610068 -36.897311) (xy 265.554334 -36.895274) (xy 265.499491 -36.885144) (xy 265.446707 -36.867137)
			(xy 265.397107 -36.841636) (xy 265.351749 -36.809185) (xy 265.3116 -36.770476) (xy 265.277514 -36.726333)
			(xy 265.250218 -36.677698) (xy 265.230295 -36.625607) (xy 265.218169 -36.57117) (xy 265.214098 -36.515548)
			(xy 264.087939 -36.515548) (xy 264.057282 -36.552123) (xy 264.017886 -36.587673) (xy 263.99617 -36.602924)
			(xy 263.98624 -36.610447) (xy 263.974517 -36.632397) (xy 263.973818 -36.644834) (xy 263.973818 -36.729162)
			(xy 263.97447 -36.741615) (xy 263.986192 -36.763593) (xy 263.99617 -36.771072) (xy 264.017938 -36.78637)
			(xy 264.057417 -36.822036) (xy 264.09156 -36.862839) (xy 264.119706 -36.907988) (xy 264.141308 -36.956609)
			(xy 264.15595 -37.007759) (xy 264.163345 -37.060446) (xy 264.16381 -37.087048) (xy 264.163204 -37.118807)
			(xy 264.152718 -37.181453) (xy 264.131978 -37.241489) (xy 264.117328 -37.269674) (xy 264.111994 -37.27958)
			(xy 264.11047 -37.301678) (xy 264.146284 -37.394896) (xy 264.162286 -37.41039) (xy 264.172954 -37.4142)
			(xy 264.197477 -37.423293) (xy 264.244008 -37.44717) (xy 264.286841 -37.477182) (xy 264.325171 -37.512764)
			(xy 264.358281 -37.553249) (xy 264.385548 -37.597879) (xy 264.406462 -37.645815) (xy 264.420631 -37.69616)
			(xy 264.427788 -37.747968) (xy 264.428224 -37.774118) (xy 264.427738 -37.801369) (xy 264.419982 -37.855317)
			(xy 264.404627 -37.907612) (xy 264.381985 -37.957189) (xy 264.352519 -38.003039) (xy 264.316828 -38.04423)
			(xy 264.275637 -38.079921) (xy 264.229787 -38.109387) (xy 264.18021 -38.132029) (xy 264.127915 -38.147384)
			(xy 264.073967 -38.15514) (xy 264.019465 -38.15514) (xy 263.965517 -38.147384) (xy 263.913222 -38.132029)
			(xy 263.863645 -38.109387) (xy 263.817795 -38.079921) (xy 263.776604 -38.04423) (xy 263.740913 -38.003039)
			(xy 263.711447 -37.957189) (xy 263.688805 -37.907612) (xy 263.67345 -37.855317) (xy 263.665694 -37.801369)
			(xy 263.665208 -37.774118) (xy 263.665798 -37.742358) (xy 263.67629 -37.679712) (xy 263.697037 -37.619676)
			(xy 263.71169 -37.591492) (xy 263.717024 -37.581586) (xy 263.718548 -37.559488) (xy 263.682734 -37.46627)
			(xy 263.666732 -37.450776) (xy 263.656064 -37.446966) (xy 263.631512 -37.437949) (xy 263.584981 -37.414059)
			(xy 263.54215 -37.384036) (xy 263.503822 -37.348444) (xy 263.470716 -37.307949) (xy 263.443453 -37.26331)
			(xy 263.422543 -37.215366) (xy 263.40838 -37.165015) (xy 263.401228 -37.113201) (xy 263.400794 -37.087048)
			(xy 259.6007 -37.087048) (xy 259.6007 -38.315138) (xy 264.61796 -38.315138) (xy 264.622031 -38.259516)
			(xy 264.634157 -38.205079) (xy 264.65408 -38.152988) (xy 264.681376 -38.104353) (xy 264.715462 -38.06021)
			(xy 264.755611 -38.021501) (xy 264.800969 -37.98905) (xy 264.850569 -37.963549) (xy 264.903353 -37.945542)
			(xy 264.958196 -37.935412) (xy 265.01393 -37.933375) (xy 265.069367 -37.939475) (xy 265.123324 -37.953581)
			(xy 265.174653 -37.975393) (xy 265.222259 -38.004447) (xy 265.265127 -38.040122) (xy 265.302344 -38.081659)
			(xy 265.333117 -38.128172) (xy 265.356789 -38.178669) (xy 265.372857 -38.232076) (xy 265.380977 -38.287252)
			(xy 265.381486 -38.315138) (xy 265.380977 -38.343024) (xy 265.372857 -38.3982) (xy 265.356789 -38.451607)
			(xy 265.333117 -38.502104) (xy 265.302344 -38.548617) (xy 265.265127 -38.590154) (xy 265.222259 -38.625829)
			(xy 265.174653 -38.654883) (xy 265.123324 -38.676695) (xy 265.069367 -38.690801) (xy 265.01393 -38.696901)
			(xy 264.958196 -38.694864) (xy 264.903353 -38.684734) (xy 264.850569 -38.666727) (xy 264.800969 -38.641226)
			(xy 264.755611 -38.608775) (xy 264.715462 -38.570066) (xy 264.681376 -38.525923) (xy 264.65408 -38.477288)
			(xy 264.634157 -38.425197) (xy 264.622031 -38.37076) (xy 264.61796 -38.315138) (xy 259.6007 -38.315138)
			(xy 259.6007 -42.44721) (xy 259.61975 -42.473626) (xy 259.635498 -42.47896) (xy 259.660492 -42.487757)
			(xy 259.707968 -42.511285) (xy 259.751732 -42.541156) (xy 259.790942 -42.576794) (xy 259.824844 -42.617515)
			(xy 259.852785 -42.662535) (xy 259.874229 -42.710988) (xy 259.888763 -42.761942) (xy 259.896106 -42.814417)
			(xy 259.89661 -42.84091) (xy 259.896172 -42.866861) (xy 259.88913 -42.918284) (xy 259.875179 -42.968276)
			(xy 259.854575 -43.015914) (xy 259.8277 -43.060317) (xy 259.79505 -43.100664) (xy 259.776468 -43.118786)
			(xy 259.775198 -43.120056) (xy 259.77469 -43.120564) (xy 259.774436 -43.120818) (xy 259.754655 -43.139166)
			(xy 259.710857 -43.170673) (xy 259.663051 -43.195684) (xy 259.637784 -43.205146) (xy 259.63499 -43.206162)
			(xy 259.629148 -43.208956) (xy 259.620785 -43.213473) (xy 259.607936 -43.227461) (xy 259.601089 -43.245177)
			(xy 259.6007 -43.254676) (xy 259.6007 -43.46321) (xy 259.61975 -43.489626) (xy 259.635498 -43.49496)
			(xy 259.660492 -43.503757) (xy 259.707968 -43.527285) (xy 259.751732 -43.557156) (xy 259.790942 -43.592794)
			(xy 259.824844 -43.633515) (xy 259.852785 -43.678535) (xy 259.874229 -43.726988) (xy 259.888763 -43.777942)
			(xy 259.896106 -43.830417) (xy 259.89661 -43.85691) (xy 259.896172 -43.882861) (xy 259.88913 -43.934284)
			(xy 259.875179 -43.984276) (xy 259.854575 -44.031914) (xy 259.8277 -44.076317) (xy 259.79505 -44.116664)
			(xy 259.776468 -44.134786) (xy 259.775198 -44.136056) (xy 259.77469 -44.136564) (xy 259.774436 -44.136818)
			(xy 259.754655 -44.155166) (xy 259.710857 -44.186673) (xy 259.663051 -44.211684) (xy 259.637784 -44.221146)
			(xy 259.63499 -44.222162) (xy 259.629148 -44.224956) (xy 259.620785 -44.229473) (xy 259.607936 -44.243461)
			(xy 259.601089 -44.261177) (xy 259.6007 -44.270676) (xy 259.6007 -44.47921) (xy 259.61975 -44.505626)
			(xy 259.635498 -44.51096) (xy 259.660492 -44.519757) (xy 259.707968 -44.543285) (xy 259.751732 -44.573156)
			(xy 259.790942 -44.608794) (xy 259.824844 -44.649515) (xy 259.852785 -44.694535) (xy 259.874229 -44.742988)
			(xy 259.888763 -44.793942) (xy 259.896106 -44.846417) (xy 259.89661 -44.87291) (xy 259.896172 -44.898861)
			(xy 259.88913 -44.950284) (xy 259.875179 -45.000276) (xy 259.854575 -45.047914) (xy 259.8277 -45.092317)
			(xy 259.79505 -45.132664) (xy 259.776468 -45.150786) (xy 259.775198 -45.152056) (xy 259.77469 -45.152564)
			(xy 259.774436 -45.152818) (xy 259.754655 -45.171166) (xy 259.710857 -45.202673) (xy 259.663051 -45.227684)
			(xy 259.637784 -45.237146) (xy 259.63499 -45.238162) (xy 259.629148 -45.240956) (xy 259.620785 -45.245473)
			(xy 259.607936 -45.259461) (xy 259.601089 -45.277177) (xy 259.6007 -45.286676) (xy 259.6007 -45.49521)
			(xy 259.61975 -45.521626) (xy 259.635498 -45.52696) (xy 259.660492 -45.535757) (xy 259.707968 -45.559285)
			(xy 259.751732 -45.589156) (xy 259.790942 -45.624794) (xy 259.824844 -45.665515) (xy 259.852785 -45.710535)
			(xy 259.874229 -45.758988) (xy 259.888763 -45.809942) (xy 259.896106 -45.862417) (xy 259.89661 -45.88891)
			(xy 259.896172 -45.914861) (xy 259.88913 -45.966284) (xy 259.875179 -46.016276) (xy 259.854575 -46.063914)
			(xy 259.8277 -46.108317) (xy 259.79505 -46.148664) (xy 259.776468 -46.166786) (xy 259.775198 -46.168056)
			(xy 259.77469 -46.168564) (xy 259.774436 -46.168818) (xy 259.754655 -46.187166) (xy 259.710857 -46.218673)
			(xy 259.663051 -46.243684) (xy 259.637784 -46.253146) (xy 259.63499 -46.254162) (xy 259.629148 -46.256956)
			(xy 259.620785 -46.261473) (xy 259.607936 -46.275461) (xy 259.601089 -46.293177) (xy 259.6007 -46.302676)
			(xy 259.6007 -47.022766) (xy 259.600937 -47.030796) (xy 259.605853 -47.046083) (xy 259.610352 -47.052738)
			(xy 259.615781 -47.05959) (xy 259.630192 -47.069469) (xy 259.638546 -47.072042) (xy 259.6388 -47.072042)
			(xy 259.665778 -47.079479) (xy 259.717363 -47.10117) (xy 259.765225 -47.130166) (xy 259.808338 -47.165844)
			(xy 259.845775 -47.207437) (xy 259.876733 -47.254054) (xy 259.900548 -47.304694) (xy 259.916709 -47.35827)
			(xy 259.924869 -47.413632) (xy 259.925312 -47.441612) (xy 259.924874 -47.467563) (xy 259.917832 -47.518986)
			(xy 259.90388 -47.568978) (xy 259.883276 -47.616616) (xy 259.856401 -47.661018) (xy 259.823751 -47.701365)
			(xy 259.80517 -47.719488) (xy 259.804662 -47.719996) (xy 259.8039 -47.720758) (xy 259.78042 -47.742505)
			(xy 259.727605 -47.778642) (xy 259.669511 -47.805481) (xy 259.6388 -47.814484) (xy 259.638292 -47.814738)
			(xy 259.637022 -47.815246) (xy 259.626729 -47.818824) (xy 259.610279 -47.833084) (xy 259.60121 -47.852876)
			(xy 259.6007 -47.86376) (xy 259.6007 -48.54321) (xy 259.61975 -48.569626) (xy 259.635498 -48.57496)
			(xy 259.660492 -48.583757) (xy 259.707968 -48.607285) (xy 259.751732 -48.637156) (xy 259.790942 -48.672794)
			(xy 259.824844 -48.713515) (xy 259.852785 -48.758535) (xy 259.874229 -48.806988) (xy 259.888763 -48.857942)
			(xy 259.896106 -48.910417) (xy 259.89661 -48.93691) (xy 259.896172 -48.962861) (xy 259.88913 -49.014284)
			(xy 259.875179 -49.064276) (xy 259.854575 -49.111914) (xy 259.8277 -49.156317) (xy 259.79505 -49.196664)
			(xy 259.776468 -49.214786) (xy 259.775198 -49.216056) (xy 259.77469 -49.216564) (xy 259.774436 -49.216818)
			(xy 259.754655 -49.235166) (xy 259.710857 -49.266673) (xy 259.663051 -49.291684) (xy 259.637784 -49.301146)
			(xy 259.63499 -49.302162) (xy 259.629148 -49.304956) (xy 259.620785 -49.309473) (xy 259.607936 -49.323461)
			(xy 259.601089 -49.341177) (xy 259.6007 -49.350676) (xy 259.6007 -49.55921) (xy 259.61975 -49.585626)
			(xy 259.635498 -49.59096) (xy 259.660492 -49.599757) (xy 259.664917 -49.60195) (xy 260.490982 -49.60195)
			(xy 260.490982 -49.54745) (xy 260.498737 -49.493506) (xy 260.514091 -49.441214) (xy 260.53673 -49.391639)
			(xy 260.566193 -49.345791) (xy 260.601881 -49.304602) (xy 260.643067 -49.268911) (xy 260.688913 -49.239444)
			(xy 260.738486 -49.216801) (xy 260.790777 -49.201444) (xy 260.84472 -49.193684) (xy 260.87197 -49.193196)
			(xy 260.89934 -49.193681) (xy 260.953518 -49.201494) (xy 261.006021 -49.216979) (xy 261.055768 -49.239816)
			(xy 261.101736 -49.269537) (xy 261.122668 -49.287176) (xy 261.12978 -49.293272) (xy 261.146798 -49.299622)
			(xy 261.232142 -49.299622) (xy 261.24916 -49.293272) (xy 261.256272 -49.287176) (xy 261.277205 -49.269535)
			(xy 261.323173 -49.239811) (xy 261.372919 -49.216965) (xy 261.425421 -49.201469) (xy 261.479599 -49.19364)
			(xy 261.534341 -49.19364) (xy 261.588519 -49.201469) (xy 261.641021 -49.216965) (xy 261.690767 -49.239811)
			(xy 261.736735 -49.269535) (xy 261.757668 -49.287176) (xy 261.76478 -49.293272) (xy 261.781798 -49.299622)
			(xy 261.867142 -49.299622) (xy 261.88416 -49.293272) (xy 261.891272 -49.287176) (xy 261.912201 -49.269533)
			(xy 261.958175 -49.239822) (xy 262.007923 -49.216988) (xy 262.060424 -49.201497) (xy 262.114601 -49.19367)
			(xy 262.14197 -49.193196) (xy 262.168287 -49.193624) (xy 262.220422 -49.200849) (xy 262.271071 -49.215167)
			(xy 262.319272 -49.236307) (xy 262.364114 -49.263866) (xy 262.404745 -49.297324) (xy 262.422894 -49.316386)
			(xy 262.430418 -49.323785) (xy 262.449696 -49.332311) (xy 262.460232 -49.332896) (xy 262.534908 -49.332896)
			(xy 262.54546 -49.332386) (xy 262.564755 -49.323838) (xy 262.572246 -49.316386) (xy 262.590355 -49.297282)
			(xy 262.630982 -49.263806) (xy 262.675828 -49.23624) (xy 262.72404 -49.215105) (xy 262.774702 -49.200806)
			(xy 262.826849 -49.193614) (xy 262.85317 -49.193196) (xy 262.880425 -49.193649) (xy 262.934379 -49.201403)
			(xy 262.986681 -49.216756) (xy 263.036266 -49.239398) (xy 263.082123 -49.268865) (xy 263.12332 -49.304559)
			(xy 263.159017 -49.345753) (xy 263.188488 -49.391608) (xy 263.211133 -49.441191) (xy 263.226491 -49.493491)
			(xy 263.234249 -49.547446) (xy 263.234249 -49.601954) (xy 263.226491 -49.655909) (xy 263.211133 -49.708209)
			(xy 263.188488 -49.757792) (xy 263.159017 -49.803647) (xy 263.12332 -49.844841) (xy 263.082123 -49.880535)
			(xy 263.036266 -49.910002) (xy 262.986681 -49.932644) (xy 262.934379 -49.947997) (xy 262.880425 -49.955751)
			(xy 262.85317 -49.956212) (xy 262.826854 -49.955755) (xy 262.77472 -49.948535) (xy 262.724073 -49.934223)
			(xy 262.675871 -49.913089) (xy 262.631029 -49.885534) (xy 262.590396 -49.852082) (xy 262.572246 -49.833022)
			(xy 262.564743 -49.825598) (xy 262.545449 -49.817086) (xy 262.534908 -49.816512) (xy 262.460232 -49.816512)
			(xy 262.449682 -49.817041) (xy 262.430387 -49.825576) (xy 262.422894 -49.833022) (xy 262.404747 -49.852089)
			(xy 262.364131 -49.885572) (xy 262.319294 -49.913146) (xy 262.271088 -49.934287) (xy 262.220432 -49.948593)
			(xy 262.168289 -49.955792) (xy 262.14197 -49.956212) (xy 262.114599 -49.955761) (xy 262.06042 -49.947939)
			(xy 262.007917 -49.932446) (xy 261.95817 -49.909601) (xy 261.912204 -49.879874) (xy 261.891272 -49.862232)
			(xy 261.88416 -49.856136) (xy 261.867142 -49.849786) (xy 261.781798 -49.849786) (xy 261.76478 -49.856136)
			(xy 261.757668 -49.862232) (xy 261.736735 -49.879873) (xy 261.690767 -49.909597) (xy 261.641021 -49.932443)
			(xy 261.588519 -49.947939) (xy 261.534341 -49.955768) (xy 261.479599 -49.955768) (xy 261.425421 -49.947939)
			(xy 261.372919 -49.932443) (xy 261.323173 -49.909597) (xy 261.277205 -49.879873) (xy 261.256272 -49.862232)
			(xy 261.24916 -49.856136) (xy 261.232142 -49.849786) (xy 261.146798 -49.849786) (xy 261.12978 -49.856136)
			(xy 261.122668 -49.862232) (xy 261.101725 -49.879858) (xy 261.055755 -49.90957) (xy 261.00601 -49.932408)
			(xy 260.953512 -49.947903) (xy 260.899338 -49.955735) (xy 260.87197 -49.956212) (xy 260.84472 -49.955716)
			(xy 260.790777 -49.947956) (xy 260.738486 -49.932599) (xy 260.688913 -49.909956) (xy 260.643067 -49.880489)
			(xy 260.601881 -49.844798) (xy 260.566193 -49.803609) (xy 260.53673 -49.757761) (xy 260.514091 -49.708186)
			(xy 260.498737 -49.655894) (xy 260.490982 -49.60195) (xy 259.664917 -49.60195) (xy 259.707968 -49.623285)
			(xy 259.751732 -49.653156) (xy 259.790942 -49.688794) (xy 259.824844 -49.729515) (xy 259.852785 -49.774535)
			(xy 259.874229 -49.822988) (xy 259.888763 -49.873942) (xy 259.896106 -49.926417) (xy 259.89661 -49.95291)
			(xy 259.896172 -49.978861) (xy 259.88913 -50.030284) (xy 259.875179 -50.080276) (xy 259.854575 -50.127914)
			(xy 259.8277 -50.172317) (xy 259.79505 -50.212664) (xy 259.776468 -50.230786) (xy 259.775198 -50.232056)
			(xy 259.77469 -50.232564) (xy 259.774436 -50.232818) (xy 259.754655 -50.251166) (xy 259.710857 -50.282673)
			(xy 259.663051 -50.307684) (xy 259.637784 -50.317146) (xy 259.63499 -50.318162) (xy 259.629148 -50.320956)
			(xy 259.620785 -50.325473) (xy 259.607936 -50.339461) (xy 259.601089 -50.357177) (xy 259.6007 -50.366676)
			(xy 259.6007 -50.62347) (xy 259.620258 -50.65014) (xy 259.636514 -50.65522) (xy 259.662071 -50.663658)
			(xy 259.710701 -50.686713) (xy 259.75561 -50.716372) (xy 259.795906 -50.752047) (xy 259.830791 -50.793029)
			(xy 259.859571 -50.838506) (xy 259.881677 -50.887576) (xy 259.896669 -50.939264) (xy 259.904251 -50.992547)
			(xy 259.904738 -51.019456) (xy 259.904302 -51.04544) (xy 259.897252 -51.096926) (xy 259.883278 -51.146979)
			(xy 259.862638 -51.194672) (xy 259.835713 -51.23912) (xy 259.803004 -51.279501) (xy 259.784342 -51.297586)
			(xy 259.783834 -51.298094) (xy 259.762587 -51.317949) (xy 259.715196 -51.351647) (xy 259.663244 -51.37777)
			(xy 259.635752 -51.387248) (xy 259.628132 -51.389788) (xy 259.615178 -51.398932) (xy 259.610606 -51.405536)
			(xy 259.606049 -51.412176) (xy 259.601001 -51.42746) (xy 259.6007 -51.435508) (xy 259.6007 -51.615086)
			(xy 259.601175 -51.625327) (xy 259.609181 -51.644181) (xy 259.616194 -51.651662) (xy 259.63626 -51.670966)
			(xy 259.646928 -51.674522) (xy 259.671674 -51.683466) (xy 259.682728 -51.689052) (xy 260.455377 -51.689052)
			(xy 260.455377 -51.634548) (xy 260.463134 -51.5806) (xy 260.47849 -51.528304) (xy 260.501132 -51.478726)
			(xy 260.530599 -51.432875) (xy 260.566292 -51.391684) (xy 260.607483 -51.355993) (xy 260.653335 -51.326527)
			(xy 260.702913 -51.303886) (xy 260.755209 -51.288532) (xy 260.809158 -51.280777) (xy 260.83641 -51.280314)
			(xy 260.863781 -51.280771) (xy 260.91796 -51.28859) (xy 260.970464 -51.304081) (xy 261.02021 -51.326925)
			(xy 261.066177 -51.356652) (xy 261.087108 -51.374294) (xy 261.09422 -51.38039) (xy 261.111238 -51.38674)
			(xy 261.196582 -51.38674) (xy 261.2136 -51.38039) (xy 261.220712 -51.374294) (xy 261.241666 -51.356682)
			(xy 261.287633 -51.326966) (xy 261.337375 -51.304125) (xy 261.389871 -51.288628) (xy 261.444042 -51.280792)
			(xy 261.47141 -51.280314) (xy 261.489753 -51.280541) (xy 261.526266 -51.284108) (xy 261.544308 -51.287426)
			(xy 261.55523 -51.289458) (xy 261.575804 -51.284632) (xy 261.653782 -51.225704) (xy 261.664196 -51.206908)
			(xy 261.664958 -51.195986) (xy 261.667845 -51.167701) (xy 261.680883 -51.112363) (xy 261.701981 -51.059569)
			(xy 261.730672 -51.010486) (xy 261.766321 -50.966199) (xy 261.786878 -50.946558) (xy 261.794297 -50.939051)
			(xy 261.802812 -50.91976) (xy 261.803388 -50.90922) (xy 261.803388 -50.834544) (xy 261.802852 -50.823995)
			(xy 261.794322 -50.804699) (xy 261.786878 -50.797206) (xy 261.767816 -50.779053) (xy 261.734334 -50.738438)
			(xy 261.706759 -50.693602) (xy 261.685617 -50.645398) (xy 261.671309 -50.594743) (xy 261.664109 -50.542601)
			(xy 261.663688 -50.516282) (xy 261.664174 -50.489031) (xy 261.67193 -50.435083) (xy 261.687285 -50.382788)
			(xy 261.709927 -50.333211) (xy 261.739393 -50.287361) (xy 261.775084 -50.24617) (xy 261.816275 -50.210479)
			(xy 261.862125 -50.181013) (xy 261.911702 -50.158371) (xy 261.963997 -50.143016) (xy 262.017945 -50.13526)
			(xy 262.072447 -50.13526) (xy 262.126395 -50.143016) (xy 262.17869 -50.158371) (xy 262.228267 -50.181013)
			(xy 262.274117 -50.210479) (xy 262.315308 -50.24617) (xy 262.350999 -50.287361) (xy 262.380465 -50.333211)
			(xy 262.403107 -50.382788) (xy 262.418462 -50.435083) (xy 262.426218 -50.489031) (xy 262.426704 -50.516282)
			(xy 262.426284 -50.542599) (xy 262.419057 -50.594735) (xy 262.404737 -50.645383) (xy 262.383597 -50.693585)
			(xy 262.356036 -50.738426) (xy 262.322577 -50.779057) (xy 262.303514 -50.797206) (xy 262.29611 -50.804725)
			(xy 262.287586 -50.824007) (xy 262.287004 -50.834544) (xy 262.287004 -50.90922) (xy 262.287562 -50.919766)
			(xy 262.296077 -50.939062) (xy 262.303514 -50.946558) (xy 262.322576 -50.96471) (xy 262.356055 -51.005327)
			(xy 262.383627 -51.050164) (xy 262.404769 -51.098368) (xy 262.419077 -51.149022) (xy 262.42628 -51.201164)
			(xy 262.426704 -51.227482) (xy 262.426228 -51.254735) (xy 262.418473 -51.308685) (xy 262.403119 -51.360983)
			(xy 262.380479 -51.410563) (xy 262.351012 -51.456417) (xy 262.31532 -51.49761) (xy 262.274128 -51.533304)
			(xy 262.228276 -51.562772) (xy 262.178696 -51.585414) (xy 262.126399 -51.60077) (xy 262.072449 -51.608527)
			(xy 262.045196 -51.60899) (xy 262.026853 -51.608762) (xy 261.99034 -51.605196) (xy 261.972298 -51.601878)
			(xy 261.961376 -51.599846) (xy 261.940802 -51.604672) (xy 261.862824 -51.6636) (xy 261.85241 -51.682396)
			(xy 261.851648 -51.693318) (xy 261.84876 -51.721577) (xy 261.835727 -51.776863) (xy 261.814642 -51.829606)
			(xy 261.78597 -51.87864) (xy 261.750345 -51.922881) (xy 261.708555 -51.961352) (xy 261.661523 -51.993202)
			(xy 261.610288 -52.017727) (xy 261.555984 -52.034384) (xy 261.499811 -52.042807) (xy 261.47141 -52.04333)
			(xy 261.444039 -52.042875) (xy 261.389859 -52.035057) (xy 261.337355 -52.019566) (xy 261.287608 -51.996722)
			(xy 261.241643 -51.966993) (xy 261.220712 -51.94935) (xy 261.2136 -51.943254) (xy 261.196582 -51.936904)
			(xy 261.111238 -51.936904) (xy 261.09422 -51.943254) (xy 261.087108 -51.94935) (xy 261.066177 -51.966991)
			(xy 261.020205 -51.996704) (xy 260.970457 -52.019541) (xy 260.917956 -52.035031) (xy 260.863779 -52.042857)
			(xy 260.83641 -52.04333) (xy 260.809158 -52.042823) (xy 260.755209 -52.035068) (xy 260.702913 -52.019714)
			(xy 260.653335 -51.997073) (xy 260.607483 -51.967607) (xy 260.566292 -51.931916) (xy 260.530599 -51.890725)
			(xy 260.501132 -51.844874) (xy 260.47849 -51.795296) (xy 260.463134 -51.743) (xy 260.455377 -51.689052)
			(xy 259.682728 -51.689052) (xy 259.718636 -51.707198) (xy 259.761891 -51.73716) (xy 259.800617 -51.772783)
			(xy 259.83408 -51.81339) (xy 259.861644 -51.858211) (xy 259.882786 -51.906394) (xy 259.897105 -51.957027)
			(xy 259.904329 -52.009147) (xy 259.904738 -52.035456) (xy 259.904302 -52.06144) (xy 259.897252 -52.112926)
			(xy 259.883278 -52.162979) (xy 259.862638 -52.210672) (xy 259.835713 -52.25512) (xy 259.803004 -52.295501)
			(xy 259.784342 -52.313586) (xy 259.783834 -52.314094) (xy 259.779516 -52.318158) (xy 259.772357 -52.325633)
			(xy 259.764232 -52.344647) (xy 259.763768 -52.354988) (xy 259.763768 -52.564153) (xy 262.02713 -52.564153)
			(xy 262.02713 -52.509647) (xy 262.034886 -52.455696) (xy 262.050241 -52.403398) (xy 262.072883 -52.353817)
			(xy 262.102349 -52.307962) (xy 262.138041 -52.266768) (xy 262.179232 -52.231072) (xy 262.225083 -52.201601)
			(xy 262.274662 -52.178955) (xy 262.326959 -52.163594) (xy 262.380909 -52.155832) (xy 262.408162 -52.155344)
			(xy 262.435532 -52.155822) (xy 262.489711 -52.163635) (xy 262.542214 -52.179121) (xy 262.591961 -52.20196)
			(xy 262.637928 -52.231683) (xy 262.65886 -52.249324) (xy 262.665972 -52.25542) (xy 262.68299 -52.26177)
			(xy 262.768334 -52.26177) (xy 262.785352 -52.25542) (xy 262.792464 -52.249324) (xy 262.813402 -52.231692)
			(xy 262.859373 -52.201978) (xy 262.909119 -52.179141) (xy 262.961618 -52.163648) (xy 263.015793 -52.155819)
			(xy 263.043162 -52.155344) (xy 263.070413 -52.155901) (xy 263.124361 -52.163652) (xy 263.176657 -52.179003)
			(xy 263.226236 -52.201641) (xy 263.272088 -52.231104) (xy 263.31328 -52.266793) (xy 263.348973 -52.307981)
			(xy 263.378441 -52.353831) (xy 263.401084 -52.403407) (xy 263.41644 -52.455701) (xy 263.424197 -52.509649)
			(xy 263.424197 -52.564151) (xy 263.41644 -52.618099) (xy 263.401084 -52.670393) (xy 263.378441 -52.719969)
			(xy 263.348973 -52.765819) (xy 263.31328 -52.807007) (xy 263.272088 -52.842696) (xy 263.226236 -52.872159)
			(xy 263.176657 -52.894797) (xy 263.124361 -52.910148) (xy 263.070413 -52.917899) (xy 263.043162 -52.91836)
			(xy 263.015793 -52.917867) (xy 262.961614 -52.910057) (xy 262.909111 -52.894575) (xy 262.859364 -52.871739)
			(xy 262.813396 -52.842019) (xy 262.792464 -52.82438) (xy 262.785352 -52.818284) (xy 262.768334 -52.811934)
			(xy 262.68299 -52.811934) (xy 262.665972 -52.818284) (xy 262.65886 -52.82438) (xy 262.637914 -52.842001)
			(xy 262.591945 -52.871717) (xy 262.542201 -52.894556) (xy 262.489704 -52.910051) (xy 262.43553 -52.917884)
			(xy 262.408162 -52.91836) (xy 262.380909 -52.917968) (xy 262.326959 -52.910206) (xy 262.274662 -52.894845)
			(xy 262.225083 -52.872199) (xy 262.179232 -52.842728) (xy 262.138041 -52.807032) (xy 262.102349 -52.765838)
			(xy 262.072883 -52.719983) (xy 262.050241 -52.670402) (xy 262.034886 -52.618104) (xy 262.02713 -52.564153)
			(xy 259.763768 -52.564153) (xy 259.763768 -52.731924) (xy 259.764169 -52.742557) (xy 259.772727 -52.762018)
			(xy 259.780278 -52.769516) (xy 259.79952 -52.787668) (xy 259.833312 -52.828366) (xy 259.861157 -52.873342)
			(xy 259.882519 -52.921735) (xy 259.89699 -52.972615) (xy 259.904292 -53.025007) (xy 259.904738 -53.051456)
			(xy 259.904302 -53.07744) (xy 259.897252 -53.128926) (xy 259.883278 -53.178979) (xy 259.862638 -53.226672)
			(xy 259.835713 -53.27112) (xy 259.803004 -53.311501) (xy 259.784342 -53.329586) (xy 259.783834 -53.330094)
			(xy 259.779516 -53.334158) (xy 259.772357 -53.341633) (xy 259.764232 -53.360647) (xy 259.763768 -53.370988)
			(xy 259.763768 -53.747924) (xy 259.764169 -53.758557) (xy 259.772727 -53.778018) (xy 259.780278 -53.785516)
			(xy 259.79952 -53.803668) (xy 259.833312 -53.844366) (xy 259.861157 -53.889342) (xy 259.882519 -53.937735)
			(xy 259.89699 -53.988615) (xy 259.904292 -54.041007) (xy 259.904738 -54.067456) (xy 259.904302 -54.09344)
			(xy 259.897252 -54.144926) (xy 259.883278 -54.194979) (xy 259.864268 -54.238906) (xy 266.585952 -54.238906)
			(xy 266.590023 -54.183284) (xy 266.602149 -54.128847) (xy 266.622072 -54.076756) (xy 266.649368 -54.028121)
			(xy 266.683454 -53.983978) (xy 266.723603 -53.945269) (xy 266.768961 -53.912818) (xy 266.818561 -53.887317)
			(xy 266.871345 -53.86931) (xy 266.926188 -53.85918) (xy 266.981922 -53.857143) (xy 267.037359 -53.863243)
			(xy 267.091316 -53.877349) (xy 267.142645 -53.899161) (xy 267.190251 -53.928215) (xy 267.233119 -53.96389)
			(xy 267.270336 -54.005427) (xy 267.301109 -54.05194) (xy 267.324781 -54.102437) (xy 267.340849 -54.155844)
			(xy 267.348969 -54.21102) (xy 267.349478 -54.238906) (xy 267.348969 -54.266792) (xy 267.340849 -54.321968)
			(xy 267.324781 -54.375375) (xy 267.301109 -54.425872) (xy 267.270336 -54.472385) (xy 267.233119 -54.513922)
			(xy 267.190251 -54.549597) (xy 267.142645 -54.578651) (xy 267.091316 -54.600463) (xy 267.037359 -54.614569)
			(xy 266.981922 -54.620669) (xy 266.926188 -54.618632) (xy 266.871345 -54.608502) (xy 266.818561 -54.590495)
			(xy 266.768961 -54.564994) (xy 266.723603 -54.532543) (xy 266.683454 -54.493834) (xy 266.649368 -54.449691)
			(xy 266.622072 -54.401056) (xy 266.602149 -54.348965) (xy 266.590023 -54.294528) (xy 266.585952 -54.238906)
			(xy 259.864268 -54.238906) (xy 259.862638 -54.242672) (xy 259.835713 -54.28712) (xy 259.803004 -54.327501)
			(xy 259.784342 -54.345586) (xy 259.783834 -54.346094) (xy 259.779516 -54.350158) (xy 259.772357 -54.357633)
			(xy 259.764232 -54.376647) (xy 259.763768 -54.386988) (xy 259.763768 -54.763924) (xy 259.764169 -54.774557)
			(xy 259.772727 -54.794018) (xy 259.780278 -54.801516) (xy 259.79952 -54.819668) (xy 259.833312 -54.860366)
			(xy 259.861157 -54.905342) (xy 259.882519 -54.953735) (xy 259.892563 -54.989051) (xy 262.101068 -54.989051)
			(xy 262.101068 -54.934549) (xy 262.108824 -54.880602) (xy 262.124178 -54.828308) (xy 262.146818 -54.778731)
			(xy 262.176283 -54.732881) (xy 262.211973 -54.69169) (xy 262.253161 -54.655997) (xy 262.29901 -54.62653)
			(xy 262.348585 -54.603887) (xy 262.400879 -54.588529) (xy 262.454825 -54.580769) (xy 262.482076 -54.580282)
			(xy 262.510167 -54.580796) (xy 262.565743 -54.58902) (xy 262.619512 -54.605307) (xy 262.670309 -54.629307)
			(xy 262.717036 -54.660499) (xy 262.758682 -54.698208) (xy 262.794345 -54.741619) (xy 262.809228 -54.765448)
			(xy 262.814562 -54.774592) (xy 262.83158 -54.786784) (xy 262.924798 -54.80685) (xy 262.945372 -54.802786)
			(xy 262.954008 -54.79669) (xy 262.978068 -54.780683) (xy 263.030001 -54.755342) (xy 263.08516 -54.738119)
			(xy 263.142285 -54.729406) (xy 263.171178 -54.728872) (xy 263.198429 -54.729376) (xy 263.252378 -54.737129)
			(xy 263.304674 -54.752481) (xy 263.354252 -54.77512) (xy 263.400105 -54.804584) (xy 263.441297 -54.840273)
			(xy 263.476991 -54.881462) (xy 263.50646 -54.927311) (xy 263.529104 -54.976887) (xy 263.544462 -55.029181)
			(xy 263.552221 -55.083129) (xy 263.552686 -55.11038) (xy 263.552212 -55.13775) (xy 263.544396 -55.191929)
			(xy 263.528909 -55.244432) (xy 263.506069 -55.294179) (xy 263.476346 -55.340146) (xy 263.458706 -55.361078)
			(xy 263.45261 -55.36819) (xy 263.44626 -55.385208) (xy 263.44626 -55.470552) (xy 263.45261 -55.48757)
			(xy 263.458706 -55.494682) (xy 263.476326 -55.515631) (xy 263.506049 -55.561597) (xy 263.528893 -55.611341)
			(xy 263.54439 -55.66384) (xy 263.552219 -55.718016) (xy 263.552222 -55.772754) (xy 263.544396 -55.826931)
			(xy 263.528904 -55.879431) (xy 263.506063 -55.929177) (xy 263.476344 -55.975145) (xy 263.458706 -55.996078)
			(xy 263.45261 -56.00319) (xy 263.44626 -56.020208) (xy 263.44626 -56.105552) (xy 263.45261 -56.12257)
			(xy 263.458706 -56.129682) (xy 263.476351 -56.150609) (xy 263.506062 -56.196583) (xy 263.528896 -56.246332)
			(xy 263.544386 -56.298834) (xy 263.552213 -56.353011) (xy 263.552686 -56.38038) (xy 263.5522 -56.407631)
			(xy 263.544444 -56.461579) (xy 263.529089 -56.513874) (xy 263.506447 -56.563451) (xy 263.476981 -56.609301)
			(xy 263.44129 -56.650492) (xy 263.400099 -56.686183) (xy 263.354249 -56.715649) (xy 263.304672 -56.738291)
			(xy 263.252377 -56.753646) (xy 263.198429 -56.761402) (xy 263.143927 -56.761402) (xy 263.089979 -56.753646)
			(xy 263.037684 -56.738291) (xy 262.988107 -56.715649) (xy 262.942257 -56.686183) (xy 262.901066 -56.650492)
			(xy 262.865375 -56.609301) (xy 262.835909 -56.563451) (xy 262.813267 -56.513874) (xy 262.797912 -56.461579)
			(xy 262.790156 -56.407631) (xy 262.78967 -56.38038) (xy 262.790107 -56.353009) (xy 262.797929 -56.298828)
			(xy 262.813424 -56.246323) (xy 262.836273 -56.196577) (xy 262.866005 -56.150612) (xy 262.88365 -56.129682)
			(xy 262.889746 -56.12257) (xy 262.896096 -56.105552) (xy 262.896096 -56.020208) (xy 262.889746 -56.00319)
			(xy 262.88365 -55.996078) (xy 262.865989 -55.975162) (xy 262.836263 -55.929192) (xy 262.813417 -55.879443)
			(xy 262.797922 -55.826938) (xy 262.790094 -55.772757) (xy 262.790097 -55.718013) (xy 262.797928 -55.663833)
			(xy 262.813428 -55.611329) (xy 262.836278 -55.561582) (xy 262.866007 -55.515614) (xy 262.88365 -55.494682)
			(xy 262.889746 -55.48757) (xy 262.896096 -55.470552) (xy 262.896096 -55.385208) (xy 262.889746 -55.36819)
			(xy 262.88365 -55.361078) (xy 262.872695 -55.348285) (xy 262.852857 -55.321064) (xy 262.844026 -55.306722)
			(xy 262.838692 -55.297578) (xy 262.821674 -55.285386) (xy 262.728456 -55.26532) (xy 262.707882 -55.269384)
			(xy 262.699246 -55.27548) (xy 262.67517 -55.29146) (xy 262.623243 -55.316808) (xy 262.568089 -55.334039)
			(xy 262.510967 -55.34276) (xy 262.482076 -55.343298) (xy 262.454825 -55.342831) (xy 262.400879 -55.335071)
			(xy 262.348585 -55.319713) (xy 262.29901 -55.29707) (xy 262.253161 -55.267603) (xy 262.211973 -55.23191)
			(xy 262.176283 -55.190719) (xy 262.146818 -55.144869) (xy 262.124178 -55.095292) (xy 262.108824 -55.042998)
			(xy 262.101068 -54.989051) (xy 259.892563 -54.989051) (xy 259.89699 -55.004615) (xy 259.904292 -55.057007)
			(xy 259.904738 -55.083456) (xy 259.904302 -55.10944) (xy 259.897252 -55.160926) (xy 259.883278 -55.210979)
			(xy 259.862638 -55.258672) (xy 259.835713 -55.30312) (xy 259.803004 -55.343501) (xy 259.784342 -55.361586)
			(xy 259.783834 -55.362094) (xy 259.779516 -55.366158) (xy 259.772357 -55.373633) (xy 259.764232 -55.392647)
			(xy 259.763768 -55.402988) (xy 259.763768 -55.420851) (xy 260.424668 -55.420851) (xy 260.424668 -55.366349)
			(xy 260.432424 -55.312402) (xy 260.447778 -55.260108) (xy 260.470418 -55.210531) (xy 260.499883 -55.164681)
			(xy 260.535573 -55.12349) (xy 260.576761 -55.087797) (xy 260.62261 -55.05833) (xy 260.672185 -55.035687)
			(xy 260.724479 -55.020329) (xy 260.778425 -55.012569) (xy 260.805676 -55.012082) (xy 260.831993 -55.01251)
			(xy 260.884128 -55.019736) (xy 260.934776 -55.034055) (xy 260.982978 -55.055194) (xy 261.027819 -55.082753)
			(xy 261.06845 -55.11621) (xy 261.0866 -55.135272) (xy 261.094123 -55.142672) (xy 261.113402 -55.151198)
			(xy 261.123938 -55.151782) (xy 261.198614 -55.151782) (xy 261.209167 -55.151279) (xy 261.228462 -55.142726)
			(xy 261.235952 -55.135272) (xy 261.254075 -55.116181) (xy 261.294697 -55.082701) (xy 261.339539 -55.055131)
			(xy 261.387749 -55.033994) (xy 261.438409 -55.019692) (xy 261.490556 -55.012499) (xy 261.516876 -55.012082)
			(xy 261.544129 -55.012564) (xy 261.598081 -55.020318) (xy 261.650381 -55.035671) (xy 261.699963 -55.058312)
			(xy 261.745817 -55.087778) (xy 261.787012 -55.123471) (xy 261.822707 -55.164663) (xy 261.852177 -55.210516)
			(xy 261.87482 -55.260097) (xy 261.890177 -55.312395) (xy 261.897935 -55.366347) (xy 261.897935 -55.420853)
			(xy 261.890177 -55.474805) (xy 261.87482 -55.527103) (xy 261.852177 -55.576684) (xy 261.822707 -55.622537)
			(xy 261.787012 -55.663729) (xy 261.745817 -55.699422) (xy 261.699963 -55.728888) (xy 261.650381 -55.751529)
			(xy 261.598081 -55.766882) (xy 261.544129 -55.774636) (xy 261.516876 -55.775098) (xy 261.49056 -55.774641)
			(xy 261.438426 -55.767422) (xy 261.387778 -55.75311) (xy 261.339576 -55.731976) (xy 261.294734 -55.704421)
			(xy 261.254102 -55.670968) (xy 261.235952 -55.651908) (xy 261.228449 -55.644484) (xy 261.209155 -55.635972)
			(xy 261.198614 -55.635398) (xy 261.123938 -55.635398) (xy 261.113389 -55.635935) (xy 261.094094 -55.644465)
			(xy 261.0866 -55.651908) (xy 261.068467 -55.670989) (xy 261.027846 -55.704466) (xy 260.983005 -55.732037)
			(xy 260.934797 -55.753175) (xy 260.88414 -55.767479) (xy 260.831996 -55.774677) (xy 260.805676 -55.775098)
			(xy 260.778425 -55.774631) (xy 260.724479 -55.766871) (xy 260.672185 -55.751513) (xy 260.62261 -55.72887)
			(xy 260.576761 -55.699403) (xy 260.535573 -55.66371) (xy 260.499883 -55.622519) (xy 260.470418 -55.576669)
			(xy 260.447778 -55.527092) (xy 260.432424 -55.474798) (xy 260.424668 -55.420851) (xy 259.763768 -55.420851)
			(xy 259.763768 -56.033924) (xy 259.764169 -56.044557) (xy 259.772727 -56.064018) (xy 259.780278 -56.071516)
			(xy 259.79952 -56.089668) (xy 259.833312 -56.130366) (xy 259.861157 -56.175342) (xy 259.882519 -56.223735)
			(xy 259.89699 -56.274615) (xy 259.904292 -56.327007) (xy 259.904738 -56.353456) (xy 259.904302 -56.37944)
			(xy 259.897252 -56.430926) (xy 259.883278 -56.480979) (xy 259.862638 -56.528672) (xy 259.835713 -56.57312)
			(xy 259.803004 -56.613501) (xy 259.784342 -56.631586) (xy 259.783834 -56.632094) (xy 259.779516 -56.636158)
			(xy 259.772357 -56.643633) (xy 259.764232 -56.662647) (xy 259.763768 -56.672988) (xy 259.763768 -57.48528)
			(xy 262.805924 -57.48528) (xy 262.809995 -57.429658) (xy 262.822121 -57.375221) (xy 262.842044 -57.32313)
			(xy 262.86934 -57.274495) (xy 262.903426 -57.230352) (xy 262.943575 -57.191643) (xy 262.988933 -57.159192)
			(xy 263.038533 -57.133691) (xy 263.091317 -57.115684) (xy 263.14616 -57.105554) (xy 263.201894 -57.103517)
			(xy 263.257331 -57.109617) (xy 263.311288 -57.123723) (xy 263.362617 -57.145535) (xy 263.410223 -57.174589)
			(xy 263.453091 -57.210264) (xy 263.490308 -57.251801) (xy 263.521081 -57.298314) (xy 263.544753 -57.348811)
			(xy 263.560821 -57.402218) (xy 263.568941 -57.457394) (xy 263.56945 -57.48528) (xy 263.568941 -57.513166)
			(xy 263.560821 -57.568342) (xy 263.544753 -57.621749) (xy 263.521081 -57.672246) (xy 263.490308 -57.718759)
			(xy 263.453091 -57.760296) (xy 263.410223 -57.795971) (xy 263.362617 -57.825025) (xy 263.311288 -57.846837)
			(xy 263.257331 -57.860943) (xy 263.201894 -57.867043) (xy 263.14616 -57.865006) (xy 263.091317 -57.854876)
			(xy 263.038533 -57.836869) (xy 262.988933 -57.811368) (xy 262.943575 -57.778917) (xy 262.903426 -57.740208)
			(xy 262.86934 -57.696065) (xy 262.842044 -57.64743) (xy 262.822121 -57.595339) (xy 262.809995 -57.540902)
			(xy 262.805924 -57.48528) (xy 259.763768 -57.48528) (xy 259.763768 -58.076084) (xy 263.558018 -58.076084)
			(xy 263.562089 -58.020462) (xy 263.574215 -57.966025) (xy 263.594138 -57.913934) (xy 263.621434 -57.865299)
			(xy 263.65552 -57.821156) (xy 263.695669 -57.782447) (xy 263.741027 -57.749996) (xy 263.790627 -57.724495)
			(xy 263.843411 -57.706488) (xy 263.898254 -57.696358) (xy 263.953988 -57.694321) (xy 264.009425 -57.700421)
			(xy 264.063382 -57.714527) (xy 264.114711 -57.736339) (xy 264.162317 -57.765393) (xy 264.205185 -57.801068)
			(xy 264.242402 -57.842605) (xy 264.258738 -57.867296) (xy 265.842748 -57.867296) (xy 265.846821 -57.811637)
			(xy 265.858956 -57.757164) (xy 265.878892 -57.705038) (xy 265.906206 -57.65637) (xy 265.940314 -57.612198)
			(xy 265.980491 -57.573463) (xy 266.025879 -57.540991) (xy 266.075511 -57.515473) (xy 266.128331 -57.497454)
			(xy 266.18321 -57.487317) (xy 266.238981 -57.485279) (xy 266.294455 -57.491382) (xy 266.348448 -57.505498)
			(xy 266.399811 -57.527325) (xy 266.447449 -57.556398) (xy 266.490345 -57.592097) (xy 266.527587 -57.633661)
			(xy 266.558381 -57.680205) (xy 266.582069 -57.730736) (xy 266.598147 -57.784178) (xy 266.606273 -57.839392)
			(xy 266.606782 -57.867296) (xy 266.606273 -57.8952) (xy 266.598147 -57.950414) (xy 266.582069 -58.003856)
			(xy 266.558381 -58.054387) (xy 266.527587 -58.100931) (xy 266.490345 -58.142495) (xy 266.447449 -58.178194)
			(xy 266.399811 -58.207267) (xy 266.348448 -58.229094) (xy 266.294455 -58.24321) (xy 266.238981 -58.249313)
			(xy 266.18321 -58.247275) (xy 266.128331 -58.237138) (xy 266.075511 -58.219119) (xy 266.025879 -58.193601)
			(xy 265.980491 -58.161129) (xy 265.940314 -58.122394) (xy 265.906206 -58.078222) (xy 265.878892 -58.029554)
			(xy 265.858956 -57.977428) (xy 265.846821 -57.922955) (xy 265.842748 -57.867296) (xy 264.258738 -57.867296)
			(xy 264.273175 -57.889118) (xy 264.296847 -57.939615) (xy 264.312915 -57.993022) (xy 264.321035 -58.048198)
			(xy 264.321544 -58.076084) (xy 264.321035 -58.10397) (xy 264.312915 -58.159146) (xy 264.296847 -58.212553)
			(xy 264.273175 -58.26305) (xy 264.242402 -58.309563) (xy 264.205185 -58.3511) (xy 264.162317 -58.386775)
			(xy 264.114711 -58.415829) (xy 264.063382 -58.437641) (xy 264.009425 -58.451747) (xy 263.953988 -58.457847)
			(xy 263.898254 -58.45581) (xy 263.843411 -58.44568) (xy 263.790627 -58.427673) (xy 263.741027 -58.402172)
			(xy 263.695669 -58.369721) (xy 263.65552 -58.331012) (xy 263.621434 -58.286869) (xy 263.594138 -58.238234)
			(xy 263.574215 -58.186143) (xy 263.562089 -58.131706) (xy 263.558018 -58.076084) (xy 259.763768 -58.076084)
			(xy 259.763768 -58.561224) (xy 264.762232 -58.561224) (xy 264.766303 -58.505602) (xy 264.778429 -58.451165)
			(xy 264.798352 -58.399074) (xy 264.825648 -58.350439) (xy 264.859734 -58.306296) (xy 264.899883 -58.267587)
			(xy 264.945241 -58.235136) (xy 264.994841 -58.209635) (xy 265.047625 -58.191628) (xy 265.102468 -58.181498)
			(xy 265.158202 -58.179461) (xy 265.213639 -58.185561) (xy 265.267596 -58.199667) (xy 265.318925 -58.221479)
			(xy 265.366531 -58.250533) (xy 265.409399 -58.286208) (xy 265.446616 -58.327745) (xy 265.477389 -58.374258)
			(xy 265.501061 -58.424755) (xy 265.508571 -58.449718) (xy 267.008862 -58.449718) (xy 267.012933 -58.394096)
			(xy 267.025059 -58.339659) (xy 267.044982 -58.287568) (xy 267.072278 -58.238933) (xy 267.106364 -58.19479)
			(xy 267.146513 -58.156081) (xy 267.191871 -58.12363) (xy 267.241471 -58.098129) (xy 267.294255 -58.080122)
			(xy 267.349098 -58.069992) (xy 267.404832 -58.067955) (xy 267.460269 -58.074055) (xy 267.514226 -58.088161)
			(xy 267.565555 -58.109973) (xy 267.613161 -58.139027) (xy 267.656029 -58.174702) (xy 267.693246 -58.216239)
			(xy 267.724019 -58.262752) (xy 267.747691 -58.313249) (xy 267.763759 -58.366656) (xy 267.771879 -58.421832)
			(xy 267.772388 -58.449718) (xy 267.771879 -58.477604) (xy 267.763759 -58.53278) (xy 267.747691 -58.586187)
			(xy 267.724019 -58.636684) (xy 267.693246 -58.683197) (xy 267.656029 -58.724734) (xy 267.613161 -58.760409)
			(xy 267.565555 -58.789463) (xy 267.514226 -58.811275) (xy 267.460269 -58.825381) (xy 267.404832 -58.831481)
			(xy 267.349098 -58.829444) (xy 267.294255 -58.819314) (xy 267.241471 -58.801307) (xy 267.191871 -58.775806)
			(xy 267.146513 -58.743355) (xy 267.106364 -58.704646) (xy 267.072278 -58.660503) (xy 267.044982 -58.611868)
			(xy 267.025059 -58.559777) (xy 267.012933 -58.50534) (xy 267.008862 -58.449718) (xy 265.508571 -58.449718)
			(xy 265.517129 -58.478162) (xy 265.525249 -58.533338) (xy 265.525758 -58.561224) (xy 265.525249 -58.58911)
			(xy 265.517129 -58.644286) (xy 265.501061 -58.697693) (xy 265.477389 -58.74819) (xy 265.446616 -58.794703)
			(xy 265.409399 -58.83624) (xy 265.366531 -58.871915) (xy 265.318925 -58.900969) (xy 265.267596 -58.922781)
			(xy 265.213639 -58.936887) (xy 265.158202 -58.942987) (xy 265.102468 -58.94095) (xy 265.047625 -58.93082)
			(xy 264.994841 -58.912813) (xy 264.945241 -58.887312) (xy 264.899883 -58.854861) (xy 264.859734 -58.816152)
			(xy 264.825648 -58.772009) (xy 264.798352 -58.723374) (xy 264.778429 -58.671283) (xy 264.766303 -58.616846)
			(xy 264.762232 -58.561224) (xy 259.763768 -58.561224) (xy 259.763768 -59.974734) (xy 263.287002 -59.974734)
			(xy 263.287433 -59.947907) (xy 263.294953 -59.894782) (xy 263.309837 -59.843234) (xy 263.33179 -59.794277)
			(xy 263.360381 -59.748875) (xy 263.395047 -59.707923) (xy 263.435104 -59.672227) (xy 263.457182 -59.65698)
			(xy 263.468752 -59.648765) (xy 263.487163 -59.627186) (xy 263.498921 -59.601373) (xy 263.503117 -59.573319)
			(xy 263.499427 -59.545195) (xy 263.488136 -59.519174) (xy 263.470117 -59.497267) (xy 263.458706 -59.488832)
			(xy 263.437256 -59.47347) (xy 263.398342 -59.437846) (xy 263.364708 -59.397199) (xy 263.336996 -59.352305)
			(xy 263.315734 -59.304021) (xy 263.301329 -59.253267) (xy 263.294054 -59.201013) (xy 263.293606 -59.174634)
			(xy 263.294092 -59.147383) (xy 263.301848 -59.093435) (xy 263.317203 -59.04114) (xy 263.339845 -58.991563)
			(xy 263.369311 -58.945713) (xy 263.405002 -58.904522) (xy 263.446193 -58.868831) (xy 263.492043 -58.839365)
			(xy 263.54162 -58.816723) (xy 263.593915 -58.801368) (xy 263.647863 -58.793612) (xy 263.702365 -58.793612)
			(xy 263.756313 -58.801368) (xy 263.808608 -58.816723) (xy 263.858185 -58.839365) (xy 263.904035 -58.868831)
			(xy 263.945226 -58.904522) (xy 263.980917 -58.945713) (xy 264.010383 -58.991563) (xy 264.033025 -59.04114)
			(xy 264.04838 -59.093435) (xy 264.056136 -59.147383) (xy 264.056622 -59.174634) (xy 264.056156 -59.20146)
			(xy 264.048641 -59.254582) (xy 264.033762 -59.30613) (xy 264.011814 -59.355086) (xy 263.983229 -59.400488)
			(xy 263.948569 -59.441442) (xy 263.908517 -59.47714) (xy 263.886442 -59.492388) (xy 263.87491 -59.500647)
			(xy 263.856513 -59.522221) (xy 263.844763 -59.548023) (xy 263.840566 -59.576063) (xy 263.844247 -59.604175)
			(xy 263.855521 -59.630189) (xy 263.873518 -59.652096) (xy 263.884918 -59.660536) (xy 263.906405 -59.675848)
			(xy 263.945317 -59.711482) (xy 263.978948 -59.752138) (xy 264.006655 -59.79704) (xy 264.02791 -59.845332)
			(xy 264.042308 -59.896092) (xy 264.049574 -59.948353) (xy 264.050018 -59.974734) (xy 264.049532 -60.001985)
			(xy 264.041776 -60.055933) (xy 264.026421 -60.108228) (xy 264.003779 -60.157805) (xy 263.974313 -60.203655)
			(xy 263.938622 -60.244846) (xy 263.897431 -60.280537) (xy 263.851581 -60.310003) (xy 263.802004 -60.332645)
			(xy 263.749709 -60.348) (xy 263.695761 -60.355756) (xy 263.641259 -60.355756) (xy 263.587311 -60.348)
			(xy 263.535016 -60.332645) (xy 263.485439 -60.310003) (xy 263.439589 -60.280537) (xy 263.398398 -60.244846)
			(xy 263.362707 -60.203655) (xy 263.333241 -60.157805) (xy 263.310599 -60.108228) (xy 263.295244 -60.055933)
			(xy 263.287488 -60.001985) (xy 263.287002 -59.974734) (xy 259.763768 -59.974734) (xy 259.763768 -60.601606)
			(xy 262.533128 -60.601606) (xy 262.537199 -60.545984) (xy 262.549325 -60.491547) (xy 262.569248 -60.439456)
			(xy 262.596544 -60.390821) (xy 262.63063 -60.346678) (xy 262.670779 -60.307969) (xy 262.716137 -60.275518)
			(xy 262.765737 -60.250017) (xy 262.818521 -60.23201) (xy 262.873364 -60.22188) (xy 262.929098 -60.219843)
			(xy 262.984535 -60.225943) (xy 263.038492 -60.240049) (xy 263.089821 -60.261861) (xy 263.137427 -60.290915)
			(xy 263.180295 -60.32659) (xy 263.217512 -60.368127) (xy 263.248285 -60.41464) (xy 263.271957 -60.465137)
			(xy 263.288025 -60.518544) (xy 263.296145 -60.57372) (xy 263.296654 -60.601606) (xy 263.29619 -60.627006)
			(xy 264.921236 -60.627006) (xy 264.925307 -60.571384) (xy 264.937433 -60.516947) (xy 264.957356 -60.464856)
			(xy 264.984652 -60.416221) (xy 265.018738 -60.372078) (xy 265.058887 -60.333369) (xy 265.104245 -60.300918)
			(xy 265.153845 -60.275417) (xy 265.206629 -60.25741) (xy 265.261472 -60.24728) (xy 265.317206 -60.245243)
			(xy 265.372643 -60.251343) (xy 265.4266 -60.265449) (xy 265.477929 -60.287261) (xy 265.525535 -60.316315)
			(xy 265.568403 -60.35199) (xy 265.60562 -60.393527) (xy 265.636393 -60.44004) (xy 265.660065 -60.490537)
			(xy 265.676133 -60.543944) (xy 265.684253 -60.59912) (xy 265.684762 -60.627006) (xy 265.684646 -60.633356)
			(xy 267.012926 -60.633356) (xy 267.016997 -60.577734) (xy 267.029123 -60.523297) (xy 267.049046 -60.471206)
			(xy 267.076342 -60.422571) (xy 267.110428 -60.378428) (xy 267.150577 -60.339719) (xy 267.195935 -60.307268)
			(xy 267.245535 -60.281767) (xy 267.298319 -60.26376) (xy 267.353162 -60.25363) (xy 267.408896 -60.251593)
			(xy 267.464333 -60.257693) (xy 267.51829 -60.271799) (xy 267.569619 -60.293611) (xy 267.617225 -60.322665)
			(xy 267.660093 -60.35834) (xy 267.69731 -60.399877) (xy 267.728083 -60.44639) (xy 267.751755 -60.496887)
			(xy 267.767823 -60.550294) (xy 267.775943 -60.60547) (xy 267.776452 -60.633356) (xy 267.775943 -60.661242)
			(xy 267.767823 -60.716418) (xy 267.751755 -60.769825) (xy 267.728083 -60.820322) (xy 267.69731 -60.866835)
			(xy 267.660093 -60.908372) (xy 267.617225 -60.944047) (xy 267.569619 -60.973101) (xy 267.51829 -60.994913)
			(xy 267.464333 -61.009019) (xy 267.408896 -61.015119) (xy 267.353162 -61.013082) (xy 267.298319 -61.002952)
			(xy 267.245535 -60.984945) (xy 267.195935 -60.959444) (xy 267.150577 -60.926993) (xy 267.110428 -60.888284)
			(xy 267.076342 -60.844141) (xy 267.049046 -60.795506) (xy 267.029123 -60.743415) (xy 267.016997 -60.688978)
			(xy 267.012926 -60.633356) (xy 265.684646 -60.633356) (xy 265.684253 -60.654892) (xy 265.676133 -60.710068)
			(xy 265.660065 -60.763475) (xy 265.636393 -60.813972) (xy 265.60562 -60.860485) (xy 265.568403 -60.902022)
			(xy 265.525535 -60.937697) (xy 265.477929 -60.966751) (xy 265.4266 -60.988563) (xy 265.372643 -61.002669)
			(xy 265.317206 -61.008769) (xy 265.261472 -61.006732) (xy 265.206629 -60.996602) (xy 265.153845 -60.978595)
			(xy 265.104245 -60.953094) (xy 265.058887 -60.920643) (xy 265.018738 -60.881934) (xy 264.984652 -60.837791)
			(xy 264.957356 -60.789156) (xy 264.937433 -60.737065) (xy 264.925307 -60.682628) (xy 264.921236 -60.627006)
			(xy 263.29619 -60.627006) (xy 263.296145 -60.629492) (xy 263.288025 -60.684668) (xy 263.271957 -60.738075)
			(xy 263.248285 -60.788572) (xy 263.217512 -60.835085) (xy 263.180295 -60.876622) (xy 263.137427 -60.912297)
			(xy 263.089821 -60.941351) (xy 263.038492 -60.963163) (xy 262.984535 -60.977269) (xy 262.929098 -60.983369)
			(xy 262.873364 -60.981332) (xy 262.818521 -60.971202) (xy 262.765737 -60.953195) (xy 262.716137 -60.927694)
			(xy 262.670779 -60.895243) (xy 262.63063 -60.856534) (xy 262.596544 -60.812391) (xy 262.569248 -60.763756)
			(xy 262.549325 -60.711665) (xy 262.537199 -60.657228) (xy 262.533128 -60.601606) (xy 259.763768 -60.601606)
			(xy 259.763768 -61.49594) (xy 259.764249 -61.505905) (xy 259.771826 -61.524339) (xy 259.7785 -61.531754)
			(xy 259.814568 -61.567822) (xy 259.83438 -61.575442) (xy 259.845302 -61.574934) (xy 259.861558 -61.57468)
			(xy 262.38454 -61.57468) (xy 262.393577 -61.574723) (xy 262.411623 -61.57574) (xy 262.420608 -61.576712)
			(xy 263.22401 -61.576712)
		)
		(stroke
			(width 0)
			(type solid)
		)
		(fill yes)
		(layer "In9.Cu")
		(net "P3V3_SSD9")
	)
	(gr_poly
		(pts
			(xy 405.328882 -61.576712) (xy 405.363426 -61.57468) (xy 406.497282 -61.57468) (xy 406.506426 -61.573918)
			(xy 406.510744 -61.573156) (xy 406.518052 -61.571552) (xy 406.531345 -61.564701) (xy 406.536906 -61.559694)
			(xy 406.584912 -61.51372) (xy 406.59154 -61.50675) (xy 406.599505 -61.489259) (xy 406.600406 -61.479684)
			(xy 406.600406 -61.478668) (xy 406.601912 -61.451595) (xy 406.611619 -61.398249) (xy 406.628774 -61.346813)
			(xy 406.653032 -61.298321) (xy 406.683906 -61.253747) (xy 406.702006 -61.233558) (xy 406.702514 -61.23305)
			(xy 406.703276 -61.232288) (xy 406.7048 -61.23051) (xy 406.705308 -61.230002) (xy 406.706578 -61.228478)
			(xy 406.724708 -61.209567) (xy 406.765251 -61.176387) (xy 406.80995 -61.149063) (xy 406.857965 -61.128107)
			(xy 406.908395 -61.113914) (xy 406.960292 -61.106748) (xy 406.986486 -61.106304) (xy 407.013498 -61.106772)
			(xy 407.066982 -61.114389) (xy 407.118857 -61.129474) (xy 407.168086 -61.151724) (xy 407.213685 -61.180695)
			(xy 407.254742 -61.215808) (xy 407.290436 -61.256361) (xy 407.320054 -61.301542) (xy 407.343004 -61.350449)
			(xy 407.358826 -61.402104) (xy 407.367205 -61.455475) (xy 407.367994 -61.482478) (xy 407.368248 -61.492892)
			(xy 407.376122 -61.51118) (xy 407.420318 -61.553852) (xy 407.42616 -61.55944) (xy 407.431757 -61.564539)
			(xy 407.445183 -61.571523) (xy 407.452576 -61.573156) (xy 407.461466 -61.57468) (xy 408.443176 -61.57468)
			(xy 408.45215 -61.574729) (xy 408.470068 -61.575744) (xy 408.47899 -61.576712) (xy 409.343098 -61.576712)
			(xy 409.35202 -61.575747) (xy 409.369938 -61.574733) (xy 409.378912 -61.57468) (xy 411.05328 -61.57468)
			(xy 411.059575 -61.574494) (xy 411.071783 -61.571413) (xy 411.07741 -61.568584) (xy 411.084014 -61.565028)
			(xy 411.71241 -60.936632) (xy 411.715458 -60.93333) (xy 411.725872 -60.922916) (xy 411.728546 -60.917445)
			(xy 411.731501 -60.905634) (xy 411.731714 -60.899548) (xy 411.731714 -38.90645) (xy 411.730952 -38.897306)
			(xy 411.728158 -38.882574) (xy 411.719776 -38.867842) (xy 411.713172 -38.862) (xy 411.680513 -38.83269)
			(xy 411.620206 -38.768934) (xy 411.566104 -38.699835) (xy 411.518676 -38.625996) (xy 411.478336 -38.548057)
			(xy 411.445434 -38.466699) (xy 411.420258 -38.382628) (xy 411.403026 -38.296577) (xy 411.393889 -38.209295)
			(xy 411.392925 -38.121541) (xy 411.400144 -38.034079) (xy 411.415482 -37.94767) (xy 411.438806 -37.863067)
			(xy 411.469913 -37.781005) (xy 411.508532 -37.7022) (xy 411.554327 -37.627336) (xy 411.606899 -37.557067)
			(xy 411.635956 -37.524182) (xy 411.640528 -37.519102) (xy 411.640782 -37.518594) (xy 411.65245 -37.505892)
			(xy 411.676586 -37.481248) (xy 411.689042 -37.469318) (xy 411.702504 -37.457126) (xy 411.702758 -37.456872)
			(xy 411.707076 -37.452808) (xy 411.71114 -37.448998) (xy 411.717236 -37.440616) (xy 411.727396 -37.417248)
			(xy 411.729398 -37.412408) (xy 411.731575 -37.402164) (xy 411.731714 -37.396928) (xy 411.731714 -31.777432)
			(xy 411.72892 -31.769304) (xy 411.718762 -31.738539) (xy 411.707781 -31.674695) (xy 411.707076 -31.642304)
			(xy 411.707786 -31.609914) (xy 411.718772 -31.546072) (xy 411.72892 -31.515304) (xy 411.731714 -31.507176)
			(xy 411.731714 -31.238444) (xy 411.731828 -31.233489) (xy 411.73374 -31.223764) (xy 411.735524 -31.21914)
			(xy 411.740604 -31.207202) (xy 411.742402 -31.202515) (xy 411.744321 -31.192663) (xy 411.744414 -31.187644)
			(xy 411.744414 -29.841952) (xy 411.744152 -29.834014) (xy 411.739368 -29.818878) (xy 411.735016 -29.812234)
			(xy 411.718164 -29.787795) (xy 411.691425 -29.734798) (xy 411.673211 -29.6783) (xy 411.663964 -29.619664)
			(xy 411.663388 -29.589984) (xy 411.66397 -29.560303) (xy 411.673203 -29.501664) (xy 411.691411 -29.445163)
			(xy 411.718155 -29.392167) (xy 411.735016 -29.367734) (xy 411.739381 -29.361094) (xy 411.744184 -29.345958)
			(xy 411.744414 -29.338016) (xy 411.744414 -28.112974) (xy 411.744534 -28.108426) (xy 411.746187 -28.099479)
			(xy 411.747716 -28.095194) (xy 411.749481 -28.090051) (xy 411.751014 -28.07929) (xy 411.750764 -28.073858)
			(xy 411.748478 -28.044394) (xy 411.747743 -28.037201) (xy 411.742709 -28.023654) (xy 411.738572 -28.017724)
			(xy 411.720885 -27.992879) (xy 411.692798 -27.938748) (xy 411.673671 -27.880842) (xy 411.663989 -27.820632)
			(xy 411.663388 -27.79014) (xy 411.663849 -27.762885) (xy 411.671601 -27.70893) (xy 411.686953 -27.656627)
			(xy 411.709594 -27.607041) (xy 411.73906 -27.561183) (xy 411.774754 -27.519985) (xy 411.815948 -27.484287)
			(xy 411.861803 -27.454815) (xy 411.911386 -27.432169) (xy 411.963687 -27.41681) (xy 412.017641 -27.409052)
			(xy 412.044896 -27.408632) (xy 412.070444 -27.409041) (xy 412.121083 -27.415855) (xy 412.17036 -27.429364)
			(xy 412.217396 -27.449324) (xy 412.261349 -27.47538) (xy 412.281624 -27.490928) (xy 412.297118 -27.50312)
			(xy 412.335218 -27.501088) (xy 412.488634 -27.347672) (xy 412.496031 -27.340823) (xy 412.51463 -27.33309)
			(xy 412.524702 -27.332686) (xy 412.671006 -27.332686) (xy 412.675324 -27.331924) (xy 412.695644 -27.32913)
			(xy 412.695898 -27.32913) (xy 412.727394 -27.327352) (xy 416.772852 -27.327352) (xy 416.78243 -27.326945)
			(xy 416.800256 -27.319932) (xy 416.814291 -27.306895) (xy 416.822598 -27.289634) (xy 416.823652 -27.280108)
			(xy 416.823652 -26.479246) (xy 416.823884 -26.457911) (xy 416.827824 -26.415423) (xy 416.831526 -26.39441)
			(xy 416.832796 -26.387044) (xy 416.831272 -26.372566) (xy 416.828478 -26.365708) (xy 416.825492 -26.358991)
			(xy 416.816333 -26.347501) (xy 416.810444 -26.343102) (xy 416.80257 -26.337768) (xy 416.794822 -26.332869)
			(xy 416.77706 -26.328392) (xy 416.758857 -26.330439) (xy 416.7505 -26.334212) (xy 416.723369 -26.34756)
			(xy 416.665933 -26.366449) (xy 416.606233 -26.376021) (xy 416.576002 -26.37663) (xy 416.54875 -26.376144)
			(xy 416.494801 -26.368388) (xy 416.442505 -26.353033) (xy 416.392926 -26.330393) (xy 416.347074 -26.300927)
			(xy 416.305881 -26.265236) (xy 416.270188 -26.224046) (xy 416.240719 -26.178195) (xy 416.218075 -26.128618)
			(xy 416.202717 -26.076323) (xy 416.194957 -26.022374) (xy 416.194494 -25.995122) (xy 416.195034 -25.965825)
			(xy 416.204 -25.907922) (xy 416.22171 -25.852068) (xy 416.247746 -25.799577) (xy 416.281499 -25.751681)
			(xy 416.301428 -25.7302) (xy 416.30219 -25.729438) (xy 416.302698 -25.72893) (xy 416.320801 -25.710287)
			(xy 416.361181 -25.677578) (xy 416.405626 -25.650651) (xy 416.453314 -25.630005) (xy 416.503362 -25.616022)
			(xy 416.554845 -25.60896) (xy 416.580828 -25.608534) (xy 416.609777 -25.609073) (xy 416.667011 -25.617824)
			(xy 416.722266 -25.635123) (xy 416.774273 -25.66057) (xy 416.821838 -25.693583) (xy 416.863869 -25.733403)
			(xy 416.899402 -25.779116) (xy 416.927621 -25.829673) (xy 416.92851 -25.832054) (xy 418.487858 -25.832054)
			(xy 418.491929 -25.776432) (xy 418.504055 -25.721995) (xy 418.523978 -25.669904) (xy 418.551274 -25.621269)
			(xy 418.58536 -25.577126) (xy 418.625509 -25.538417) (xy 418.670867 -25.505966) (xy 418.720467 -25.480465)
			(xy 418.773251 -25.462458) (xy 418.828094 -25.452328) (xy 418.883828 -25.450291) (xy 418.939265 -25.456391)
			(xy 418.993222 -25.470497) (xy 419.044551 -25.492309) (xy 419.092157 -25.521363) (xy 419.135025 -25.557038)
			(xy 419.136559 -25.55875) (xy 422.942258 -25.55875) (xy 422.942744 -25.531499) (xy 422.9505 -25.477551)
			(xy 422.965855 -25.425256) (xy 422.988497 -25.375679) (xy 423.017963 -25.329829) (xy 423.053654 -25.288638)
			(xy 423.094845 -25.252947) (xy 423.140695 -25.223481) (xy 423.190272 -25.200839) (xy 423.242567 -25.185484)
			(xy 423.296515 -25.177728) (xy 423.351017 -25.177728) (xy 423.404965 -25.185484) (xy 423.45726 -25.200839)
			(xy 423.506837 -25.223481) (xy 423.552687 -25.252947) (xy 423.593878 -25.288638) (xy 423.629569 -25.329829)
			(xy 423.659035 -25.375679) (xy 423.681677 -25.425256) (xy 423.697032 -25.477551) (xy 423.704788 -25.531499)
			(xy 423.705274 -25.55875) (xy 423.704711 -25.589012) (xy 423.69516 -25.648778) (xy 423.676289 -25.706285)
			(xy 423.648572 -25.76009) (xy 423.631106 -25.78481) (xy 423.622804 -25.796943) (xy 423.612848 -25.824591)
			(xy 423.611179 -25.85393) (xy 423.617935 -25.882529) (xy 423.632555 -25.90802) (xy 423.653829 -25.928292)
			(xy 423.679996 -25.941665) (xy 423.694352 -25.94483) (xy 423.720253 -25.950136) (xy 423.770376 -25.966959)
			(xy 423.817694 -25.990543) (xy 423.861302 -26.020437) (xy 423.900363 -26.056068) (xy 423.934128 -26.096752)
			(xy 423.96195 -26.14171) (xy 423.983296 -26.19008) (xy 423.997756 -26.240934) (xy 424.005054 -26.293299)
			(xy 424.005502 -26.319734) (xy 425.141896 -26.319734) (xy 425.145967 -26.264112) (xy 425.158093 -26.209675)
			(xy 425.178016 -26.157584) (xy 425.205312 -26.108949) (xy 425.239398 -26.064806) (xy 425.279547 -26.026097)
			(xy 425.324905 -25.993646) (xy 425.374505 -25.968145) (xy 425.427289 -25.950138) (xy 425.482132 -25.940008)
			(xy 425.537866 -25.937971) (xy 425.593303 -25.944071) (xy 425.64726 -25.958177) (xy 425.698589 -25.979989)
			(xy 425.746195 -26.009043) (xy 425.789063 -26.044718) (xy 425.82628 -26.086255) (xy 425.857053 -26.132768)
			(xy 425.880725 -26.183265) (xy 425.896793 -26.236672) (xy 425.904913 -26.291848) (xy 425.905422 -26.319734)
			(xy 425.904913 -26.34762) (xy 425.896793 -26.402796) (xy 425.880725 -26.456203) (xy 425.857053 -26.5067)
			(xy 425.82628 -26.553213) (xy 425.789063 -26.59475) (xy 425.746195 -26.630425) (xy 425.698589 -26.659479)
			(xy 425.64726 -26.681291) (xy 425.593303 -26.695397) (xy 425.537866 -26.701497) (xy 425.482132 -26.69946)
			(xy 425.427289 -26.68933) (xy 425.374505 -26.671323) (xy 425.324905 -26.645822) (xy 425.279547 -26.613371)
			(xy 425.239398 -26.574662) (xy 425.205312 -26.530519) (xy 425.178016 -26.481884) (xy 425.158093 -26.429793)
			(xy 425.145967 -26.375356) (xy 425.141896 -26.319734) (xy 424.005502 -26.319734) (xy 424.005016 -26.346985)
			(xy 423.99726 -26.400933) (xy 423.981905 -26.453228) (xy 423.959263 -26.502805) (xy 423.929797 -26.548655)
			(xy 423.894106 -26.589846) (xy 423.852915 -26.625537) (xy 423.807065 -26.655003) (xy 423.757488 -26.677645)
			(xy 423.705193 -26.693) (xy 423.651245 -26.700756) (xy 423.596743 -26.700756) (xy 423.542795 -26.693)
			(xy 423.4905 -26.677645) (xy 423.440923 -26.655003) (xy 423.395073 -26.625537) (xy 423.353882 -26.589846)
			(xy 423.318191 -26.548655) (xy 423.288725 -26.502805) (xy 423.266083 -26.453228) (xy 423.250728 -26.400933)
			(xy 423.242972 -26.346985) (xy 423.242486 -26.319734) (xy 423.243029 -26.289471) (xy 423.252585 -26.229704)
			(xy 423.271461 -26.172196) (xy 423.299184 -26.118392) (xy 423.316654 -26.093674) (xy 423.324939 -26.081533)
			(xy 423.334883 -26.053888) (xy 423.336546 -26.024557) (xy 423.329792 -25.995965) (xy 423.315178 -25.970479)
			(xy 423.293914 -25.950206) (xy 423.267759 -25.936825) (xy 423.253408 -25.933654) (xy 423.227513 -25.928319)
			(xy 423.177389 -25.911503) (xy 423.130069 -25.887924) (xy 423.08646 -25.858035) (xy 423.047397 -25.822408)
			(xy 423.013631 -25.781726) (xy 422.985808 -25.73677) (xy 422.964462 -25.688402) (xy 422.950002 -25.637548)
			(xy 422.942705 -25.585185) (xy 422.942258 -25.55875) (xy 419.136559 -25.55875) (xy 419.172242 -25.598575)
			(xy 419.203015 -25.645088) (xy 419.226687 -25.695585) (xy 419.242755 -25.748992) (xy 419.250875 -25.804168)
			(xy 419.251384 -25.832054) (xy 419.250875 -25.85994) (xy 419.242755 -25.915116) (xy 419.226687 -25.968523)
			(xy 419.203015 -26.01902) (xy 419.172242 -26.065533) (xy 419.135025 -26.10707) (xy 419.092157 -26.142745)
			(xy 419.044551 -26.171799) (xy 418.993222 -26.193611) (xy 418.939265 -26.207717) (xy 418.883828 -26.213817)
			(xy 418.828094 -26.21178) (xy 418.773251 -26.20165) (xy 418.720467 -26.183643) (xy 418.670867 -26.158142)
			(xy 418.625509 -26.125691) (xy 418.58536 -26.086982) (xy 418.551274 -26.042839) (xy 418.523978 -25.994204)
			(xy 418.504055 -25.942113) (xy 418.491929 -25.887676) (xy 418.487858 -25.832054) (xy 416.92851 -25.832054)
			(xy 416.947877 -25.883913) (xy 416.959707 -25.940591) (xy 416.961828 -25.969468) (xy 416.961828 -25.969976)
			(xy 416.963325 -25.982028) (xy 416.975796 -26.002827) (xy 416.985704 -26.009854) (xy 417.066476 -26.060654)
			(xy 417.091114 -26.062432) (xy 417.102544 -26.057606) (xy 417.13086 -26.046142) (xy 417.18977 -26.029976)
			(xy 417.250308 -26.021798) (xy 417.280852 -26.021284) (xy 417.298886 -26.021284) (xy 417.304982 -26.022046)
			(xy 417.306506 -26.022046) (xy 417.337982 -26.024324) (xy 417.399915 -26.036443) (xy 417.459597 -26.056952)
			(xy 417.515898 -26.085462) (xy 417.567752 -26.121432) (xy 417.614175 -26.164181) (xy 417.654288 -26.212899)
			(xy 417.687333 -26.266664) (xy 417.712682 -26.324457) (xy 417.722983 -26.360882) (xy 420.405558 -26.360882)
			(xy 420.409629 -26.30526) (xy 420.421755 -26.250823) (xy 420.441678 -26.198732) (xy 420.468974 -26.150097)
			(xy 420.50306 -26.105954) (xy 420.543209 -26.067245) (xy 420.588567 -26.034794) (xy 420.638167 -26.009293)
			(xy 420.690951 -25.991286) (xy 420.745794 -25.981156) (xy 420.801528 -25.979119) (xy 420.856965 -25.985219)
			(xy 420.910922 -25.999325) (xy 420.962251 -26.021137) (xy 421.009857 -26.050191) (xy 421.052725 -26.085866)
			(xy 421.089942 -26.127403) (xy 421.120715 -26.173916) (xy 421.144387 -26.224413) (xy 421.160455 -26.27782)
			(xy 421.168575 -26.332996) (xy 421.169084 -26.360882) (xy 421.168575 -26.388768) (xy 421.160455 -26.443944)
			(xy 421.144387 -26.497351) (xy 421.120715 -26.547848) (xy 421.089942 -26.594361) (xy 421.052725 -26.635898)
			(xy 421.009857 -26.671573) (xy 420.962251 -26.700627) (xy 420.910922 -26.722439) (xy 420.856965 -26.736545)
			(xy 420.801528 -26.742645) (xy 420.745794 -26.740608) (xy 420.690951 -26.730478) (xy 420.638167 -26.712471)
			(xy 420.588567 -26.68697) (xy 420.543209 -26.654519) (xy 420.50306 -26.61581) (xy 420.468974 -26.571667)
			(xy 420.441678 -26.523032) (xy 420.421755 -26.470941) (xy 420.409629 -26.416504) (xy 420.405558 -26.360882)
			(xy 417.722983 -26.360882) (xy 417.729855 -26.385183) (xy 417.738528 -26.447692) (xy 417.739068 -26.479246)
			(xy 417.739068 -27.280108) (xy 417.740123 -27.289647) (xy 417.748369 -27.306959) (xy 417.762412 -27.320018)
			(xy 417.780278 -27.326986) (xy 417.789868 -27.327352) (xy 426.995844 -27.327352) (xy 427.00572 -27.326889)
			(xy 427.024017 -27.319444) (xy 427.031404 -27.312874) (xy 427.031658 -27.31262) (xy 427.390814 -26.953464)
			(xy 427.397664 -26.946068) (xy 427.405399 -26.927469) (xy 427.4058 -26.917396) (xy 427.4058 -24.082756)
			(xy 427.402752 -24.074374) (xy 427.392542 -24.043557) (xy 427.381564 -23.979578) (xy 427.380908 -23.94712)
			(xy 427.380908 -23.946866) (xy 427.381562 -23.914409) (xy 427.392547 -23.85043) (xy 427.402752 -23.819612)
			(xy 427.4058 -23.810976) (xy 427.4058 -22.239478) (xy 427.388782 -22.214078) (xy 427.374558 -22.207982)
			(xy 427.348793 -22.196774) (xy 427.300597 -22.167897) (xy 427.25716 -22.132259) (xy 427.219423 -22.090633)
			(xy 427.188204 -22.043919) (xy 427.164179 -21.993129) (xy 427.147867 -21.939364) (xy 427.139622 -21.883787)
			(xy 427.139623 -21.827601) (xy 427.14787 -21.772024) (xy 427.164183 -21.718259) (xy 427.18821 -21.66747)
			(xy 427.219431 -21.620758) (xy 427.257169 -21.579132) (xy 427.300607 -21.543496) (xy 427.348804 -21.514621)
			(xy 427.374558 -21.503386) (xy 427.388782 -21.49729) (xy 427.4058 -21.47189) (xy 427.4058 -15.83563)
			(xy 427.4058 -15.832074) (xy 427.404022 -15.808198) (xy 427.376336 -15.783306) (xy 427.374304 -15.781274)
			(xy 427.333918 -15.740634) (xy 427.315884 -15.733014) (xy 427.305724 -15.73276) (xy 427.280007 -15.73191)
			(xy 427.229139 -15.724148) (xy 427.179775 -15.709625) (xy 427.132808 -15.688604) (xy 427.089091 -15.661466)
			(xy 427.049414 -15.628701) (xy 427.031658 -15.610078) (xy 427.024038 -15.60195) (xy 427.003972 -15.593568)
			(xy 426.90542 -15.596108) (xy 426.885862 -15.605506) (xy 426.87875 -15.614142) (xy 426.860539 -15.63529)
			(xy 426.818991 -15.672553) (xy 426.772459 -15.703367) (xy 426.721936 -15.727075) (xy 426.668497 -15.743171)
			(xy 426.613285 -15.751312) (xy 426.58538 -15.75181) (xy 426.55813 -15.751323) (xy 426.504184 -15.743564)
			(xy 426.451891 -15.728207) (xy 426.402316 -15.705565) (xy 426.356468 -15.676098) (xy 426.31528 -15.640406)
			(xy 426.27959 -15.599216) (xy 426.250126 -15.553366) (xy 426.227486 -15.50379) (xy 426.212132 -15.451497)
			(xy 426.204376 -15.39755) (xy 426.204376 -15.34305) (xy 426.212132 -15.289103) (xy 426.227486 -15.23681)
			(xy 426.250126 -15.187234) (xy 426.27959 -15.141384) (xy 426.31528 -15.100194) (xy 426.356468 -15.064502)
			(xy 426.402316 -15.035035) (xy 426.451891 -15.012393) (xy 426.504184 -14.997036) (xy 426.55813 -14.989277)
			(xy 426.58538 -14.988794) (xy 426.611617 -14.98923) (xy 426.663596 -14.996425) (xy 426.714096 -15.010681)
			(xy 426.762164 -15.031729) (xy 426.806891 -15.05917) (xy 426.847431 -15.092488) (xy 426.865542 -15.111476)
			(xy 426.873162 -15.119604) (xy 426.893228 -15.127986) (xy 426.99178 -15.125446) (xy 427.011338 -15.116048)
			(xy 427.01845 -15.107412) (xy 427.036329 -15.086648) (xy 427.077024 -15.049958) (xy 427.122545 -15.019459)
			(xy 427.171957 -14.995779) (xy 427.224246 -14.979403) (xy 427.278339 -14.970668) (xy 427.305724 -14.969744)
			(xy 427.31563 -14.969744) (xy 427.334172 -14.96187) (xy 427.378622 -14.916912) (xy 427.391068 -14.904212)
			(xy 427.397125 -14.897551) (xy 427.404534 -14.881155) (xy 427.405546 -14.872208) (xy 427.4058 -14.868652)
			(xy 427.4058 -13.73124) (xy 427.405366 -13.721175) (xy 427.397636 -13.702586) (xy 427.390814 -13.695172)
			(xy 427.085506 -13.389864) (xy 427.078111 -13.38301) (xy 427.059512 -13.375263) (xy 427.049438 -13.374878)
			(xy 422.342818 -13.374878) (xy 422.332768 -13.375384) (xy 422.314208 -13.383106) (xy 422.30675 -13.389864)
			(xy 421.596312 -14.100302) (xy 426.343062 -14.100302) (xy 426.347133 -14.04468) (xy 426.359259 -13.990243)
			(xy 426.379182 -13.938152) (xy 426.406478 -13.889517) (xy 426.440564 -13.845374) (xy 426.480713 -13.806665)
			(xy 426.526071 -13.774214) (xy 426.575671 -13.748713) (xy 426.628455 -13.730706) (xy 426.683298 -13.720576)
			(xy 426.739032 -13.718539) (xy 426.794469 -13.724639) (xy 426.848426 -13.738745) (xy 426.899755 -13.760557)
			(xy 426.947361 -13.789611) (xy 426.990229 -13.825286) (xy 427.027446 -13.866823) (xy 427.058219 -13.913336)
			(xy 427.081891 -13.963833) (xy 427.097959 -14.01724) (xy 427.106079 -14.072416) (xy 427.106588 -14.100302)
			(xy 427.106079 -14.128188) (xy 427.097959 -14.183364) (xy 427.081891 -14.236771) (xy 427.058219 -14.287268)
			(xy 427.027446 -14.333781) (xy 426.990229 -14.375318) (xy 426.947361 -14.410993) (xy 426.899755 -14.440047)
			(xy 426.848426 -14.461859) (xy 426.794469 -14.475965) (xy 426.739032 -14.482065) (xy 426.683298 -14.480028)
			(xy 426.628455 -14.469898) (xy 426.575671 -14.451891) (xy 426.526071 -14.42639) (xy 426.480713 -14.393939)
			(xy 426.440564 -14.35523) (xy 426.406478 -14.311087) (xy 426.379182 -14.262452) (xy 426.359259 -14.210361)
			(xy 426.347133 -14.155924) (xy 426.343062 -14.100302) (xy 421.596312 -14.100302) (xy 421.000936 -14.695678)
			(xy 420.995722 -14.700587) (xy 420.983219 -14.707555) (xy 420.976298 -14.709394) (xy 420.966646 -14.71168)
			(xy 420.951152 -14.722348) (xy 420.893748 -14.807438) (xy 420.891208 -14.83233) (xy 420.896034 -14.844268)
			(xy 420.921529 -14.908231) (xy 420.965207 -15.038831) (xy 421.00037 -15.171977) (xy 421.02687 -15.307113)
			(xy 421.044596 -15.443677) (xy 421.053477 -15.581101) (xy 421.054022 -15.649956) (xy 421.053514 -15.700756)
			(xy 421.053514 -15.70101) (xy 421.05326 -15.705836) (xy 421.05104 -15.771769) (xy 421.039463 -15.903196)
			(xy 421.019788 -16.033657) (xy 420.99209 -16.162653) (xy 420.956474 -16.289692) (xy 420.913077 -16.414287)
			(xy 420.862064 -16.535962) (xy 420.803631 -16.654253) (xy 420.738 -16.768708) (xy 420.665423 -16.878888)
			(xy 420.586177 -16.984374) (xy 420.500565 -17.084762) (xy 420.45509 -17.132554) (xy 420.450518 -17.137126)
			(xy 420.435278 -17.15262) (xy 420.389253 -17.19864) (xy 420.292428 -17.285637) (xy 420.19048 -17.36657)
			(xy 420.083789 -17.441139) (xy 419.97275 -17.509065) (xy 419.857778 -17.570097) (xy 419.7393 -17.624008)
			(xy 419.617755 -17.670597) (xy 419.493597 -17.709691) (xy 419.367287 -17.741144) (xy 419.239295 -17.76484)
			(xy 419.110096 -17.78069) (xy 418.980172 -17.788636) (xy 418.915088 -17.789144) (xy 418.850617 -17.788657)
			(xy 418.721909 -17.780871) (xy 418.593907 -17.765328) (xy 418.467076 -17.742085) (xy 418.34188 -17.711227)
			(xy 418.218776 -17.672866) (xy 418.098212 -17.627142) (xy 417.980629 -17.574222) (xy 417.866456 -17.5143)
			(xy 417.756109 -17.447593) (xy 417.649991 -17.374345) (xy 417.548489 -17.294824) (xy 417.451973 -17.20932)
			(xy 417.360797 -17.118144) (xy 417.275291 -17.02163) (xy 417.195769 -16.920128) (xy 417.12252 -16.814011)
			(xy 417.055812 -16.703665) (xy 416.995888 -16.589492) (xy 416.942967 -16.47191) (xy 416.897242 -16.351347)
			(xy 416.85888 -16.228243) (xy 416.82802 -16.103048) (xy 416.804776 -15.976217) (xy 416.789231 -15.848215)
			(xy 416.781444 -15.719507) (xy 416.78098 -15.655036) (xy 416.781532 -15.586705) (xy 416.790291 -15.450325)
			(xy 416.807764 -15.314786) (xy 416.833878 -15.180643) (xy 416.868526 -15.048447) (xy 416.911567 -14.91874)
			(xy 416.936682 -14.85519) (xy 416.93846 -14.850618) (xy 416.940492 -14.83995) (xy 416.942046 -14.830042)
			(xy 416.938129 -14.810389) (xy 416.932872 -14.80185) (xy 416.88639 -14.733016) (xy 416.878859 -14.723)
			(xy 416.856743 -14.71128) (xy 416.844226 -14.710664) (xy 415.029396 -14.710664) (xy 415.02005 -14.711131)
			(xy 415.002621 -14.7179) (xy 414.98875 -14.730438) (xy 414.984184 -14.738604) (xy 414.940242 -14.825218)
			(xy 414.942528 -14.853666) (xy 414.95091 -14.86535) (xy 414.978053 -14.903466) (xy 415.025495 -14.984127)
			(xy 415.06469 -15.069102) (xy 415.09525 -15.157549) (xy 415.116872 -15.248596) (xy 415.129344 -15.341339)
			(xy 415.131504 -15.388082) (xy 415.131504 -15.388336) (xy 415.132266 -15.402306) (xy 415.132266 -15.420086)
			(xy 415.131687 -15.466599) (xy 415.122474 -15.559167) (xy 415.104167 -15.650373) (xy 415.076944 -15.739327)
			(xy 415.041072 -15.825158) (xy 415.01949 -15.866364) (xy 415.013394 -15.877794) (xy 415.013394 -15.903194)
			(xy 415.061654 -15.992602) (xy 415.08299 -16.006572) (xy 415.095944 -16.007588) (xy 415.139335 -16.011726)
			(xy 415.225186 -16.026839) (xy 415.309325 -16.049627) (xy 415.391068 -16.079904) (xy 415.469751 -16.117425)
			(xy 415.544731 -16.161884) (xy 415.615401 -16.212919) (xy 415.681183 -16.270115) (xy 415.741544 -16.333006)
			(xy 415.795991 -16.401081) (xy 415.844083 -16.473785) (xy 415.885426 -16.550528) (xy 415.919686 -16.630684)
			(xy 415.946583 -16.713601) (xy 415.965898 -16.798605) (xy 415.977474 -16.885003) (xy 415.981217 -16.972093)
			(xy 415.977097 -17.059167) (xy 415.965146 -17.145514) (xy 415.945463 -17.230433) (xy 415.918207 -17.313233)
			(xy 415.883601 -17.39324) (xy 415.841925 -17.469803) (xy 415.793519 -17.542298) (xy 415.738777 -17.610137)
			(xy 415.708846 -17.641824) (xy 415.708592 -17.642078) (xy 415.677305 -17.67411) (xy 415.609732 -17.732871)
			(xy 415.53701 -17.785123) (xy 415.459762 -17.830418) (xy 415.378653 -17.868367) (xy 415.294379 -17.898643)
			(xy 415.207663 -17.920987) (xy 415.119251 -17.935206) (xy 415.029903 -17.941179) (xy 414.940385 -17.938855)
			(xy 414.851467 -17.928252) (xy 414.763913 -17.909463) (xy 414.678474 -17.882648) (xy 414.636966 -17.865852)
			(xy 414.595904 -17.848109) (xy 414.516941 -17.80607) (xy 414.442205 -17.756907) (xy 414.372337 -17.701042)
			(xy 414.307936 -17.638953) (xy 414.249555 -17.571173) (xy 414.197695 -17.498283) (xy 414.152799 -17.420908)
			(xy 414.115253 -17.339712) (xy 414.08538 -17.25539) (xy 414.063434 -17.168667) (xy 414.049605 -17.080286)
			(xy 414.044011 -16.991005) (xy 414.0467 -16.901589) (xy 414.057648 -16.812804) (xy 414.076763 -16.725414)
			(xy 414.103879 -16.640166) (xy 414.138765 -16.557792) (xy 414.159446 -16.518128) (xy 414.1597 -16.517366)
			(xy 414.161224 -16.514318) (xy 414.162748 -16.510762) (xy 414.167098 -16.499101) (xy 414.165113 -16.474322)
			(xy 414.158938 -16.463518) (xy 414.158176 -16.462502) (xy 414.114996 -16.390112) (xy 414.110198 -16.382736)
			(xy 414.096644 -16.371535) (xy 414.0801 -16.365581) (xy 414.071308 -16.36522) (xy 412.332932 -16.36522)
			(xy 412.289493 -16.364735) (xy 412.202985 -16.356721) (xy 412.117585 -16.34076) (xy 412.034023 -16.316986)
			(xy 411.953011 -16.285603) (xy 411.87524 -16.246879) (xy 411.801374 -16.201144) (xy 411.732043 -16.148789)
			(xy 411.667839 -16.090259) (xy 411.60931 -16.026055) (xy 411.556954 -15.956724) (xy 411.51122 -15.882858)
			(xy 411.472496 -15.805088) (xy 411.441113 -15.724075) (xy 411.41734 -15.640513) (xy 411.401378 -15.555113)
			(xy 411.393365 -15.468605) (xy 411.392878 -15.425166) (xy 411.392878 -15.424658) (xy 411.393362 -15.382462)
			(xy 411.400975 -15.298413) (xy 411.416092 -15.215385) (xy 411.438591 -15.134046) (xy 411.468291 -15.055052)
			(xy 411.504952 -14.979038) (xy 411.54828 -14.906616) (xy 411.57271 -14.872208) (xy 411.581092 -14.86027)
			(xy 411.583378 -14.83233) (xy 411.529276 -14.725396) (xy 411.505146 -14.710664) (xy 402.16963 -14.710664)
			(xy 402.159567 -14.711102) (xy 402.140987 -14.718841) (xy 402.133562 -14.72565) (xy 401.939252 -14.91996)
			(xy 401.932381 -14.927516) (xy 401.924758 -14.946443) (xy 401.9251 -14.966845) (xy 401.928838 -14.976348)
			(xy 401.928838 -14.976602) (xy 401.966938 -15.062708) (xy 401.970388 -15.069802) (xy 401.980858 -15.081587)
			(xy 401.987512 -15.085822) (xy 401.994624 -15.09014) (xy 402.008848 -15.093696) (xy 402.016214 -15.093188)
			(xy 402.017738 -15.093188) (xy 402.036788 -15.09268) (xy 402.064042 -15.093142) (xy 402.117996 -15.100898)
			(xy 402.170297 -15.116253) (xy 402.219881 -15.138896) (xy 402.265737 -15.168365) (xy 402.306932 -15.204059)
			(xy 402.342628 -15.245254) (xy 402.372098 -15.291109) (xy 402.394742 -15.340691) (xy 402.4101 -15.392992)
			(xy 402.417857 -15.446946) (xy 402.417857 -15.501454) (xy 402.4101 -15.555408) (xy 402.394742 -15.607709)
			(xy 402.372098 -15.657291) (xy 402.342628 -15.703146) (xy 402.306932 -15.744341) (xy 402.265737 -15.780035)
			(xy 402.219881 -15.809504) (xy 402.170297 -15.832147) (xy 402.117996 -15.847502) (xy 402.064042 -15.855258)
			(xy 402.036788 -15.855696) (xy 402.006798 -15.85514) (xy 401.947558 -15.845746) (xy 401.890526 -15.827177)
			(xy 401.86356 -15.81404) (xy 401.851622 -15.807944) (xy 401.82546 -15.80896) (xy 401.740116 -15.861284)
			(xy 401.73295 -15.866113) (xy 401.722106 -15.879554) (xy 401.716334 -15.89583) (xy 401.715986 -15.904464)
			(xy 401.715986 -18.44421) (xy 422.576242 -18.44421) (xy 422.580313 -18.388588) (xy 422.592439 -18.334151)
			(xy 422.612362 -18.28206) (xy 422.639658 -18.233425) (xy 422.673744 -18.189282) (xy 422.713893 -18.150573)
			(xy 422.759251 -18.118122) (xy 422.808851 -18.092621) (xy 422.861635 -18.074614) (xy 422.916478 -18.064484)
			(xy 422.972212 -18.062447) (xy 423.027649 -18.068547) (xy 423.081606 -18.082653) (xy 423.132935 -18.104465)
			(xy 423.180541 -18.133519) (xy 423.223409 -18.169194) (xy 423.260626 -18.210731) (xy 423.291399 -18.257244)
			(xy 423.315071 -18.307741) (xy 423.331139 -18.361148) (xy 423.339259 -18.416324) (xy 423.339768 -18.44421)
			(xy 423.339259 -18.472096) (xy 423.331139 -18.527272) (xy 423.315071 -18.580679) (xy 423.291399 -18.631176)
			(xy 423.260626 -18.677689) (xy 423.223409 -18.719226) (xy 423.180541 -18.754901) (xy 423.132935 -18.783955)
			(xy 423.081606 -18.805767) (xy 423.027649 -18.819873) (xy 422.972212 -18.825973) (xy 422.916478 -18.823936)
			(xy 422.861635 -18.813806) (xy 422.808851 -18.795799) (xy 422.759251 -18.770298) (xy 422.713893 -18.737847)
			(xy 422.673744 -18.699138) (xy 422.639658 -18.654995) (xy 422.612362 -18.60636) (xy 422.592439 -18.554269)
			(xy 422.580313 -18.499832) (xy 422.576242 -18.44421) (xy 401.715986 -18.44421) (xy 401.715986 -20.72513)
			(xy 405.480532 -20.72513) (xy 405.484502 -20.594996) (xy 405.496398 -20.465346) (xy 405.516177 -20.336663)
			(xy 405.543763 -20.209424) (xy 405.579056 -20.084105) (xy 405.621922 -19.961169) (xy 405.672204 -19.841076)
			(xy 405.729713 -19.724272) (xy 405.794237 -19.61119) (xy 405.865534 -19.502253) (xy 405.943339 -19.397865)
			(xy 406.027364 -19.298414) (xy 406.117296 -19.204271) (xy 406.2128 -19.115786) (xy 406.31352 -19.033287)
			(xy 406.419082 -18.957082) (xy 406.529094 -18.887455) (xy 406.643146 -18.824664) (xy 406.760814 -18.768942)
			(xy 406.88166 -18.720498) (xy 407.005235 -18.679511) (xy 407.131078 -18.646134) (xy 407.258723 -18.620491)
			(xy 407.387693 -18.602677) (xy 407.517509 -18.592759) (xy 407.647688 -18.590774) (xy 407.777747 -18.596728)
			(xy 407.9072 -18.610601) (xy 408.035567 -18.632339) (xy 408.16237 -18.661863) (xy 408.287137 -18.699062)
			(xy 408.409404 -18.743798) (xy 408.528717 -18.795906) (xy 408.64463 -18.855189) (xy 408.756715 -18.92143)
			(xy 408.864552 -18.99438) (xy 408.967741 -19.073768) (xy 409.065899 -19.1593) (xy 409.15866 -19.250657)
			(xy 409.245679 -19.347499) (xy 409.326632 -19.449466) (xy 409.401218 -19.556178) (xy 409.469159 -19.667239)
			(xy 409.530204 -19.782235) (xy 409.584125 -19.900739) (xy 409.63072 -20.02231) (xy 409.669818 -20.146495)
			(xy 409.701272 -20.272833) (xy 409.724966 -20.400854) (xy 409.74081 -20.53008) (xy 409.748748 -20.660033)
			(xy 409.749244 -20.72513) (xy 409.748748 -20.790227) (xy 409.74081 -20.92018) (xy 409.724966 -21.049406)
			(xy 409.701272 -21.177427) (xy 409.669818 -21.303765) (xy 409.63072 -21.42795) (xy 409.584125 -21.549521)
			(xy 409.530204 -21.668025) (xy 409.49288 -21.738336) (xy 411.716728 -21.738336) (xy 411.717232 -21.709597)
			(xy 411.725862 -21.652769) (xy 411.742918 -21.597879) (xy 411.768014 -21.546168) (xy 411.800581 -21.498805)
			(xy 411.819852 -21.477478) (xy 411.826456 -21.470366) (xy 411.833568 -21.45284) (xy 411.833568 -21.363432)
			(xy 411.826456 -21.345906) (xy 411.819852 -21.338794) (xy 411.800616 -21.317437) (xy 411.768047 -21.27008)
			(xy 411.742951 -21.218374) (xy 411.725897 -21.163487) (xy 411.717271 -21.106664) (xy 411.717267 -21.049189)
			(xy 411.725886 -20.992364) (xy 411.742932 -20.937475) (xy 411.76802 -20.885765) (xy 411.800583 -20.838404)
			(xy 411.819852 -20.817078) (xy 411.826456 -20.809966) (xy 411.833568 -20.79244) (xy 411.833568 -20.703032)
			(xy 411.826456 -20.685506) (xy 411.819852 -20.678394) (xy 411.800616 -20.657037) (xy 411.768047 -20.60968)
			(xy 411.742951 -20.557974) (xy 411.725897 -20.503087) (xy 411.717271 -20.446264) (xy 411.717267 -20.388789)
			(xy 411.725886 -20.331964) (xy 411.742932 -20.277075) (xy 411.76802 -20.225365) (xy 411.800583 -20.178004)
			(xy 411.819852 -20.156678) (xy 411.826456 -20.149566) (xy 411.833568 -20.13204) (xy 411.833568 -20.042632)
			(xy 411.826456 -20.025106) (xy 411.819852 -20.017994) (xy 411.800616 -19.996637) (xy 411.768047 -19.94928)
			(xy 411.742951 -19.897574) (xy 411.725897 -19.842687) (xy 411.717271 -19.785864) (xy 411.717267 -19.728389)
			(xy 411.725886 -19.671564) (xy 411.742932 -19.616675) (xy 411.76802 -19.564965) (xy 411.800583 -19.517604)
			(xy 411.819852 -19.496278) (xy 411.826456 -19.489166) (xy 411.833568 -19.47164) (xy 411.833568 -19.382232)
			(xy 411.826456 -19.364706) (xy 411.819852 -19.357594) (xy 411.800601 -19.33625) (xy 411.768031 -19.288893)
			(xy 411.742935 -19.237186) (xy 411.72588 -19.182298) (xy 411.717252 -19.125474) (xy 411.716728 -19.096736)
			(xy 411.717214 -19.069485) (xy 411.72497 -19.015537) (xy 411.740325 -18.963242) (xy 411.762967 -18.913665)
			(xy 411.792433 -18.867815) (xy 411.828124 -18.826624) (xy 411.869315 -18.790933) (xy 411.915165 -18.761467)
			(xy 411.964742 -18.738825) (xy 412.017037 -18.72347) (xy 412.070985 -18.715714) (xy 412.125487 -18.715714)
			(xy 412.179435 -18.72347) (xy 412.23173 -18.738825) (xy 412.281307 -18.761467) (xy 412.327157 -18.790933)
			(xy 412.368348 -18.826624) (xy 412.404039 -18.867815) (xy 412.433505 -18.913665) (xy 412.456147 -18.963242)
			(xy 412.471502 -19.015537) (xy 412.479258 -19.069485) (xy 412.479744 -19.096736) (xy 412.47923 -19.125475)
			(xy 412.470604 -19.182302) (xy 412.45355 -19.237193) (xy 412.428457 -19.288904) (xy 412.395891 -19.336267)
			(xy 412.37662 -19.357594) (xy 412.370016 -19.364706) (xy 412.362904 -19.382232) (xy 412.362904 -19.47164)
			(xy 412.370016 -19.489166) (xy 412.37662 -19.496278) (xy 412.395924 -19.517575) (xy 412.428485 -19.564944)
			(xy 412.453572 -19.616661) (xy 412.470617 -19.671556) (xy 412.479235 -19.728386) (xy 412.479231 -19.785866)
			(xy 412.470605 -19.842696) (xy 412.453552 -19.897588) (xy 412.428458 -19.949302) (xy 412.395892 -19.996666)
			(xy 412.37662 -20.017994) (xy 412.370016 -20.025106) (xy 412.362904 -20.042632) (xy 412.362904 -20.13204)
			(xy 412.370016 -20.149566) (xy 412.37662 -20.156678) (xy 412.395924 -20.177975) (xy 412.428485 -20.225344)
			(xy 412.453572 -20.277061) (xy 412.470617 -20.331956) (xy 412.479235 -20.388786) (xy 412.479231 -20.446266)
			(xy 412.470605 -20.503096) (xy 412.453552 -20.557988) (xy 412.428458 -20.609702) (xy 412.395892 -20.657066)
			(xy 412.37662 -20.678394) (xy 412.370016 -20.685506) (xy 412.362904 -20.703032) (xy 412.362904 -20.79244)
			(xy 412.370016 -20.809966) (xy 412.37662 -20.817078) (xy 412.395924 -20.838375) (xy 412.428485 -20.885744)
			(xy 412.453572 -20.937461) (xy 412.470617 -20.992356) (xy 412.479235 -21.049186) (xy 412.479231 -21.106666)
			(xy 412.470605 -21.163496) (xy 412.453552 -21.218388) (xy 412.428458 -21.270102) (xy 412.395892 -21.317466)
			(xy 412.37662 -21.338794) (xy 412.370016 -21.345906) (xy 412.362904 -21.363432) (xy 412.362904 -21.45284)
			(xy 412.370016 -21.470366) (xy 412.37662 -21.477478) (xy 412.395901 -21.498796) (xy 412.428467 -21.54616)
			(xy 412.453559 -21.597874) (xy 412.470607 -21.652767) (xy 412.479226 -21.709596) (xy 412.479538 -21.726906)
			(xy 416.373818 -21.726906) (xy 416.374367 -21.698168) (xy 416.382987 -21.641343) (xy 416.400032 -21.586453)
			(xy 416.425118 -21.534741) (xy 416.457675 -21.487377) (xy 416.476942 -21.466048) (xy 416.483546 -21.458936)
			(xy 416.490658 -21.44141) (xy 416.490658 -21.352002) (xy 416.483546 -21.334476) (xy 416.476942 -21.327364)
			(xy 416.457676 -21.306032) (xy 416.425109 -21.258671) (xy 416.400016 -21.20696) (xy 416.382965 -21.15207)
			(xy 416.374341 -21.095243) (xy 416.374341 -21.037766) (xy 416.382963 -20.980938) (xy 416.400013 -20.926048)
			(xy 416.425105 -20.874336) (xy 416.457671 -20.826974) (xy 416.476942 -20.805648) (xy 416.483546 -20.798536)
			(xy 416.490658 -20.78101) (xy 416.490658 -20.691602) (xy 416.483546 -20.674076) (xy 416.476942 -20.666964)
			(xy 416.457676 -20.645632) (xy 416.425109 -20.598271) (xy 416.400016 -20.54656) (xy 416.382965 -20.49167)
			(xy 416.374341 -20.434843) (xy 416.374341 -20.377366) (xy 416.382963 -20.320538) (xy 416.400013 -20.265648)
			(xy 416.425105 -20.213936) (xy 416.457671 -20.166574) (xy 416.476942 -20.145248) (xy 416.483546 -20.138136)
			(xy 416.490658 -20.12061) (xy 416.490658 -20.031202) (xy 416.483546 -20.013676) (xy 416.476942 -20.006564)
			(xy 416.457676 -19.985232) (xy 416.425109 -19.937871) (xy 416.400016 -19.88616) (xy 416.382965 -19.83127)
			(xy 416.374341 -19.774443) (xy 416.374341 -19.716966) (xy 416.382963 -19.660138) (xy 416.400013 -19.605248)
			(xy 416.425105 -19.553536) (xy 416.457671 -19.506174) (xy 416.476942 -19.484848) (xy 416.483546 -19.477736)
			(xy 416.490658 -19.46021) (xy 416.490658 -19.370802) (xy 416.483546 -19.353276) (xy 416.476942 -19.346164)
			(xy 416.457675 -19.324834) (xy 416.425108 -19.277473) (xy 416.400015 -19.225762) (xy 416.382963 -19.170872)
			(xy 416.374339 -19.114045) (xy 416.373818 -19.085306) (xy 416.374304 -19.058055) (xy 416.38206 -19.004107)
			(xy 416.397415 -18.951812) (xy 416.420057 -18.902235) (xy 416.449523 -18.856385) (xy 416.485214 -18.815194)
			(xy 416.526405 -18.779503) (xy 416.572255 -18.750037) (xy 416.621832 -18.727395) (xy 416.674127 -18.71204)
			(xy 416.728075 -18.704284) (xy 416.782577 -18.704284) (xy 416.836525 -18.71204) (xy 416.88882 -18.727395)
			(xy 416.938397 -18.750037) (xy 416.984247 -18.779503) (xy 417.025438 -18.815194) (xy 417.061129 -18.856385)
			(xy 417.090595 -18.902235) (xy 417.113237 -18.951812) (xy 417.128592 -19.004107) (xy 417.136348 -19.058055)
			(xy 417.136834 -19.085306) (xy 417.136305 -19.114045) (xy 417.127682 -19.170871) (xy 417.110633 -19.225762)
			(xy 417.085543 -19.277473) (xy 417.05298 -19.324837) (xy 417.03371 -19.346164) (xy 417.027106 -19.353276)
			(xy 417.021596 -19.366853) (xy 421.879238 -19.366853) (xy 421.879238 -19.312347) (xy 421.886994 -19.258397)
			(xy 421.902349 -19.206099) (xy 421.924991 -19.156519) (xy 421.954457 -19.110665) (xy 421.990149 -19.069471)
			(xy 422.03134 -19.033776) (xy 422.077191 -19.004306) (xy 422.126769 -18.981661) (xy 422.179065 -18.966301)
			(xy 422.233015 -18.95854) (xy 422.260268 -18.958052) (xy 422.287038 -18.958552) (xy 422.340051 -18.966045)
			(xy 422.391497 -18.980875) (xy 422.440364 -19.00275) (xy 422.485694 -19.031241) (xy 422.526596 -19.065789)
			(xy 422.562268 -19.105715) (xy 422.577514 -19.127724) (xy 422.58361 -19.136614) (xy 422.601136 -19.148044)
			(xy 422.695624 -19.163284) (xy 422.715944 -19.158204) (xy 422.724326 -19.1516) (xy 422.744467 -19.136467)
			(xy 422.787992 -19.111096) (xy 422.834481 -19.091682) (xy 422.883123 -19.078565) (xy 422.93307 -19.071972)
			(xy 422.95826 -19.07159) (xy 422.985515 -19.072055) (xy 423.03947 -19.079807) (xy 423.091772 -19.095159)
			(xy 423.141357 -19.117799) (xy 423.187215 -19.147266) (xy 423.228412 -19.18296) (xy 423.26411 -19.224153)
			(xy 423.293581 -19.270008) (xy 423.316227 -19.319591) (xy 423.331585 -19.371891) (xy 423.339343 -19.425845)
			(xy 423.339343 -19.480355) (xy 423.331585 -19.534309) (xy 423.316227 -19.586609) (xy 423.293581 -19.636192)
			(xy 423.26411 -19.682047) (xy 423.228412 -19.72324) (xy 423.187215 -19.758934) (xy 423.141357 -19.788401)
			(xy 423.091772 -19.811041) (xy 423.03947 -19.826393) (xy 422.985515 -19.834145) (xy 422.95826 -19.834606)
			(xy 422.931487 -19.83418) (xy 422.87847 -19.826676) (xy 422.827022 -19.811834) (xy 422.778154 -19.789947)
			(xy 422.732825 -19.761445) (xy 422.691925 -19.726885) (xy 422.656257 -19.686948) (xy 422.641014 -19.664934)
			(xy 422.634918 -19.656044) (xy 422.617392 -19.644614) (xy 422.522904 -19.629374) (xy 422.502584 -19.634454)
			(xy 422.494202 -19.641058) (xy 422.474047 -19.656173) (xy 422.430527 -19.681548) (xy 422.384041 -19.700966)
			(xy 422.335402 -19.714087) (xy 422.285457 -19.720684) (xy 422.260268 -19.721068) (xy 422.233015 -19.72066)
			(xy 422.179065 -19.712899) (xy 422.126769 -19.697539) (xy 422.077191 -19.674894) (xy 422.031339 -19.645424)
			(xy 421.990149 -19.609729) (xy 421.954457 -19.568535) (xy 421.924991 -19.522681) (xy 421.902349 -19.473101)
			(xy 421.886994 -19.420803) (xy 421.879238 -19.366853) (xy 417.021596 -19.366853) (xy 417.019994 -19.370802)
			(xy 417.019994 -19.46021) (xy 417.027106 -19.477736) (xy 417.03371 -19.484848) (xy 417.052985 -19.50617)
			(xy 417.085547 -19.553535) (xy 417.110636 -19.605247) (xy 417.127684 -19.660138) (xy 417.136306 -19.716966)
			(xy 417.136305 -19.774443) (xy 417.127682 -19.83127) (xy 417.110633 -19.886161) (xy 417.085543 -19.937873)
			(xy 417.05298 -19.985236) (xy 417.03371 -20.006564) (xy 417.027106 -20.013676) (xy 417.019994 -20.031202)
			(xy 417.019994 -20.12061) (xy 417.027106 -20.138136) (xy 417.03371 -20.145248) (xy 417.052985 -20.16657)
			(xy 417.085547 -20.213935) (xy 417.110636 -20.265647) (xy 417.127684 -20.320538) (xy 417.132998 -20.35556)
			(xy 421.87825 -20.35556) (xy 421.882321 -20.299938) (xy 421.894447 -20.245501) (xy 421.91437 -20.19341)
			(xy 421.941666 -20.144775) (xy 421.975752 -20.100632) (xy 422.015901 -20.061923) (xy 422.061259 -20.029472)
			(xy 422.110859 -20.003971) (xy 422.163643 -19.985964) (xy 422.218486 -19.975834) (xy 422.27422 -19.973797)
			(xy 422.329657 -19.979897) (xy 422.383614 -19.994003) (xy 422.434943 -20.015815) (xy 422.482549 -20.044869)
			(xy 422.525417 -20.080544) (xy 422.562634 -20.122081) (xy 422.593407 -20.168594) (xy 422.617079 -20.219091)
			(xy 422.633147 -20.272498) (xy 422.641267 -20.327674) (xy 422.641776 -20.35556) (xy 422.641267 -20.383446)
			(xy 422.633147 -20.438622) (xy 422.617079 -20.492029) (xy 422.593407 -20.542526) (xy 422.562634 -20.589039)
			(xy 422.525417 -20.630576) (xy 422.482549 -20.666251) (xy 422.434943 -20.695305) (xy 422.383614 -20.717117)
			(xy 422.329657 -20.731223) (xy 422.27422 -20.737323) (xy 422.218486 -20.735286) (xy 422.163643 -20.725156)
			(xy 422.110859 -20.707149) (xy 422.061259 -20.681648) (xy 422.015901 -20.649197) (xy 421.975752 -20.610488)
			(xy 421.941666 -20.566345) (xy 421.91437 -20.51771) (xy 421.894447 -20.465619) (xy 421.882321 -20.411182)
			(xy 421.87825 -20.35556) (xy 417.132998 -20.35556) (xy 417.136306 -20.377366) (xy 417.136305 -20.434843)
			(xy 417.127682 -20.49167) (xy 417.110633 -20.546561) (xy 417.085543 -20.598273) (xy 417.05298 -20.645636)
			(xy 417.03371 -20.666964) (xy 417.027106 -20.674076) (xy 417.019994 -20.691602) (xy 417.019994 -20.78101)
			(xy 417.027106 -20.798536) (xy 417.03371 -20.805648) (xy 417.052985 -20.82697) (xy 417.085547 -20.874335)
			(xy 417.110636 -20.926047) (xy 417.127684 -20.980938) (xy 417.136306 -21.037766) (xy 417.136305 -21.095243)
			(xy 417.127682 -21.15207) (xy 417.110633 -21.206961) (xy 417.085543 -21.258673) (xy 417.05298 -21.306036)
			(xy 417.03371 -21.327364) (xy 417.027106 -21.334476) (xy 417.019994 -21.352002) (xy 417.019994 -21.37156)
			(xy 421.87825 -21.37156) (xy 421.882321 -21.315938) (xy 421.894447 -21.261501) (xy 421.91437 -21.20941)
			(xy 421.941666 -21.160775) (xy 421.975752 -21.116632) (xy 422.015901 -21.077923) (xy 422.061259 -21.045472)
			(xy 422.110859 -21.019971) (xy 422.163643 -21.001964) (xy 422.218486 -20.991834) (xy 422.27422 -20.989797)
			(xy 422.329657 -20.995897) (xy 422.383614 -21.010003) (xy 422.434943 -21.031815) (xy 422.482549 -21.060869)
			(xy 422.525417 -21.096544) (xy 422.562634 -21.138081) (xy 422.593407 -21.184594) (xy 422.617079 -21.235091)
			(xy 422.633147 -21.288498) (xy 422.641267 -21.343674) (xy 422.641776 -21.37156) (xy 422.641267 -21.399446)
			(xy 422.633147 -21.454622) (xy 422.617079 -21.508029) (xy 422.593407 -21.558526) (xy 422.562634 -21.605039)
			(xy 422.525417 -21.646576) (xy 422.482549 -21.682251) (xy 422.434943 -21.711305) (xy 422.383614 -21.733117)
			(xy 422.329657 -21.747223) (xy 422.27422 -21.753323) (xy 422.218486 -21.751286) (xy 422.163643 -21.741156)
			(xy 422.110859 -21.723149) (xy 422.061259 -21.697648) (xy 422.015901 -21.665197) (xy 421.975752 -21.626488)
			(xy 421.941666 -21.582345) (xy 421.91437 -21.53371) (xy 421.894447 -21.481619) (xy 421.882321 -21.427182)
			(xy 421.87825 -21.37156) (xy 417.019994 -21.37156) (xy 417.019994 -21.44141) (xy 417.027106 -21.458936)
			(xy 417.03371 -21.466048) (xy 417.052975 -21.487381) (xy 417.085544 -21.53474) (xy 417.110638 -21.58645)
			(xy 417.12769 -21.64134) (xy 417.136313 -21.698167) (xy 417.136834 -21.726906) (xy 417.136348 -21.754157)
			(xy 417.133255 -21.775674) (xy 426.235874 -21.775674) (xy 426.239945 -21.720052) (xy 426.252071 -21.665615)
			(xy 426.271994 -21.613524) (xy 426.29929 -21.564889) (xy 426.333376 -21.520746) (xy 426.373525 -21.482037)
			(xy 426.418883 -21.449586) (xy 426.468483 -21.424085) (xy 426.521267 -21.406078) (xy 426.57611 -21.395948)
			(xy 426.631844 -21.393911) (xy 426.687281 -21.400011) (xy 426.741238 -21.414117) (xy 426.792567 -21.435929)
			(xy 426.840173 -21.464983) (xy 426.883041 -21.500658) (xy 426.920258 -21.542195) (xy 426.951031 -21.588708)
			(xy 426.974703 -21.639205) (xy 426.990771 -21.692612) (xy 426.998891 -21.747788) (xy 426.9994 -21.775674)
			(xy 426.998891 -21.80356) (xy 426.990771 -21.858736) (xy 426.974703 -21.912143) (xy 426.951031 -21.96264)
			(xy 426.920258 -22.009153) (xy 426.883041 -22.05069) (xy 426.840173 -22.086365) (xy 426.792567 -22.115419)
			(xy 426.741238 -22.137231) (xy 426.687281 -22.151337) (xy 426.631844 -22.157437) (xy 426.57611 -22.1554)
			(xy 426.521267 -22.14527) (xy 426.468483 -22.127263) (xy 426.418883 -22.101762) (xy 426.373525 -22.069311)
			(xy 426.333376 -22.030602) (xy 426.29929 -21.986459) (xy 426.271994 -21.937824) (xy 426.252071 -21.885733)
			(xy 426.239945 -21.831296) (xy 426.235874 -21.775674) (xy 417.133255 -21.775674) (xy 417.128592 -21.808105)
			(xy 417.113237 -21.8604) (xy 417.090595 -21.909977) (xy 417.061129 -21.955827) (xy 417.025438 -21.997018)
			(xy 416.984247 -22.032709) (xy 416.938397 -22.062175) (xy 416.88882 -22.084817) (xy 416.836525 -22.100172)
			(xy 416.782577 -22.107928) (xy 416.728075 -22.107928) (xy 416.674127 -22.100172) (xy 416.621832 -22.084817)
			(xy 416.572255 -22.062175) (xy 416.526405 -22.032709) (xy 416.485214 -21.997018) (xy 416.449523 -21.955827)
			(xy 416.420057 -21.909977) (xy 416.397415 -21.8604) (xy 416.38206 -21.808105) (xy 416.374304 -21.754157)
			(xy 416.373818 -21.726906) (xy 412.479538 -21.726906) (xy 412.479744 -21.738336) (xy 412.479258 -21.765587)
			(xy 412.471502 -21.819535) (xy 412.456147 -21.87183) (xy 412.433505 -21.921407) (xy 412.404039 -21.967257)
			(xy 412.368348 -22.008448) (xy 412.327157 -22.044139) (xy 412.281307 -22.073605) (xy 412.23173 -22.096247)
			(xy 412.179435 -22.111602) (xy 412.125487 -22.119358) (xy 412.070985 -22.119358) (xy 412.017037 -22.111602)
			(xy 411.964742 -22.096247) (xy 411.915165 -22.073605) (xy 411.869315 -22.044139) (xy 411.828124 -22.008448)
			(xy 411.792433 -21.967257) (xy 411.762967 -21.921407) (xy 411.740325 -21.87183) (xy 411.72497 -21.819535)
			(xy 411.717214 -21.765587) (xy 411.716728 -21.738336) (xy 409.49288 -21.738336) (xy 409.469159 -21.783021)
			(xy 409.401218 -21.894082) (xy 409.326632 -22.000794) (xy 409.245679 -22.102761) (xy 409.15866 -22.199603)
			(xy 409.065899 -22.29096) (xy 408.967741 -22.376492) (xy 408.864552 -22.45588) (xy 408.756715 -22.52883)
			(xy 408.64463 -22.595071) (xy 408.528717 -22.654354) (xy 408.409404 -22.706462) (xy 408.287137 -22.751198)
			(xy 408.16237 -22.788397) (xy 408.035567 -22.817921) (xy 407.9072 -22.839659) (xy 407.777747 -22.853532)
			(xy 407.647688 -22.859486) (xy 407.517509 -22.857501) (xy 407.387693 -22.847583) (xy 407.258723 -22.829769)
			(xy 407.131078 -22.804126) (xy 407.005235 -22.770749) (xy 406.88166 -22.729762) (xy 406.760814 -22.681318)
			(xy 406.643146 -22.625596) (xy 406.529094 -22.562805) (xy 406.419082 -22.493178) (xy 406.31352 -22.416973)
			(xy 406.2128 -22.334474) (xy 406.117296 -22.245989) (xy 406.027364 -22.151846) (xy 405.943339 -22.052395)
			(xy 405.865534 -21.948007) (xy 405.794237 -21.83907) (xy 405.729713 -21.725988) (xy 405.672204 -21.609184)
			(xy 405.621922 -21.489091) (xy 405.579056 -21.366155) (xy 405.543763 -21.240836) (xy 405.516177 -21.113597)
			(xy 405.496398 -20.984914) (xy 405.484502 -20.855264) (xy 405.480532 -20.72513) (xy 401.715986 -20.72513)
			(xy 401.715986 -21.487892) (xy 401.716159 -21.494044) (xy 401.71912 -21.505987) (xy 401.721828 -21.511514)
			(xy 401.735036 -21.53666) (xy 401.742402 -21.545296) (xy 401.746974 -21.548598) (xy 401.768806 -21.565279)
			(xy 401.807905 -21.603879) (xy 401.841063 -21.647689) (xy 401.867591 -21.695802) (xy 401.886943 -21.747224)
			(xy 401.898717 -21.80089) (xy 401.902047 -21.847048) (xy 402.372828 -21.847048) (xy 402.376899 -21.791426)
			(xy 402.389025 -21.736989) (xy 402.408948 -21.684898) (xy 402.436244 -21.636263) (xy 402.47033 -21.59212)
			(xy 402.510479 -21.553411) (xy 402.555837 -21.52096) (xy 402.605437 -21.495459) (xy 402.658221 -21.477452)
			(xy 402.713064 -21.467322) (xy 402.768798 -21.465285) (xy 402.824235 -21.471385) (xy 402.878192 -21.485491)
			(xy 402.929521 -21.507303) (xy 402.977127 -21.536357) (xy 403.019995 -21.572032) (xy 403.057212 -21.613569)
			(xy 403.087985 -21.660082) (xy 403.111657 -21.710579) (xy 403.127725 -21.763986) (xy 403.135845 -21.819162)
			(xy 403.136354 -21.847048) (xy 403.135845 -21.874934) (xy 403.127725 -21.93011) (xy 403.111657 -21.983517)
			(xy 403.087985 -22.034014) (xy 403.057212 -22.080527) (xy 403.019995 -22.122064) (xy 402.977127 -22.157739)
			(xy 402.929521 -22.186793) (xy 402.878192 -22.208605) (xy 402.824235 -22.222711) (xy 402.768798 -22.228811)
			(xy 402.713064 -22.226774) (xy 402.658221 -22.216644) (xy 402.605437 -22.198637) (xy 402.555837 -22.173136)
			(xy 402.510479 -22.140685) (xy 402.47033 -22.101976) (xy 402.436244 -22.057833) (xy 402.408948 -22.009198)
			(xy 402.389025 -21.957107) (xy 402.376899 -21.90267) (xy 402.372828 -21.847048) (xy 401.902047 -21.847048)
			(xy 401.90267 -21.85569) (xy 401.89872 -21.910491) (xy 401.886948 -21.964158) (xy 401.867599 -22.015581)
			(xy 401.841073 -22.063695) (xy 401.807918 -22.107507) (xy 401.768821 -22.146108) (xy 401.746974 -22.16277)
			(xy 401.742402 -22.166072) (xy 401.735036 -22.174708) (xy 401.721828 -22.199854) (xy 401.719128 -22.205384)
			(xy 401.716165 -22.217325) (xy 401.715986 -22.223476) (xy 401.715986 -23.0251) (xy 411.66237 -23.0251)
			(xy 411.666441 -22.969478) (xy 411.678567 -22.915041) (xy 411.69849 -22.86295) (xy 411.725786 -22.814315)
			(xy 411.759872 -22.770172) (xy 411.800021 -22.731463) (xy 411.845379 -22.699012) (xy 411.894979 -22.673511)
			(xy 411.947763 -22.655504) (xy 412.002606 -22.645374) (xy 412.05834 -22.643337) (xy 412.113777 -22.649437)
			(xy 412.167734 -22.663543) (xy 412.219063 -22.685355) (xy 412.266669 -22.714409) (xy 412.309537 -22.750084)
			(xy 412.346754 -22.791621) (xy 412.377527 -22.838134) (xy 412.401199 -22.888631) (xy 412.417267 -22.942038)
			(xy 412.425387 -22.997214) (xy 412.425896 -23.0251) (xy 412.425387 -23.052986) (xy 412.417267 -23.108162)
			(xy 412.401199 -23.161569) (xy 412.377527 -23.212066) (xy 412.346754 -23.258579) (xy 412.309537 -23.300116)
			(xy 412.266669 -23.335791) (xy 412.219063 -23.364845) (xy 412.167734 -23.386657) (xy 412.113777 -23.400763)
			(xy 412.05834 -23.406863) (xy 412.002606 -23.404826) (xy 411.947763 -23.394696) (xy 411.894979 -23.376689)
			(xy 411.845379 -23.351188) (xy 411.800021 -23.318737) (xy 411.759872 -23.280028) (xy 411.725786 -23.235885)
			(xy 411.69849 -23.18725) (xy 411.678567 -23.135159) (xy 411.666441 -23.080722) (xy 411.66237 -23.0251)
			(xy 401.715986 -23.0251) (xy 401.715986 -23.49373) (xy 401.716466 -23.503695) (xy 401.724042 -23.52213)
			(xy 401.730718 -23.529544) (xy 401.757302 -23.55637) (xy 412.366023 -23.55637) (xy 412.373775 -23.502431)
			(xy 412.389125 -23.450145) (xy 412.411759 -23.400575) (xy 412.441216 -23.35473) (xy 412.476898 -23.313544)
			(xy 412.518078 -23.277855) (xy 412.563918 -23.24839) (xy 412.613484 -23.225747) (xy 412.665768 -23.210389)
			(xy 412.719706 -23.202627) (xy 412.746952 -23.202138) (xy 412.770982 -23.202499) (xy 412.81866 -23.208544)
			(xy 412.865201 -23.220531) (xy 412.887668 -23.229062) (xy 412.900808 -23.233882) (xy 412.928639 -23.236777)
			(xy 412.956213 -23.232017) (xy 412.981464 -23.21996) (xy 413.0025 -23.201508) (xy 413.017745 -23.178044)
			(xy 413.026057 -23.151325) (xy 413.026814 -23.123354) (xy 413.023812 -23.109682) (xy 413.018361 -23.086699)
			(xy 413.0125 -23.039828) (xy 413.012128 -23.01621) (xy 413.012567 -22.988958) (xy 413.020322 -22.93501)
			(xy 413.035676 -22.882714) (xy 413.058316 -22.833135) (xy 413.087781 -22.787283) (xy 413.123471 -22.746091)
			(xy 413.164661 -22.710398) (xy 413.21051 -22.680929) (xy 413.260087 -22.658286) (xy 413.312382 -22.642928)
			(xy 413.36633 -22.635169) (xy 413.420833 -22.635166) (xy 413.474782 -22.64292) (xy 413.527078 -22.658273)
			(xy 413.576657 -22.680912) (xy 413.62251 -22.710376) (xy 413.663702 -22.746065) (xy 413.699397 -22.787254)
			(xy 413.728866 -22.833103) (xy 413.751511 -22.882679) (xy 413.76687 -22.934973) (xy 413.77463 -22.988921)
			(xy 413.774634 -23.043424) (xy 413.766882 -23.097373) (xy 413.75153 -23.14967) (xy 413.728893 -23.199249)
			(xy 413.69943 -23.245103) (xy 413.663741 -23.286296) (xy 413.622553 -23.321992) (xy 413.576705 -23.351462)
			(xy 413.527129 -23.374108) (xy 413.474835 -23.389468) (xy 413.420888 -23.39723) (xy 413.393636 -23.397718)
			(xy 413.369606 -23.397357) (xy 413.321928 -23.391311) (xy 413.275388 -23.379324) (xy 413.25292 -23.370794)
			(xy 413.23977 -23.366012) (xy 413.211947 -23.363123) (xy 413.184382 -23.367884) (xy 413.15914 -23.379937)
			(xy 413.138109 -23.398381) (xy 413.122864 -23.421835) (xy 413.114547 -23.448543) (xy 413.113781 -23.476505)
			(xy 413.116776 -23.490174) (xy 413.122237 -23.513155) (xy 413.128092 -23.560028) (xy 413.12846 -23.583646)
			(xy 413.128346 -23.589996) (xy 416.384484 -23.589996) (xy 416.388555 -23.534374) (xy 416.400681 -23.479937)
			(xy 416.420604 -23.427846) (xy 416.4479 -23.379211) (xy 416.481986 -23.335068) (xy 416.522135 -23.296359)
			(xy 416.567493 -23.263908) (xy 416.617093 -23.238407) (xy 416.669877 -23.2204) (xy 416.72472 -23.21027)
			(xy 416.780454 -23.208233) (xy 416.835891 -23.214333) (xy 416.889848 -23.228439) (xy 416.941177 -23.250251)
			(xy 416.988783 -23.279305) (xy 417.031651 -23.31498) (xy 417.068005 -23.355554) (xy 425.630594 -23.355554)
			(xy 425.631065 -23.328743) (xy 425.638572 -23.275649) (xy 425.653446 -23.224131) (xy 425.675393 -23.175206)
			(xy 425.703981 -23.129839) (xy 425.738644 -23.088927) (xy 425.778699 -23.053276) (xy 425.800774 -23.038054)
			(xy 425.812318 -23.029769) (xy 425.830727 -23.00814) (xy 425.842467 -22.982278) (xy 425.846632 -22.954184)
			(xy 425.842899 -22.926028) (xy 425.831556 -22.89999) (xy 425.813482 -22.878081) (xy 425.802044 -22.869652)
			(xy 425.780589 -22.854297) (xy 425.741678 -22.818669) (xy 425.708047 -22.77802) (xy 425.680336 -22.733125)
			(xy 425.659075 -22.68484) (xy 425.64467 -22.634087) (xy 425.637394 -22.581833) (xy 425.636944 -22.555454)
			(xy 425.63743 -22.528203) (xy 425.645186 -22.474255) (xy 425.660541 -22.42196) (xy 425.683183 -22.372383)
			(xy 425.712649 -22.326533) (xy 425.74834 -22.285342) (xy 425.789531 -22.249651) (xy 425.835381 -22.220185)
			(xy 425.884958 -22.197543) (xy 425.937253 -22.182188) (xy 425.991201 -22.174432) (xy 426.045703 -22.174432)
			(xy 426.099651 -22.182188) (xy 426.151946 -22.197543) (xy 426.201523 -22.220185) (xy 426.247373 -22.249651)
			(xy 426.288564 -22.285342) (xy 426.324255 -22.326533) (xy 426.353721 -22.372383) (xy 426.376363 -22.42196)
			(xy 426.391718 -22.474255) (xy 426.399474 -22.528203) (xy 426.39996 -22.555454) (xy 426.399472 -22.582264)
			(xy 426.391964 -22.635357) (xy 426.377091 -22.686873) (xy 426.355147 -22.735797) (xy 426.326562 -22.781164)
			(xy 426.291903 -22.822077) (xy 426.251853 -22.85773) (xy 426.22978 -22.872954) (xy 426.218232 -22.881232)
			(xy 426.199832 -22.902865) (xy 426.188097 -22.928727) (xy 426.183936 -22.956821) (xy 426.187668 -22.984974)
			(xy 426.199007 -23.011013) (xy 426.217075 -23.032924) (xy 426.22851 -23.041356) (xy 426.249958 -23.05672)
			(xy 426.288872 -23.092345) (xy 426.322505 -23.132992) (xy 426.350217 -23.177885) (xy 426.371479 -23.226169)
			(xy 426.385885 -23.276922) (xy 426.393161 -23.329175) (xy 426.39361 -23.355554) (xy 426.393124 -23.382805)
			(xy 426.385368 -23.436753) (xy 426.370013 -23.489048) (xy 426.347371 -23.538625) (xy 426.317905 -23.584475)
			(xy 426.282214 -23.625666) (xy 426.241023 -23.661357) (xy 426.195173 -23.690823) (xy 426.145596 -23.713465)
			(xy 426.093301 -23.72882) (xy 426.039353 -23.736576) (xy 425.984851 -23.736576) (xy 425.930903 -23.72882)
			(xy 425.878608 -23.713465) (xy 425.829031 -23.690823) (xy 425.783181 -23.661357) (xy 425.74199 -23.625666)
			(xy 425.706299 -23.584475) (xy 425.676833 -23.538625) (xy 425.654191 -23.489048) (xy 425.638836 -23.436753)
			(xy 425.63108 -23.382805) (xy 425.630594 -23.355554) (xy 417.068005 -23.355554) (xy 417.068868 -23.356517)
			(xy 417.099641 -23.40303) (xy 417.123313 -23.453527) (xy 417.139381 -23.506934) (xy 417.147501 -23.56211)
			(xy 417.14801 -23.589996) (xy 417.147501 -23.617882) (xy 417.139381 -23.673058) (xy 417.123313 -23.726465)
			(xy 417.099641 -23.776962) (xy 417.068868 -23.823475) (xy 417.031651 -23.865012) (xy 417.013259 -23.880318)
			(xy 417.540692 -23.880318) (xy 417.544763 -23.824696) (xy 417.556889 -23.770259) (xy 417.576812 -23.718168)
			(xy 417.604108 -23.669533) (xy 417.638194 -23.62539) (xy 417.678343 -23.586681) (xy 417.723701 -23.55423)
			(xy 417.773301 -23.528729) (xy 417.826085 -23.510722) (xy 417.880928 -23.500592) (xy 417.936662 -23.498555)
			(xy 417.992099 -23.504655) (xy 418.046056 -23.518761) (xy 418.097385 -23.540573) (xy 418.144991 -23.569627)
			(xy 418.187859 -23.605302) (xy 418.225076 -23.646839) (xy 418.255849 -23.693352) (xy 418.279521 -23.743849)
			(xy 418.295589 -23.797256) (xy 418.303709 -23.852432) (xy 418.304218 -23.880318) (xy 418.556692 -23.880318)
			(xy 418.560763 -23.824696) (xy 418.572889 -23.770259) (xy 418.592812 -23.718168) (xy 418.620108 -23.669533)
			(xy 418.654194 -23.62539) (xy 418.694343 -23.586681) (xy 418.739701 -23.55423) (xy 418.789301 -23.528729)
			(xy 418.842085 -23.510722) (xy 418.896928 -23.500592) (xy 418.952662 -23.498555) (xy 419.008099 -23.504655)
			(xy 419.062056 -23.518761) (xy 419.113385 -23.540573) (xy 419.160991 -23.569627) (xy 419.203859 -23.605302)
			(xy 419.241076 -23.646839) (xy 419.271849 -23.693352) (xy 419.295521 -23.743849) (xy 419.311589 -23.797256)
			(xy 419.319709 -23.852432) (xy 419.320218 -23.880318) (xy 419.572692 -23.880318) (xy 419.576763 -23.824696)
			(xy 419.588889 -23.770259) (xy 419.608812 -23.718168) (xy 419.636108 -23.669533) (xy 419.670194 -23.62539)
			(xy 419.710343 -23.586681) (xy 419.755701 -23.55423) (xy 419.805301 -23.528729) (xy 419.858085 -23.510722)
			(xy 419.912928 -23.500592) (xy 419.968662 -23.498555) (xy 420.024099 -23.504655) (xy 420.078056 -23.518761)
			(xy 420.129385 -23.540573) (xy 420.176991 -23.569627) (xy 420.219859 -23.605302) (xy 420.257076 -23.646839)
			(xy 420.287849 -23.693352) (xy 420.311521 -23.743849) (xy 420.327589 -23.797256) (xy 420.335709 -23.852432)
			(xy 420.336218 -23.880318) (xy 420.590978 -23.880318) (xy 420.595049 -23.824696) (xy 420.607175 -23.770259)
			(xy 420.627098 -23.718168) (xy 420.654394 -23.669533) (xy 420.68848 -23.62539) (xy 420.728629 -23.586681)
			(xy 420.773987 -23.55423) (xy 420.823587 -23.528729) (xy 420.876371 -23.510722) (xy 420.931214 -23.500592)
			(xy 420.986948 -23.498555) (xy 421.042385 -23.504655) (xy 421.096342 -23.518761) (xy 421.147671 -23.540573)
			(xy 421.195277 -23.569627) (xy 421.238145 -23.605302) (xy 421.275362 -23.646839) (xy 421.306135 -23.693352)
			(xy 421.329807 -23.743849) (xy 421.345875 -23.797256) (xy 421.353995 -23.852432) (xy 421.354504 -23.880318)
			(xy 421.353995 -23.908204) (xy 421.345875 -23.96338) (xy 421.345341 -23.965154) (xy 426.377352 -23.965154)
			(xy 426.381423 -23.909532) (xy 426.393549 -23.855095) (xy 426.413472 -23.803004) (xy 426.440768 -23.754369)
			(xy 426.474854 -23.710226) (xy 426.515003 -23.671517) (xy 426.560361 -23.639066) (xy 426.609961 -23.613565)
			(xy 426.662745 -23.595558) (xy 426.717588 -23.585428) (xy 426.773322 -23.583391) (xy 426.828759 -23.589491)
			(xy 426.882716 -23.603597) (xy 426.934045 -23.625409) (xy 426.981651 -23.654463) (xy 427.024519 -23.690138)
			(xy 427.061736 -23.731675) (xy 427.092509 -23.778188) (xy 427.116181 -23.828685) (xy 427.132249 -23.882092)
			(xy 427.140369 -23.937268) (xy 427.140878 -23.965154) (xy 427.140369 -23.99304) (xy 427.132249 -24.048216)
			(xy 427.116181 -24.101623) (xy 427.092509 -24.15212) (xy 427.061736 -24.198633) (xy 427.024519 -24.24017)
			(xy 426.981651 -24.275845) (xy 426.934045 -24.304899) (xy 426.882716 -24.326711) (xy 426.828759 -24.340817)
			(xy 426.773322 -24.346917) (xy 426.717588 -24.34488) (xy 426.662745 -24.33475) (xy 426.609961 -24.316743)
			(xy 426.560361 -24.291242) (xy 426.515003 -24.258791) (xy 426.474854 -24.220082) (xy 426.440768 -24.175939)
			(xy 426.413472 -24.127304) (xy 426.393549 -24.075213) (xy 426.381423 -24.020776) (xy 426.377352 -23.965154)
			(xy 421.345341 -23.965154) (xy 421.329807 -24.016787) (xy 421.306135 -24.067284) (xy 421.275362 -24.113797)
			(xy 421.238145 -24.155334) (xy 421.195277 -24.191009) (xy 421.147671 -24.220063) (xy 421.096342 -24.241875)
			(xy 421.042385 -24.255981) (xy 420.986948 -24.262081) (xy 420.931214 -24.260044) (xy 420.876371 -24.249914)
			(xy 420.823587 -24.231907) (xy 420.773987 -24.206406) (xy 420.728629 -24.173955) (xy 420.68848 -24.135246)
			(xy 420.654394 -24.091103) (xy 420.627098 -24.042468) (xy 420.607175 -23.990377) (xy 420.595049 -23.93594)
			(xy 420.590978 -23.880318) (xy 420.336218 -23.880318) (xy 420.335709 -23.908204) (xy 420.327589 -23.96338)
			(xy 420.311521 -24.016787) (xy 420.287849 -24.067284) (xy 420.257076 -24.113797) (xy 420.219859 -24.155334)
			(xy 420.176991 -24.191009) (xy 420.129385 -24.220063) (xy 420.078056 -24.241875) (xy 420.024099 -24.255981)
			(xy 419.968662 -24.262081) (xy 419.912928 -24.260044) (xy 419.858085 -24.249914) (xy 419.805301 -24.231907)
			(xy 419.755701 -24.206406) (xy 419.710343 -24.173955) (xy 419.670194 -24.135246) (xy 419.636108 -24.091103)
			(xy 419.608812 -24.042468) (xy 419.588889 -23.990377) (xy 419.576763 -23.93594) (xy 419.572692 -23.880318)
			(xy 419.320218 -23.880318) (xy 419.319709 -23.908204) (xy 419.311589 -23.96338) (xy 419.295521 -24.016787)
			(xy 419.271849 -24.067284) (xy 419.241076 -24.113797) (xy 419.203859 -24.155334) (xy 419.160991 -24.191009)
			(xy 419.113385 -24.220063) (xy 419.062056 -24.241875) (xy 419.008099 -24.255981) (xy 418.952662 -24.262081)
			(xy 418.896928 -24.260044) (xy 418.842085 -24.249914) (xy 418.789301 -24.231907) (xy 418.739701 -24.206406)
			(xy 418.694343 -24.173955) (xy 418.654194 -24.135246) (xy 418.620108 -24.091103) (xy 418.592812 -24.042468)
			(xy 418.572889 -23.990377) (xy 418.560763 -23.93594) (xy 418.556692 -23.880318) (xy 418.304218 -23.880318)
			(xy 418.303709 -23.908204) (xy 418.295589 -23.96338) (xy 418.279521 -24.016787) (xy 418.255849 -24.067284)
			(xy 418.225076 -24.113797) (xy 418.187859 -24.155334) (xy 418.144991 -24.191009) (xy 418.097385 -24.220063)
			(xy 418.046056 -24.241875) (xy 417.992099 -24.255981) (xy 417.936662 -24.262081) (xy 417.880928 -24.260044)
			(xy 417.826085 -24.249914) (xy 417.773301 -24.231907) (xy 417.723701 -24.206406) (xy 417.678343 -24.173955)
			(xy 417.638194 -24.135246) (xy 417.604108 -24.091103) (xy 417.576812 -24.042468) (xy 417.556889 -23.990377)
			(xy 417.544763 -23.93594) (xy 417.540692 -23.880318) (xy 417.013259 -23.880318) (xy 416.988783 -23.900687)
			(xy 416.941177 -23.929741) (xy 416.889848 -23.951553) (xy 416.835891 -23.965659) (xy 416.780454 -23.971759)
			(xy 416.72472 -23.969722) (xy 416.669877 -23.959592) (xy 416.617093 -23.941585) (xy 416.567493 -23.916084)
			(xy 416.522135 -23.883633) (xy 416.481986 -23.844924) (xy 416.4479 -23.800781) (xy 416.420604 -23.752146)
			(xy 416.400681 -23.700055) (xy 416.388555 -23.645618) (xy 416.384484 -23.589996) (xy 413.128346 -23.589996)
			(xy 413.127973 -23.610892) (xy 413.120211 -23.66483) (xy 413.104853 -23.717114) (xy 413.082211 -23.76668)
			(xy 413.052746 -23.81252) (xy 413.017057 -23.8537) (xy 412.975871 -23.889382) (xy 412.930027 -23.91884)
			(xy 412.880457 -23.941475) (xy 412.828171 -23.956824) (xy 412.774232 -23.964577) (xy 412.719739 -23.964575)
			(xy 412.665801 -23.956818) (xy 412.613515 -23.941464) (xy 412.563947 -23.918826) (xy 412.518105 -23.889365)
			(xy 412.476922 -23.853679) (xy 412.441236 -23.812497) (xy 412.411775 -23.766655) (xy 412.389136 -23.717086)
			(xy 412.373782 -23.664801) (xy 412.366025 -23.610863) (xy 412.366023 -23.55637) (xy 401.757302 -23.55637)
			(xy 401.758658 -23.557738) (xy 401.775422 -23.565358) (xy 401.785074 -23.56612) (xy 401.813833 -23.568361)
			(xy 401.870241 -23.580417) (xy 401.924192 -23.600827) (xy 401.974456 -23.629125) (xy 402.019888 -23.664666)
			(xy 402.059452 -23.706641) (xy 402.092247 -23.754093) (xy 402.117526 -23.805941) (xy 402.134713 -23.861003)
			(xy 402.143416 -23.918025) (xy 402.143976 -23.946866) (xy 402.14423 -23.946866) (xy 402.143792 -23.970996)
			(xy 402.372828 -23.970996) (xy 402.376899 -23.915374) (xy 402.389025 -23.860937) (xy 402.408948 -23.808846)
			(xy 402.436244 -23.760211) (xy 402.47033 -23.716068) (xy 402.510479 -23.677359) (xy 402.555837 -23.644908)
			(xy 402.605437 -23.619407) (xy 402.658221 -23.6014) (xy 402.713064 -23.59127) (xy 402.768798 -23.589233)
			(xy 402.824235 -23.595333) (xy 402.878192 -23.609439) (xy 402.929521 -23.631251) (xy 402.977127 -23.660305)
			(xy 403.019995 -23.69598) (xy 403.057212 -23.737517) (xy 403.087985 -23.78403) (xy 403.111657 -23.834527)
			(xy 403.127725 -23.887934) (xy 403.135845 -23.94311) (xy 403.136354 -23.970996) (xy 403.135845 -23.998882)
			(xy 403.127725 -24.054058) (xy 403.111657 -24.107465) (xy 403.087985 -24.157962) (xy 403.087832 -24.158194)
			(xy 407.75077 -24.158194) (xy 407.754841 -24.102572) (xy 407.766967 -24.048135) (xy 407.78689 -23.996044)
			(xy 407.814186 -23.947409) (xy 407.848272 -23.903266) (xy 407.888421 -23.864557) (xy 407.933779 -23.832106)
			(xy 407.983379 -23.806605) (xy 408.036163 -23.788598) (xy 408.091006 -23.778468) (xy 408.14674 -23.776431)
			(xy 408.202177 -23.782531) (xy 408.256134 -23.796637) (xy 408.307463 -23.818449) (xy 408.355069 -23.847503)
			(xy 408.397937 -23.883178) (xy 408.435154 -23.924715) (xy 408.465927 -23.971228) (xy 408.489599 -24.021725)
			(xy 408.505667 -24.075132) (xy 408.513787 -24.130308) (xy 408.514296 -24.158194) (xy 408.513787 -24.18608)
			(xy 408.513218 -24.189944) (xy 411.59887 -24.189944) (xy 411.602941 -24.134322) (xy 411.615067 -24.079885)
			(xy 411.63499 -24.027794) (xy 411.662286 -23.979159) (xy 411.696372 -23.935016) (xy 411.736521 -23.896307)
			(xy 411.781879 -23.863856) (xy 411.831479 -23.838355) (xy 411.884263 -23.820348) (xy 411.939106 -23.810218)
			(xy 411.99484 -23.808181) (xy 412.050277 -23.814281) (xy 412.104234 -23.828387) (xy 412.155563 -23.850199)
			(xy 412.203169 -23.879253) (xy 412.246037 -23.914928) (xy 412.283254 -23.956465) (xy 412.314027 -24.002978)
			(xy 412.337699 -24.053475) (xy 412.353767 -24.106882) (xy 412.361887 -24.162058) (xy 412.362396 -24.189944)
			(xy 414.121852 -24.189944) (xy 414.125923 -24.134322) (xy 414.138049 -24.079885) (xy 414.157972 -24.027794)
			(xy 414.185268 -23.979159) (xy 414.219354 -23.935016) (xy 414.259503 -23.896307) (xy 414.304861 -23.863856)
			(xy 414.354461 -23.838355) (xy 414.407245 -23.820348) (xy 414.462088 -23.810218) (xy 414.517822 -23.808181)
			(xy 414.573259 -23.814281) (xy 414.627216 -23.828387) (xy 414.678545 -23.850199) (xy 414.726151 -23.879253)
			(xy 414.769019 -23.914928) (xy 414.806236 -23.956465) (xy 414.837009 -24.002978) (xy 414.860681 -24.053475)
			(xy 414.876749 -24.106882) (xy 414.884869 -24.162058) (xy 414.885378 -24.189944) (xy 414.884869 -24.21783)
			(xy 414.876749 -24.273006) (xy 414.860681 -24.326413) (xy 414.837009 -24.37691) (xy 414.806236 -24.423423)
			(xy 414.769019 -24.46496) (xy 414.726151 -24.500635) (xy 414.678545 -24.529689) (xy 414.627216 -24.551501)
			(xy 414.573259 -24.565607) (xy 414.517822 -24.571707) (xy 414.462088 -24.56967) (xy 414.407245 -24.55954)
			(xy 414.354461 -24.541533) (xy 414.304861 -24.516032) (xy 414.259503 -24.483581) (xy 414.219354 -24.444872)
			(xy 414.185268 -24.400729) (xy 414.157972 -24.352094) (xy 414.138049 -24.300003) (xy 414.125923 -24.245566)
			(xy 414.121852 -24.189944) (xy 412.362396 -24.189944) (xy 412.361887 -24.21783) (xy 412.353767 -24.273006)
			(xy 412.337699 -24.326413) (xy 412.314027 -24.37691) (xy 412.283254 -24.423423) (xy 412.246037 -24.46496)
			(xy 412.203169 -24.500635) (xy 412.155563 -24.529689) (xy 412.104234 -24.551501) (xy 412.050277 -24.565607)
			(xy 411.99484 -24.571707) (xy 411.939106 -24.56967) (xy 411.884263 -24.55954) (xy 411.831479 -24.541533)
			(xy 411.781879 -24.516032) (xy 411.736521 -24.483581) (xy 411.696372 -24.444872) (xy 411.662286 -24.400729)
			(xy 411.63499 -24.352094) (xy 411.615067 -24.300003) (xy 411.602941 -24.245566) (xy 411.59887 -24.189944)
			(xy 408.513218 -24.189944) (xy 408.505667 -24.241256) (xy 408.489599 -24.294663) (xy 408.465927 -24.34516)
			(xy 408.435154 -24.391673) (xy 408.397937 -24.43321) (xy 408.355069 -24.468885) (xy 408.307463 -24.497939)
			(xy 408.256134 -24.519751) (xy 408.202177 -24.533857) (xy 408.14674 -24.539957) (xy 408.091006 -24.53792)
			(xy 408.036163 -24.52779) (xy 407.983379 -24.509783) (xy 407.933779 -24.484282) (xy 407.888421 -24.451831)
			(xy 407.848272 -24.413122) (xy 407.814186 -24.368979) (xy 407.78689 -24.320344) (xy 407.766967 -24.268253)
			(xy 407.754841 -24.213816) (xy 407.75077 -24.158194) (xy 403.087832 -24.158194) (xy 403.057212 -24.204475)
			(xy 403.019995 -24.246012) (xy 402.977127 -24.281687) (xy 402.929521 -24.310741) (xy 402.878192 -24.332553)
			(xy 402.824235 -24.346659) (xy 402.768798 -24.352759) (xy 402.713064 -24.350722) (xy 402.658221 -24.340592)
			(xy 402.605437 -24.322585) (xy 402.555837 -24.297084) (xy 402.510479 -24.264633) (xy 402.47033 -24.225924)
			(xy 402.436244 -24.181781) (xy 402.408948 -24.133146) (xy 402.389025 -24.081055) (xy 402.376899 -24.026618)
			(xy 402.372828 -23.970996) (xy 402.143792 -23.970996) (xy 402.143716 -23.975195) (xy 402.135344 -24.031232)
			(xy 402.118779 -24.085416) (xy 402.094385 -24.136554) (xy 402.062698 -24.183524) (xy 402.024416 -24.225293)
			(xy 401.980378 -24.260943) (xy 401.931553 -24.28969) (xy 401.879015 -24.310902) (xy 401.823918 -24.324114)
			(xy 401.795742 -24.327104) (xy 401.784566 -24.327866) (xy 401.775168 -24.332692) (xy 401.771282 -24.3348)
			(xy 401.764255 -24.340166) (xy 401.761198 -24.34336) (xy 401.714462 -24.393906) (xy 401.708277 -24.401165)
			(xy 401.701356 -24.41892) (xy 401.701 -24.42845) (xy 401.701 -24.807418) (xy 408.920186 -24.807418)
			(xy 408.924257 -24.751796) (xy 408.936383 -24.697359) (xy 408.956306 -24.645268) (xy 408.983602 -24.596633)
			(xy 409.017688 -24.55249) (xy 409.057837 -24.513781) (xy 409.103195 -24.48133) (xy 409.152795 -24.455829)
			(xy 409.205579 -24.437822) (xy 409.260422 -24.427692) (xy 409.316156 -24.425655) (xy 409.371593 -24.431755)
			(xy 409.42555 -24.445861) (xy 409.476879 -24.467673) (xy 409.524485 -24.496727) (xy 409.567353 -24.532402)
			(xy 409.60457 -24.573939) (xy 409.635343 -24.620452) (xy 409.659015 -24.670949) (xy 409.675083 -24.724356)
			(xy 409.68013 -24.75865) (xy 421.168574 -24.75865) (xy 421.172645 -24.703028) (xy 421.184771 -24.648591)
			(xy 421.204694 -24.5965) (xy 421.23199 -24.547865) (xy 421.266076 -24.503722) (xy 421.306225 -24.465013)
			(xy 421.351583 -24.432562) (xy 421.401183 -24.407061) (xy 421.453967 -24.389054) (xy 421.50881 -24.378924)
			(xy 421.564544 -24.376887) (xy 421.619981 -24.382987) (xy 421.673938 -24.397093) (xy 421.725267 -24.418905)
			(xy 421.772873 -24.447959) (xy 421.815741 -24.483634) (xy 421.852958 -24.525171) (xy 421.883731 -24.571684)
			(xy 421.907403 -24.622181) (xy 421.923471 -24.675588) (xy 421.931591 -24.730764) (xy 421.9321 -24.75865)
			(xy 421.931591 -24.786536) (xy 421.923471 -24.841712) (xy 421.907403 -24.895119) (xy 421.883731 -24.945616)
			(xy 421.852958 -24.992129) (xy 421.815741 -25.033666) (xy 421.772873 -25.069341) (xy 421.725267 -25.098395)
			(xy 421.673938 -25.120207) (xy 421.619981 -25.134313) (xy 421.564544 -25.140413) (xy 421.50881 -25.138376)
			(xy 421.453967 -25.128246) (xy 421.401183 -25.110239) (xy 421.351583 -25.084738) (xy 421.306225 -25.052287)
			(xy 421.266076 -25.013578) (xy 421.23199 -24.969435) (xy 421.204694 -24.9208) (xy 421.184771 -24.868709)
			(xy 421.172645 -24.814272) (xy 421.168574 -24.75865) (xy 409.68013 -24.75865) (xy 409.683203 -24.779532)
			(xy 409.683712 -24.807418) (xy 409.683203 -24.835304) (xy 409.675083 -24.89048) (xy 409.659015 -24.943887)
			(xy 409.635343 -24.994384) (xy 409.60457 -25.040897) (xy 409.567353 -25.082434) (xy 409.524485 -25.118109)
			(xy 409.476879 -25.147163) (xy 409.42555 -25.168975) (xy 409.371593 -25.183081) (xy 409.316156 -25.189181)
			(xy 409.260422 -25.187144) (xy 409.205579 -25.177014) (xy 409.152795 -25.159007) (xy 409.103195 -25.133506)
			(xy 409.057837 -25.101055) (xy 409.017688 -25.062346) (xy 408.983602 -25.018203) (xy 408.956306 -24.969568)
			(xy 408.936383 -24.917477) (xy 408.924257 -24.86304) (xy 408.920186 -24.807418) (xy 401.701 -24.807418)
			(xy 401.701 -25.390094) (xy 414.109662 -25.390094) (xy 414.110148 -25.362843) (xy 414.117904 -25.308895)
			(xy 414.133259 -25.2566) (xy 414.155901 -25.207023) (xy 414.185367 -25.161173) (xy 414.221058 -25.119982)
			(xy 414.262249 -25.084291) (xy 414.308099 -25.054825) (xy 414.357676 -25.032183) (xy 414.409971 -25.016828)
			(xy 414.463919 -25.009072) (xy 414.518421 -25.009072) (xy 414.572369 -25.016828) (xy 414.624664 -25.032183)
			(xy 414.674241 -25.054825) (xy 414.720091 -25.084291) (xy 414.761282 -25.119982) (xy 414.796973 -25.161173)
			(xy 414.826439 -25.207023) (xy 414.849081 -25.2566) (xy 414.864436 -25.308895) (xy 414.872192 -25.362843)
			(xy 414.872678 -25.390094) (xy 414.872096 -25.419113) (xy 414.863307 -25.476482) (xy 414.84593 -25.531859)
			(xy 414.820367 -25.583964) (xy 414.787207 -25.631597) (xy 414.747215 -25.673658) (xy 414.724596 -25.691846)
			(xy 414.714051 -25.700616) (xy 414.69761 -25.72255) (xy 414.687604 -25.748072) (xy 414.684757 -25.775336)
			(xy 414.689275 -25.802373) (xy 414.70083 -25.827231) (xy 414.718588 -25.848114) (xy 414.729676 -25.856184)
			(xy 414.751309 -25.871514) (xy 414.790567 -25.907149) (xy 414.824511 -25.947878) (xy 414.852487 -25.992916)
			(xy 414.873954 -26.041395) (xy 414.8885 -26.09238) (xy 414.895844 -26.144888) (xy 414.8963 -26.171398)
			(xy 414.895814 -26.198649) (xy 414.888058 -26.252597) (xy 414.872703 -26.304892) (xy 414.850061 -26.354469)
			(xy 414.820595 -26.400319) (xy 414.784904 -26.44151) (xy 414.743713 -26.477201) (xy 414.697863 -26.506667)
			(xy 414.648286 -26.529309) (xy 414.595991 -26.544664) (xy 414.542043 -26.55242) (xy 414.487541 -26.55242)
			(xy 414.433593 -26.544664) (xy 414.381298 -26.529309) (xy 414.331721 -26.506667) (xy 414.285871 -26.477201)
			(xy 414.24468 -26.44151) (xy 414.208989 -26.400319) (xy 414.179523 -26.354469) (xy 414.156881 -26.304892)
			(xy 414.141526 -26.252597) (xy 414.13377 -26.198649) (xy 414.133284 -26.171398) (xy 414.133836 -26.142377)
			(xy 414.142628 -26.085006) (xy 414.160009 -26.029628) (xy 414.185578 -25.977522) (xy 414.218745 -25.92989)
			(xy 414.258744 -25.887832) (xy 414.281366 -25.869646) (xy 414.291924 -25.860889) (xy 414.308371 -25.838953)
			(xy 414.318381 -25.813428) (xy 414.321228 -25.786159) (xy 414.316707 -25.759117) (xy 414.305145 -25.734257)
			(xy 414.287378 -25.713376) (xy 414.276286 -25.705308) (xy 414.25464 -25.689995) (xy 414.215384 -25.654356)
			(xy 414.181443 -25.613623) (xy 414.153469 -25.568582) (xy 414.132004 -25.520101) (xy 414.11746 -25.469114)
			(xy 414.110117 -25.416604) (xy 414.109662 -25.390094) (xy 401.701 -25.390094) (xy 401.701 -25.971246)
			(xy 402.259798 -25.971246) (xy 402.263869 -25.915624) (xy 402.275995 -25.861187) (xy 402.295918 -25.809096)
			(xy 402.323214 -25.760461) (xy 402.3573 -25.716318) (xy 402.397449 -25.677609) (xy 402.442807 -25.645158)
			(xy 402.492407 -25.619657) (xy 402.545191 -25.60165) (xy 402.600034 -25.59152) (xy 402.655768 -25.589483)
			(xy 402.711205 -25.595583) (xy 402.765162 -25.609689) (xy 402.816491 -25.631501) (xy 402.864097 -25.660555)
			(xy 402.906965 -25.69623) (xy 402.944182 -25.737767) (xy 402.974955 -25.78428) (xy 402.998627 -25.834777)
			(xy 403.014695 -25.888184) (xy 403.022815 -25.94336) (xy 403.023324 -25.971246) (xy 403.275798 -25.971246)
			(xy 403.279869 -25.915624) (xy 403.291995 -25.861187) (xy 403.311918 -25.809096) (xy 403.339214 -25.760461)
			(xy 403.3733 -25.716318) (xy 403.413449 -25.677609) (xy 403.458807 -25.645158) (xy 403.508407 -25.619657)
			(xy 403.561191 -25.60165) (xy 403.616034 -25.59152) (xy 403.671768 -25.589483) (xy 403.727205 -25.595583)
			(xy 403.781162 -25.609689) (xy 403.832491 -25.631501) (xy 403.880097 -25.660555) (xy 403.922965 -25.69623)
			(xy 403.960182 -25.737767) (xy 403.990955 -25.78428) (xy 404.014627 -25.834777) (xy 404.030695 -25.888184)
			(xy 404.038815 -25.94336) (xy 404.039324 -25.971246) (xy 404.291798 -25.971246) (xy 404.295869 -25.915624)
			(xy 404.307995 -25.861187) (xy 404.327918 -25.809096) (xy 404.355214 -25.760461) (xy 404.3893 -25.716318)
			(xy 404.429449 -25.677609) (xy 404.474807 -25.645158) (xy 404.524407 -25.619657) (xy 404.577191 -25.60165)
			(xy 404.632034 -25.59152) (xy 404.687768 -25.589483) (xy 404.743205 -25.595583) (xy 404.797162 -25.609689)
			(xy 404.848491 -25.631501) (xy 404.896097 -25.660555) (xy 404.938965 -25.69623) (xy 404.976182 -25.737767)
			(xy 405.006955 -25.78428) (xy 405.030627 -25.834777) (xy 405.046695 -25.888184) (xy 405.054815 -25.94336)
			(xy 405.055324 -25.971246) (xy 405.054815 -25.999132) (xy 405.049723 -26.03373) (xy 405.567894 -26.03373)
			(xy 405.571965 -25.978108) (xy 405.584091 -25.923671) (xy 405.604014 -25.87158) (xy 405.63131 -25.822945)
			(xy 405.665396 -25.778802) (xy 405.705545 -25.740093) (xy 405.750903 -25.707642) (xy 405.800503 -25.682141)
			(xy 405.853287 -25.664134) (xy 405.90813 -25.654004) (xy 405.963864 -25.651967) (xy 406.019301 -25.658067)
			(xy 406.073258 -25.672173) (xy 406.124587 -25.693985) (xy 406.172193 -25.723039) (xy 406.215061 -25.758714)
			(xy 406.252278 -25.800251) (xy 406.283051 -25.846764) (xy 406.306723 -25.897261) (xy 406.322791 -25.950668)
			(xy 406.330911 -26.005844) (xy 406.33142 -26.03373) (xy 406.330911 -26.061616) (xy 406.322791 -26.116792)
			(xy 406.306723 -26.170199) (xy 406.283051 -26.220696) (xy 406.252817 -26.266394) (xy 408.82062 -26.266394)
			(xy 408.82105 -26.23914) (xy 408.828808 -26.185186) (xy 408.844167 -26.132886) (xy 408.866812 -26.083304)
			(xy 408.896283 -26.03745) (xy 408.93198 -25.996256) (xy 408.973177 -25.960563) (xy 409.019034 -25.931095)
			(xy 409.068618 -25.908455) (xy 409.120919 -25.893101) (xy 409.174874 -25.885347) (xy 409.202128 -25.884886)
			(xy 409.231454 -25.8854) (xy 409.289412 -25.894387) (xy 409.345311 -25.912145) (xy 409.397831 -25.938253)
			(xy 409.422092 -25.954736) (xy 409.432506 -25.961848) (xy 409.45689 -25.96515) (xy 409.559252 -25.927304)
			(xy 409.576016 -25.908762) (xy 409.579064 -25.89657) (xy 409.586383 -25.869477) (xy 409.607945 -25.817663)
			(xy 409.636868 -25.769568) (xy 409.672527 -25.726232) (xy 409.714152 -25.688589) (xy 409.760844 -25.657454)
			(xy 409.811596 -25.633497) (xy 409.86531 -25.617237) (xy 409.920827 -25.609025) (xy 409.948888 -25.608534)
			(xy 409.976144 -25.608912) (xy 410.030103 -25.616669) (xy 410.082408 -25.632025) (xy 410.131995 -25.65467)
			(xy 410.177855 -25.684141) (xy 410.219053 -25.719838) (xy 410.254752 -25.761036) (xy 410.284225 -25.806895)
			(xy 410.306871 -25.856481) (xy 410.322229 -25.908786) (xy 410.329987 -25.962744) (xy 410.329987 -25.990042)
			(xy 411.59887 -25.990042) (xy 411.602941 -25.93442) (xy 411.615067 -25.879983) (xy 411.63499 -25.827892)
			(xy 411.662286 -25.779257) (xy 411.696372 -25.735114) (xy 411.736521 -25.696405) (xy 411.781879 -25.663954)
			(xy 411.831479 -25.638453) (xy 411.884263 -25.620446) (xy 411.939106 -25.610316) (xy 411.99484 -25.608279)
			(xy 412.050277 -25.614379) (xy 412.104234 -25.628485) (xy 412.155563 -25.650297) (xy 412.203169 -25.679351)
			(xy 412.246037 -25.715026) (xy 412.283254 -25.756563) (xy 412.314027 -25.803076) (xy 412.337699 -25.853573)
			(xy 412.353767 -25.90698) (xy 412.361887 -25.962156) (xy 412.362396 -25.990042) (xy 412.361887 -26.017928)
			(xy 412.353767 -26.073104) (xy 412.337699 -26.126511) (xy 412.314027 -26.177008) (xy 412.283254 -26.223521)
			(xy 412.246037 -26.265058) (xy 412.203169 -26.300733) (xy 412.155563 -26.329787) (xy 412.104234 -26.351599)
			(xy 412.050277 -26.365705) (xy 411.99484 -26.371805) (xy 411.939106 -26.369768) (xy 411.884263 -26.359638)
			(xy 411.831479 -26.341631) (xy 411.781879 -26.31613) (xy 411.736521 -26.283679) (xy 411.696372 -26.24497)
			(xy 411.662286 -26.200827) (xy 411.63499 -26.152192) (xy 411.615067 -26.100101) (xy 411.602941 -26.045664)
			(xy 411.59887 -25.990042) (xy 410.329987 -25.990042) (xy 410.329987 -26.017256) (xy 410.322229 -26.071214)
			(xy 410.306871 -26.123519) (xy 410.284225 -26.173105) (xy 410.254752 -26.218964) (xy 410.219053 -26.260162)
			(xy 410.177855 -26.295859) (xy 410.131995 -26.32533) (xy 410.082408 -26.347975) (xy 410.030103 -26.363331)
			(xy 409.976144 -26.371088) (xy 409.948888 -26.37155) (xy 409.919563 -26.371021) (xy 409.861605 -26.362038)
			(xy 409.805707 -26.344284) (xy 409.753186 -26.31818) (xy 409.728924 -26.3017) (xy 409.71851 -26.294588)
			(xy 409.694126 -26.291286) (xy 409.591764 -26.329132) (xy 409.575 -26.347674) (xy 409.571952 -26.359866)
			(xy 409.56517 -26.384898) (xy 409.545754 -26.432989) (xy 409.519997 -26.478003) (xy 409.488375 -26.519109)
			(xy 409.451472 -26.555549) (xy 409.430982 -26.571448) (xy 409.420822 -26.579322) (xy 409.410154 -26.601928)
			(xy 409.415742 -26.711656) (xy 409.428696 -26.733246) (xy 409.439618 -26.73985) (xy 409.463359 -26.754748)
			(xy 409.506593 -26.790416) (xy 409.544144 -26.832025) (xy 409.575203 -26.87868) (xy 409.599102 -26.929377)
			(xy 409.615326 -26.983025) (xy 409.623527 -27.03847) (xy 409.624022 -27.066494) (xy 409.623536 -27.093745)
			(xy 409.61578 -27.147693) (xy 409.600425 -27.199988) (xy 409.577783 -27.249565) (xy 409.548317 -27.295415)
			(xy 409.512626 -27.336606) (xy 409.471435 -27.372297) (xy 409.425585 -27.401763) (xy 409.376008 -27.424405)
			(xy 409.323713 -27.43976) (xy 409.269765 -27.447516) (xy 409.215263 -27.447516) (xy 409.161315 -27.43976)
			(xy 409.10902 -27.424405) (xy 409.059443 -27.401763) (xy 409.013593 -27.372297) (xy 408.972402 -27.336606)
			(xy 408.936711 -27.295415) (xy 408.907245 -27.249565) (xy 408.884603 -27.199988) (xy 408.869248 -27.147693)
			(xy 408.861492 -27.093745) (xy 408.861006 -27.066494) (xy 408.861547 -27.037006) (xy 408.870644 -26.978735)
			(xy 408.888604 -26.922559) (xy 408.914999 -26.869819) (xy 408.9492 -26.821771) (xy 408.990391 -26.779562)
			(xy 409.01366 -26.76144) (xy 409.02382 -26.753566) (xy 409.034488 -26.73096) (xy 409.0289 -26.621232)
			(xy 409.015946 -26.599642) (xy 409.005024 -26.593038) (xy 408.981288 -26.578133) (xy 408.938051 -26.542468)
			(xy 408.900499 -26.500861) (xy 408.869438 -26.454207) (xy 408.845538 -26.40351) (xy 408.829314 -26.349862)
			(xy 408.821114 -26.294418) (xy 408.82062 -26.266394) (xy 406.252817 -26.266394) (xy 406.252278 -26.267209)
			(xy 406.215061 -26.308746) (xy 406.172193 -26.344421) (xy 406.124587 -26.373475) (xy 406.073258 -26.395287)
			(xy 406.019301 -26.409393) (xy 405.963864 -26.415493) (xy 405.90813 -26.413456) (xy 405.853287 -26.403326)
			(xy 405.800503 -26.385319) (xy 405.750903 -26.359818) (xy 405.705545 -26.327367) (xy 405.665396 -26.288658)
			(xy 405.63131 -26.244515) (xy 405.604014 -26.19588) (xy 405.584091 -26.143789) (xy 405.571965 -26.089352)
			(xy 405.567894 -26.03373) (xy 405.049723 -26.03373) (xy 405.046695 -26.054308) (xy 405.030627 -26.107715)
			(xy 405.006955 -26.158212) (xy 404.976182 -26.204725) (xy 404.938965 -26.246262) (xy 404.896097 -26.281937)
			(xy 404.848491 -26.310991) (xy 404.797162 -26.332803) (xy 404.743205 -26.346909) (xy 404.687768 -26.353009)
			(xy 404.632034 -26.350972) (xy 404.577191 -26.340842) (xy 404.524407 -26.322835) (xy 404.474807 -26.297334)
			(xy 404.429449 -26.264883) (xy 404.3893 -26.226174) (xy 404.355214 -26.182031) (xy 404.327918 -26.133396)
			(xy 404.307995 -26.081305) (xy 404.295869 -26.026868) (xy 404.291798 -25.971246) (xy 404.039324 -25.971246)
			(xy 404.038815 -25.999132) (xy 404.030695 -26.054308) (xy 404.014627 -26.107715) (xy 403.990955 -26.158212)
			(xy 403.960182 -26.204725) (xy 403.922965 -26.246262) (xy 403.880097 -26.281937) (xy 403.832491 -26.310991)
			(xy 403.781162 -26.332803) (xy 403.727205 -26.346909) (xy 403.671768 -26.353009) (xy 403.616034 -26.350972)
			(xy 403.561191 -26.340842) (xy 403.508407 -26.322835) (xy 403.458807 -26.297334) (xy 403.413449 -26.264883)
			(xy 403.3733 -26.226174) (xy 403.339214 -26.182031) (xy 403.311918 -26.133396) (xy 403.291995 -26.081305)
			(xy 403.279869 -26.026868) (xy 403.275798 -25.971246) (xy 403.023324 -25.971246) (xy 403.022815 -25.999132)
			(xy 403.014695 -26.054308) (xy 402.998627 -26.107715) (xy 402.974955 -26.158212) (xy 402.944182 -26.204725)
			(xy 402.906965 -26.246262) (xy 402.864097 -26.281937) (xy 402.816491 -26.310991) (xy 402.765162 -26.332803)
			(xy 402.711205 -26.346909) (xy 402.655768 -26.353009) (xy 402.600034 -26.350972) (xy 402.545191 -26.340842)
			(xy 402.492407 -26.322835) (xy 402.442807 -26.297334) (xy 402.397449 -26.264883) (xy 402.3573 -26.226174)
			(xy 402.323214 -26.182031) (xy 402.295918 -26.133396) (xy 402.275995 -26.081305) (xy 402.263869 -26.026868)
			(xy 402.259798 -25.971246) (xy 401.701 -25.971246) (xy 401.701 -27.654758) (xy 401.701359 -27.664322)
			(xy 401.708291 -27.682145) (xy 401.721281 -27.69618) (xy 401.729702 -27.700732) (xy 401.729956 -27.700732)
			(xy 401.756759 -27.714211) (xy 401.806167 -27.74824) (xy 401.815342 -27.756955) (xy 405.059043 -27.756955)
			(xy 405.059043 -27.702445) (xy 405.066801 -27.648489) (xy 405.082159 -27.596187) (xy 405.104805 -27.546603)
			(xy 405.134277 -27.500747) (xy 405.169976 -27.459552) (xy 405.211174 -27.423857) (xy 405.257033 -27.394389)
			(xy 405.306619 -27.371747) (xy 405.358922 -27.356394) (xy 405.412879 -27.348641) (xy 405.440134 -27.34818)
			(xy 405.454219 -27.348281) (xy 405.482315 -27.350315) (xy 405.496268 -27.352244) (xy 405.509984 -27.354276)
			(xy 405.535892 -27.343862) (xy 405.60625 -27.249882) (xy 405.609298 -27.221942) (xy 405.603456 -27.209242)
			(xy 405.592414 -27.184113) (xy 405.57681 -27.131489) (xy 405.568904 -27.077174) (xy 405.568404 -27.04973)
			(xy 405.56889 -27.022479) (xy 405.576646 -26.968531) (xy 405.592001 -26.916236) (xy 405.614643 -26.866659)
			(xy 405.644109 -26.820809) (xy 405.6798 -26.779618) (xy 405.720991 -26.743927) (xy 405.766841 -26.714461)
			(xy 405.816418 -26.691819) (xy 405.868713 -26.676464) (xy 405.922661 -26.668708) (xy 405.977163 -26.668708)
			(xy 406.031111 -26.676464) (xy 406.083406 -26.691819) (xy 406.132983 -26.714461) (xy 406.178833 -26.743927)
			(xy 406.220024 -26.779618) (xy 406.255715 -26.820809) (xy 406.285181 -26.866659) (xy 406.307823 -26.916236)
			(xy 406.323178 -26.968531) (xy 406.330934 -27.022479) (xy 406.33142 -27.04973) (xy 406.330797 -27.081146)
			(xy 406.320535 -27.143133) (xy 406.300261 -27.202602) (xy 406.285954 -27.230578) (xy 406.28062 -27.24023)
			(xy 406.279096 -27.262074) (xy 406.313386 -27.354022) (xy 406.328626 -27.369516) (xy 406.338786 -27.37358)
			(xy 406.365427 -27.384353) (xy 406.415395 -27.41273) (xy 406.460538 -27.448285) (xy 406.499834 -27.490212)
			(xy 406.532393 -27.537562) (xy 406.557476 -27.589262) (xy 406.574516 -27.644141) (xy 406.583127 -27.700956)
			(xy 406.583642 -27.729688) (xy 406.583111 -27.756937) (xy 406.575357 -27.810882) (xy 406.560005 -27.863173)
			(xy 406.537368 -27.912748) (xy 406.507906 -27.958597) (xy 406.472219 -27.999786) (xy 406.431034 -28.035478)
			(xy 406.385189 -28.064945) (xy 406.335617 -28.087589) (xy 406.283327 -28.102947) (xy 406.229383 -28.110707)
			(xy 406.202134 -28.111196) (xy 406.173218 -28.110655) (xy 406.116048 -28.101931) (xy 406.060849 -28.084677)
			(xy 406.008888 -28.05929) (xy 405.961353 -28.026351) (xy 405.919335 -27.986614) (xy 405.901144 -27.96413)
			(xy 405.893571 -27.955381) (xy 405.87282 -27.945193) (xy 405.861266 -27.944572) (xy 405.781002 -27.944572)
			(xy 405.76943 -27.945119) (xy 405.748658 -27.955328) (xy 405.741124 -27.96413) (xy 405.722927 -27.986608)
			(xy 405.680908 -28.026342) (xy 405.633374 -28.059281) (xy 405.581414 -28.08467) (xy 405.526218 -28.101928)
			(xy 405.46905 -28.110659) (xy 405.440134 -28.111196) (xy 405.412879 -28.110759) (xy 405.358922 -28.103006)
			(xy 405.306619 -28.087653) (xy 405.257033 -28.065011) (xy 405.211174 -28.035543) (xy 405.169976 -27.999848)
			(xy 405.134277 -27.958653) (xy 405.104805 -27.912797) (xy 405.082159 -27.863213) (xy 405.066801 -27.810911)
			(xy 405.059043 -27.756955) (xy 401.815342 -27.756955) (xy 401.849663 -27.789557) (xy 401.868386 -27.813)
			(xy 401.870672 -27.816048) (xy 401.873212 -27.818588) (xy 401.87626 -27.821636) (xy 401.882219 -27.827146)
			(xy 401.896723 -27.834411) (xy 401.904708 -27.83586) (xy 401.915884 -27.837638) (xy 401.983702 -27.847544)
			(xy 402.00326 -27.842464) (xy 402.011388 -27.836114) (xy 402.031438 -27.821289) (xy 402.074654 -27.796413)
			(xy 402.120742 -27.777379) (xy 402.168917 -27.76451) (xy 402.218358 -27.758026) (xy 402.24329 -27.757628)
			(xy 402.27134 -27.758123) (xy 402.326836 -27.766336) (xy 402.380531 -27.782586) (xy 402.431267 -27.806523)
			(xy 402.477953 -27.837631) (xy 402.51958 -27.875239) (xy 402.555252 -27.918537) (xy 402.570188 -27.942286)
			(xy 402.573744 -27.947874) (xy 402.58238 -27.956764) (xy 402.608288 -27.97175) (xy 402.618448 -27.976322)
			(xy 402.627846 -27.978608) (xy 402.633942 -27.978862) (xy 402.687536 -27.978862) (xy 402.693973 -27.978656)
			(xy 402.706441 -27.975446) (xy 402.712174 -27.972512) (xy 402.737828 -27.958288) (xy 402.746972 -27.949398)
			(xy 402.750528 -27.94381) (xy 402.761599 -27.926394) (xy 402.786927 -27.893811) (xy 402.801074 -27.878786)
			(xy 402.801582 -27.878278) (xy 402.80209 -27.87777) (xy 402.82019 -27.859166) (xy 402.860549 -27.826529)
			(xy 402.904958 -27.799663) (xy 402.952599 -27.779062) (xy 403.002591 -27.765107) (xy 403.054014 -27.758055)
			(xy 403.079966 -27.757628) (xy 403.10722 -27.758089) (xy 403.161172 -27.765842) (xy 403.213472 -27.781196)
			(xy 403.263054 -27.803837) (xy 403.308909 -27.833304) (xy 403.350103 -27.868999) (xy 403.385797 -27.910193)
			(xy 403.415264 -27.956048) (xy 403.437905 -28.00563) (xy 403.453258 -28.05793) (xy 403.461011 -28.111882)
			(xy 403.461474 -28.139136) (xy 403.967948 -28.139136) (xy 403.972019 -28.083514) (xy 403.984145 -28.029077)
			(xy 404.004068 -27.976986) (xy 404.031364 -27.928351) (xy 404.06545 -27.884208) (xy 404.105599 -27.845499)
			(xy 404.150957 -27.813048) (xy 404.200557 -27.787547) (xy 404.253341 -27.76954) (xy 404.308184 -27.75941)
			(xy 404.363918 -27.757373) (xy 404.419355 -27.763473) (xy 404.473312 -27.777579) (xy 404.524641 -27.799391)
			(xy 404.572247 -27.828445) (xy 404.615115 -27.86412) (xy 404.652332 -27.905657) (xy 404.683105 -27.95217)
			(xy 404.706777 -28.002667) (xy 404.722845 -28.056074) (xy 404.730965 -28.11125) (xy 404.731474 -28.139136)
			(xy 404.730965 -28.167022) (xy 404.722845 -28.222198) (xy 404.706777 -28.275605) (xy 404.683105 -28.326102)
			(xy 404.652332 -28.372615) (xy 404.615115 -28.414152) (xy 404.572247 -28.449827) (xy 404.524641 -28.478881)
			(xy 404.473312 -28.500693) (xy 404.419355 -28.514799) (xy 404.363918 -28.520899) (xy 404.308184 -28.518862)
			(xy 404.253341 -28.508732) (xy 404.200557 -28.490725) (xy 404.150957 -28.465224) (xy 404.105599 -28.432773)
			(xy 404.06545 -28.394064) (xy 404.031364 -28.349921) (xy 404.004068 -28.301286) (xy 403.984145 -28.249195)
			(xy 403.972019 -28.194758) (xy 403.967948 -28.139136) (xy 403.461474 -28.139136) (xy 403.460938 -28.168435)
			(xy 403.451979 -28.226343) (xy 403.434276 -28.282202) (xy 403.408247 -28.334701) (xy 403.374501 -28.382605)
			(xy 403.35454 -28.404058) (xy 403.353778 -28.40482) (xy 403.352 -28.406598) (xy 403.333927 -28.425059)
			(xy 403.293665 -28.457432) (xy 403.2494 -28.48407) (xy 403.201942 -28.504486) (xy 403.152162 -28.518305)
			(xy 403.100971 -28.525275) (xy 403.07514 -28.525724) (xy 403.046587 -28.525187) (xy 402.99012 -28.516671)
			(xy 402.935552 -28.499837) (xy 402.8841 -28.475063) (xy 402.836913 -28.4429) (xy 402.795044 -28.404066)
			(xy 402.759427 -28.359429) (xy 402.744686 -28.33497) (xy 402.739906 -28.327476) (xy 402.726303 -28.31606)
			(xy 402.709623 -28.309961) (xy 402.700744 -28.30957) (xy 402.614638 -28.30957) (xy 402.605846 -28.309934)
			(xy 402.589297 -28.31588) (xy 402.575742 -28.327081) (xy 402.57095 -28.334462) (xy 402.560097 -28.352116)
			(xy 402.535153 -28.385211) (xy 402.521166 -28.400502) (xy 402.520404 -28.401264) (xy 402.519388 -28.402534)
			(xy 402.518626 -28.403296) (xy 402.518372 -28.40355) (xy 402.500242 -28.422463) (xy 402.4597 -28.455645)
			(xy 402.415001 -28.482973) (xy 402.366986 -28.503933) (xy 402.316557 -28.518133) (xy 402.264659 -28.525304)
			(xy 402.238464 -28.525724) (xy 402.209307 -28.525169) (xy 402.151673 -28.516292) (xy 402.096061 -28.49875)
			(xy 402.043764 -28.472952) (xy 401.996001 -28.439498) (xy 401.953884 -28.399167) (xy 401.935696 -28.376372)
			(xy 401.93341 -28.373324) (xy 401.93087 -28.370784) (xy 401.927822 -28.367736) (xy 401.921861 -28.36223)
			(xy 401.907356 -28.354975) (xy 401.899374 -28.353512) (xy 401.834858 -28.34386) (xy 401.82891 -28.343131)
			(xy 401.816976 -28.34417) (xy 401.811236 -28.345892) (xy 401.791678 -28.352496) (xy 401.785836 -28.35656)
			(xy 401.779994 -28.36037) (xy 401.774914 -28.363926) (xy 401.770596 -28.368752) (xy 401.763484 -28.378658)
			(xy 401.752054 -28.399486) (xy 401.749229 -28.405115) (xy 401.746145 -28.417321) (xy 401.745958 -28.423616)
			(xy 401.745958 -28.428696) (xy 401.746142 -28.435136) (xy 401.749346 -28.447613) (xy 401.752308 -28.453334)
			(xy 401.756626 -28.460954) (xy 401.759813 -28.466304) (xy 401.768283 -28.475426) (xy 401.77339 -28.478988)
			(xy 401.773898 -28.479242) (xy 401.774152 -28.479242) (xy 401.797123 -28.494339) (xy 401.838883 -28.53008)
			(xy 401.875091 -28.571437) (xy 401.904998 -28.617556) (xy 401.927986 -28.667485) (xy 401.943582 -28.720193)
			(xy 401.951463 -28.774592) (xy 401.951952 -28.802076) (xy 401.951436 -28.83078) (xy 401.942839 -28.887541)
			(xy 401.925835 -28.942374) (xy 401.900808 -28.99404) (xy 401.868324 -29.041374) (xy 401.849082 -29.06268)
			(xy 401.848574 -29.063188) (xy 401.847812 -29.064204) (xy 401.846542 -29.065474) (xy 401.846034 -29.065982)
			(xy 401.82935 -29.083504) (xy 401.792305 -29.114626) (xy 401.751627 -29.140821) (xy 401.729956 -29.15158)
			(xy 401.716494 -29.15793) (xy 401.701 -29.182568) (xy 401.701 -29.222446) (xy 401.70144 -29.232121)
			(xy 401.708607 -29.250098) (xy 401.721883 -29.26418) (xy 401.730464 -29.268674) (xy 401.754909 -29.280478)
			(xy 401.800477 -29.309979) (xy 401.841399 -29.345646) (xy 401.876846 -29.386758) (xy 401.906103 -29.432483)
			(xy 401.928576 -29.481896) (xy 401.943812 -29.533998) (xy 401.951503 -29.587734) (xy 401.951952 -29.614876)
			(xy 401.951422 -29.644139) (xy 401.942489 -29.701978) (xy 401.924828 -29.757776) (xy 401.898854 -29.810222)
			(xy 401.865176 -29.858086) (xy 401.845272 -29.879544) (xy 401.844764 -29.880052) (xy 401.844256 -29.88056)
			(xy 401.833914 -29.891405) (xy 401.811793 -29.911624) (xy 401.80006 -29.920946) (xy 401.79123 -29.928537)
			(xy 401.781042 -29.949446) (xy 401.780502 -29.961078) (xy 401.780502 -30.02026) (xy 401.780684 -30.026063)
			(xy 401.783372 -30.037355) (xy 401.785836 -30.042612) (xy 401.797774 -30.066996) (xy 401.804632 -30.075632)
			(xy 401.80895 -30.078934) (xy 401.830859 -30.097164) (xy 401.869542 -30.139017) (xy 401.901569 -30.186159)
			(xy 401.926228 -30.23754) (xy 401.94297 -30.292018) (xy 401.951421 -30.34838) (xy 401.951952 -30.376876)
			(xy 401.951436 -30.40558) (xy 401.942839 -30.462341) (xy 401.925835 -30.517174) (xy 401.900808 -30.56884)
			(xy 401.868324 -30.616174) (xy 401.849082 -30.63748) (xy 401.848574 -30.637988) (xy 401.847812 -30.639004)
			(xy 401.846542 -30.640274) (xy 401.846034 -30.640782) (xy 401.82935 -30.658304) (xy 401.792305 -30.689426)
			(xy 401.751627 -30.715621) (xy 401.729956 -30.72638) (xy 401.716494 -30.73273) (xy 401.701 -30.757368)
			(xy 401.701 -31.159958) (xy 401.72513 -31.188406) (xy 401.743418 -31.191454) (xy 401.770556 -31.196471)
			(xy 401.823118 -31.213291) (xy 401.872707 -31.237508) (xy 401.918291 -31.268617) (xy 401.958916 -31.305969)
			(xy 401.993737 -31.348785) (xy 402.022025 -31.39617) (xy 402.043192 -31.447137) (xy 402.056794 -31.500622)
			(xy 402.062549 -31.555508) (xy 402.060336 -31.610651) (xy 402.050202 -31.664899) (xy 402.032357 -31.717122)
			(xy 402.031258 -31.719266) (xy 402.585426 -31.719266) (xy 402.589497 -31.663644) (xy 402.601623 -31.609207)
			(xy 402.621546 -31.557116) (xy 402.648842 -31.508481) (xy 402.682928 -31.464338) (xy 402.723077 -31.425629)
			(xy 402.768435 -31.393178) (xy 402.818035 -31.367677) (xy 402.870819 -31.34967) (xy 402.925662 -31.33954)
			(xy 402.981396 -31.337503) (xy 403.036833 -31.343603) (xy 403.09079 -31.357709) (xy 403.142119 -31.379521)
			(xy 403.189725 -31.408575) (xy 403.232593 -31.44425) (xy 403.26981 -31.485787) (xy 403.300583 -31.5323)
			(xy 403.324255 -31.582797) (xy 403.340323 -31.636204) (xy 403.344473 -31.664402) (xy 403.861014 -31.664402)
			(xy 403.865085 -31.60878) (xy 403.877211 -31.554343) (xy 403.897134 -31.502252) (xy 403.92443 -31.453617)
			(xy 403.958516 -31.409474) (xy 403.998665 -31.370765) (xy 404.044023 -31.338314) (xy 404.093623 -31.312813)
			(xy 404.146407 -31.294806) (xy 404.20125 -31.284676) (xy 404.256984 -31.282639) (xy 404.312421 -31.288739)
			(xy 404.366378 -31.302845) (xy 404.417707 -31.324657) (xy 404.465313 -31.353711) (xy 404.508181 -31.389386)
			(xy 404.545398 -31.430923) (xy 404.576171 -31.477436) (xy 404.599843 -31.527933) (xy 404.615911 -31.58134)
			(xy 404.624031 -31.636516) (xy 404.62454 -31.664402) (xy 404.624031 -31.692288) (xy 404.615911 -31.747464)
			(xy 404.606971 -31.777178) (xy 405.126188 -31.777178) (xy 405.130259 -31.721556) (xy 405.142385 -31.667119)
			(xy 405.162308 -31.615028) (xy 405.189604 -31.566393) (xy 405.22369 -31.52225) (xy 405.263839 -31.483541)
			(xy 405.309197 -31.45109) (xy 405.358797 -31.425589) (xy 405.411581 -31.407582) (xy 405.466424 -31.397452)
			(xy 405.522158 -31.395415) (xy 405.577595 -31.401515) (xy 405.631552 -31.415621) (xy 405.682881 -31.437433)
			(xy 405.730487 -31.466487) (xy 405.773355 -31.502162) (xy 405.810572 -31.543699) (xy 405.841345 -31.590212)
			(xy 405.865017 -31.640709) (xy 405.881085 -31.694116) (xy 405.889205 -31.749292) (xy 405.889714 -31.777178)
			(xy 405.889205 -31.805064) (xy 405.881085 -31.86024) (xy 405.865017 -31.913647) (xy 405.841345 -31.964144)
			(xy 405.810572 -32.010657) (xy 405.773355 -32.052194) (xy 405.730487 -32.087869) (xy 405.682881 -32.116923)
			(xy 405.631552 -32.138735) (xy 405.577595 -32.152841) (xy 405.522158 -32.158941) (xy 405.466424 -32.156904)
			(xy 405.411581 -32.146774) (xy 405.358797 -32.128767) (xy 405.309197 -32.103266) (xy 405.263839 -32.070815)
			(xy 405.22369 -32.032106) (xy 405.189604 -31.987963) (xy 405.162308 -31.939328) (xy 405.142385 -31.887237)
			(xy 405.130259 -31.8328) (xy 405.126188 -31.777178) (xy 404.606971 -31.777178) (xy 404.599843 -31.800871)
			(xy 404.576171 -31.851368) (xy 404.545398 -31.897881) (xy 404.508181 -31.939418) (xy 404.465313 -31.975093)
			(xy 404.417707 -32.004147) (xy 404.366378 -32.025959) (xy 404.312421 -32.040065) (xy 404.256984 -32.046165)
			(xy 404.20125 -32.044128) (xy 404.146407 -32.033998) (xy 404.093623 -32.015991) (xy 404.044023 -31.99049)
			(xy 403.998665 -31.958039) (xy 403.958516 -31.91933) (xy 403.92443 -31.875187) (xy 403.897134 -31.826552)
			(xy 403.877211 -31.774461) (xy 403.865085 -31.720024) (xy 403.861014 -31.664402) (xy 403.344473 -31.664402)
			(xy 403.348443 -31.69138) (xy 403.348952 -31.719266) (xy 403.348443 -31.747152) (xy 403.340323 -31.802328)
			(xy 403.324255 -31.855735) (xy 403.300583 -31.906232) (xy 403.26981 -31.952745) (xy 403.232593 -31.994282)
			(xy 403.189725 -32.029957) (xy 403.142119 -32.059011) (xy 403.09079 -32.080823) (xy 403.036833 -32.094929)
			(xy 402.981396 -32.101029) (xy 402.925662 -32.098992) (xy 402.870819 -32.088862) (xy 402.818035 -32.070855)
			(xy 402.768435 -32.045354) (xy 402.723077 -32.012903) (xy 402.682928 -31.974194) (xy 402.648842 -31.930051)
			(xy 402.621546 -31.881416) (xy 402.601623 -31.829325) (xy 402.589497 -31.774888) (xy 402.585426 -31.719266)
			(xy 402.031258 -31.719266) (xy 402.007175 -31.766229) (xy 401.97518 -31.811195) (xy 401.956524 -31.831534)
			(xy 401.956016 -31.832042) (xy 401.955508 -31.832804) (xy 401.93409 -31.854964) (xy 401.885411 -31.892755)
			(xy 401.831293 -31.922233) (xy 401.77314 -31.942632) (xy 401.74291 -31.948628) (xy 401.724622 -31.95193)
			(xy 401.701 -31.97987) (xy 401.701 -33.512506) (xy 401.70138 -33.521932) (xy 401.708206 -33.539506)
			(xy 401.72093 -33.553418) (xy 401.729194 -33.557972) (xy 401.730464 -33.558734) (xy 401.816824 -33.595818)
			(xy 401.82396 -33.598651) (xy 401.839215 -33.600333) (xy 401.846796 -33.59912) (xy 401.85467 -33.597596)
			(xy 401.867624 -33.590738) (xy 401.872958 -33.585404) (xy 401.89449 -33.565056) (xy 401.942676 -33.530594)
			(xy 401.995609 -33.503995) (xy 402.052018 -33.485897) (xy 402.110546 -33.476735) (xy 402.140166 -33.476184)
			(xy 402.16727 -33.476658) (xy 402.220931 -33.48433) (xy 402.272965 -33.499524) (xy 402.322323 -33.521934)
			(xy 402.36801 -33.551108) (xy 402.409105 -33.586458) (xy 402.444779 -33.627271) (xy 402.474314 -33.672726)
			(xy 402.497114 -33.721905) (xy 402.505418 -33.74771) (xy 402.508212 -33.756854) (xy 402.519642 -33.771586)
			(xy 402.585682 -33.81121) (xy 402.59381 -33.812734) (xy 402.616371 -33.807503) (xy 402.662346 -33.801901)
			(xy 402.685504 -33.801558) (xy 402.712756 -33.802044) (xy 402.766705 -33.809801) (xy 402.819001 -33.825156)
			(xy 402.86858 -33.847797) (xy 402.883978 -33.857692) (xy 403.790148 -33.857692) (xy 403.794219 -33.80207)
			(xy 403.806345 -33.747633) (xy 403.826268 -33.695542) (xy 403.853564 -33.646907) (xy 403.88765 -33.602764)
			(xy 403.927799 -33.564055) (xy 403.973157 -33.531604) (xy 404.022757 -33.506103) (xy 404.075541 -33.488096)
			(xy 404.130384 -33.477966) (xy 404.186118 -33.475929) (xy 404.241555 -33.482029) (xy 404.295512 -33.496135)
			(xy 404.346841 -33.517947) (xy 404.394447 -33.547001) (xy 404.437315 -33.582676) (xy 404.474532 -33.624213)
			(xy 404.505305 -33.670726) (xy 404.528977 -33.721223) (xy 404.545045 -33.77463) (xy 404.553165 -33.829806)
			(xy 404.553674 -33.857692) (xy 404.553165 -33.885578) (xy 404.545045 -33.940754) (xy 404.528977 -33.994161)
			(xy 404.505305 -34.044658) (xy 404.474532 -34.091171) (xy 404.437315 -34.132708) (xy 404.394447 -34.168383)
			(xy 404.346841 -34.197437) (xy 404.295512 -34.219249) (xy 404.241555 -34.233355) (xy 404.186118 -34.239455)
			(xy 404.130384 -34.237418) (xy 404.075541 -34.227288) (xy 404.022757 -34.209281) (xy 403.973157 -34.18378)
			(xy 403.927799 -34.151329) (xy 403.88765 -34.11262) (xy 403.853564 -34.068477) (xy 403.826268 -34.019842)
			(xy 403.806345 -33.967751) (xy 403.794219 -33.913314) (xy 403.790148 -33.857692) (xy 402.883978 -33.857692)
			(xy 402.914432 -33.877263) (xy 402.955625 -33.912954) (xy 402.991319 -33.954143) (xy 403.020789 -33.999993)
			(xy 403.043434 -34.049571) (xy 403.058793 -34.101866) (xy 403.066554 -34.155814) (xy 403.067012 -34.183066)
			(xy 403.066473 -34.212363) (xy 403.057508 -34.270268) (xy 403.039801 -34.326123) (xy 403.013765 -34.378615)
			(xy 402.980014 -34.426513) (xy 402.960078 -34.447988) (xy 402.959316 -34.44875) (xy 402.957538 -34.450528)
			(xy 402.939468 -34.468994) (xy 402.899209 -34.501377) (xy 402.854944 -34.528024) (xy 402.807486 -34.548449)
			(xy 402.757705 -34.562275) (xy 402.706511 -34.569251) (xy 402.680678 -34.569654) (xy 402.654069 -34.569198)
			(xy 402.601367 -34.561813) (xy 402.550203 -34.547176) (xy 402.501568 -34.525571) (xy 402.456408 -34.497418)
			(xy 402.415599 -34.463261) (xy 402.379932 -34.423765) (xy 402.3501 -34.379696) (xy 402.326682 -34.331909)
			(xy 402.317966 -34.306764) (xy 402.317712 -34.306256) (xy 402.314541 -34.297742) (xy 402.303207 -34.283561)
			(xy 402.295614 -34.27857) (xy 402.230336 -34.239708) (xy 402.212556 -34.236406) (xy 402.203412 -34.238184)
			(xy 402.186601 -34.241026) (xy 402.152642 -34.244075) (xy 402.135594 -34.24428) (xy 402.13534 -34.24428)
			(xy 402.10633 -34.243736) (xy 402.048978 -34.234952) (xy 401.993614 -34.217596) (xy 401.941512 -34.192066)
			(xy 401.89387 -34.158951) (xy 401.87245 -34.139378) (xy 401.861274 -34.128964) (xy 401.831556 -34.12363)
			(xy 401.731734 -34.166302) (xy 401.722812 -34.170638) (xy 401.708926 -34.184776) (xy 401.701449 -34.203128)
			(xy 401.701 -34.213038) (xy 401.701 -35.264852) (xy 404.20239 -35.264852) (xy 404.206461 -35.20923)
			(xy 404.218587 -35.154793) (xy 404.23851 -35.102702) (xy 404.265806 -35.054067) (xy 404.299892 -35.009924)
			(xy 404.340041 -34.971215) (xy 404.385399 -34.938764) (xy 404.434999 -34.913263) (xy 404.487783 -34.895256)
			(xy 404.542626 -34.885126) (xy 404.59836 -34.883089) (xy 404.653797 -34.889189) (xy 404.707754 -34.903295)
			(xy 404.759083 -34.925107) (xy 404.806689 -34.954161) (xy 404.849557 -34.989836) (xy 404.87439 -35.017552)
			(xy 406.519856 -35.017552) (xy 406.519856 -34.963048) (xy 406.527612 -34.909098) (xy 406.542968 -34.856801)
			(xy 406.565609 -34.807222) (xy 406.595076 -34.761369) (xy 406.630769 -34.720177) (xy 406.67196 -34.684483)
			(xy 406.717811 -34.655015) (xy 406.76739 -34.632372) (xy 406.819686 -34.617015) (xy 406.873636 -34.609257)
			(xy 406.900888 -34.60877) (xy 406.918 -34.608958) (xy 406.952087 -34.612012) (xy 406.96896 -34.614866)
			(xy 406.980224 -34.61629) (xy 407.00211 -34.610342) (xy 407.011124 -34.603436) (xy 407.035508 -34.582354)
			(xy 407.043903 -34.574435) (xy 407.053021 -34.553256) (xy 407.053034 -34.541714) (xy 407.05278 -34.52241)
			(xy 407.05278 -33.65881) (xy 407.053034 -33.638744) (xy 407.052864 -33.627235) (xy 407.04376 -33.606128)
			(xy 407.035508 -33.598104) (xy 407.011124 -33.577022) (xy 407.002121 -33.570094) (xy 406.980228 -33.564153)
			(xy 406.96896 -33.565592) (xy 406.952088 -33.568455) (xy 406.918 -33.571512) (xy 406.900888 -33.571688)
			(xy 406.873636 -33.571241) (xy 406.819687 -33.563483) (xy 406.767391 -33.548126) (xy 406.717812 -33.525483)
			(xy 406.671961 -33.496015) (xy 406.63077 -33.460322) (xy 406.595078 -33.419129) (xy 406.565611 -33.373277)
			(xy 406.54297 -33.323698) (xy 406.527614 -33.271402) (xy 406.519858 -33.217452) (xy 406.519858 -33.162948)
			(xy 406.527614 -33.108998) (xy 406.54297 -33.056702) (xy 406.565611 -33.007123) (xy 406.595078 -32.961271)
			(xy 406.63077 -32.920078) (xy 406.671961 -32.884385) (xy 406.717812 -32.854917) (xy 406.767391 -32.832274)
			(xy 406.819687 -32.816917) (xy 406.873636 -32.809159) (xy 406.900888 -32.808672) (xy 406.927896 -32.809131)
			(xy 406.981374 -32.816735) (xy 407.033244 -32.831809) (xy 407.082469 -32.854049) (xy 407.128064 -32.883012)
			(xy 407.169116 -32.918117) (xy 407.204806 -32.958663) (xy 407.234418 -33.003839) (xy 407.257361 -33.05274)
			(xy 407.273176 -33.104389) (xy 407.277824 -33.130998) (xy 407.279348 -33.141666) (xy 407.290778 -33.159446)
			(xy 407.371042 -33.212786) (xy 407.391616 -33.216596) (xy 407.402284 -33.214056) (xy 407.428915 -33.207922)
			(xy 407.483164 -33.201304) (xy 407.510488 -33.200848) (xy 407.537813 -33.201294) (xy 407.592061 -33.207921)
			(xy 407.618692 -33.214056) (xy 407.62936 -33.216596) (xy 407.649934 -33.212786) (xy 407.730198 -33.159446)
			(xy 407.741628 -33.141666) (xy 407.743152 -33.130998) (xy 407.747768 -33.104385) (xy 407.763602 -33.052745)
			(xy 407.786559 -33.003852) (xy 407.816181 -32.958685) (xy 407.851875 -32.918147) (xy 407.892928 -32.883046)
			(xy 407.938521 -32.854084) (xy 407.987742 -32.83184) (xy 408.039607 -32.816759) (xy 408.093081 -32.809141)
			(xy 408.120088 -32.808672) (xy 408.147459 -32.809128) (xy 408.201639 -32.816945) (xy 408.254143 -32.832436)
			(xy 408.30389 -32.85528) (xy 408.349855 -32.885009) (xy 408.370786 -32.902652) (xy 408.377898 -32.908748)
			(xy 408.394916 -32.915098) (xy 408.48026 -32.915098) (xy 408.497278 -32.908748) (xy 408.50439 -32.902652)
			(xy 408.525322 -32.885012) (xy 408.571294 -32.855299) (xy 408.621041 -32.832462) (xy 408.673542 -32.816971)
			(xy 408.727719 -32.809145) (xy 408.755088 -32.808672) (xy 408.7722 -32.80886) (xy 408.806287 -32.811914)
			(xy 408.82316 -32.814768) (xy 408.834424 -32.816192) (xy 408.85631 -32.810244) (xy 408.865324 -32.803338)
			(xy 408.889708 -32.782256) (xy 408.898102 -32.774336) (xy 408.907221 -32.753158) (xy 408.907234 -32.741616)
			(xy 408.90698 -32.722312) (xy 408.90698 -31.858712) (xy 408.907234 -31.838646) (xy 408.907063 -31.827137)
			(xy 408.89796 -31.80603) (xy 408.889708 -31.798006) (xy 408.865324 -31.776924) (xy 408.856321 -31.769996)
			(xy 408.834428 -31.764055) (xy 408.82316 -31.765494) (xy 408.806288 -31.768357) (xy 408.7722 -31.771414)
			(xy 408.755088 -31.77159) (xy 408.727717 -31.771133) (xy 408.673538 -31.763314) (xy 408.621034 -31.747822)
			(xy 408.571288 -31.724979) (xy 408.525321 -31.695252) (xy 408.50439 -31.67761) (xy 408.497278 -31.671514)
			(xy 408.480514 -31.665164) (xy 408.394916 -31.665164) (xy 408.377898 -31.671514) (xy 408.37104 -31.677864)
			(xy 408.350091 -31.695523) (xy 408.304074 -31.725264) (xy 408.254274 -31.748111) (xy 408.201717 -31.763593)
			(xy 408.147484 -31.771392) (xy 408.120088 -31.771844) (xy 408.09311 -31.771385) (xy 408.039691 -31.763802)
			(xy 407.987874 -31.748761) (xy 407.938697 -31.726563) (xy 407.893142 -31.697652) (xy 407.852119 -31.662605)
			(xy 407.816449 -31.622123) (xy 407.786845 -31.577015) (xy 407.763898 -31.528182) (xy 407.748067 -31.476602)
			(xy 407.743406 -31.450026) (xy 407.741628 -31.439358) (xy 407.730198 -31.421832) (xy 407.649934 -31.368238)
			(xy 407.62936 -31.364682) (xy 407.618946 -31.367222) (xy 407.592246 -31.373302) (xy 407.537869 -31.379792)
			(xy 407.510488 -31.380176) (xy 407.483106 -31.3798) (xy 407.42873 -31.373306) (xy 407.40203 -31.367222)
			(xy 407.391616 -31.364682) (xy 407.371042 -31.368238) (xy 407.290778 -31.421832) (xy 407.279348 -31.439358)
			(xy 407.27757 -31.450026) (xy 407.272878 -31.476592) (xy 407.257023 -31.528154) (xy 407.234062 -31.576969)
			(xy 407.204452 -31.622061) (xy 407.168784 -31.662532) (xy 407.12777 -31.697574) (xy 407.082228 -31.726488)
			(xy 407.033066 -31.748697) (xy 406.981266 -31.763758) (xy 406.927861 -31.771371) (xy 406.900888 -31.771844)
			(xy 406.87364 -31.771285) (xy 406.819699 -31.763528) (xy 406.76741 -31.748173) (xy 406.717839 -31.725533)
			(xy 406.671995 -31.69607) (xy 406.63081 -31.660382) (xy 406.595123 -31.619196) (xy 406.565661 -31.57335)
			(xy 406.543023 -31.523778) (xy 406.52767 -31.47149) (xy 406.519914 -31.417548) (xy 406.519914 -31.363052)
			(xy 406.52767 -31.30911) (xy 406.543023 -31.256822) (xy 406.565661 -31.20725) (xy 406.595123 -31.161404)
			(xy 406.63081 -31.120218) (xy 406.671995 -31.08453) (xy 406.717839 -31.055067) (xy 406.76741 -31.032427)
			(xy 406.819699 -31.017072) (xy 406.87364 -31.009315) (xy 406.900888 -31.008828) (xy 406.918 -31.009016)
			(xy 406.952087 -31.012071) (xy 406.96896 -31.014924) (xy 406.980224 -31.016358) (xy 407.002112 -31.010405)
			(xy 407.011124 -31.003494) (xy 407.035508 -30.982412) (xy 407.043875 -30.974468) (xy 407.053009 -30.953309)
			(xy 407.053034 -30.941772) (xy 407.05278 -30.922468) (xy 407.05278 -30.058868) (xy 407.053034 -30.038802)
			(xy 407.05283 -30.027296) (xy 407.04375 -30.00619) (xy 407.035508 -29.998162) (xy 407.011124 -29.97708)
			(xy 407.002124 -29.970148) (xy 406.980228 -29.964211) (xy 406.96896 -29.96565) (xy 406.952088 -29.968514)
			(xy 406.918 -29.97157) (xy 406.900888 -29.971746) (xy 406.87364 -29.971183) (xy 406.819699 -29.963426)
			(xy 406.767411 -29.948071) (xy 406.71784 -29.925432) (xy 406.671996 -29.895968) (xy 406.630811 -29.86028)
			(xy 406.595125 -29.819094) (xy 406.565663 -29.773249) (xy 406.543025 -29.723678) (xy 406.527672 -29.671389)
			(xy 406.519916 -29.617448) (xy 406.519916 -29.562952) (xy 406.527672 -29.509011) (xy 406.543025 -29.456722)
			(xy 406.565663 -29.407151) (xy 406.595125 -29.361306) (xy 406.630811 -29.32012) (xy 406.671996 -29.284432)
			(xy 406.71784 -29.254968) (xy 406.767411 -29.232329) (xy 406.819699 -29.216974) (xy 406.87364 -29.209217)
			(xy 406.900888 -29.20873) (xy 406.927894 -29.209224) (xy 406.981369 -29.216828) (xy 407.033237 -29.231899)
			(xy 407.082459 -29.254137) (xy 407.128053 -29.283095) (xy 407.169105 -29.318196) (xy 407.204795 -29.358738)
			(xy 407.234409 -29.403908) (xy 407.257355 -29.452805) (xy 407.273173 -29.504449) (xy 407.277824 -29.531056)
			(xy 407.279348 -29.541724) (xy 407.290778 -29.559504) (xy 407.371042 -29.612844) (xy 407.391616 -29.616654)
			(xy 407.402284 -29.614114) (xy 407.428924 -29.608057) (xy 407.483171 -29.60156) (xy 407.510488 -29.60116)
			(xy 407.537806 -29.601543) (xy 407.592055 -29.60804) (xy 407.618692 -29.614114) (xy 407.62936 -29.616654)
			(xy 407.649934 -29.612844) (xy 407.730198 -29.559504) (xy 407.741628 -29.541724) (xy 407.743152 -29.531056)
			(xy 407.747813 -29.504451) (xy 407.763639 -29.452811) (xy 407.786589 -29.403918) (xy 407.816204 -29.35875)
			(xy 407.851893 -29.31821) (xy 407.892942 -29.283108) (xy 407.938531 -29.254144) (xy 407.987749 -29.231899)
			(xy 408.039611 -29.216817) (xy 408.093082 -29.209199) (xy 408.120088 -29.20873) (xy 408.147458 -29.209196)
			(xy 408.201638 -29.217013) (xy 408.254141 -29.232501) (xy 408.303888 -29.255343) (xy 408.349855 -29.285068)
			(xy 408.370786 -29.30271) (xy 408.377898 -29.308806) (xy 408.394916 -29.315156) (xy 408.48026 -29.315156)
			(xy 408.497278 -29.308806) (xy 408.50439 -29.30271) (xy 408.525316 -29.285064) (xy 408.571291 -29.255353)
			(xy 408.621039 -29.232518) (xy 408.673542 -29.217029) (xy 408.727718 -29.209203) (xy 408.755088 -29.20873)
			(xy 408.7722 -29.208918) (xy 408.806287 -29.211973) (xy 408.82316 -29.214826) (xy 408.834424 -29.21626)
			(xy 408.856312 -29.210307) (xy 408.865324 -29.203396) (xy 408.889708 -29.182314) (xy 408.898074 -29.174369)
			(xy 408.907209 -29.153211) (xy 408.907234 -29.141674) (xy 408.90698 -29.12237) (xy 408.90698 -28.25877)
			(xy 408.907234 -28.238704) (xy 408.907029 -28.227198) (xy 408.89795 -28.206092) (xy 408.889708 -28.198064)
			(xy 408.865324 -28.176982) (xy 408.856323 -28.170051) (xy 408.834428 -28.164113) (xy 408.82316 -28.165552)
			(xy 408.806288 -28.168416) (xy 408.7722 -28.171472) (xy 408.755088 -28.171648) (xy 408.72784 -28.171081)
			(xy 408.673899 -28.163324) (xy 408.621612 -28.147969) (xy 408.572041 -28.12533) (xy 408.526197 -28.095866)
			(xy 408.485013 -28.060179) (xy 408.449326 -28.018993) (xy 408.419864 -27.973148) (xy 408.397226 -27.923577)
			(xy 408.381874 -27.871289) (xy 408.374118 -27.817348) (xy 408.374118 -27.762852) (xy 408.381874 -27.708911)
			(xy 408.397226 -27.656623) (xy 408.419864 -27.607052) (xy 408.449326 -27.561207) (xy 408.485013 -27.520021)
			(xy 408.526197 -27.484334) (xy 408.572041 -27.45487) (xy 408.621612 -27.432231) (xy 408.673899 -27.416876)
			(xy 408.72784 -27.409119) (xy 408.755088 -27.408632) (xy 408.782095 -27.409124) (xy 408.835569 -27.416728)
			(xy 408.887437 -27.4318) (xy 408.93666 -27.454037) (xy 408.982253 -27.482996) (xy 409.023305 -27.518097)
			(xy 409.058995 -27.558639) (xy 409.088609 -27.60381) (xy 409.111555 -27.652706) (xy 409.127373 -27.704351)
			(xy 409.132024 -27.730958) (xy 409.133548 -27.741626) (xy 409.144978 -27.759406) (xy 409.225242 -27.812746)
			(xy 409.245816 -27.816556) (xy 409.256484 -27.814016) (xy 409.283115 -27.807882) (xy 409.337364 -27.801264)
			(xy 409.364688 -27.800808) (xy 409.386866 -27.801096) (xy 409.431012 -27.805426) (xy 409.452826 -27.809444)
			(xy 409.46324 -27.811476) (xy 409.483052 -27.807412) (xy 409.560014 -27.754072) (xy 409.570936 -27.737054)
			(xy 409.572714 -27.72664) (xy 409.577649 -27.70031) (xy 409.593862 -27.649253) (xy 409.617059 -27.600967)
			(xy 409.646783 -27.556401) (xy 409.68245 -27.516432) (xy 409.723358 -27.481846) (xy 409.768702 -27.453324)
			(xy 409.81759 -27.431426) (xy 409.869062 -27.416582) (xy 409.922104 -27.409086) (xy 409.948888 -27.408632)
			(xy 409.976144 -27.409014) (xy 410.030102 -27.416771) (xy 410.082407 -27.432127) (xy 410.131994 -27.454771)
			(xy 410.177853 -27.484242) (xy 410.219052 -27.51994) (xy 410.254751 -27.561137) (xy 410.284223 -27.606995)
			(xy 410.306869 -27.656582) (xy 410.322227 -27.708886) (xy 410.329985 -27.762844) (xy 410.329985 -27.817356)
			(xy 410.322227 -27.871314) (xy 410.306869 -27.923618) (xy 410.284223 -27.973205) (xy 410.254751 -28.019063)
			(xy 410.219052 -28.06026) (xy 410.177853 -28.095958) (xy 410.131994 -28.125429) (xy 410.082407 -28.148073)
			(xy 410.030102 -28.163429) (xy 409.976144 -28.171186) (xy 409.948888 -28.171648) (xy 409.937366 -28.171552)
			(xy 409.914363 -28.170155) (xy 409.902914 -28.168854) (xy 409.892 -28.168098) (xy 409.871202 -28.174822)
			(xy 409.862782 -28.181808) (xy 409.838906 -28.203398) (xy 409.831043 -28.211242) (xy 409.822363 -28.231663)
			(xy 409.822142 -28.242768) (xy 409.822396 -28.25877) (xy 409.822396 -29.137356) (xy 409.822543 -29.148439)
			(xy 409.831099 -29.168859) (xy 409.838906 -29.176726) (xy 409.862782 -29.198316) (xy 409.871211 -29.205286)
			(xy 409.892002 -29.212005) (xy 409.902914 -29.21127) (xy 409.914362 -29.20996) (xy 409.937365 -29.208561)
			(xy 409.948888 -29.208476) (xy 409.97614 -29.20897) (xy 410.03009 -29.216726) (xy 410.082387 -29.23208)
			(xy 410.131967 -29.254721) (xy 410.17782 -29.284187) (xy 410.219012 -29.31988) (xy 410.254705 -29.361071)
			(xy 410.284173 -29.406923) (xy 410.306816 -29.456501) (xy 410.322172 -29.508798) (xy 410.329929 -29.562748)
			(xy 410.329929 -29.617252) (xy 410.322172 -29.671202) (xy 410.306816 -29.723499) (xy 410.284173 -29.773077)
			(xy 410.254705 -29.818929) (xy 410.219012 -29.86012) (xy 410.17782 -29.895813) (xy 410.131967 -29.925279)
			(xy 410.082387 -29.94792) (xy 410.03009 -29.963274) (xy 409.97614 -29.97103) (xy 409.948888 -29.971492)
			(xy 409.92214 -29.971034) (xy 409.869172 -29.963539) (xy 409.817768 -29.948725) (xy 409.768935 -29.926882)
			(xy 409.723628 -29.898438) (xy 409.682734 -29.863949) (xy 409.647053 -29.824091) (xy 409.617284 -29.779643)
			(xy 409.594009 -29.731476) (xy 409.577684 -29.680532) (xy 409.572714 -29.654246) (xy 409.570936 -29.643832)
			(xy 409.560268 -29.626814) (xy 409.483052 -29.573728) (xy 409.46324 -29.569664) (xy 409.45308 -29.571696)
			(xy 409.431206 -29.575741) (xy 409.386931 -29.580069) (xy 409.364688 -29.580332) (xy 409.3373 -29.579894)
			(xy 409.282924 -29.573269) (xy 409.25623 -29.567124) (xy 409.245816 -29.564584) (xy 409.225242 -29.56814)
			(xy 409.144978 -29.621734) (xy 409.133548 -29.63926) (xy 409.13177 -29.649928) (xy 409.12708 -29.676494)
			(xy 409.111224 -29.728057) (xy 409.088263 -29.776871) (xy 409.058652 -29.821964) (xy 409.022984 -29.862435)
			(xy 408.98197 -29.897477) (xy 408.936428 -29.92639) (xy 408.887266 -29.948599) (xy 408.835466 -29.96366)
			(xy 408.782061 -29.971273) (xy 408.755088 -29.971746) (xy 408.727717 -29.9713) (xy 408.673536 -29.963479)
			(xy 408.621033 -29.947986) (xy 408.571286 -29.92514) (xy 408.525321 -29.89541) (xy 408.50439 -29.877766)
			(xy 408.497278 -29.87167) (xy 408.48026 -29.86532) (xy 408.394916 -29.86532) (xy 408.377898 -29.87167)
			(xy 408.370786 -29.877766) (xy 408.349828 -29.895373) (xy 408.303863 -29.925091) (xy 408.254122 -29.947933)
			(xy 408.201627 -29.963432) (xy 408.147455 -29.971268) (xy 408.120088 -29.971746) (xy 408.102976 -29.971561)
			(xy 408.068889 -29.968505) (xy 408.052016 -29.96565) (xy 408.040749 -29.964268) (xy 408.018868 -29.970187)
			(xy 408.009852 -29.97708) (xy 407.985468 -29.998162) (xy 407.977061 -30.006071) (xy 407.967951 -30.027257)
			(xy 407.967942 -30.038802) (xy 407.968196 -30.058868) (xy 407.968196 -30.922468) (xy 407.967942 -30.941772)
			(xy 407.96811 -30.953281) (xy 407.977216 -30.974387) (xy 407.985468 -30.982412) (xy 408.009852 -31.003494)
			(xy 408.018863 -31.01041) (xy 408.04075 -31.016358) (xy 408.052016 -31.014924) (xy 408.068886 -31.01205)
			(xy 408.102975 -31.009) (xy 408.120088 -31.008828) (xy 408.147458 -31.009294) (xy 408.201638 -31.017111)
			(xy 408.254141 -31.0326) (xy 408.303888 -31.055442) (xy 408.349855 -31.085166) (xy 408.370786 -31.102808)
			(xy 408.377898 -31.108904) (xy 408.394662 -31.115254) (xy 408.48026 -31.115254) (xy 408.497278 -31.108904)
			(xy 408.504136 -31.102554) (xy 408.525097 -31.084909) (xy 408.57111 -31.055165) (xy 408.620907 -31.032316)
			(xy 408.673462 -31.01683) (xy 408.727693 -31.009028) (xy 408.755088 -31.008574) (xy 408.782096 -31.009031)
			(xy 408.835574 -31.016636) (xy 408.887444 -31.031709) (xy 408.936669 -31.05395) (xy 408.982264 -31.082913)
			(xy 409.023317 -31.118018) (xy 409.059007 -31.158564) (xy 409.088619 -31.20374) (xy 409.111562 -31.252642)
			(xy 409.127376 -31.304291) (xy 409.132024 -31.3309) (xy 409.133548 -31.341568) (xy 409.144978 -31.359348)
			(xy 409.225242 -31.412688) (xy 409.245816 -31.416498) (xy 409.256484 -31.413958) (xy 409.283124 -31.407901)
			(xy 409.337371 -31.401404) (xy 409.364688 -31.401004) (xy 409.386861 -31.401234) (xy 409.431007 -31.405431)
			(xy 409.452826 -31.409386) (xy 409.46324 -31.411418) (xy 409.483052 -31.407354) (xy 409.560014 -31.354014)
			(xy 409.570936 -31.336996) (xy 409.572714 -31.326582) (xy 409.577605 -31.300243) (xy 409.593826 -31.249186)
			(xy 409.61703 -31.200901) (xy 409.64676 -31.156336) (xy 409.682432 -31.116369) (xy 409.723344 -31.081784)
			(xy 409.768692 -31.053263) (xy 409.817584 -31.031366) (xy 409.869058 -31.016523) (xy 409.922102 -31.009028)
			(xy 409.948888 -31.008574) (xy 409.97614 -31.009072) (xy 410.03009 -31.016828) (xy 410.082387 -31.032182)
			(xy 410.131966 -31.054823) (xy 410.177818 -31.084289) (xy 410.219011 -31.119981) (xy 410.254704 -31.161172)
			(xy 410.284172 -31.207024) (xy 410.306814 -31.256602) (xy 410.32217 -31.308898) (xy 410.329927 -31.362848)
			(xy 410.329927 -31.417352) (xy 410.32217 -31.471302) (xy 410.306814 -31.523598) (xy 410.284172 -31.573176)
			(xy 410.254704 -31.619028) (xy 410.219011 -31.660219) (xy 410.177818 -31.695911) (xy 410.131966 -31.725377)
			(xy 410.082387 -31.748018) (xy 410.03009 -31.763372) (xy 409.97614 -31.771128) (xy 409.948888 -31.77159)
			(xy 409.937366 -31.771492) (xy 409.914363 -31.770095) (xy 409.902914 -31.768796) (xy 409.892 -31.768029)
			(xy 409.8712 -31.774759) (xy 409.862782 -31.78175) (xy 409.838906 -31.80334) (xy 409.83107 -31.811206)
			(xy 409.822375 -31.83161) (xy 409.822142 -31.84271) (xy 409.822396 -31.858712) (xy 409.822396 -32.722312)
			(xy 409.822142 -32.737552) (xy 409.822311 -32.748666) (xy 409.831016 -32.769091) (xy 409.838906 -32.776922)
			(xy 409.862782 -32.798512) (xy 409.871211 -32.805482) (xy 409.892002 -32.812201) (xy 409.902914 -32.811466)
			(xy 409.914362 -32.810156) (xy 409.937365 -32.808757) (xy 409.948888 -32.808672) (xy 409.97614 -32.809174)
			(xy 410.030089 -32.81693) (xy 410.082386 -32.832284) (xy 410.131965 -32.854924) (xy 410.177817 -32.884391)
			(xy 410.219009 -32.920082) (xy 410.254702 -32.961273) (xy 410.28417 -33.007124) (xy 410.306812 -33.056703)
			(xy 410.322168 -33.108999) (xy 410.329925 -33.162948) (xy 410.329925 -33.217452) (xy 410.322168 -33.271401)
			(xy 410.306812 -33.323697) (xy 410.28417 -33.373276) (xy 410.254702 -33.419127) (xy 410.219009 -33.460318)
			(xy 410.177817 -33.496009) (xy 410.131965 -33.525476) (xy 410.082386 -33.548116) (xy 410.030089 -33.56347)
			(xy 409.97614 -33.571226) (xy 409.948888 -33.571688) (xy 409.922123 -33.571236) (xy 409.869114 -33.563777)
			(xy 409.81767 -33.548978) (xy 409.768801 -33.527131) (xy 409.723467 -33.498665) (xy 409.682559 -33.464139)
			(xy 409.646881 -33.424232) (xy 409.617134 -33.379727) (xy 409.593903 -33.331501) (xy 409.577643 -33.280499)
			(xy 409.572714 -33.254188) (xy 409.570936 -33.243774) (xy 409.560268 -33.226756) (xy 409.483052 -33.17367)
			(xy 409.46324 -33.169606) (xy 409.45308 -33.171638) (xy 409.4312 -33.175616) (xy 409.386925 -33.179817)
			(xy 409.364688 -33.18002) (xy 409.337306 -33.179645) (xy 409.28293 -33.17315) (xy 409.25623 -33.167066)
			(xy 409.245816 -33.164526) (xy 409.225242 -33.168082) (xy 409.144978 -33.221676) (xy 409.133548 -33.239202)
			(xy 409.13177 -33.24987) (xy 409.127036 -33.276428) (xy 409.111188 -33.32799) (xy 409.088233 -33.376805)
			(xy 409.058629 -33.421899) (xy 409.022966 -33.462371) (xy 408.981956 -33.497415) (xy 408.936418 -33.52633)
			(xy 408.88726 -33.54854) (xy 408.835462 -33.563602) (xy 408.782059 -33.571215) (xy 408.755088 -33.571688)
			(xy 408.727717 -33.571232) (xy 408.673538 -33.563412) (xy 408.621034 -33.547921) (xy 408.571288 -33.525077)
			(xy 408.525321 -33.49535) (xy 408.50439 -33.477708) (xy 408.497278 -33.471612) (xy 408.48026 -33.465262)
			(xy 408.394916 -33.465262) (xy 408.377898 -33.471612) (xy 408.370786 -33.477708) (xy 408.349833 -33.495321)
			(xy 408.303866 -33.525037) (xy 408.254124 -33.547878) (xy 408.201628 -33.563375) (xy 408.147456 -33.57121)
			(xy 408.120088 -33.571688) (xy 408.102976 -33.571503) (xy 408.068889 -33.568446) (xy 408.052016 -33.565592)
			(xy 408.04075 -33.564201) (xy 408.018867 -33.570124) (xy 408.009852 -33.577022) (xy 407.985468 -33.598104)
			(xy 407.977089 -33.606038) (xy 407.967963 -33.627205) (xy 407.967942 -33.638744) (xy 407.968196 -33.65881)
			(xy 407.968196 -34.52241) (xy 407.967942 -34.541714) (xy 407.968144 -34.55322) (xy 407.977226 -34.574326)
			(xy 407.985468 -34.582354) (xy 408.009852 -34.603436) (xy 408.018867 -34.610347) (xy 408.04075 -34.6163)
			(xy 408.052016 -34.614866) (xy 408.068886 -34.611992) (xy 408.102975 -34.608942) (xy 408.120088 -34.60877)
			(xy 408.14734 -34.609276) (xy 408.201289 -34.617032) (xy 408.253585 -34.632386) (xy 408.303164 -34.655026)
			(xy 408.349016 -34.684492) (xy 408.390208 -34.720184) (xy 408.425901 -34.761374) (xy 408.455368 -34.807225)
			(xy 408.47801 -34.856804) (xy 408.493366 -34.909099) (xy 408.501123 -34.963048) (xy 408.501123 -34.990024)
			(xy 409.56687 -34.990024) (xy 409.570941 -34.934402) (xy 409.583067 -34.879965) (xy 409.60299 -34.827874)
			(xy 409.630286 -34.779239) (xy 409.664372 -34.735096) (xy 409.704521 -34.696387) (xy 409.749879 -34.663936)
			(xy 409.799479 -34.638435) (xy 409.852263 -34.620428) (xy 409.907106 -34.610298) (xy 409.96284 -34.608261)
			(xy 410.018277 -34.614361) (xy 410.072234 -34.628467) (xy 410.123563 -34.650279) (xy 410.171169 -34.679333)
			(xy 410.214037 -34.715008) (xy 410.251254 -34.756545) (xy 410.282027 -34.803058) (xy 410.305699 -34.853555)
			(xy 410.321767 -34.906962) (xy 410.329887 -34.962138) (xy 410.330396 -34.990024) (xy 410.329887 -35.01791)
			(xy 410.321767 -35.073086) (xy 410.305699 -35.126493) (xy 410.282027 -35.17699) (xy 410.251254 -35.223503)
			(xy 410.214037 -35.26504) (xy 410.171169 -35.300715) (xy 410.123563 -35.329769) (xy 410.072234 -35.351581)
			(xy 410.018277 -35.365687) (xy 409.96284 -35.371787) (xy 409.907106 -35.36975) (xy 409.852263 -35.35962)
			(xy 409.799479 -35.341613) (xy 409.749879 -35.316112) (xy 409.704521 -35.283661) (xy 409.664372 -35.244952)
			(xy 409.630286 -35.200809) (xy 409.60299 -35.152174) (xy 409.583067 -35.100083) (xy 409.570941 -35.045646)
			(xy 409.56687 -34.990024) (xy 408.501123 -34.990024) (xy 408.501123 -35.017552) (xy 408.493366 -35.071501)
			(xy 408.47801 -35.123796) (xy 408.455368 -35.173375) (xy 408.425901 -35.219226) (xy 408.390208 -35.260416)
			(xy 408.349016 -35.296108) (xy 408.303164 -35.325574) (xy 408.253585 -35.348214) (xy 408.201289 -35.363568)
			(xy 408.14734 -35.371324) (xy 408.120088 -35.371786) (xy 408.093112 -35.371292) (xy 408.039695 -35.36371)
			(xy 407.987882 -35.348671) (xy 407.938707 -35.326476) (xy 407.893153 -35.297568) (xy 407.852131 -35.262526)
			(xy 407.81646 -35.222048) (xy 407.786854 -35.176945) (xy 407.763905 -35.128118) (xy 407.74807 -35.076542)
			(xy 407.743406 -35.049968) (xy 407.741628 -35.0393) (xy 407.730198 -35.021774) (xy 407.649934 -34.96818)
			(xy 407.62936 -34.964624) (xy 407.618946 -34.967164) (xy 407.592251 -34.973304) (xy 407.537876 -34.979926)
			(xy 407.510488 -34.980372) (xy 407.4831 -34.979933) (xy 407.428724 -34.973308) (xy 407.40203 -34.967164)
			(xy 407.391616 -34.964624) (xy 407.371042 -34.96818) (xy 407.290778 -35.021774) (xy 407.279348 -35.0393)
			(xy 407.27757 -35.049968) (xy 407.27291 -35.07654) (xy 407.25705 -35.128103) (xy 407.234083 -35.176917)
			(xy 407.204469 -35.222008) (xy 407.168797 -35.262478) (xy 407.12778 -35.297519) (xy 407.082235 -35.326432)
			(xy 407.033071 -35.34864) (xy 406.981269 -35.363701) (xy 406.927861 -35.371313) (xy 406.900888 -35.371786)
			(xy 406.873636 -35.371343) (xy 406.819686 -35.363585) (xy 406.76739 -35.348228) (xy 406.717811 -35.325585)
			(xy 406.67196 -35.296117) (xy 406.630769 -35.260423) (xy 406.595076 -35.219231) (xy 406.565609 -35.173378)
			(xy 406.542968 -35.123799) (xy 406.527612 -35.071502) (xy 406.519856 -35.017552) (xy 404.87439 -35.017552)
			(xy 404.886774 -35.031373) (xy 404.917547 -35.077886) (xy 404.941219 -35.128383) (xy 404.957287 -35.18179)
			(xy 404.965407 -35.236966) (xy 404.965916 -35.264852) (xy 404.965407 -35.292738) (xy 404.957287 -35.347914)
			(xy 404.941219 -35.401321) (xy 404.917547 -35.451818) (xy 404.886774 -35.498331) (xy 404.849557 -35.539868)
			(xy 404.806689 -35.575543) (xy 404.759083 -35.604597) (xy 404.707754 -35.626409) (xy 404.653797 -35.640515)
			(xy 404.59836 -35.646615) (xy 404.542626 -35.644578) (xy 404.487783 -35.634448) (xy 404.434999 -35.616441)
			(xy 404.385399 -35.59094) (xy 404.340041 -35.558489) (xy 404.299892 -35.51978) (xy 404.265806 -35.475637)
			(xy 404.23851 -35.427002) (xy 404.218587 -35.374911) (xy 404.206461 -35.320474) (xy 404.20239 -35.264852)
			(xy 401.701 -35.264852) (xy 401.701 -37.087048) (xy 405.50084 -37.087048) (xy 405.501308 -37.060444)
			(xy 405.508684 -37.007751) (xy 405.523313 -36.956595) (xy 405.544913 -36.90797) (xy 405.573062 -36.862819)
			(xy 405.607214 -36.82202) (xy 405.646706 -36.786365) (xy 405.66848 -36.771072) (xy 405.678403 -36.76354)
			(xy 405.690132 -36.741598) (xy 405.690832 -36.729162) (xy 405.690832 -36.644834) (xy 405.690162 -36.632384)
			(xy 405.678451 -36.610408) (xy 405.66848 -36.602924) (xy 405.646721 -36.587613) (xy 405.60724 -36.551951)
			(xy 405.573094 -36.511151) (xy 405.544947 -36.466004) (xy 405.523343 -36.417384) (xy 405.5087 -36.366236)
			(xy 405.501304 -36.313549) (xy 405.50084 -36.286948) (xy 405.5013 -36.259694) (xy 405.509052 -36.205741)
			(xy 405.524404 -36.15344) (xy 405.547045 -36.103857) (xy 405.576512 -36.058001) (xy 405.612206 -36.016806)
			(xy 405.653401 -35.981112) (xy 405.699257 -35.951645) (xy 405.74884 -35.929004) (xy 405.801141 -35.913652)
			(xy 405.855094 -35.9059) (xy 405.882348 -35.90544) (xy 405.88692 -35.90544) (xy 405.896572 -35.905694)
			(xy 405.913336 -35.899344) (xy 405.978868 -35.843464) (xy 405.987504 -35.827462) (xy 405.988774 -35.818064)
			(xy 405.993129 -35.791135) (xy 406.008439 -35.73878) (xy 406.03105 -35.689139) (xy 406.0605 -35.643224)
			(xy 406.09619 -35.601972) (xy 406.137391 -35.566224) (xy 406.183264 -35.536709) (xy 406.232873 -35.514028)
			(xy 406.285207 -35.498644) (xy 406.339198 -35.490871) (xy 406.366472 -35.490404) (xy 406.393727 -35.490841)
			(xy 406.447683 -35.498595) (xy 406.499986 -35.513949) (xy 406.549571 -35.536591) (xy 406.595429 -35.566059)
			(xy 406.636626 -35.601754) (xy 406.672324 -35.642948) (xy 406.701796 -35.688804) (xy 406.724441 -35.738388)
			(xy 406.739799 -35.79069) (xy 406.747557 -35.844645) (xy 406.747557 -35.899155) (xy 406.739799 -35.95311)
			(xy 406.724441 -36.005412) (xy 406.701796 -36.054996) (xy 406.672324 -36.100852) (xy 406.636626 -36.142046)
			(xy 406.595429 -36.177741) (xy 406.549571 -36.207209) (xy 406.499986 -36.229851) (xy 406.447683 -36.245205)
			(xy 406.393727 -36.252959) (xy 406.366472 -36.25342) (xy 406.3619 -36.25342) (xy 406.352248 -36.253166)
			(xy 406.335484 -36.259516) (xy 406.269952 -36.315396) (xy 406.261316 -36.331398) (xy 406.260046 -36.340796)
			(xy 406.255851 -36.367) (xy 406.241166 -36.417994) (xy 406.219553 -36.46646) (xy 406.191428 -36.511461)
			(xy 406.188002 -36.515548) (xy 407.314144 -36.515548) (xy 407.318215 -36.459926) (xy 407.330341 -36.405489)
			(xy 407.350264 -36.353398) (xy 407.37756 -36.304763) (xy 407.411646 -36.26062) (xy 407.451795 -36.221911)
			(xy 407.497153 -36.18946) (xy 407.546753 -36.163959) (xy 407.599537 -36.145952) (xy 407.65438 -36.135822)
			(xy 407.710114 -36.133785) (xy 407.765551 -36.139885) (xy 407.819508 -36.153991) (xy 407.870837 -36.175803)
			(xy 407.918443 -36.204857) (xy 407.961311 -36.240532) (xy 407.998528 -36.282069) (xy 408.029301 -36.328582)
			(xy 408.052973 -36.379079) (xy 408.069041 -36.432486) (xy 408.077161 -36.487662) (xy 408.07767 -36.515548)
			(xy 408.077161 -36.543434) (xy 408.069041 -36.59861) (xy 408.052973 -36.652017) (xy 408.029301 -36.702514)
			(xy 407.998528 -36.749027) (xy 407.961311 -36.790564) (xy 407.918443 -36.826239) (xy 407.870837 -36.855293)
			(xy 407.819508 -36.877105) (xy 407.765551 -36.891211) (xy 407.710114 -36.897311) (xy 407.65438 -36.895274)
			(xy 407.599537 -36.885144) (xy 407.546753 -36.867137) (xy 407.497153 -36.841636) (xy 407.451795 -36.809185)
			(xy 407.411646 -36.770476) (xy 407.37756 -36.726333) (xy 407.350264 -36.677698) (xy 407.330341 -36.625607)
			(xy 407.318215 -36.57117) (xy 407.314144 -36.515548) (xy 406.188002 -36.515548) (xy 406.157336 -36.552128)
			(xy 406.117934 -36.587675) (xy 406.096216 -36.602924) (xy 406.086294 -36.610457) (xy 406.074565 -36.632399)
			(xy 406.073864 -36.644834) (xy 406.073864 -36.729162) (xy 406.074538 -36.741612) (xy 406.086246 -36.763588)
			(xy 406.096216 -36.771072) (xy 406.117972 -36.786386) (xy 406.157454 -36.822048) (xy 406.191599 -36.862847)
			(xy 406.219747 -36.907994) (xy 406.241352 -36.956613) (xy 406.255995 -37.007761) (xy 406.263391 -37.060447)
			(xy 406.263856 -37.087048) (xy 406.263256 -37.118808) (xy 406.252769 -37.181454) (xy 406.232026 -37.24149)
			(xy 406.217374 -37.269674) (xy 406.21204 -37.27958) (xy 406.210516 -37.301678) (xy 406.24633 -37.394896)
			(xy 406.262332 -37.41039) (xy 406.273 -37.4142) (xy 406.297533 -37.423266) (xy 406.344063 -37.447149)
			(xy 406.386895 -37.477165) (xy 406.425223 -37.512751) (xy 406.458331 -37.55324) (xy 406.485597 -37.597872)
			(xy 406.50651 -37.645811) (xy 406.520678 -37.696157) (xy 406.527834 -37.747967) (xy 406.52827 -37.774118)
			(xy 406.527784 -37.801369) (xy 406.520028 -37.855317) (xy 406.504673 -37.907612) (xy 406.482031 -37.957189)
			(xy 406.452565 -38.003039) (xy 406.416874 -38.04423) (xy 406.375683 -38.079921) (xy 406.329833 -38.109387)
			(xy 406.280256 -38.132029) (xy 406.227961 -38.147384) (xy 406.174013 -38.15514) (xy 406.119511 -38.15514)
			(xy 406.065563 -38.147384) (xy 406.013268 -38.132029) (xy 405.963691 -38.109387) (xy 405.917841 -38.079921)
			(xy 405.87665 -38.04423) (xy 405.840959 -38.003039) (xy 405.811493 -37.957189) (xy 405.788851 -37.907612)
			(xy 405.773496 -37.855317) (xy 405.76574 -37.801369) (xy 405.765254 -37.774118) (xy 405.765839 -37.742358)
			(xy 405.776332 -37.679711) (xy 405.797081 -37.619676) (xy 405.811736 -37.591492) (xy 405.81707 -37.581586)
			(xy 405.818594 -37.559488) (xy 405.78278 -37.46627) (xy 405.766778 -37.450776) (xy 405.75611 -37.446966)
			(xy 405.731568 -37.437923) (xy 405.685036 -37.414038) (xy 405.642204 -37.38402) (xy 405.603874 -37.348431)
			(xy 405.570767 -37.307939) (xy 405.543502 -37.263304) (xy 405.522591 -37.215362) (xy 405.508427 -37.165012)
			(xy 405.501274 -37.1132) (xy 405.50084 -37.087048) (xy 401.701 -37.087048) (xy 401.701 -38.315138)
			(xy 406.718006 -38.315138) (xy 406.722077 -38.259516) (xy 406.734203 -38.205079) (xy 406.754126 -38.152988)
			(xy 406.781422 -38.104353) (xy 406.815508 -38.06021) (xy 406.855657 -38.021501) (xy 406.901015 -37.98905)
			(xy 406.950615 -37.963549) (xy 407.003399 -37.945542) (xy 407.058242 -37.935412) (xy 407.113976 -37.933375)
			(xy 407.169413 -37.939475) (xy 407.22337 -37.953581) (xy 407.274699 -37.975393) (xy 407.322305 -38.004447)
			(xy 407.365173 -38.040122) (xy 407.40239 -38.081659) (xy 407.433163 -38.128172) (xy 407.456835 -38.178669)
			(xy 407.472903 -38.232076) (xy 407.481023 -38.287252) (xy 407.481532 -38.315138) (xy 407.481023 -38.343024)
			(xy 407.472903 -38.3982) (xy 407.456835 -38.451607) (xy 407.433163 -38.502104) (xy 407.40239 -38.548617)
			(xy 407.365173 -38.590154) (xy 407.322305 -38.625829) (xy 407.274699 -38.654883) (xy 407.22337 -38.676695)
			(xy 407.169413 -38.690801) (xy 407.113976 -38.696901) (xy 407.058242 -38.694864) (xy 407.003399 -38.684734)
			(xy 406.950615 -38.666727) (xy 406.901015 -38.641226) (xy 406.855657 -38.608775) (xy 406.815508 -38.570066)
			(xy 406.781422 -38.525923) (xy 406.754126 -38.477288) (xy 406.734203 -38.425197) (xy 406.722077 -38.37076)
			(xy 406.718006 -38.315138) (xy 401.701 -38.315138) (xy 401.701 -42.4307) (xy 401.70129 -42.438369)
			(xy 401.705932 -42.452988) (xy 401.710144 -42.459402) (xy 401.710144 -42.459656) (xy 401.714988 -42.466078)
			(xy 401.727791 -42.4758) (xy 401.73529 -42.478706) (xy 401.735798 -42.47896) (xy 401.760784 -42.487763)
			(xy 401.808241 -42.511301) (xy 401.851986 -42.541179) (xy 401.891177 -42.576822) (xy 401.925059 -42.617544)
			(xy 401.952981 -42.662562) (xy 401.974406 -42.711011) (xy 401.988922 -42.761958) (xy 401.99625 -42.814423)
			(xy 401.996656 -42.84091) (xy 401.996115 -42.87028) (xy 401.987114 -42.928327) (xy 401.969325 -42.984308)
			(xy 401.943168 -43.036904) (xy 401.909262 -43.08487) (xy 401.889214 -43.10634) (xy 401.888452 -43.107102)
			(xy 401.887944 -43.10761) (xy 401.866875 -43.129147) (xy 401.819181 -43.165957) (xy 401.766287 -43.194802)
			(xy 401.738084 -43.2054) (xy 401.73529 -43.206416) (xy 401.729194 -43.209464) (xy 401.720961 -43.21405)
			(xy 401.708275 -43.227964) (xy 401.70146 -43.245516) (xy 401.701 -43.25493) (xy 401.701 -43.4467)
			(xy 401.70129 -43.454369) (xy 401.705932 -43.468988) (xy 401.710144 -43.475402) (xy 401.710144 -43.475656)
			(xy 401.714988 -43.482078) (xy 401.727791 -43.4918) (xy 401.73529 -43.494706) (xy 401.735798 -43.49496)
			(xy 401.760784 -43.503763) (xy 401.808241 -43.527301) (xy 401.851986 -43.557179) (xy 401.891177 -43.592822)
			(xy 401.925059 -43.633544) (xy 401.952981 -43.678562) (xy 401.974406 -43.727011) (xy 401.988922 -43.777958)
			(xy 401.99625 -43.830423) (xy 401.996656 -43.85691) (xy 401.996115 -43.88628) (xy 401.987114 -43.944327)
			(xy 401.969325 -44.000308) (xy 401.943168 -44.052904) (xy 401.909262 -44.10087) (xy 401.889214 -44.12234)
			(xy 401.888452 -44.123102) (xy 401.887944 -44.12361) (xy 401.866875 -44.145147) (xy 401.819181 -44.181957)
			(xy 401.766287 -44.210802) (xy 401.738084 -44.2214) (xy 401.73529 -44.222416) (xy 401.729194 -44.225464)
			(xy 401.720961 -44.23005) (xy 401.708275 -44.243964) (xy 401.70146 -44.261516) (xy 401.701 -44.27093)
			(xy 401.701 -44.4627) (xy 401.70129 -44.470369) (xy 401.705932 -44.484988) (xy 401.710144 -44.491402)
			(xy 401.710144 -44.491656) (xy 401.714988 -44.498078) (xy 401.727791 -44.5078) (xy 401.73529 -44.510706)
			(xy 401.735798 -44.51096) (xy 401.760784 -44.519763) (xy 401.808241 -44.543301) (xy 401.851986 -44.573179)
			(xy 401.891177 -44.608822) (xy 401.925059 -44.649544) (xy 401.952981 -44.694562) (xy 401.974406 -44.743011)
			(xy 401.988922 -44.793958) (xy 401.99625 -44.846423) (xy 401.996656 -44.87291) (xy 401.996115 -44.90228)
			(xy 401.987114 -44.960327) (xy 401.969325 -45.016308) (xy 401.943168 -45.068904) (xy 401.909262 -45.11687)
			(xy 401.889214 -45.13834) (xy 401.888452 -45.139102) (xy 401.887944 -45.13961) (xy 401.866875 -45.161147)
			(xy 401.819181 -45.197957) (xy 401.766287 -45.226802) (xy 401.738084 -45.2374) (xy 401.73529 -45.238416)
			(xy 401.729194 -45.241464) (xy 401.720961 -45.24605) (xy 401.708275 -45.259964) (xy 401.70146 -45.277516)
			(xy 401.701 -45.28693) (xy 401.701 -45.4787) (xy 401.70129 -45.486369) (xy 401.705932 -45.500988)
			(xy 401.710144 -45.507402) (xy 401.710144 -45.507656) (xy 401.714988 -45.514078) (xy 401.727791 -45.5238)
			(xy 401.73529 -45.526706) (xy 401.735798 -45.52696) (xy 401.760784 -45.535763) (xy 401.808241 -45.559301)
			(xy 401.851986 -45.589179) (xy 401.891177 -45.624822) (xy 401.925059 -45.665544) (xy 401.952981 -45.710562)
			(xy 401.974406 -45.759011) (xy 401.988922 -45.809958) (xy 401.99625 -45.862423) (xy 401.996656 -45.88891)
			(xy 401.996115 -45.91828) (xy 401.987114 -45.976327) (xy 401.969325 -46.032308) (xy 401.943168 -46.084904)
			(xy 401.909262 -46.13287) (xy 401.889214 -46.15434) (xy 401.888452 -46.155102) (xy 401.887944 -46.15561)
			(xy 401.866875 -46.177147) (xy 401.819181 -46.213957) (xy 401.766287 -46.242802) (xy 401.738084 -46.2534)
			(xy 401.73529 -46.254416) (xy 401.729194 -46.257464) (xy 401.720961 -46.26205) (xy 401.708275 -46.275964)
			(xy 401.70146 -46.293516) (xy 401.701 -46.30293) (xy 401.701 -47.040546) (xy 401.722082 -47.067724)
			(xy 401.7391 -47.072296) (xy 401.766053 -47.079733) (xy 401.817588 -47.101417) (xy 401.865401 -47.130399)
			(xy 401.908467 -47.166056) (xy 401.945861 -47.207622) (xy 401.976781 -47.254206) (xy 402.000562 -47.304807)
			(xy 402.016695 -47.35834) (xy 402.024833 -47.413656) (xy 402.025358 -47.441612) (xy 402.025279 -47.45435)
			(xy 402.023625 -47.479771) (xy 402.022056 -47.492412) (xy 402.021802 -47.494952) (xy 402.017021 -47.524513)
			(xy 401.99946 -47.581759) (xy 401.973173 -47.63556) (xy 401.938804 -47.684594) (xy 401.918424 -47.706534)
			(xy 401.917916 -47.707042) (xy 401.916138 -47.709074) (xy 401.897861 -47.727722) (xy 401.857095 -47.76035)
			(xy 401.812258 -47.78711) (xy 401.764188 -47.8075) (xy 401.7391 -47.814738) (xy 401.738592 -47.814992)
			(xy 401.737322 -47.8155) (xy 401.727035 -47.81908) (xy 401.7106 -47.833344) (xy 401.701551 -47.853134)
			(xy 401.701 -47.864014) (xy 401.701 -48.5267) (xy 401.70129 -48.534369) (xy 401.705932 -48.548988)
			(xy 401.710144 -48.555402) (xy 401.710144 -48.555656) (xy 401.714988 -48.562078) (xy 401.727791 -48.5718)
			(xy 401.73529 -48.574706) (xy 401.735798 -48.57496) (xy 401.760784 -48.583763) (xy 401.808241 -48.607301)
			(xy 401.851986 -48.637179) (xy 401.891177 -48.672822) (xy 401.925059 -48.713544) (xy 401.952981 -48.758562)
			(xy 401.974406 -48.807011) (xy 401.988922 -48.857958) (xy 401.99625 -48.910423) (xy 401.996656 -48.93691)
			(xy 401.996115 -48.96628) (xy 401.987114 -49.024327) (xy 401.969325 -49.080308) (xy 401.943168 -49.132904)
			(xy 401.909262 -49.18087) (xy 401.889214 -49.20234) (xy 401.888452 -49.203102) (xy 401.887944 -49.20361)
			(xy 401.866875 -49.225147) (xy 401.819181 -49.261957) (xy 401.766287 -49.290802) (xy 401.738084 -49.3014)
			(xy 401.73529 -49.302416) (xy 401.729194 -49.305464) (xy 401.720961 -49.31005) (xy 401.708275 -49.323964)
			(xy 401.70146 -49.341516) (xy 401.701 -49.35093) (xy 401.701 -49.5427) (xy 401.70129 -49.550369)
			(xy 401.705932 -49.564988) (xy 401.710144 -49.571402) (xy 401.710144 -49.571656) (xy 401.714988 -49.578078)
			(xy 401.727791 -49.5878) (xy 401.73529 -49.590706) (xy 401.735798 -49.59096) (xy 401.760784 -49.599763)
			(xy 401.765199 -49.601953) (xy 402.590959 -49.601953) (xy 402.590959 -49.547447) (xy 402.598717 -49.493495)
			(xy 402.614073 -49.441196) (xy 402.636717 -49.391616) (xy 402.666186 -49.345762) (xy 402.701881 -49.30457)
			(xy 402.743075 -49.268876) (xy 402.78893 -49.239409) (xy 402.838511 -49.216768) (xy 402.890811 -49.201413)
			(xy 402.944763 -49.193658) (xy 402.972016 -49.193196) (xy 402.999387 -49.193654) (xy 403.053566 -49.201474)
			(xy 403.106069 -49.216965) (xy 403.155816 -49.239808) (xy 403.201782 -49.269534) (xy 403.222714 -49.287176)
			(xy 403.229826 -49.293272) (xy 403.246844 -49.299622) (xy 403.332188 -49.299622) (xy 403.349206 -49.293272)
			(xy 403.356318 -49.287176) (xy 403.377251 -49.269535) (xy 403.423219 -49.239811) (xy 403.472965 -49.216965)
			(xy 403.525467 -49.201469) (xy 403.579645 -49.19364) (xy 403.634387 -49.19364) (xy 403.688565 -49.201469)
			(xy 403.741067 -49.216965) (xy 403.790813 -49.239811) (xy 403.836781 -49.269535) (xy 403.857714 -49.287176)
			(xy 403.864826 -49.293272) (xy 403.881844 -49.299622) (xy 403.967188 -49.299622) (xy 403.984206 -49.293272)
			(xy 403.991318 -49.287176) (xy 404.012267 -49.269558) (xy 404.058236 -49.239844) (xy 404.107979 -49.217004)
			(xy 404.160476 -49.201508) (xy 404.214648 -49.193674) (xy 404.242016 -49.193196) (xy 404.268332 -49.19366)
			(xy 404.320465 -49.200878) (xy 404.371113 -49.215189) (xy 404.419315 -49.236321) (xy 404.464157 -49.263875)
			(xy 404.50479 -49.297327) (xy 404.52294 -49.316386) (xy 404.530447 -49.323805) (xy 404.549738 -49.33232)
			(xy 404.560278 -49.332896) (xy 404.634954 -49.332896) (xy 404.645503 -49.332357) (xy 404.664798 -49.323829)
			(xy 404.672292 -49.316386) (xy 404.690428 -49.297308) (xy 404.731048 -49.26383) (xy 404.775889 -49.23626)
			(xy 404.824096 -49.215121) (xy 404.874753 -49.200816) (xy 404.926897 -49.193617) (xy 404.953216 -49.193196)
			(xy 404.980467 -49.193675) (xy 405.034413 -49.201433) (xy 405.086707 -49.21679) (xy 405.136282 -49.239432)
			(xy 405.182131 -49.268899) (xy 405.22332 -49.304591) (xy 405.25901 -49.345781) (xy 405.288475 -49.391632)
			(xy 405.311116 -49.441208) (xy 405.32647 -49.493502) (xy 405.334226 -49.547449) (xy 405.334226 -49.601951)
			(xy 405.32647 -49.655898) (xy 405.311116 -49.708192) (xy 405.288475 -49.757768) (xy 405.25901 -49.803619)
			(xy 405.22332 -49.844809) (xy 405.182131 -49.880501) (xy 405.136282 -49.909968) (xy 405.086707 -49.93261)
			(xy 405.034413 -49.947967) (xy 404.980467 -49.955725) (xy 404.953216 -49.956212) (xy 404.926899 -49.955791)
			(xy 404.874764 -49.948564) (xy 404.824115 -49.934244) (xy 404.775913 -49.913104) (xy 404.731072 -49.885543)
			(xy 404.690441 -49.852084) (xy 404.672292 -49.833022) (xy 404.664772 -49.825618) (xy 404.645491 -49.817094)
			(xy 404.634954 -49.816512) (xy 404.560278 -49.816512) (xy 404.549731 -49.817066) (xy 404.530435 -49.825583)
			(xy 404.52294 -49.833022) (xy 404.50477 -49.852067) (xy 404.464159 -49.885551) (xy 404.419327 -49.913128)
			(xy 404.371126 -49.934273) (xy 404.320474 -49.948584) (xy 404.268334 -49.955788) (xy 404.242016 -49.956212)
			(xy 404.214646 -49.955734) (xy 404.160468 -49.947918) (xy 404.107965 -49.932432) (xy 404.058218 -49.909593)
			(xy 404.01225 -49.879872) (xy 403.991318 -49.862232) (xy 403.984206 -49.856136) (xy 403.967188 -49.849786)
			(xy 403.881844 -49.849786) (xy 403.864826 -49.856136) (xy 403.857714 -49.862232) (xy 403.836781 -49.879873)
			(xy 403.790813 -49.909597) (xy 403.741067 -49.932443) (xy 403.688565 -49.947939) (xy 403.634387 -49.955768)
			(xy 403.579645 -49.955768) (xy 403.525467 -49.947939) (xy 403.472965 -49.932443) (xy 403.423219 -49.909597)
			(xy 403.377251 -49.879873) (xy 403.356318 -49.862232) (xy 403.349206 -49.856136) (xy 403.332188 -49.849786)
			(xy 403.246844 -49.849786) (xy 403.229826 -49.856136) (xy 403.222714 -49.862232) (xy 403.201792 -49.879883)
			(xy 403.155816 -49.909592) (xy 403.106066 -49.932425) (xy 403.053563 -49.947913) (xy 402.999386 -49.955739)
			(xy 402.972016 -49.956212) (xy 402.944763 -49.955742) (xy 402.890811 -49.947987) (xy 402.838511 -49.932632)
			(xy 402.78893 -49.909991) (xy 402.743075 -49.880524) (xy 402.701881 -49.84483) (xy 402.666186 -49.803638)
			(xy 402.636717 -49.757784) (xy 402.614073 -49.708204) (xy 402.598717 -49.655905) (xy 402.590959 -49.601953)
			(xy 401.765199 -49.601953) (xy 401.808241 -49.623301) (xy 401.851986 -49.653179) (xy 401.891177 -49.688822)
			(xy 401.925059 -49.729544) (xy 401.952981 -49.774562) (xy 401.974406 -49.823011) (xy 401.988922 -49.873958)
			(xy 401.99625 -49.926423) (xy 401.996656 -49.95291) (xy 401.996115 -49.98228) (xy 401.987114 -50.040327)
			(xy 401.969325 -50.096308) (xy 401.943168 -50.148904) (xy 401.909262 -50.19687) (xy 401.889214 -50.21834)
			(xy 401.888452 -50.219102) (xy 401.887944 -50.21961) (xy 401.866875 -50.241147) (xy 401.819181 -50.277957)
			(xy 401.766287 -50.306802) (xy 401.738084 -50.3174) (xy 401.73529 -50.318416) (xy 401.729194 -50.321464)
			(xy 401.720961 -50.32605) (xy 401.708275 -50.339964) (xy 401.70146 -50.357516) (xy 401.701 -50.36693)
			(xy 401.701 -50.62347) (xy 401.720558 -50.65014) (xy 401.736814 -50.65522) (xy 401.762359 -50.663666)
			(xy 401.810963 -50.686734) (xy 401.855845 -50.716403) (xy 401.896112 -50.752084) (xy 401.930966 -50.793068)
			(xy 401.959715 -50.838544) (xy 401.98179 -50.887608) (xy 401.996752 -50.939287) (xy 402.004303 -50.992555)
			(xy 402.004784 -51.019456) (xy 402.00423 -51.048682) (xy 401.995322 -51.10645) (xy 401.977709 -51.162184)
			(xy 401.951802 -51.21458) (xy 401.918207 -51.262412) (xy 401.898358 -51.28387) (xy 401.897596 -51.284632)
			(xy 401.897088 -51.28514) (xy 401.874629 -51.308172) (xy 401.823433 -51.347117) (xy 401.766437 -51.376935)
			(xy 401.736052 -51.387502) (xy 401.728432 -51.390042) (xy 401.715478 -51.399186) (xy 401.710906 -51.40579)
			(xy 401.706342 -51.412428) (xy 401.70128 -51.427712) (xy 401.701 -51.435762) (xy 401.701 -51.63947)
			(xy 401.720558 -51.66614) (xy 401.736814 -51.67122) (xy 401.762359 -51.679666) (xy 401.782127 -51.689048)
			(xy 402.5555 -51.689048) (xy 402.5555 -51.634552) (xy 402.563255 -51.580612) (xy 402.578607 -51.528324)
			(xy 402.601244 -51.478752) (xy 402.630704 -51.432907) (xy 402.666389 -51.39172) (xy 402.707571 -51.35603)
			(xy 402.753413 -51.326565) (xy 402.802982 -51.303922) (xy 402.855269 -51.288564) (xy 402.909208 -51.280803)
			(xy 402.936456 -51.280314) (xy 402.963825 -51.280802) (xy 403.018004 -51.288614) (xy 403.070507 -51.304098)
			(xy 403.120254 -51.326935) (xy 403.166222 -51.356655) (xy 403.187154 -51.374294) (xy 403.194266 -51.38039)
			(xy 403.211284 -51.38674) (xy 403.296628 -51.38674) (xy 403.313646 -51.38039) (xy 403.320758 -51.374294)
			(xy 403.341694 -51.35666) (xy 403.387666 -51.326948) (xy 403.437412 -51.304111) (xy 403.489912 -51.288619)
			(xy 403.544087 -51.280789) (xy 403.571456 -51.280314) (xy 403.589799 -51.280549) (xy 403.626312 -51.28411)
			(xy 403.644354 -51.287426) (xy 403.655276 -51.289458) (xy 403.67585 -51.284632) (xy 403.753828 -51.225704)
			(xy 403.764242 -51.206908) (xy 403.765004 -51.195986) (xy 403.767908 -51.167703) (xy 403.780944 -51.112367)
			(xy 403.802038 -51.059573) (xy 403.830725 -51.01049) (xy 403.86637 -50.9662) (xy 403.886924 -50.946558)
			(xy 403.894335 -50.939044) (xy 403.902857 -50.919759) (xy 403.903434 -50.90922) (xy 403.903434 -50.834544)
			(xy 403.902884 -50.823997) (xy 403.894362 -50.804702) (xy 403.886924 -50.797206) (xy 403.867852 -50.779064)
			(xy 403.834372 -50.738445) (xy 403.8068 -50.693607) (xy 403.78566 -50.645401) (xy 403.771355 -50.594744)
			(xy 403.764155 -50.542601) (xy 403.763734 -50.516282) (xy 403.76422 -50.489031) (xy 403.771976 -50.435083)
			(xy 403.787331 -50.382788) (xy 403.809973 -50.333211) (xy 403.839439 -50.287361) (xy 403.87513 -50.24617)
			(xy 403.916321 -50.210479) (xy 403.962171 -50.181013) (xy 404.011748 -50.158371) (xy 404.064043 -50.143016)
			(xy 404.117991 -50.13526) (xy 404.172493 -50.13526) (xy 404.226441 -50.143016) (xy 404.278736 -50.158371)
			(xy 404.328313 -50.181013) (xy 404.374163 -50.210479) (xy 404.415354 -50.24617) (xy 404.451045 -50.287361)
			(xy 404.480511 -50.333211) (xy 404.503153 -50.382788) (xy 404.518508 -50.435083) (xy 404.526264 -50.489031)
			(xy 404.52675 -50.516282) (xy 404.526347 -50.5426) (xy 404.519119 -50.594737) (xy 404.504797 -50.645387)
			(xy 404.483654 -50.693589) (xy 404.456089 -50.738429) (xy 404.422625 -50.779058) (xy 404.40356 -50.797206)
			(xy 404.396163 -50.804731) (xy 404.387634 -50.824008) (xy 404.38705 -50.834544) (xy 404.38705 -50.90922)
			(xy 404.387624 -50.919764) (xy 404.396129 -50.939059) (xy 404.40356 -50.946558) (xy 404.422611 -50.964721)
			(xy 404.456093 -51.005335) (xy 404.483669 -51.050169) (xy 404.504812 -51.098371) (xy 404.519122 -51.149024)
			(xy 404.526326 -51.201164) (xy 404.52675 -51.227482) (xy 404.526205 -51.254731) (xy 404.518452 -51.308674)
			(xy 404.503101 -51.360965) (xy 404.480465 -51.41054) (xy 404.451005 -51.456388) (xy 404.41532 -51.497577)
			(xy 404.374136 -51.533269) (xy 404.328292 -51.562737) (xy 404.278722 -51.58538) (xy 404.226433 -51.600739)
			(xy 404.172491 -51.608501) (xy 404.145242 -51.60899) (xy 404.126899 -51.608755) (xy 404.090386 -51.605194)
			(xy 404.072344 -51.601878) (xy 404.061422 -51.599846) (xy 404.040848 -51.604672) (xy 403.96287 -51.6636)
			(xy 403.952456 -51.682396) (xy 403.951694 -51.693318) (xy 403.948761 -51.721571) (xy 403.93573 -51.776853)
			(xy 403.914648 -51.829593) (xy 403.88598 -51.878625) (xy 403.85036 -51.922865) (xy 403.808576 -51.961335)
			(xy 403.76155 -51.993186) (xy 403.710321 -52.017714) (xy 403.656023 -52.034376) (xy 403.599855 -52.042804)
			(xy 403.571456 -52.04333) (xy 403.544086 -52.042848) (xy 403.489907 -52.035037) (xy 403.437403 -52.019552)
			(xy 403.387656 -51.996714) (xy 403.341689 -51.966991) (xy 403.320758 -51.94935) (xy 403.313646 -51.943254)
			(xy 403.296628 -51.936904) (xy 403.211284 -51.936904) (xy 403.194266 -51.943254) (xy 403.187154 -51.94935)
			(xy 403.166206 -51.966969) (xy 403.120238 -51.996686) (xy 403.070495 -52.019526) (xy 403.017998 -52.035022)
			(xy 402.963824 -52.042854) (xy 402.936456 -52.04333) (xy 402.909208 -52.042797) (xy 402.855269 -52.035036)
			(xy 402.802982 -52.019678) (xy 402.753413 -51.997035) (xy 402.707571 -51.96757) (xy 402.666389 -51.93188)
			(xy 402.630704 -51.890693) (xy 402.601244 -51.844848) (xy 402.578607 -51.795277) (xy 402.563255 -51.742988)
			(xy 402.5555 -51.689048) (xy 401.782127 -51.689048) (xy 401.810963 -51.702734) (xy 401.855845 -51.732403)
			(xy 401.896112 -51.768084) (xy 401.930966 -51.809068) (xy 401.959715 -51.854544) (xy 401.98179 -51.903608)
			(xy 401.996752 -51.955287) (xy 402.004303 -52.008555) (xy 402.004784 -52.035456) (xy 402.00423 -52.064682)
			(xy 401.995322 -52.12245) (xy 401.977709 -52.178184) (xy 401.951802 -52.23058) (xy 401.918207 -52.278412)
			(xy 401.898358 -52.29987) (xy 401.897596 -52.300632) (xy 401.897088 -52.30114) (xy 401.874629 -52.324172)
			(xy 401.823433 -52.363117) (xy 401.766437 -52.392935) (xy 401.736052 -52.403502) (xy 401.728432 -52.406042)
			(xy 401.715478 -52.415186) (xy 401.710906 -52.42179) (xy 401.706342 -52.428428) (xy 401.70128 -52.443712)
			(xy 401.701 -52.451762) (xy 401.701 -52.564157) (xy 404.127107 -52.564157) (xy 404.127107 -52.509643)
			(xy 404.134865 -52.455685) (xy 404.150224 -52.40338) (xy 404.172869 -52.353793) (xy 404.202342 -52.307933)
			(xy 404.238041 -52.266735) (xy 404.27924 -52.231037) (xy 404.3251 -52.201566) (xy 404.374687 -52.178921)
			(xy 404.426993 -52.163563) (xy 404.480951 -52.155806) (xy 404.508208 -52.155344) (xy 404.535579 -52.155795)
			(xy 404.589759 -52.163615) (xy 404.642263 -52.179107) (xy 404.692009 -52.201952) (xy 404.737975 -52.231681)
			(xy 404.758906 -52.249324) (xy 404.766018 -52.25542) (xy 404.783036 -52.26177) (xy 404.86838 -52.26177)
			(xy 404.885398 -52.25542) (xy 404.89251 -52.249324) (xy 404.913431 -52.23167) (xy 404.959406 -52.20196)
			(xy 405.009157 -52.179126) (xy 405.06166 -52.163639) (xy 405.115838 -52.155815) (xy 405.143208 -52.155344)
			(xy 405.170455 -52.155927) (xy 405.224395 -52.163683) (xy 405.276683 -52.179037) (xy 405.326253 -52.201676)
			(xy 405.372096 -52.231139) (xy 405.41328 -52.266826) (xy 405.448966 -52.30801) (xy 405.478428 -52.353855)
			(xy 405.501066 -52.403425) (xy 405.516419 -52.455712) (xy 405.524174 -52.509653) (xy 405.524174 -52.564147)
			(xy 405.516419 -52.618088) (xy 405.501066 -52.670375) (xy 405.478428 -52.719945) (xy 405.448966 -52.76579)
			(xy 405.41328 -52.806974) (xy 405.372096 -52.842661) (xy 405.326253 -52.872124) (xy 405.276683 -52.894763)
			(xy 405.224395 -52.910117) (xy 405.170455 -52.917873) (xy 405.143208 -52.91836) (xy 405.115837 -52.917899)
			(xy 405.061658 -52.910081) (xy 405.009154 -52.894592) (xy 404.959407 -52.871749) (xy 404.913441 -52.842022)
			(xy 404.89251 -52.82438) (xy 404.885398 -52.818284) (xy 404.86838 -52.811934) (xy 404.783036 -52.811934)
			(xy 404.766018 -52.818284) (xy 404.758906 -52.82438) (xy 404.73798 -52.842027) (xy 404.692006 -52.871738)
			(xy 404.642257 -52.894573) (xy 404.589755 -52.910062) (xy 404.535578 -52.917888) (xy 404.508208 -52.91836)
			(xy 404.480951 -52.917994) (xy 404.426993 -52.910237) (xy 404.374687 -52.894879) (xy 404.3251 -52.872234)
			(xy 404.27924 -52.842763) (xy 404.238041 -52.807065) (xy 404.202342 -52.765867) (xy 404.172869 -52.720007)
			(xy 404.150224 -52.67042) (xy 404.134865 -52.618115) (xy 404.127107 -52.564157) (xy 401.701 -52.564157)
			(xy 401.701 -52.65547) (xy 401.720558 -52.68214) (xy 401.736814 -52.68722) (xy 401.762359 -52.695666)
			(xy 401.810963 -52.718734) (xy 401.855845 -52.748403) (xy 401.896112 -52.784084) (xy 401.930966 -52.825068)
			(xy 401.959715 -52.870544) (xy 401.98179 -52.919608) (xy 401.996752 -52.971287) (xy 402.004303 -53.024555)
			(xy 402.004784 -53.051456) (xy 402.00423 -53.080682) (xy 401.995322 -53.13845) (xy 401.977709 -53.194184)
			(xy 401.951802 -53.24658) (xy 401.918207 -53.294412) (xy 401.898358 -53.31587) (xy 401.897596 -53.316632)
			(xy 401.897088 -53.31714) (xy 401.874629 -53.340172) (xy 401.823433 -53.379117) (xy 401.766437 -53.408935)
			(xy 401.736052 -53.419502) (xy 401.728432 -53.422042) (xy 401.715478 -53.431186) (xy 401.710906 -53.43779)
			(xy 401.706342 -53.444428) (xy 401.70128 -53.459712) (xy 401.701 -53.467762) (xy 401.701 -53.67147)
			(xy 401.720558 -53.69814) (xy 401.736814 -53.70322) (xy 401.762359 -53.711666) (xy 401.810963 -53.734734)
			(xy 401.855845 -53.764403) (xy 401.896112 -53.800084) (xy 401.930966 -53.841068) (xy 401.959715 -53.886544)
			(xy 401.98179 -53.935608) (xy 401.996752 -53.987287) (xy 402.004303 -54.040555) (xy 402.004784 -54.067456)
			(xy 402.00423 -54.096682) (xy 401.995322 -54.15445) (xy 401.977709 -54.210184) (xy 401.963508 -54.238906)
			(xy 408.685998 -54.238906) (xy 408.690069 -54.183284) (xy 408.702195 -54.128847) (xy 408.722118 -54.076756)
			(xy 408.749414 -54.028121) (xy 408.7835 -53.983978) (xy 408.823649 -53.945269) (xy 408.869007 -53.912818)
			(xy 408.918607 -53.887317) (xy 408.971391 -53.86931) (xy 409.026234 -53.85918) (xy 409.081968 -53.857143)
			(xy 409.137405 -53.863243) (xy 409.191362 -53.877349) (xy 409.242691 -53.899161) (xy 409.290297 -53.928215)
			(xy 409.333165 -53.96389) (xy 409.370382 -54.005427) (xy 409.401155 -54.05194) (xy 409.424827 -54.102437)
			(xy 409.440895 -54.155844) (xy 409.449015 -54.21102) (xy 409.449524 -54.238906) (xy 409.449015 -54.266792)
			(xy 409.440895 -54.321968) (xy 409.424827 -54.375375) (xy 409.401155 -54.425872) (xy 409.370382 -54.472385)
			(xy 409.333165 -54.513922) (xy 409.290297 -54.549597) (xy 409.242691 -54.578651) (xy 409.191362 -54.600463)
			(xy 409.137405 -54.614569) (xy 409.081968 -54.620669) (xy 409.026234 -54.618632) (xy 408.971391 -54.608502)
			(xy 408.918607 -54.590495) (xy 408.869007 -54.564994) (xy 408.823649 -54.532543) (xy 408.7835 -54.493834)
			(xy 408.749414 -54.449691) (xy 408.722118 -54.401056) (xy 408.702195 -54.348965) (xy 408.690069 -54.294528)
			(xy 408.685998 -54.238906) (xy 401.963508 -54.238906) (xy 401.951802 -54.26258) (xy 401.918207 -54.310412)
			(xy 401.898358 -54.33187) (xy 401.897596 -54.332632) (xy 401.897088 -54.33314) (xy 401.874629 -54.356172)
			(xy 401.823433 -54.395117) (xy 401.766437 -54.424935) (xy 401.736052 -54.435502) (xy 401.728432 -54.438042)
			(xy 401.715478 -54.447186) (xy 401.710906 -54.45379) (xy 401.706342 -54.460428) (xy 401.70128 -54.475712)
			(xy 401.701 -54.483762) (xy 401.701 -54.68747) (xy 401.720558 -54.71414) (xy 401.736814 -54.71922)
			(xy 401.762359 -54.727666) (xy 401.810963 -54.750734) (xy 401.855845 -54.780403) (xy 401.896112 -54.816084)
			(xy 401.930966 -54.857068) (xy 401.959715 -54.902544) (xy 401.98179 -54.951608) (xy 401.992632 -54.989055)
			(xy 404.201045 -54.989055) (xy 404.201045 -54.934545) (xy 404.208803 -54.880591) (xy 404.22416 -54.82829)
			(xy 404.246805 -54.778707) (xy 404.276276 -54.732852) (xy 404.311973 -54.691657) (xy 404.353169 -54.655963)
			(xy 404.399026 -54.626494) (xy 404.448611 -54.603853) (xy 404.500913 -54.588498) (xy 404.554867 -54.580743)
			(xy 404.582122 -54.580282) (xy 404.610214 -54.580759) (xy 404.665792 -54.58899) (xy 404.719562 -54.605284)
			(xy 404.770359 -54.629289) (xy 404.817086 -54.660487) (xy 404.85873 -54.698201) (xy 404.894392 -54.741616)
			(xy 404.909274 -54.765448) (xy 404.914608 -54.774592) (xy 404.931626 -54.786784) (xy 405.024844 -54.80685)
			(xy 405.045418 -54.802786) (xy 405.054054 -54.79669) (xy 405.078128 -54.780706) (xy 405.130056 -54.75536)
			(xy 405.185211 -54.73813) (xy 405.242332 -54.72941) (xy 405.271224 -54.728872) (xy 405.298475 -54.729355)
			(xy 405.352422 -54.737115) (xy 405.404715 -54.752472) (xy 405.454291 -54.775114) (xy 405.500141 -54.804581)
			(xy 405.54133 -54.840273) (xy 405.577021 -54.881463) (xy 405.606488 -54.927312) (xy 405.62913 -54.976888)
			(xy 405.644486 -55.029182) (xy 405.652245 -55.083129) (xy 405.652732 -55.11038) (xy 405.652271 -55.137751)
			(xy 405.644454 -55.191931) (xy 405.628965 -55.244434) (xy 405.606122 -55.294181) (xy 405.576395 -55.340147)
			(xy 405.558752 -55.361078) (xy 405.552656 -55.36819) (xy 405.546306 -55.385208) (xy 405.546306 -55.470552)
			(xy 405.552656 -55.48757) (xy 405.558752 -55.494682) (xy 405.576374 -55.51563) (xy 405.606101 -55.561595)
			(xy 405.628949 -55.611338) (xy 405.644448 -55.663838) (xy 405.652279 -55.718015) (xy 405.652281 -55.772755)
			(xy 405.644454 -55.826932) (xy 405.62896 -55.879433) (xy 405.606116 -55.929179) (xy 405.576392 -55.975146)
			(xy 405.558752 -55.996078) (xy 405.552656 -56.00319) (xy 405.546306 -56.020208) (xy 405.546306 -56.105552)
			(xy 405.552656 -56.12257) (xy 405.558752 -56.129682) (xy 405.576389 -56.150616) (xy 405.606103 -56.196588)
			(xy 405.62894 -56.246335) (xy 405.644431 -56.298835) (xy 405.652259 -56.353011) (xy 405.652732 -56.38038)
			(xy 405.652246 -56.407631) (xy 405.64449 -56.461579) (xy 405.629135 -56.513874) (xy 405.606493 -56.563451)
			(xy 405.577027 -56.609301) (xy 405.541336 -56.650492) (xy 405.500145 -56.686183) (xy 405.454295 -56.715649)
			(xy 405.404718 -56.738291) (xy 405.352423 -56.753646) (xy 405.298475 -56.761402) (xy 405.243973 -56.761402)
			(xy 405.190025 -56.753646) (xy 405.13773 -56.738291) (xy 405.088153 -56.715649) (xy 405.042303 -56.686183)
			(xy 405.001112 -56.650492) (xy 404.965421 -56.609301) (xy 404.935955 -56.563451) (xy 404.913313 -56.513874)
			(xy 404.897958 -56.461579) (xy 404.890202 -56.407631) (xy 404.889716 -56.38038) (xy 404.890166 -56.353009)
			(xy 404.897987 -56.298829) (xy 404.91348 -56.246326) (xy 404.936325 -56.196579) (xy 404.966053 -56.150613)
			(xy 404.983696 -56.129682) (xy 404.989792 -56.12257) (xy 404.996142 -56.105552) (xy 404.996142 -56.020208)
			(xy 404.989792 -56.00319) (xy 404.983696 -55.996078) (xy 404.966037 -55.975161) (xy 404.936315 -55.929189)
			(xy 404.913473 -55.87944) (xy 404.89798 -55.826936) (xy 404.890154 -55.772756) (xy 404.890156 -55.718014)
			(xy 404.897986 -55.663834) (xy 404.913484 -55.611331) (xy 404.93633 -55.561584) (xy 404.966055 -55.515615)
			(xy 404.983696 -55.494682) (xy 404.989792 -55.48757) (xy 404.996142 -55.470552) (xy 404.996142 -55.385208)
			(xy 404.989792 -55.36819) (xy 404.983696 -55.361078) (xy 404.972744 -55.348283) (xy 404.952904 -55.321063)
			(xy 404.944072 -55.306722) (xy 404.938738 -55.297578) (xy 404.92172 -55.285386) (xy 404.828502 -55.26532)
			(xy 404.807928 -55.269384) (xy 404.799292 -55.27548) (xy 404.77523 -55.291483) (xy 404.723298 -55.316826)
			(xy 404.66814 -55.334051) (xy 404.611015 -55.342764) (xy 404.582122 -55.343298) (xy 404.554867 -55.342857)
			(xy 404.500913 -55.335102) (xy 404.448611 -55.319747) (xy 404.399026 -55.297106) (xy 404.353169 -55.267637)
			(xy 404.311973 -55.231943) (xy 404.276276 -55.190748) (xy 404.246805 -55.144893) (xy 404.22416 -55.09531)
			(xy 404.208803 -55.043009) (xy 404.201045 -54.989055) (xy 401.992632 -54.989055) (xy 401.996752 -55.003287)
			(xy 402.004303 -55.056555) (xy 402.004784 -55.083456) (xy 402.00423 -55.112682) (xy 401.995322 -55.17045)
			(xy 401.977709 -55.226184) (xy 401.951802 -55.27858) (xy 401.918207 -55.326412) (xy 401.898358 -55.34787)
			(xy 401.897596 -55.348632) (xy 401.897088 -55.34914) (xy 401.874629 -55.372172) (xy 401.823433 -55.411117)
			(xy 401.804819 -55.420855) (xy 402.524645 -55.420855) (xy 402.524645 -55.366345) (xy 402.532403 -55.312391)
			(xy 402.54776 -55.26009) (xy 402.570405 -55.210507) (xy 402.599876 -55.164652) (xy 402.635573 -55.123457)
			(xy 402.676769 -55.087763) (xy 402.722626 -55.058294) (xy 402.772211 -55.035653) (xy 402.824513 -55.020298)
			(xy 402.878467 -55.012543) (xy 402.905722 -55.012082) (xy 402.932037 -55.012546) (xy 402.984171 -55.019765)
			(xy 403.034819 -55.034076) (xy 403.08302 -55.055209) (xy 403.127863 -55.082762) (xy 403.168495 -55.116213)
			(xy 403.186646 -55.135272) (xy 403.194152 -55.142692) (xy 403.213444 -55.151207) (xy 403.223984 -55.151782)
			(xy 403.29866 -55.151782) (xy 403.30921 -55.15125) (xy 403.328505 -55.142718) (xy 403.335998 -55.135272)
			(xy 403.354148 -55.116207) (xy 403.394763 -55.082725) (xy 403.4396 -55.055151) (xy 403.487805 -55.034009)
			(xy 403.538461 -55.019703) (xy 403.590603 -55.012503) (xy 403.616922 -55.012082) (xy 403.644171 -55.01259)
			(xy 403.698115 -55.020349) (xy 403.750406 -55.035705) (xy 403.799979 -55.058347) (xy 403.845825 -55.087813)
			(xy 403.887012 -55.123504) (xy 403.9227 -55.164692) (xy 403.952164 -55.21054) (xy 403.974802 -55.260115)
			(xy 403.990156 -55.312406) (xy 403.997912 -55.366351) (xy 403.997912 -55.420849) (xy 403.990156 -55.474794)
			(xy 403.974802 -55.527085) (xy 403.952164 -55.57666) (xy 403.9227 -55.622508) (xy 403.887012 -55.663696)
			(xy 403.845826 -55.699387) (xy 403.799979 -55.728853) (xy 403.750406 -55.751495) (xy 403.698115 -55.766851)
			(xy 403.644171 -55.77461) (xy 403.616922 -55.775098) (xy 403.590605 -55.774677) (xy 403.538469 -55.767451)
			(xy 403.487821 -55.753131) (xy 403.439619 -55.731991) (xy 403.394778 -55.70443) (xy 403.354147 -55.670971)
			(xy 403.335998 -55.651908) (xy 403.328478 -55.644505) (xy 403.309197 -55.635981) (xy 403.29866 -55.635398)
			(xy 403.223984 -55.635398) (xy 403.213432 -55.635905) (xy 403.194137 -55.644456) (xy 403.186646 -55.651908)
			(xy 403.168539 -55.671015) (xy 403.127913 -55.70449) (xy 403.083066 -55.732057) (xy 403.034853 -55.753191)
			(xy 402.984191 -55.767489) (xy 402.932043 -55.774681) (xy 402.905722 -55.775098) (xy 402.878467 -55.774657)
			(xy 402.824513 -55.766902) (xy 402.772211 -55.751547) (xy 402.722626 -55.728906) (xy 402.676769 -55.699437)
			(xy 402.635573 -55.663743) (xy 402.599876 -55.622548) (xy 402.570405 -55.576693) (xy 402.54776 -55.52711)
			(xy 402.532403 -55.474809) (xy 402.524645 -55.420855) (xy 401.804819 -55.420855) (xy 401.766437 -55.440935)
			(xy 401.736052 -55.451502) (xy 401.728432 -55.454042) (xy 401.715478 -55.463186) (xy 401.710906 -55.46979)
			(xy 401.706342 -55.476428) (xy 401.70128 -55.491712) (xy 401.701 -55.499762) (xy 401.701 -55.95747)
			(xy 401.720558 -55.98414) (xy 401.736814 -55.98922) (xy 401.762359 -55.997666) (xy 401.810963 -56.020734)
			(xy 401.855845 -56.050403) (xy 401.896112 -56.086084) (xy 401.930966 -56.127068) (xy 401.959715 -56.172544)
			(xy 401.98179 -56.221608) (xy 401.996752 -56.273287) (xy 402.004303 -56.326555) (xy 402.004784 -56.353456)
			(xy 402.00423 -56.382682) (xy 401.995322 -56.44045) (xy 401.977709 -56.496184) (xy 401.951802 -56.54858)
			(xy 401.918207 -56.596412) (xy 401.898358 -56.61787) (xy 401.897596 -56.618632) (xy 401.897088 -56.61914)
			(xy 401.874629 -56.642172) (xy 401.823433 -56.681117) (xy 401.766437 -56.710935) (xy 401.736052 -56.721502)
			(xy 401.728432 -56.724042) (xy 401.715478 -56.733186) (xy 401.710906 -56.73979) (xy 401.706342 -56.746428)
			(xy 401.70128 -56.761712) (xy 401.701 -56.769762) (xy 401.701 -57.48528) (xy 404.90597 -57.48528)
			(xy 404.910041 -57.429658) (xy 404.922167 -57.375221) (xy 404.94209 -57.32313) (xy 404.969386 -57.274495)
			(xy 405.003472 -57.230352) (xy 405.043621 -57.191643) (xy 405.088979 -57.159192) (xy 405.138579 -57.133691)
			(xy 405.191363 -57.115684) (xy 405.246206 -57.105554) (xy 405.30194 -57.103517) (xy 405.357377 -57.109617)
			(xy 405.411334 -57.123723) (xy 405.462663 -57.145535) (xy 405.510269 -57.174589) (xy 405.553137 -57.210264)
			(xy 405.590354 -57.251801) (xy 405.621127 -57.298314) (xy 405.644799 -57.348811) (xy 405.660867 -57.402218)
			(xy 405.668987 -57.457394) (xy 405.669496 -57.48528) (xy 405.668987 -57.513166) (xy 405.660867 -57.568342)
			(xy 405.644799 -57.621749) (xy 405.621127 -57.672246) (xy 405.590354 -57.718759) (xy 405.553137 -57.760296)
			(xy 405.510269 -57.795971) (xy 405.462663 -57.825025) (xy 405.411334 -57.846837) (xy 405.357377 -57.860943)
			(xy 405.30194 -57.867043) (xy 405.246206 -57.865006) (xy 405.191363 -57.854876) (xy 405.138579 -57.836869)
			(xy 405.088979 -57.811368) (xy 405.043621 -57.778917) (xy 405.003472 -57.740208) (xy 404.969386 -57.696065)
			(xy 404.94209 -57.64743) (xy 404.922167 -57.595339) (xy 404.910041 -57.540902) (xy 404.90597 -57.48528)
			(xy 401.701 -57.48528) (xy 401.701 -58.076084) (xy 405.658064 -58.076084) (xy 405.662135 -58.020462)
			(xy 405.674261 -57.966025) (xy 405.694184 -57.913934) (xy 405.72148 -57.865299) (xy 405.755566 -57.821156)
			(xy 405.795715 -57.782447) (xy 405.841073 -57.749996) (xy 405.890673 -57.724495) (xy 405.943457 -57.706488)
			(xy 405.9983 -57.696358) (xy 406.054034 -57.694321) (xy 406.109471 -57.700421) (xy 406.163428 -57.714527)
			(xy 406.214757 -57.736339) (xy 406.262363 -57.765393) (xy 406.305231 -57.801068) (xy 406.342448 -57.842605)
			(xy 406.358784 -57.867296) (xy 407.942794 -57.867296) (xy 407.946867 -57.811637) (xy 407.959002 -57.757164)
			(xy 407.978938 -57.705038) (xy 408.006252 -57.65637) (xy 408.04036 -57.612198) (xy 408.080537 -57.573463)
			(xy 408.125925 -57.540991) (xy 408.175557 -57.515473) (xy 408.228377 -57.497454) (xy 408.283256 -57.487317)
			(xy 408.339027 -57.485279) (xy 408.394501 -57.491382) (xy 408.448494 -57.505498) (xy 408.499857 -57.527325)
			(xy 408.547495 -57.556398) (xy 408.590391 -57.592097) (xy 408.627633 -57.633661) (xy 408.658427 -57.680205)
			(xy 408.682115 -57.730736) (xy 408.698193 -57.784178) (xy 408.706319 -57.839392) (xy 408.706828 -57.867296)
			(xy 408.706319 -57.8952) (xy 408.698193 -57.950414) (xy 408.682115 -58.003856) (xy 408.658427 -58.054387)
			(xy 408.627633 -58.100931) (xy 408.590391 -58.142495) (xy 408.547495 -58.178194) (xy 408.499857 -58.207267)
			(xy 408.448494 -58.229094) (xy 408.394501 -58.24321) (xy 408.339027 -58.249313) (xy 408.283256 -58.247275)
			(xy 408.228377 -58.237138) (xy 408.175557 -58.219119) (xy 408.125925 -58.193601) (xy 408.080537 -58.161129)
			(xy 408.04036 -58.122394) (xy 408.006252 -58.078222) (xy 407.978938 -58.029554) (xy 407.959002 -57.977428)
			(xy 407.946867 -57.922955) (xy 407.942794 -57.867296) (xy 406.358784 -57.867296) (xy 406.373221 -57.889118)
			(xy 406.396893 -57.939615) (xy 406.412961 -57.993022) (xy 406.421081 -58.048198) (xy 406.42159 -58.076084)
			(xy 406.421081 -58.10397) (xy 406.412961 -58.159146) (xy 406.396893 -58.212553) (xy 406.373221 -58.26305)
			(xy 406.342448 -58.309563) (xy 406.305231 -58.3511) (xy 406.262363 -58.386775) (xy 406.214757 -58.415829)
			(xy 406.163428 -58.437641) (xy 406.109471 -58.451747) (xy 406.054034 -58.457847) (xy 405.9983 -58.45581)
			(xy 405.943457 -58.44568) (xy 405.890673 -58.427673) (xy 405.841073 -58.402172) (xy 405.795715 -58.369721)
			(xy 405.755566 -58.331012) (xy 405.72148 -58.286869) (xy 405.694184 -58.238234) (xy 405.674261 -58.186143)
			(xy 405.662135 -58.131706) (xy 405.658064 -58.076084) (xy 401.701 -58.076084) (xy 401.701 -58.561224)
			(xy 406.862278 -58.561224) (xy 406.866349 -58.505602) (xy 406.878475 -58.451165) (xy 406.898398 -58.399074)
			(xy 406.925694 -58.350439) (xy 406.95978 -58.306296) (xy 406.999929 -58.267587) (xy 407.045287 -58.235136)
			(xy 407.094887 -58.209635) (xy 407.147671 -58.191628) (xy 407.202514 -58.181498) (xy 407.258248 -58.179461)
			(xy 407.313685 -58.185561) (xy 407.367642 -58.199667) (xy 407.418971 -58.221479) (xy 407.466577 -58.250533)
			(xy 407.509445 -58.286208) (xy 407.546662 -58.327745) (xy 407.577435 -58.374258) (xy 407.601107 -58.424755)
			(xy 407.608617 -58.449718) (xy 409.108908 -58.449718) (xy 409.112979 -58.394096) (xy 409.125105 -58.339659)
			(xy 409.145028 -58.287568) (xy 409.172324 -58.238933) (xy 409.20641 -58.19479) (xy 409.246559 -58.156081)
			(xy 409.291917 -58.12363) (xy 409.341517 -58.098129) (xy 409.394301 -58.080122) (xy 409.449144 -58.069992)
			(xy 409.504878 -58.067955) (xy 409.560315 -58.074055) (xy 409.614272 -58.088161) (xy 409.665601 -58.109973)
			(xy 409.713207 -58.139027) (xy 409.756075 -58.174702) (xy 409.793292 -58.216239) (xy 409.824065 -58.262752)
			(xy 409.847737 -58.313249) (xy 409.863805 -58.366656) (xy 409.871925 -58.421832) (xy 409.872434 -58.449718)
			(xy 409.871925 -58.477604) (xy 409.863805 -58.53278) (xy 409.847737 -58.586187) (xy 409.824065 -58.636684)
			(xy 409.793292 -58.683197) (xy 409.756075 -58.724734) (xy 409.713207 -58.760409) (xy 409.665601 -58.789463)
			(xy 409.614272 -58.811275) (xy 409.560315 -58.825381) (xy 409.504878 -58.831481) (xy 409.449144 -58.829444)
			(xy 409.394301 -58.819314) (xy 409.341517 -58.801307) (xy 409.291917 -58.775806) (xy 409.246559 -58.743355)
			(xy 409.20641 -58.704646) (xy 409.172324 -58.660503) (xy 409.145028 -58.611868) (xy 409.125105 -58.559777)
			(xy 409.112979 -58.50534) (xy 409.108908 -58.449718) (xy 407.608617 -58.449718) (xy 407.617175 -58.478162)
			(xy 407.625295 -58.533338) (xy 407.625804 -58.561224) (xy 407.625295 -58.58911) (xy 407.617175 -58.644286)
			(xy 407.601107 -58.697693) (xy 407.577435 -58.74819) (xy 407.546662 -58.794703) (xy 407.509445 -58.83624)
			(xy 407.466577 -58.871915) (xy 407.418971 -58.900969) (xy 407.367642 -58.922781) (xy 407.313685 -58.936887)
			(xy 407.258248 -58.942987) (xy 407.202514 -58.94095) (xy 407.147671 -58.93082) (xy 407.094887 -58.912813)
			(xy 407.045287 -58.887312) (xy 406.999929 -58.854861) (xy 406.95978 -58.816152) (xy 406.925694 -58.772009)
			(xy 406.898398 -58.723374) (xy 406.878475 -58.671283) (xy 406.866349 -58.616846) (xy 406.862278 -58.561224)
			(xy 401.701 -58.561224) (xy 401.701 -59.974734) (xy 405.387048 -59.974734) (xy 405.387458 -59.947906)
			(xy 405.39498 -59.89478) (xy 405.409865 -59.84323) (xy 405.431822 -59.794272) (xy 405.460416 -59.74887)
			(xy 405.495086 -59.707919) (xy 405.535148 -59.672225) (xy 405.557228 -59.65698) (xy 405.568794 -59.648762)
			(xy 405.587197 -59.627181) (xy 405.598949 -59.601369) (xy 405.603143 -59.573319) (xy 405.599455 -59.545199)
			(xy 405.58817 -59.519179) (xy 405.570159 -59.49727) (xy 405.558752 -59.488832) (xy 405.53729 -59.473487)
			(xy 405.498379 -59.437858) (xy 405.464747 -59.397207) (xy 405.437038 -59.35231) (xy 405.415778 -59.304024)
			(xy 405.401374 -59.253269) (xy 405.3941 -59.201014) (xy 405.393652 -59.174634) (xy 405.394138 -59.147383)
			(xy 405.401894 -59.093435) (xy 405.417249 -59.04114) (xy 405.439891 -58.991563) (xy 405.469357 -58.945713)
			(xy 405.505048 -58.904522) (xy 405.546239 -58.868831) (xy 405.592089 -58.839365) (xy 405.641666 -58.816723)
			(xy 405.693961 -58.801368) (xy 405.747909 -58.793612) (xy 405.802411 -58.793612) (xy 405.856359 -58.801368)
			(xy 405.908654 -58.816723) (xy 405.958231 -58.839365) (xy 406.004081 -58.868831) (xy 406.045272 -58.904522)
			(xy 406.080963 -58.945713) (xy 406.110429 -58.991563) (xy 406.133071 -59.04114) (xy 406.148426 -59.093435)
			(xy 406.156182 -59.147383) (xy 406.156668 -59.174634) (xy 406.156226 -59.201461) (xy 406.148709 -59.254585)
			(xy 406.133829 -59.306134) (xy 406.111877 -59.355092) (xy 406.083288 -59.400494) (xy 406.048623 -59.441446)
			(xy 406.008566 -59.477142) (xy 405.986488 -59.492388) (xy 405.974952 -59.500645) (xy 405.956547 -59.522216)
			(xy 405.944791 -59.54802) (xy 405.940593 -59.576063) (xy 405.944275 -59.604178) (xy 405.955555 -59.630194)
			(xy 405.97356 -59.652099) (xy 405.984964 -59.660536) (xy 406.006462 -59.675834) (xy 406.045371 -59.711471)
			(xy 406.078999 -59.752131) (xy 406.106704 -59.797035) (xy 406.127958 -59.845329) (xy 406.142355 -59.896091)
			(xy 406.14962 -59.948352) (xy 406.150064 -59.974734) (xy 406.149578 -60.001985) (xy 406.141822 -60.055933)
			(xy 406.126467 -60.108228) (xy 406.103825 -60.157805) (xy 406.074359 -60.203655) (xy 406.038668 -60.244846)
			(xy 405.997477 -60.280537) (xy 405.951627 -60.310003) (xy 405.90205 -60.332645) (xy 405.849755 -60.348)
			(xy 405.795807 -60.355756) (xy 405.741305 -60.355756) (xy 405.687357 -60.348) (xy 405.635062 -60.332645)
			(xy 405.585485 -60.310003) (xy 405.539635 -60.280537) (xy 405.498444 -60.244846) (xy 405.462753 -60.203655)
			(xy 405.433287 -60.157805) (xy 405.410645 -60.108228) (xy 405.39529 -60.055933) (xy 405.387534 -60.001985)
			(xy 405.387048 -59.974734) (xy 401.701 -59.974734) (xy 401.701 -60.601606) (xy 404.633174 -60.601606)
			(xy 404.637245 -60.545984) (xy 404.649371 -60.491547) (xy 404.669294 -60.439456) (xy 404.69659 -60.390821)
			(xy 404.730676 -60.346678) (xy 404.770825 -60.307969) (xy 404.816183 -60.275518) (xy 404.865783 -60.250017)
			(xy 404.918567 -60.23201) (xy 404.97341 -60.22188) (xy 405.029144 -60.219843) (xy 405.084581 -60.225943)
			(xy 405.138538 -60.240049) (xy 405.189867 -60.261861) (xy 405.237473 -60.290915) (xy 405.280341 -60.32659)
			(xy 405.317558 -60.368127) (xy 405.348331 -60.41464) (xy 405.372003 -60.465137) (xy 405.388071 -60.518544)
			(xy 405.396191 -60.57372) (xy 405.3967 -60.601606) (xy 405.396236 -60.627006) (xy 407.021282 -60.627006)
			(xy 407.025353 -60.571384) (xy 407.037479 -60.516947) (xy 407.057402 -60.464856) (xy 407.084698 -60.416221)
			(xy 407.118784 -60.372078) (xy 407.158933 -60.333369) (xy 407.204291 -60.300918) (xy 407.253891 -60.275417)
			(xy 407.306675 -60.25741) (xy 407.361518 -60.24728) (xy 407.417252 -60.245243) (xy 407.472689 -60.251343)
			(xy 407.526646 -60.265449) (xy 407.577975 -60.287261) (xy 407.625581 -60.316315) (xy 407.668449 -60.35199)
			(xy 407.705666 -60.393527) (xy 407.736439 -60.44004) (xy 407.760111 -60.490537) (xy 407.776179 -60.543944)
			(xy 407.784299 -60.59912) (xy 407.784808 -60.627006) (xy 407.784692 -60.633356) (xy 409.112972 -60.633356)
			(xy 409.117043 -60.577734) (xy 409.129169 -60.523297) (xy 409.149092 -60.471206) (xy 409.176388 -60.422571)
			(xy 409.210474 -60.378428) (xy 409.250623 -60.339719) (xy 409.295981 -60.307268) (xy 409.345581 -60.281767)
			(xy 409.398365 -60.26376) (xy 409.453208 -60.25363) (xy 409.508942 -60.251593) (xy 409.564379 -60.257693)
			(xy 409.618336 -60.271799) (xy 409.669665 -60.293611) (xy 409.717271 -60.322665) (xy 409.760139 -60.35834)
			(xy 409.797356 -60.399877) (xy 409.828129 -60.44639) (xy 409.851801 -60.496887) (xy 409.867869 -60.550294)
			(xy 409.875989 -60.60547) (xy 409.876498 -60.633356) (xy 409.875989 -60.661242) (xy 409.867869 -60.716418)
			(xy 409.851801 -60.769825) (xy 409.828129 -60.820322) (xy 409.797356 -60.866835) (xy 409.760139 -60.908372)
			(xy 409.717271 -60.944047) (xy 409.669665 -60.973101) (xy 409.618336 -60.994913) (xy 409.564379 -61.009019)
			(xy 409.508942 -61.015119) (xy 409.453208 -61.013082) (xy 409.398365 -61.002952) (xy 409.345581 -60.984945)
			(xy 409.295981 -60.959444) (xy 409.250623 -60.926993) (xy 409.210474 -60.888284) (xy 409.176388 -60.844141)
			(xy 409.149092 -60.795506) (xy 409.129169 -60.743415) (xy 409.117043 -60.688978) (xy 409.112972 -60.633356)
			(xy 407.784692 -60.633356) (xy 407.784299 -60.654892) (xy 407.776179 -60.710068) (xy 407.760111 -60.763475)
			(xy 407.736439 -60.813972) (xy 407.705666 -60.860485) (xy 407.668449 -60.902022) (xy 407.625581 -60.937697)
			(xy 407.577975 -60.966751) (xy 407.526646 -60.988563) (xy 407.472689 -61.002669) (xy 407.417252 -61.008769)
			(xy 407.361518 -61.006732) (xy 407.306675 -60.996602) (xy 407.253891 -60.978595) (xy 407.204291 -60.953094)
			(xy 407.158933 -60.920643) (xy 407.118784 -60.881934) (xy 407.084698 -60.837791) (xy 407.057402 -60.789156)
			(xy 407.037479 -60.737065) (xy 407.025353 -60.682628) (xy 407.021282 -60.627006) (xy 405.396236 -60.627006)
			(xy 405.396191 -60.629492) (xy 405.388071 -60.684668) (xy 405.372003 -60.738075) (xy 405.348331 -60.788572)
			(xy 405.317558 -60.835085) (xy 405.280341 -60.876622) (xy 405.237473 -60.912297) (xy 405.189867 -60.941351)
			(xy 405.138538 -60.963163) (xy 405.084581 -60.977269) (xy 405.029144 -60.983369) (xy 404.97341 -60.981332)
			(xy 404.918567 -60.971202) (xy 404.865783 -60.953195) (xy 404.816183 -60.927694) (xy 404.770825 -60.895243)
			(xy 404.730676 -60.856534) (xy 404.69659 -60.812391) (xy 404.669294 -60.763756) (xy 404.649371 -60.711665)
			(xy 404.637245 -60.657228) (xy 404.633174 -60.601606) (xy 401.701 -60.601606) (xy 401.701 -61.333126)
			(xy 401.701428 -61.343194) (xy 401.709149 -61.361792) (xy 401.715986 -61.369194) (xy 401.914868 -61.568076)
			(xy 401.934934 -61.575696) (xy 401.945856 -61.575188) (xy 401.961858 -61.57468) (xy 404.485094 -61.57468)
			(xy 404.519892 -61.576712) (xy 404.52294 -61.576966) (xy 405.325834 -61.576966)
		)
		(stroke
			(width 0)
			(type solid)
		)
		(fill yes)
		(layer "In9.Cu")
		(net "P3V3_SSD14")
	)
	(gr_poly
		(pts
			(xy 238.997744 -61.57468) (xy 240.565432 -61.57468) (xy 240.574538 -61.574311) (xy 240.591598 -61.567937)
			(xy 240.598706 -61.562234) (xy 240.603532 -61.55817) (xy 240.612168 -61.542676) (xy 240.613946 -61.531246)
			(xy 240.61848 -61.503359) (xy 240.634699 -61.449239) (xy 240.658728 -61.398106) (xy 240.690039 -61.351079)
			(xy 240.727948 -61.309187) (xy 240.771624 -61.273349) (xy 240.820111 -61.244349) (xy 240.872346 -61.222821)
			(xy 240.927187 -61.209239) (xy 240.983431 -61.203898) (xy 241.039848 -61.206916) (xy 241.095202 -61.218227)
			(xy 241.14828 -61.237584) (xy 241.197921 -61.264561) (xy 241.243037 -61.298569) (xy 241.28264 -61.338863)
			(xy 241.315863 -61.38456) (xy 241.329464 -61.409326) (xy 241.343964 -61.438523) (xy 241.363895 -61.500587)
			(xy 241.369088 -61.53277) (xy 241.369088 -61.533024) (xy 241.370612 -61.542676) (xy 241.379248 -61.55817)
			(xy 241.384074 -61.562234) (xy 241.391199 -61.567905) (xy 241.408249 -61.574266) (xy 241.417348 -61.57468)
			(xy 242.954048 -61.57468) (xy 242.954048 -61.574426) (xy 242.961922 -61.573918) (xy 242.967256 -61.572902)
			(xy 242.970304 -61.572394) (xy 242.976908 -61.568838) (xy 242.980163 -61.567003) (xy 242.986159 -61.562545)
			(xy 242.988846 -61.559948) (xy 243.62537 -60.923424) (xy 243.628172 -60.917855) (xy 243.631256 -60.905779)
			(xy 243.631466 -60.899548) (xy 243.631466 -38.904926) (xy 243.630958 -38.899084) (xy 243.628418 -38.885368)
			(xy 243.626132 -38.878002) (xy 243.623338 -38.871144) (xy 243.622576 -38.870382) (xy 243.613432 -38.862508)
			(xy 243.613178 -38.862254) (xy 243.581923 -38.834257) (xy 243.523983 -38.773555) (xy 243.471683 -38.70793)
			(xy 243.425438 -38.637906) (xy 243.385618 -38.56404) (xy 243.352538 -38.486919) (xy 243.326462 -38.407158)
			(xy 243.307598 -38.32539) (xy 243.296095 -38.242266) (xy 243.292045 -38.158448) (xy 243.295481 -38.074602)
			(xy 243.300504 -38.032944) (xy 243.306504 -37.990845) (xy 243.325135 -37.907868) (xy 243.351184 -37.826913)
			(xy 243.384439 -37.748642) (xy 243.424628 -37.673694) (xy 243.471423 -37.602683) (xy 243.52444 -37.536189)
			(xy 243.553488 -37.505132) (xy 243.553996 -37.504624) (xy 243.556282 -37.502084) (xy 243.55679 -37.501576)
			(xy 243.557044 -37.501068) (xy 243.573554 -37.484558) (xy 243.574062 -37.48405) (xy 243.599716 -37.459158)
			(xy 243.600732 -37.45865) (xy 243.604542 -37.455094) (xy 243.605304 -37.454332) (xy 243.60759 -37.4523)
			(xy 243.609622 -37.450522) (xy 243.615464 -37.444934) (xy 243.625624 -37.421566) (xy 243.627148 -37.41801)
			(xy 243.629148 -37.41317) (xy 243.631319 -37.402926) (xy 243.631466 -37.39769) (xy 243.631466 -31.238444)
			(xy 243.63158 -31.233489) (xy 243.63349 -31.223764) (xy 243.635276 -31.21914) (xy 243.640356 -31.206948)
			(xy 243.642134 -31.202321) (xy 243.644063 -31.192599) (xy 243.644166 -31.187644) (xy 243.644166 -29.841444)
			(xy 243.643946 -29.834198) (xy 243.639948 -29.820271) (xy 243.636292 -29.814012) (xy 243.621003 -29.792215)
			(xy 243.596007 -29.745207) (xy 243.577797 -29.695176) (xy 243.566729 -29.643099) (xy 243.563016 -29.589987)
			(xy 243.566732 -29.536876) (xy 243.577805 -29.484799) (xy 243.596017 -29.43477) (xy 243.621017 -29.387763)
			(xy 243.636292 -29.365956) (xy 243.639951 -29.359698) (xy 243.643949 -29.34577) (xy 243.644166 -29.338524)
			(xy 243.644166 -28.112974) (xy 243.644286 -28.108426) (xy 243.645941 -28.09948) (xy 243.647468 -28.095194)
			(xy 243.649754 -28.086812) (xy 243.650516 -28.073858) (xy 243.648992 -28.051506) (xy 243.645944 -28.037536)
			(xy 243.638832 -28.017978) (xy 243.638578 -28.01747) (xy 243.620904 -27.992653) (xy 243.592831 -27.938584)
			(xy 243.573697 -27.880745) (xy 243.563988 -27.820601) (xy 243.563394 -27.79014) (xy 243.563855 -27.762885)
			(xy 243.571607 -27.70893) (xy 243.58696 -27.656628) (xy 243.6096 -27.607043) (xy 243.639067 -27.561185)
			(xy 243.67476 -27.519987) (xy 243.715954 -27.48429) (xy 243.761809 -27.454818) (xy 243.811392 -27.432173)
			(xy 243.863693 -27.416815) (xy 243.917647 -27.409057) (xy 243.944902 -27.408632) (xy 243.97045 -27.409041)
			(xy 244.021088 -27.415856) (xy 244.070365 -27.429365) (xy 244.1174 -27.449326) (xy 244.161353 -27.475383)
			(xy 244.18163 -27.490928) (xy 244.181884 -27.491182) (xy 244.19085 -27.4975) (xy 244.212176 -27.502528)
			(xy 244.233653 -27.498188) (xy 244.242844 -27.492198) (xy 244.24894 -27.487118) (xy 244.388386 -27.347672)
			(xy 244.395786 -27.340831) (xy 244.414385 -27.333117) (xy 244.424454 -27.332686) (xy 244.571012 -27.332686)
			(xy 244.57533 -27.331924) (xy 244.593618 -27.329384) (xy 244.596158 -27.32913) (xy 244.596666 -27.32913)
			(xy 244.600476 -27.328622) (xy 244.601492 -27.328622) (xy 244.6274 -27.327352) (xy 248.672858 -27.327352)
			(xy 248.682835 -27.326942) (xy 248.701275 -27.319318) (xy 248.715391 -27.305215) (xy 248.723032 -27.286783)
			(xy 248.723404 -27.276806) (xy 248.723404 -26.477722) (xy 248.723605 -26.461533) (xy 248.726018 -26.429244)
			(xy 248.72823 -26.413206) (xy 248.72823 -26.41219) (xy 248.728992 -26.407618) (xy 248.729246 -26.406094)
			(xy 248.7295 -26.405332) (xy 248.7295 -26.405078) (xy 248.730262 -26.401522) (xy 248.730262 -26.400506)
			(xy 248.730516 -26.400252) (xy 248.73077 -26.398728) (xy 248.731532 -26.39441) (xy 248.732802 -26.387044)
			(xy 248.731532 -26.373074) (xy 248.72823 -26.364946) (xy 248.725477 -26.359049) (xy 248.717501 -26.348769)
			(xy 248.712482 -26.344626) (xy 248.707656 -26.341324) (xy 248.701052 -26.336752) (xy 248.690503 -26.330703)
			(xy 248.666344 -26.328295) (xy 248.654824 -26.33218) (xy 248.650506 -26.334466) (xy 248.6234 -26.347744)
			(xy 248.566041 -26.366522) (xy 248.50644 -26.376035) (xy 248.476262 -26.37663) (xy 248.475754 -26.37663)
			(xy 248.448504 -26.376141) (xy 248.39456 -26.368379) (xy 248.34227 -26.353021) (xy 248.292697 -26.330377)
			(xy 248.246851 -26.30091) (xy 248.205664 -26.265219) (xy 248.169976 -26.22403) (xy 248.140511 -26.178182)
			(xy 248.117871 -26.128608) (xy 248.102516 -26.076316) (xy 248.094757 -26.022372) (xy 248.094246 -25.995122)
			(xy 248.094819 -25.964926) (xy 248.104334 -25.905288) (xy 248.12313 -25.847895) (xy 248.150736 -25.794182)
			(xy 248.186463 -25.745491) (xy 248.20753 -25.72385) (xy 248.207784 -25.723596) (xy 248.225799 -25.70573)
			(xy 248.265734 -25.674435) (xy 248.309466 -25.648709) (xy 248.356221 -25.629008) (xy 248.405176 -25.61568)
			(xy 248.455466 -25.608958) (xy 248.480834 -25.608534) (xy 248.509783 -25.609073) (xy 248.567016 -25.617826)
			(xy 248.62227 -25.635124) (xy 248.674276 -25.660572) (xy 248.72184 -25.693585) (xy 248.763871 -25.733405)
			(xy 248.799404 -25.779118) (xy 248.827622 -25.829675) (xy 248.82851 -25.832054) (xy 250.387864 -25.832054)
			(xy 250.391935 -25.776432) (xy 250.404061 -25.721995) (xy 250.423984 -25.669904) (xy 250.45128 -25.621269)
			(xy 250.485366 -25.577126) (xy 250.525515 -25.538417) (xy 250.570873 -25.505966) (xy 250.620473 -25.480465)
			(xy 250.673257 -25.462458) (xy 250.7281 -25.452328) (xy 250.783834 -25.450291) (xy 250.839271 -25.456391)
			(xy 250.893228 -25.470497) (xy 250.944557 -25.492309) (xy 250.992163 -25.521363) (xy 251.035031 -25.557038)
			(xy 251.036565 -25.55875) (xy 254.842264 -25.55875) (xy 254.84275 -25.531499) (xy 254.850506 -25.477551)
			(xy 254.865861 -25.425256) (xy 254.888503 -25.375679) (xy 254.917969 -25.329829) (xy 254.95366 -25.288638)
			(xy 254.994851 -25.252947) (xy 255.040701 -25.223481) (xy 255.090278 -25.200839) (xy 255.142573 -25.185484)
			(xy 255.196521 -25.177728) (xy 255.251023 -25.177728) (xy 255.304971 -25.185484) (xy 255.357266 -25.200839)
			(xy 255.406843 -25.223481) (xy 255.452693 -25.252947) (xy 255.493884 -25.288638) (xy 255.529575 -25.329829)
			(xy 255.559041 -25.375679) (xy 255.581683 -25.425256) (xy 255.597038 -25.477551) (xy 255.604794 -25.531499)
			(xy 255.60528 -25.55875) (xy 255.604716 -25.589012) (xy 255.595165 -25.648778) (xy 255.576294 -25.706285)
			(xy 255.548578 -25.76009) (xy 255.531112 -25.78481) (xy 255.522806 -25.796941) (xy 255.51285 -25.82459)
			(xy 255.51118 -25.85393) (xy 255.517936 -25.88253) (xy 255.532557 -25.908021) (xy 255.553833 -25.928293)
			(xy 255.580001 -25.941666) (xy 255.594358 -25.94483) (xy 255.62026 -25.950132) (xy 255.670383 -25.966955)
			(xy 255.717701 -25.99054) (xy 255.761309 -26.020435) (xy 255.800369 -26.056066) (xy 255.834134 -26.096751)
			(xy 255.861956 -26.141709) (xy 255.883302 -26.190079) (xy 255.897762 -26.240934) (xy 255.90506 -26.293299)
			(xy 255.905508 -26.319734) (xy 257.041902 -26.319734) (xy 257.045973 -26.264112) (xy 257.058099 -26.209675)
			(xy 257.078022 -26.157584) (xy 257.105318 -26.108949) (xy 257.139404 -26.064806) (xy 257.179553 -26.026097)
			(xy 257.224911 -25.993646) (xy 257.274511 -25.968145) (xy 257.327295 -25.950138) (xy 257.382138 -25.940008)
			(xy 257.437872 -25.937971) (xy 257.493309 -25.944071) (xy 257.547266 -25.958177) (xy 257.598595 -25.979989)
			(xy 257.646201 -26.009043) (xy 257.689069 -26.044718) (xy 257.726286 -26.086255) (xy 257.757059 -26.132768)
			(xy 257.780731 -26.183265) (xy 257.796799 -26.236672) (xy 257.804919 -26.291848) (xy 257.805428 -26.319734)
			(xy 257.804919 -26.34762) (xy 257.796799 -26.402796) (xy 257.780731 -26.456203) (xy 257.757059 -26.5067)
			(xy 257.726286 -26.553213) (xy 257.689069 -26.59475) (xy 257.646201 -26.630425) (xy 257.598595 -26.659479)
			(xy 257.547266 -26.681291) (xy 257.493309 -26.695397) (xy 257.437872 -26.701497) (xy 257.382138 -26.69946)
			(xy 257.327295 -26.68933) (xy 257.274511 -26.671323) (xy 257.224911 -26.645822) (xy 257.179553 -26.613371)
			(xy 257.139404 -26.574662) (xy 257.105318 -26.530519) (xy 257.078022 -26.481884) (xy 257.058099 -26.429793)
			(xy 257.045973 -26.375356) (xy 257.041902 -26.319734) (xy 255.905508 -26.319734) (xy 255.905022 -26.346985)
			(xy 255.897266 -26.400933) (xy 255.881911 -26.453228) (xy 255.859269 -26.502805) (xy 255.829803 -26.548655)
			(xy 255.794112 -26.589846) (xy 255.752921 -26.625537) (xy 255.707071 -26.655003) (xy 255.657494 -26.677645)
			(xy 255.605199 -26.693) (xy 255.551251 -26.700756) (xy 255.496749 -26.700756) (xy 255.442801 -26.693)
			(xy 255.390506 -26.677645) (xy 255.340929 -26.655003) (xy 255.295079 -26.625537) (xy 255.253888 -26.589846)
			(xy 255.218197 -26.548655) (xy 255.188731 -26.502805) (xy 255.166089 -26.453228) (xy 255.150734 -26.400933)
			(xy 255.142978 -26.346985) (xy 255.142492 -26.319734) (xy 255.143053 -26.289472) (xy 255.152606 -26.229706)
			(xy 255.171478 -26.172199) (xy 255.199194 -26.118394) (xy 255.21666 -26.093674) (xy 255.225003 -26.081565)
			(xy 255.234961 -26.053909) (xy 255.236629 -26.024561) (xy 255.229869 -25.995954) (xy 255.21524 -25.970458)
			(xy 255.193954 -25.950185) (xy 255.167776 -25.936815) (xy 255.153414 -25.933654) (xy 255.12752 -25.928315)
			(xy 255.077396 -25.911499) (xy 255.030076 -25.887921) (xy 254.986466 -25.858032) (xy 254.947404 -25.822406)
			(xy 254.913637 -25.781725) (xy 254.885814 -25.736769) (xy 254.864468 -25.688401) (xy 254.850008 -25.637548)
			(xy 254.842711 -25.585185) (xy 254.842264 -25.55875) (xy 251.036565 -25.55875) (xy 251.072248 -25.598575)
			(xy 251.103021 -25.645088) (xy 251.126693 -25.695585) (xy 251.142761 -25.748992) (xy 251.150881 -25.804168)
			(xy 251.15139 -25.832054) (xy 251.150881 -25.85994) (xy 251.142761 -25.915116) (xy 251.126693 -25.968523)
			(xy 251.103021 -26.01902) (xy 251.072248 -26.065533) (xy 251.035031 -26.10707) (xy 250.992163 -26.142745)
			(xy 250.944557 -26.171799) (xy 250.893228 -26.193611) (xy 250.839271 -26.207717) (xy 250.783834 -26.213817)
			(xy 250.7281 -26.21178) (xy 250.673257 -26.20165) (xy 250.620473 -26.183643) (xy 250.570873 -26.158142)
			(xy 250.525515 -26.125691) (xy 250.485366 -26.086982) (xy 250.45128 -26.042839) (xy 250.423984 -25.994204)
			(xy 250.404061 -25.942113) (xy 250.391935 -25.887676) (xy 250.387864 -25.832054) (xy 248.82851 -25.832054)
			(xy 248.847878 -25.883914) (xy 248.859707 -25.940592) (xy 248.861834 -25.969468) (xy 248.862596 -25.982422)
			(xy 248.868438 -25.992328) (xy 248.870519 -25.995788) (xy 248.875621 -26.002046) (xy 248.878598 -26.004774)
			(xy 248.885456 -26.009854) (xy 248.921016 -26.031952) (xy 248.959116 -26.055574) (xy 248.963869 -26.05803)
			(xy 248.974116 -26.061105) (xy 248.979436 -26.06167) (xy 248.99112 -26.062432) (xy 249.00255 -26.057606)
			(xy 249.003058 -26.057606) (xy 249.030935 -26.0463) (xy 249.088916 -26.030272) (xy 249.148498 -26.021981)
			(xy 249.178572 -26.021284) (xy 249.181366 -26.021284) (xy 249.211352 -26.021751) (xy 249.270811 -26.029575)
			(xy 249.328741 -26.045095) (xy 249.384148 -26.068043) (xy 249.436086 -26.098028) (xy 249.483665 -26.134537)
			(xy 249.526071 -26.176944) (xy 249.562578 -26.224524) (xy 249.592562 -26.276463) (xy 249.615509 -26.331871)
			(xy 249.62328 -26.360882) (xy 252.305564 -26.360882) (xy 252.309635 -26.30526) (xy 252.321761 -26.250823)
			(xy 252.341684 -26.198732) (xy 252.36898 -26.150097) (xy 252.403066 -26.105954) (xy 252.443215 -26.067245)
			(xy 252.488573 -26.034794) (xy 252.538173 -26.009293) (xy 252.590957 -25.991286) (xy 252.6458 -25.981156)
			(xy 252.701534 -25.979119) (xy 252.756971 -25.985219) (xy 252.810928 -25.999325) (xy 252.862257 -26.021137)
			(xy 252.909863 -26.050191) (xy 252.952731 -26.085866) (xy 252.989948 -26.127403) (xy 253.020721 -26.173916)
			(xy 253.044393 -26.224413) (xy 253.060461 -26.27782) (xy 253.068581 -26.332996) (xy 253.06909 -26.360882)
			(xy 253.068581 -26.388768) (xy 253.060461 -26.443944) (xy 253.044393 -26.497351) (xy 253.020721 -26.547848)
			(xy 252.989948 -26.594361) (xy 252.952731 -26.635898) (xy 252.909863 -26.671573) (xy 252.862257 -26.700627)
			(xy 252.810928 -26.722439) (xy 252.756971 -26.736545) (xy 252.701534 -26.742645) (xy 252.6458 -26.740608)
			(xy 252.590957 -26.730478) (xy 252.538173 -26.712471) (xy 252.488573 -26.68697) (xy 252.443215 -26.654519)
			(xy 252.403066 -26.61581) (xy 252.36898 -26.571667) (xy 252.341684 -26.523032) (xy 252.321761 -26.470941)
			(xy 252.309635 -26.416504) (xy 252.305564 -26.360882) (xy 249.62328 -26.360882) (xy 249.631027 -26.3898)
			(xy 249.63885 -26.44926) (xy 249.639328 -26.479246) (xy 249.639328 -27.276806) (xy 249.639715 -27.28679)
			(xy 249.647318 -27.305251) (xy 249.661432 -27.319371) (xy 249.67989 -27.326981) (xy 249.689874 -27.327352)
			(xy 258.895596 -27.327352) (xy 258.904994 -27.326336) (xy 258.905502 -27.326336) (xy 258.912661 -27.32463)
			(xy 258.925687 -27.317798) (xy 258.931156 -27.312874) (xy 259.291074 -26.952956) (xy 259.296049 -26.947523)
			(xy 259.302886 -26.934482) (xy 259.304536 -26.927302) (xy 259.304536 -26.926794) (xy 259.305552 -26.917396)
			(xy 259.305552 -25.13457) (xy 259.305056 -25.123729) (xy 259.296112 -25.10398) (xy 259.28828 -25.09647)
			(xy 259.244846 -25.058116) (xy 259.231384 -25.046178) (xy 259.227166 -25.042637) (xy 259.217558 -25.037256)
			(xy 259.212334 -25.03551) (xy 259.202682 -25.032716) (xy 259.19176 -25.033986) (xy 259.179996 -25.035332)
			(xy 259.156357 -25.03673) (xy 259.144516 -25.03678) (xy 259.117263 -25.036318) (xy 259.063312 -25.028562)
			(xy 259.011014 -25.013208) (xy 258.961433 -24.990566) (xy 258.91558 -24.961098) (xy 258.874388 -24.925403)
			(xy 258.838695 -24.88421) (xy 258.809229 -24.838356) (xy 258.786588 -24.788775) (xy 258.771235 -24.736476)
			(xy 258.763481 -24.682525) (xy 258.763008 -24.655272) (xy 258.763519 -24.626705) (xy 258.772048 -24.57021)
			(xy 258.788911 -24.51562) (xy 258.800854 -24.489664) (xy 258.803648 -24.483568) (xy 258.806188 -24.470614)
			(xy 258.80568 -24.46401) (xy 258.804958 -24.457141) (xy 258.80031 -24.444141) (xy 258.796536 -24.438356)
			(xy 258.743704 -24.36368) (xy 258.736176 -24.355008) (xy 258.715549 -24.344966) (xy 258.70408 -24.344376)
			(xy 258.698746 -24.34463) (xy 258.688932 -24.345585) (xy 258.669237 -24.346602) (xy 258.659376 -24.346662)
			(xy 258.658868 -24.346662) (xy 258.631643 -24.346139) (xy 258.577755 -24.338321) (xy 258.525527 -24.32292)
			(xy 258.47602 -24.300248) (xy 258.430239 -24.270766) (xy 258.389116 -24.235074) (xy 258.353487 -24.193897)
			(xy 258.324075 -24.148073) (xy 258.301478 -24.098531) (xy 258.286155 -24.046279) (xy 258.278419 -23.99238)
			(xy 258.277868 -23.965154) (xy 258.278354 -23.937903) (xy 258.28611 -23.883955) (xy 258.301465 -23.83166)
			(xy 258.324107 -23.782083) (xy 258.353573 -23.736233) (xy 258.389264 -23.695042) (xy 258.430455 -23.659351)
			(xy 258.476305 -23.629885) (xy 258.525882 -23.607243) (xy 258.578177 -23.591888) (xy 258.632125 -23.584132)
			(xy 258.686627 -23.584132) (xy 258.740575 -23.591888) (xy 258.79287 -23.607243) (xy 258.842447 -23.629885)
			(xy 258.888297 -23.659351) (xy 258.929488 -23.695042) (xy 258.965179 -23.736233) (xy 258.994645 -23.782083)
			(xy 259.017287 -23.83166) (xy 259.032642 -23.883955) (xy 259.040398 -23.937903) (xy 259.040884 -23.965154)
			(xy 259.040378 -23.993723) (xy 259.031859 -24.050221) (xy 259.015005 -24.104816) (xy 259.003038 -24.130762)
			(xy 259.000244 -24.136858) (xy 258.997704 -24.149812) (xy 258.998212 -24.156416) (xy 258.998924 -24.163289)
			(xy 259.003556 -24.1763) (xy 259.007356 -24.18207) (xy 259.060188 -24.256746) (xy 259.067717 -24.265416)
			(xy 259.088344 -24.275455) (xy 259.099812 -24.27605) (xy 259.105146 -24.275796) (xy 259.11496 -24.274841)
			(xy 259.134655 -24.273824) (xy 259.144516 -24.273764) (xy 259.147056 -24.273764) (xy 259.15826 -24.273894)
			(xy 259.180627 -24.275292) (xy 259.19176 -24.276558) (xy 259.202682 -24.277828) (xy 259.212334 -24.275034)
			(xy 259.217567 -24.273309) (xy 259.227175 -24.267921) (xy 259.231384 -24.264366) (xy 259.244846 -24.252428)
			(xy 259.28828 -24.214074) (xy 259.296077 -24.206538) (xy 259.305021 -24.186805) (xy 259.305552 -24.175974)
			(xy 259.305552 -24.081994) (xy 259.302758 -24.073866) (xy 259.292596 -24.043102) (xy 259.281607 -23.979257)
			(xy 259.280914 -23.946866) (xy 259.281618 -23.914475) (xy 259.292594 -23.850629) (xy 259.302758 -23.819866)
			(xy 259.305552 -23.811738) (xy 259.305552 -22.254718) (xy 259.305318 -22.247216) (xy 259.300924 -22.23287)
			(xy 259.296916 -22.226524) (xy 259.293106 -22.220428) (xy 259.281676 -22.21103) (xy 259.280914 -22.210776)
			(xy 259.254556 -22.199836) (xy 259.205156 -22.171267) (xy 259.160565 -22.135655) (xy 259.121778 -22.093796)
			(xy 259.089662 -22.046624) (xy 259.064935 -21.995193) (xy 259.048148 -21.940652) (xy 259.039676 -21.884218)
			(xy 259.039106 -21.855684) (xy 259.039599 -21.827599) (xy 259.047825 -21.772036) (xy 259.064112 -21.71828)
			(xy 259.088106 -21.667494) (xy 259.11929 -21.620777) (xy 259.156988 -21.579138) (xy 259.200386 -21.543479)
			(xy 259.248545 -21.514571) (xy 259.27431 -21.503386) (xy 259.274818 -21.503132) (xy 259.281521 -21.500028)
			(xy 259.292891 -21.49061) (xy 259.29717 -21.48459) (xy 259.301234 -21.478494) (xy 259.303266 -21.47189)
			(xy 259.304317 -21.468232) (xy 259.305459 -21.460709) (xy 259.305552 -21.456904) (xy 259.305552 -15.832328)
			(xy 259.305298 -15.829534) (xy 259.304285 -15.821412) (xy 259.297793 -15.806397) (xy 259.292598 -15.80007)
			(xy 259.278374 -15.785592) (xy 259.240782 -15.747492) (xy 259.237305 -15.744201) (xy 259.229384 -15.738824)
			(xy 259.225034 -15.736824) (xy 259.216144 -15.733014) (xy 259.205222 -15.73276) (xy 259.204968 -15.73276)
			(xy 259.18414 -15.731744) (xy 259.155555 -15.729138) (xy 259.099579 -15.71644) (xy 259.046132 -15.695513)
			(xy 258.996416 -15.666829) (xy 258.951549 -15.631032) (xy 258.931664 -15.610332) (xy 258.93141 -15.609824)
			(xy 258.927619 -15.606004) (xy 258.918781 -15.599865) (xy 258.913884 -15.597632) (xy 258.904232 -15.593568)
			(xy 258.867656 -15.594584) (xy 258.816348 -15.595854) (xy 258.810945 -15.596123) (xy 258.800438 -15.598681)
			(xy 258.79552 -15.600934) (xy 258.785868 -15.605506) (xy 258.778756 -15.614142) (xy 258.760545 -15.635291)
			(xy 258.718998 -15.672554) (xy 258.672466 -15.703369) (xy 258.621942 -15.727078) (xy 258.568504 -15.743174)
			(xy 258.513291 -15.751316) (xy 258.485386 -15.75181) (xy 258.458135 -15.751323) (xy 258.404189 -15.743565)
			(xy 258.351895 -15.728209) (xy 258.30232 -15.705567) (xy 258.256471 -15.6761) (xy 258.215282 -15.640408)
			(xy 258.179592 -15.599218) (xy 258.150127 -15.553368) (xy 258.127486 -15.503791) (xy 258.112132 -15.451498)
			(xy 258.104376 -15.397551) (xy 258.104376 -15.343049) (xy 258.112132 -15.289102) (xy 258.127486 -15.236809)
			(xy 258.150127 -15.187232) (xy 258.179592 -15.141382) (xy 258.215282 -15.100192) (xy 258.256471 -15.0645)
			(xy 258.30232 -15.035033) (xy 258.351895 -15.012391) (xy 258.404189 -14.997035) (xy 258.458135 -14.989277)
			(xy 258.485386 -14.988794) (xy 258.485894 -14.988794) (xy 258.51208 -14.989241) (xy 258.563956 -14.996439)
			(xy 258.614357 -15.010673) (xy 258.662335 -15.031674) (xy 258.706985 -15.059047) (xy 258.747466 -15.092276)
			(xy 258.765548 -15.111222) (xy 258.765802 -15.11173) (xy 258.769588 -15.115558) (xy 258.778417 -15.121716)
			(xy 258.783328 -15.123922) (xy 258.79298 -15.127986) (xy 258.829556 -15.12697) (xy 258.880864 -15.1257)
			(xy 258.886266 -15.125429) (xy 258.896772 -15.122867) (xy 258.901692 -15.12062) (xy 258.911344 -15.116048)
			(xy 258.918456 -15.107412) (xy 258.936321 -15.086664) (xy 258.976981 -15.049998) (xy 259.02246 -15.019513)
			(xy 259.071826 -14.995836) (xy 259.124067 -14.97945) (xy 259.178113 -14.970693) (xy 259.205476 -14.969744)
			(xy 259.20573 -14.969744) (xy 259.216144 -14.96949) (xy 259.225034 -14.96568) (xy 259.229393 -14.963696)
			(xy 259.237318 -14.95832) (xy 259.240782 -14.955012) (xy 259.278374 -14.916912) (xy 259.292598 -14.902434)
			(xy 259.297814 -14.896124) (xy 259.304284 -14.881095) (xy 259.305298 -14.87297) (xy 259.305552 -14.870176)
			(xy 259.305552 -13.73124) (xy 259.305384 -13.72523) (xy 259.302561 -13.713548) (xy 259.299964 -13.708126)
			(xy 259.298126 -13.704651) (xy 259.293534 -13.69827) (xy 259.29082 -13.695426) (xy 258.985004 -13.38961)
			(xy 258.982152 -13.386905) (xy 258.975773 -13.382314) (xy 258.972304 -13.380466) (xy 258.966876 -13.37789)
			(xy 258.955196 -13.37508) (xy 258.94919 -13.374878) (xy 254.24257 -13.374878) (xy 254.23656 -13.375043)
			(xy 254.224875 -13.377861) (xy 254.219456 -13.380466) (xy 254.215982 -13.382306) (xy 254.209603 -13.3869)
			(xy 254.206756 -13.38961) (xy 253.496064 -14.100302) (xy 258.243068 -14.100302) (xy 258.247139 -14.04468)
			(xy 258.259265 -13.990243) (xy 258.279188 -13.938152) (xy 258.306484 -13.889517) (xy 258.34057 -13.845374)
			(xy 258.380719 -13.806665) (xy 258.426077 -13.774214) (xy 258.475677 -13.748713) (xy 258.528461 -13.730706)
			(xy 258.583304 -13.720576) (xy 258.639038 -13.718539) (xy 258.694475 -13.724639) (xy 258.748432 -13.738745)
			(xy 258.799761 -13.760557) (xy 258.847367 -13.789611) (xy 258.890235 -13.825286) (xy 258.927452 -13.866823)
			(xy 258.958225 -13.913336) (xy 258.981897 -13.963833) (xy 258.997965 -14.01724) (xy 259.006085 -14.072416)
			(xy 259.006594 -14.100302) (xy 259.006085 -14.128188) (xy 258.997965 -14.183364) (xy 258.981897 -14.236771)
			(xy 258.958225 -14.287268) (xy 258.927452 -14.333781) (xy 258.890235 -14.375318) (xy 258.847367 -14.410993)
			(xy 258.799761 -14.440047) (xy 258.748432 -14.461859) (xy 258.694475 -14.475965) (xy 258.639038 -14.482065)
			(xy 258.583304 -14.480028) (xy 258.528461 -14.469898) (xy 258.475677 -14.451891) (xy 258.426077 -14.42639)
			(xy 258.380719 -14.393939) (xy 258.34057 -14.35523) (xy 258.306484 -14.311087) (xy 258.279188 -14.262452)
			(xy 258.259265 -14.210361) (xy 258.247139 -14.155924) (xy 258.243068 -14.100302) (xy 253.496064 -14.100302)
			(xy 252.900688 -14.695678) (xy 252.896624 -14.699488) (xy 252.890274 -14.704568) (xy 252.881384 -14.718284)
			(xy 252.864366 -14.784578) (xy 252.862581 -14.792563) (xy 252.863626 -14.808883) (xy 252.866398 -14.816582)
			(xy 252.892737 -14.882753) (xy 252.937862 -15.017851) (xy 252.974197 -15.155574) (xy 253.001592 -15.295351)
			(xy 253.019932 -15.436601) (xy 253.029142 -15.578738) (xy 253.02972 -15.649956) (xy 253.029216 -15.716714)
			(xy 253.021155 -15.849986) (xy 253.005061 -15.982528) (xy 252.980994 -16.113857) (xy 252.949042 -16.243493)
			(xy 252.90932 -16.370963) (xy 252.861975 -16.495803) (xy 252.807179 -16.617556) (xy 252.745131 -16.735778)
			(xy 252.676058 -16.850039) (xy 252.600212 -16.95992) (xy 252.517871 -17.065021) (xy 252.429333 -17.164959)
			(xy 252.334923 -17.259369) (xy 252.234985 -17.347907) (xy 252.129884 -17.430248) (xy 252.020003 -17.506094)
			(xy 251.905742 -17.575167) (xy 251.78752 -17.637215) (xy 251.665767 -17.692011) (xy 251.540927 -17.739356)
			(xy 251.413457 -17.779078) (xy 251.283821 -17.81103) (xy 251.152492 -17.835097) (xy 251.01995 -17.851191)
			(xy 250.886678 -17.859252) (xy 250.753162 -17.859252) (xy 250.61989 -17.851191) (xy 250.487348 -17.835097)
			(xy 250.356019 -17.81103) (xy 250.226383 -17.779078) (xy 250.098913 -17.739356) (xy 249.974073 -17.692011)
			(xy 249.85232 -17.637215) (xy 249.734098 -17.575167) (xy 249.619837 -17.506094) (xy 249.509956 -17.430248)
			(xy 249.404855 -17.347907) (xy 249.304917 -17.259369) (xy 249.210507 -17.164959) (xy 249.121969 -17.065021)
			(xy 249.039628 -16.95992) (xy 248.963782 -16.850039) (xy 248.894709 -16.735778) (xy 248.832661 -16.617556)
			(xy 248.777865 -16.495803) (xy 248.73052 -16.370963) (xy 248.690798 -16.243493) (xy 248.658846 -16.113857)
			(xy 248.634779 -15.982528) (xy 248.618685 -15.849986) (xy 248.610624 -15.716714) (xy 248.61012 -15.649956)
			(xy 248.61012 -15.649702) (xy 248.610668 -15.579764) (xy 248.619512 -15.440167) (xy 248.637173 -15.301409)
			(xy 248.66358 -15.164047) (xy 248.698625 -15.028632) (xy 248.742169 -14.895705) (xy 248.7676 -14.830552)
			(xy 248.77014 -14.824202) (xy 248.707656 -14.732762) (xy 248.700131 -14.722864) (xy 248.678164 -14.711272)
			(xy 248.665746 -14.710664) (xy 246.928894 -14.710664) (xy 246.920258 -14.711426) (xy 246.916215 -14.712208)
			(xy 246.908428 -14.714883) (xy 246.904764 -14.71676) (xy 246.904764 -14.717014) (xy 246.898257 -14.720907)
			(xy 246.887669 -14.731751) (xy 246.883936 -14.73835) (xy 246.880634 -14.744954) (xy 246.841518 -14.822424)
			(xy 246.839282 -14.828055) (xy 246.837228 -14.839992) (xy 246.837454 -14.846046) (xy 246.837454 -14.846554)
			(xy 246.850916 -14.865096) (xy 246.875559 -14.899596) (xy 246.919239 -14.972268) (xy 246.956204 -15.048574)
			(xy 246.986155 -15.127897) (xy 247.008849 -15.209593) (xy 247.024101 -15.292998) (xy 247.031788 -15.377438)
			(xy 247.032272 -15.419832) (xy 247.032272 -15.425674) (xy 247.031429 -15.471623) (xy 247.021889 -15.563034)
			(xy 247.003476 -15.653078) (xy 246.976363 -15.740896) (xy 246.940811 -15.825649) (xy 246.919496 -15.866364)
			(xy 246.919496 -15.866618) (xy 246.9167 -15.872189) (xy 246.913628 -15.884265) (xy 246.9134 -15.890494)
			(xy 246.9134 -15.903194) (xy 246.93753 -15.947898) (xy 246.956072 -15.982696) (xy 246.959208 -15.987751)
			(xy 246.967422 -15.99635) (xy 246.972328 -15.999714) (xy 246.982742 -16.006572) (xy 246.995696 -16.007588)
			(xy 247.039931 -16.011814) (xy 247.127429 -16.02736) (xy 247.213128 -16.050877) (xy 247.296305 -16.082167)
			(xy 247.376256 -16.120966) (xy 247.452305 -16.166945) (xy 247.523809 -16.219715) (xy 247.590164 -16.27883)
			(xy 247.650807 -16.34379) (xy 247.705227 -16.414046) (xy 247.752963 -16.489005) (xy 247.793612 -16.568031)
			(xy 247.82683 -16.650457) (xy 247.852336 -16.735586) (xy 247.869914 -16.822698) (xy 247.879416 -16.911056)
			(xy 247.880762 -16.999914) (xy 247.873939 -17.088519) (xy 247.859006 -17.176124) (xy 247.836089 -17.261986)
			(xy 247.805382 -17.34538) (xy 247.767144 -17.4256) (xy 247.721699 -17.501969) (xy 247.669431 -17.573841)
			(xy 247.610782 -17.640607) (xy 247.57888 -17.671542) (xy 247.546745 -17.701734) (xy 247.477851 -17.756774)
			(xy 247.404227 -17.805304) (xy 247.326484 -17.84692) (xy 247.245272 -17.881276) (xy 247.161266 -17.908085)
			(xy 247.075165 -17.927125) (xy 246.987688 -17.938235) (xy 246.899562 -17.941325) (xy 246.811521 -17.936369)
			(xy 246.724298 -17.923407) (xy 246.638621 -17.902547) (xy 246.555201 -17.873964) (xy 246.474735 -17.837895)
			(xy 246.397892 -17.794641) (xy 246.325312 -17.744561) (xy 246.2576 -17.688074) (xy 246.195319 -17.625649)
			(xy 246.138989 -17.557806) (xy 246.089077 -17.485111) (xy 246.046001 -17.408168) (xy 246.010118 -17.327618)
			(xy 245.981728 -17.244133) (xy 245.961067 -17.158408) (xy 245.948306 -17.071155) (xy 245.943553 -16.983103)
			(xy 245.946847 -16.894984) (xy 245.958161 -16.807533) (xy 245.977399 -16.721477) (xy 246.004402 -16.637533)
			(xy 246.038946 -16.5564) (xy 246.059452 -16.517366) (xy 246.060976 -16.514318) (xy 246.063008 -16.509492)
			(xy 246.066763 -16.498566) (xy 246.065031 -16.475551) (xy 246.059706 -16.465296) (xy 246.057928 -16.462502)
			(xy 246.014748 -16.390112) (xy 246.012165 -16.386069) (xy 246.005767 -16.37892) (xy 246.002048 -16.375888)
			(xy 245.995262 -16.370978) (xy 245.979431 -16.365534) (xy 245.97106 -16.36522) (xy 244.232684 -16.36522)
			(xy 244.189246 -16.364733) (xy 244.102741 -16.356715) (xy 244.017345 -16.34075) (xy 243.933787 -16.316974)
			(xy 243.852778 -16.285589) (xy 243.775011 -16.246864) (xy 243.701149 -16.201128) (xy 243.631823 -16.148772)
			(xy 243.567622 -16.090242) (xy 243.509096 -16.026039) (xy 243.456744 -15.956709) (xy 243.411012 -15.882845)
			(xy 243.372291 -15.805076) (xy 243.34091 -15.724066) (xy 243.317138 -15.640506) (xy 243.301178 -15.555109)
			(xy 243.293165 -15.468604) (xy 243.29263 -15.425166) (xy 243.29263 -15.424658) (xy 243.293101 -15.382443)
			(xy 243.300694 -15.298354) (xy 243.315798 -15.215285) (xy 243.338289 -15.133905) (xy 243.367988 -15.05487)
			(xy 243.404655 -14.978817) (xy 243.447994 -14.906358) (xy 243.472462 -14.871954) (xy 243.47678 -14.866112)
			(xy 243.481352 -14.853412) (xy 243.482114 -14.846046) (xy 243.482383 -14.839073) (xy 243.479545 -14.825414)
			(xy 243.476526 -14.819122) (xy 243.470938 -14.8082) (xy 243.433854 -14.735048) (xy 243.430724 -14.730377)
			(xy 243.422781 -14.722423) (xy 243.418106 -14.7193) (xy 243.412264 -14.715998) (xy 243.406998 -14.713558)
			(xy 243.395712 -14.710866) (xy 243.389912 -14.710664) (xy 234.069382 -14.710664) (xy 234.063371 -14.710827)
			(xy 234.051685 -14.713643) (xy 234.046268 -14.716252) (xy 234.042796 -14.718094) (xy 234.036421 -14.722692)
			(xy 234.033568 -14.725396) (xy 233.63047 -15.128494) (xy 233.627762 -15.131344) (xy 233.623166 -15.13772)
			(xy 233.621326 -15.141194) (xy 233.618747 -15.146622) (xy 233.615934 -15.158301) (xy 233.615738 -15.164308)
			(xy 233.615738 -18.44421) (xy 254.476248 -18.44421) (xy 254.480319 -18.388588) (xy 254.492445 -18.334151)
			(xy 254.512368 -18.28206) (xy 254.539664 -18.233425) (xy 254.57375 -18.189282) (xy 254.613899 -18.150573)
			(xy 254.659257 -18.118122) (xy 254.708857 -18.092621) (xy 254.761641 -18.074614) (xy 254.816484 -18.064484)
			(xy 254.872218 -18.062447) (xy 254.927655 -18.068547) (xy 254.981612 -18.082653) (xy 255.032941 -18.104465)
			(xy 255.080547 -18.133519) (xy 255.123415 -18.169194) (xy 255.160632 -18.210731) (xy 255.191405 -18.257244)
			(xy 255.215077 -18.307741) (xy 255.231145 -18.361148) (xy 255.239265 -18.416324) (xy 255.239774 -18.44421)
			(xy 255.239265 -18.472096) (xy 255.231145 -18.527272) (xy 255.215077 -18.580679) (xy 255.191405 -18.631176)
			(xy 255.160632 -18.677689) (xy 255.123415 -18.719226) (xy 255.080547 -18.754901) (xy 255.032941 -18.783955)
			(xy 254.981612 -18.805767) (xy 254.927655 -18.819873) (xy 254.872218 -18.825973) (xy 254.816484 -18.823936)
			(xy 254.761641 -18.813806) (xy 254.708857 -18.795799) (xy 254.659257 -18.770298) (xy 254.613899 -18.737847)
			(xy 254.57375 -18.699138) (xy 254.539664 -18.654995) (xy 254.512368 -18.60636) (xy 254.492445 -18.554269)
			(xy 254.480319 -18.499832) (xy 254.476248 -18.44421) (xy 233.615738 -18.44421) (xy 233.615738 -20.72513)
			(xy 237.380538 -20.72513) (xy 237.384508 -20.594996) (xy 237.396404 -20.465346) (xy 237.416183 -20.336663)
			(xy 237.443769 -20.209424) (xy 237.479062 -20.084105) (xy 237.521928 -19.961169) (xy 237.57221 -19.841076)
			(xy 237.629719 -19.724272) (xy 237.694243 -19.61119) (xy 237.76554 -19.502253) (xy 237.843345 -19.397865)
			(xy 237.92737 -19.298414) (xy 238.017302 -19.204271) (xy 238.112806 -19.115786) (xy 238.213526 -19.033287)
			(xy 238.319088 -18.957082) (xy 238.4291 -18.887455) (xy 238.543152 -18.824664) (xy 238.66082 -18.768942)
			(xy 238.781666 -18.720498) (xy 238.905241 -18.679511) (xy 239.031084 -18.646134) (xy 239.158729 -18.620491)
			(xy 239.287699 -18.602677) (xy 239.417515 -18.592759) (xy 239.547694 -18.590774) (xy 239.677753 -18.596728)
			(xy 239.807206 -18.610601) (xy 239.935573 -18.632339) (xy 240.062376 -18.661863) (xy 240.187143 -18.699062)
			(xy 240.30941 -18.743798) (xy 240.428723 -18.795906) (xy 240.544636 -18.855189) (xy 240.656721 -18.92143)
			(xy 240.764558 -18.99438) (xy 240.867747 -19.073768) (xy 240.965905 -19.1593) (xy 241.058666 -19.250657)
			(xy 241.145685 -19.347499) (xy 241.226638 -19.449466) (xy 241.301224 -19.556178) (xy 241.369165 -19.667239)
			(xy 241.43021 -19.782235) (xy 241.484131 -19.900739) (xy 241.530726 -20.02231) (xy 241.569824 -20.146495)
			(xy 241.601278 -20.272833) (xy 241.624972 -20.400854) (xy 241.640816 -20.53008) (xy 241.648754 -20.660033)
			(xy 241.64925 -20.72513) (xy 241.648754 -20.790227) (xy 241.640816 -20.92018) (xy 241.624972 -21.049406)
			(xy 241.601278 -21.177427) (xy 241.569824 -21.303765) (xy 241.530726 -21.42795) (xy 241.484131 -21.549521)
			(xy 241.43021 -21.668025) (xy 241.392886 -21.738336) (xy 243.616734 -21.738336) (xy 243.617236 -21.709597)
			(xy 243.625867 -21.652769) (xy 243.642923 -21.597879) (xy 243.668019 -21.546167) (xy 243.700586 -21.498805)
			(xy 243.719858 -21.477478) (xy 243.726462 -21.47062) (xy 243.733574 -21.452586) (xy 243.733574 -21.363686)
			(xy 243.726462 -21.345652) (xy 243.719858 -21.338794) (xy 243.700621 -21.317437) (xy 243.668052 -21.270081)
			(xy 243.642956 -21.218374) (xy 243.625902 -21.163488) (xy 243.617275 -21.106664) (xy 243.617271 -21.049189)
			(xy 243.62589 -20.992364) (xy 243.642937 -20.937475) (xy 243.668026 -20.885765) (xy 243.700588 -20.838404)
			(xy 243.719858 -20.817078) (xy 243.726462 -20.81022) (xy 243.733574 -20.792186) (xy 243.733574 -20.703286)
			(xy 243.726462 -20.685252) (xy 243.719858 -20.678394) (xy 243.700621 -20.657037) (xy 243.668052 -20.609681)
			(xy 243.642956 -20.557974) (xy 243.625902 -20.503088) (xy 243.617275 -20.446264) (xy 243.617271 -20.388789)
			(xy 243.62589 -20.331964) (xy 243.642937 -20.277075) (xy 243.668026 -20.225365) (xy 243.700588 -20.178004)
			(xy 243.719858 -20.156678) (xy 243.726462 -20.14982) (xy 243.733574 -20.131786) (xy 243.733574 -20.042886)
			(xy 243.726462 -20.024852) (xy 243.719858 -20.017994) (xy 243.700621 -19.996637) (xy 243.668052 -19.949281)
			(xy 243.642956 -19.897574) (xy 243.625902 -19.842688) (xy 243.617275 -19.785864) (xy 243.617271 -19.728389)
			(xy 243.62589 -19.671564) (xy 243.642937 -19.616675) (xy 243.668026 -19.564965) (xy 243.700588 -19.517604)
			(xy 243.719858 -19.496278) (xy 243.726462 -19.48942) (xy 243.733574 -19.471386) (xy 243.733574 -19.382486)
			(xy 243.726462 -19.364452) (xy 243.719858 -19.357594) (xy 243.700608 -19.336249) (xy 243.668038 -19.288892)
			(xy 243.642941 -19.237185) (xy 243.625886 -19.182298) (xy 243.617258 -19.125474) (xy 243.616734 -19.096736)
			(xy 243.61722 -19.069485) (xy 243.624976 -19.015537) (xy 243.640331 -18.963242) (xy 243.662973 -18.913665)
			(xy 243.692439 -18.867815) (xy 243.72813 -18.826624) (xy 243.769321 -18.790933) (xy 243.815171 -18.761467)
			(xy 243.864748 -18.738825) (xy 243.917043 -18.72347) (xy 243.970991 -18.715714) (xy 244.025493 -18.715714)
			(xy 244.079441 -18.72347) (xy 244.131736 -18.738825) (xy 244.181313 -18.761467) (xy 244.227163 -18.790933)
			(xy 244.268354 -18.826624) (xy 244.304045 -18.867815) (xy 244.333511 -18.913665) (xy 244.356153 -18.963242)
			(xy 244.371508 -19.015537) (xy 244.379264 -19.069485) (xy 244.37975 -19.096736) (xy 244.379235 -19.125475)
			(xy 244.370608 -19.182302) (xy 244.353555 -19.237193) (xy 244.328462 -19.288904) (xy 244.295897 -19.336267)
			(xy 244.276626 -19.357594) (xy 244.270022 -19.364452) (xy 244.26291 -19.382486) (xy 244.26291 -19.471386)
			(xy 244.270022 -19.48942) (xy 244.276626 -19.496278) (xy 244.29593 -19.517575) (xy 244.32849 -19.564944)
			(xy 244.353576 -19.616661) (xy 244.370621 -19.671556) (xy 244.379239 -19.728386) (xy 244.379235 -19.785866)
			(xy 244.37061 -19.842696) (xy 244.353557 -19.897588) (xy 244.328464 -19.949302) (xy 244.295897 -19.996666)
			(xy 244.276626 -20.017994) (xy 244.270022 -20.024852) (xy 244.26291 -20.042886) (xy 244.26291 -20.131786)
			(xy 244.270022 -20.14982) (xy 244.276626 -20.156678) (xy 244.29593 -20.177975) (xy 244.32849 -20.225344)
			(xy 244.353576 -20.277061) (xy 244.370621 -20.331956) (xy 244.379239 -20.388786) (xy 244.379235 -20.446266)
			(xy 244.37061 -20.503096) (xy 244.353557 -20.557988) (xy 244.328464 -20.609702) (xy 244.295897 -20.657066)
			(xy 244.276626 -20.678394) (xy 244.270022 -20.685252) (xy 244.26291 -20.703286) (xy 244.26291 -20.792186)
			(xy 244.270022 -20.81022) (xy 244.276626 -20.817078) (xy 244.29593 -20.838375) (xy 244.32849 -20.885744)
			(xy 244.353576 -20.937461) (xy 244.370621 -20.992356) (xy 244.379239 -21.049186) (xy 244.379235 -21.106666)
			(xy 244.37061 -21.163496) (xy 244.353557 -21.218388) (xy 244.328464 -21.270102) (xy 244.295897 -21.317466)
			(xy 244.276626 -21.338794) (xy 244.270022 -21.345652) (xy 244.26291 -21.363686) (xy 244.26291 -21.452586)
			(xy 244.270022 -21.47062) (xy 244.276626 -21.477478) (xy 244.295908 -21.498796) (xy 244.328474 -21.54616)
			(xy 244.353565 -21.597873) (xy 244.366344 -21.639022) (xy 248.273824 -21.639022) (xy 248.274381 -21.610285)
			(xy 248.282999 -21.55346) (xy 248.300042 -21.49857) (xy 248.325126 -21.446858) (xy 248.357682 -21.399493)
			(xy 248.376948 -21.378164) (xy 248.383552 -21.371306) (xy 248.390664 -21.353272) (xy 248.390664 -21.264372)
			(xy 248.383552 -21.246338) (xy 248.376948 -21.23948) (xy 248.357698 -21.218135) (xy 248.32513 -21.170776)
			(xy 248.300036 -21.119068) (xy 248.282983 -21.064179) (xy 248.274358 -21.007354) (xy 248.274355 -20.949878)
			(xy 248.282976 -20.893052) (xy 248.300024 -20.838162) (xy 248.325114 -20.786452) (xy 248.357678 -20.73909)
			(xy 248.376948 -20.717764) (xy 248.383552 -20.710906) (xy 248.390664 -20.692872) (xy 248.390664 -20.603972)
			(xy 248.383552 -20.585938) (xy 248.376948 -20.57908) (xy 248.357698 -20.557735) (xy 248.32513 -20.510376)
			(xy 248.300036 -20.458668) (xy 248.282983 -20.403779) (xy 248.274358 -20.346954) (xy 248.274355 -20.289478)
			(xy 248.282976 -20.232652) (xy 248.300024 -20.177762) (xy 248.325114 -20.126052) (xy 248.357678 -20.07869)
			(xy 248.376948 -20.057364) (xy 248.383552 -20.050506) (xy 248.390664 -20.032472) (xy 248.390664 -19.943572)
			(xy 248.383552 -19.925538) (xy 248.376948 -19.91868) (xy 248.357698 -19.897335) (xy 248.32513 -19.849976)
			(xy 248.300036 -19.798268) (xy 248.282983 -19.743379) (xy 248.274358 -19.686554) (xy 248.274355 -19.629078)
			(xy 248.282976 -19.572252) (xy 248.300024 -19.517362) (xy 248.325114 -19.465652) (xy 248.357678 -19.41829)
			(xy 248.376948 -19.396964) (xy 248.383552 -19.390106) (xy 248.390664 -19.372072) (xy 248.390664 -19.283172)
			(xy 248.383552 -19.265138) (xy 248.376948 -19.25828) (xy 248.357689 -19.236942) (xy 248.325121 -19.189584)
			(xy 248.300026 -19.137875) (xy 248.282973 -19.082986) (xy 248.274347 -19.02616) (xy 248.273824 -18.997422)
			(xy 248.27431 -18.970171) (xy 248.282066 -18.916223) (xy 248.297421 -18.863928) (xy 248.320063 -18.814351)
			(xy 248.349529 -18.768501) (xy 248.38522 -18.72731) (xy 248.426411 -18.691619) (xy 248.472261 -18.662153)
			(xy 248.521838 -18.639511) (xy 248.574133 -18.624156) (xy 248.628081 -18.6164) (xy 248.682583 -18.6164)
			(xy 248.736531 -18.624156) (xy 248.788826 -18.639511) (xy 248.838403 -18.662153) (xy 248.884253 -18.691619)
			(xy 248.925444 -18.72731) (xy 248.961135 -18.768501) (xy 248.990601 -18.814351) (xy 249.013243 -18.863928)
			(xy 249.028598 -18.916223) (xy 249.036354 -18.970171) (xy 249.03684 -18.997422) (xy 249.036319 -19.026161)
			(xy 249.027694 -19.082988) (xy 249.010643 -19.137878) (xy 248.985551 -19.18959) (xy 248.952986 -19.236953)
			(xy 248.933716 -19.25828) (xy 248.927112 -19.265138) (xy 248.92 -19.283172) (xy 248.92 -19.366853)
			(xy 253.779238 -19.366853) (xy 253.779238 -19.312347) (xy 253.786994 -19.258396) (xy 253.80235 -19.206098)
			(xy 253.824991 -19.156517) (xy 253.854458 -19.110663) (xy 253.890151 -19.069469) (xy 253.931342 -19.033774)
			(xy 253.977194 -19.004304) (xy 254.026773 -18.981659) (xy 254.079071 -18.9663) (xy 254.133021 -18.95854)
			(xy 254.160274 -18.958052) (xy 254.187044 -18.958547) (xy 254.240058 -18.966041) (xy 254.291503 -18.980872)
			(xy 254.34037 -19.002748) (xy 254.3857 -19.03124) (xy 254.426603 -19.065788) (xy 254.462274 -19.105714)
			(xy 254.47752 -19.127724) (xy 254.477774 -19.127978) (xy 254.484007 -19.13637) (xy 254.501585 -19.147646)
			(xy 254.51181 -19.149822) (xy 254.584962 -19.16176) (xy 254.595411 -19.162901) (xy 254.615743 -19.157659)
			(xy 254.624332 -19.1516) (xy 254.64445 -19.136478) (xy 254.687928 -19.111127) (xy 254.734366 -19.091722)
			(xy 254.782954 -19.078599) (xy 254.832847 -19.071987) (xy 254.858012 -19.07159) (xy 254.858266 -19.07159)
			(xy 254.88552 -19.072055) (xy 254.939475 -19.079808) (xy 254.991776 -19.095161) (xy 255.04136 -19.117801)
			(xy 255.087218 -19.147268) (xy 255.128414 -19.182962) (xy 255.164111 -19.224155) (xy 255.193582 -19.27001)
			(xy 255.216227 -19.319592) (xy 255.231585 -19.371892) (xy 255.239343 -19.425846) (xy 255.239343 -19.480354)
			(xy 255.231585 -19.534308) (xy 255.216227 -19.586608) (xy 255.193582 -19.63619) (xy 255.164111 -19.682045)
			(xy 255.128414 -19.723238) (xy 255.087218 -19.758932) (xy 255.04136 -19.788399) (xy 254.991776 -19.811039)
			(xy 254.939475 -19.826392) (xy 254.88552 -19.834145) (xy 254.858266 -19.834606) (xy 254.831493 -19.834175)
			(xy 254.778476 -19.826672) (xy 254.727029 -19.811831) (xy 254.67816 -19.789945) (xy 254.632831 -19.761443)
			(xy 254.591931 -19.726885) (xy 254.556263 -19.686948) (xy 254.54102 -19.664934) (xy 254.540766 -19.66468)
			(xy 254.534504 -19.656313) (xy 254.516948 -19.645022) (xy 254.50673 -19.642836) (xy 254.433578 -19.630898)
			(xy 254.423128 -19.629768) (xy 254.402797 -19.635001) (xy 254.394208 -19.641058) (xy 254.374073 -19.656156)
			(xy 254.3306 -19.681512) (xy 254.284166 -19.700923) (xy 254.235582 -19.714051) (xy 254.185692 -19.720668)
			(xy 254.160528 -19.721068) (xy 254.160274 -19.721068) (xy 254.133021 -19.72066) (xy 254.079071 -19.7129)
			(xy 254.026773 -19.697541) (xy 253.977194 -19.674896) (xy 253.931342 -19.645426) (xy 253.890151 -19.609731)
			(xy 253.854458 -19.568537) (xy 253.824991 -19.522683) (xy 253.80235 -19.473102) (xy 253.786994 -19.420804)
			(xy 253.779238 -19.366853) (xy 248.92 -19.366853) (xy 248.92 -19.372072) (xy 248.927112 -19.390106)
			(xy 248.933716 -19.396964) (xy 248.953007 -19.418273) (xy 248.985568 -19.465639) (xy 249.010656 -19.517354)
			(xy 249.027702 -19.572248) (xy 249.036322 -19.629077) (xy 249.036319 -19.686556) (xy 249.027695 -19.743384)
			(xy 249.010644 -19.798275) (xy 248.985552 -19.849988) (xy 248.952987 -19.897352) (xy 248.933716 -19.91868)
			(xy 248.927112 -19.925538) (xy 248.92 -19.943572) (xy 248.92 -20.032472) (xy 248.927112 -20.050506)
			(xy 248.933716 -20.057364) (xy 248.953007 -20.078673) (xy 248.985568 -20.126039) (xy 249.010656 -20.177754)
			(xy 249.027702 -20.232648) (xy 249.036322 -20.289477) (xy 249.036319 -20.346956) (xy 249.035013 -20.35556)
			(xy 253.778256 -20.35556) (xy 253.782327 -20.299938) (xy 253.794453 -20.245501) (xy 253.814376 -20.19341)
			(xy 253.841672 -20.144775) (xy 253.875758 -20.100632) (xy 253.915907 -20.061923) (xy 253.961265 -20.029472)
			(xy 254.010865 -20.003971) (xy 254.063649 -19.985964) (xy 254.118492 -19.975834) (xy 254.174226 -19.973797)
			(xy 254.229663 -19.979897) (xy 254.28362 -19.994003) (xy 254.334949 -20.015815) (xy 254.382555 -20.044869)
			(xy 254.425423 -20.080544) (xy 254.46264 -20.122081) (xy 254.493413 -20.168594) (xy 254.517085 -20.219091)
			(xy 254.533153 -20.272498) (xy 254.541273 -20.327674) (xy 254.541782 -20.35556) (xy 254.541273 -20.383446)
			(xy 254.533153 -20.438622) (xy 254.517085 -20.492029) (xy 254.493413 -20.542526) (xy 254.46264 -20.589039)
			(xy 254.425423 -20.630576) (xy 254.382555 -20.666251) (xy 254.334949 -20.695305) (xy 254.28362 -20.717117)
			(xy 254.229663 -20.731223) (xy 254.174226 -20.737323) (xy 254.118492 -20.735286) (xy 254.063649 -20.725156)
			(xy 254.010865 -20.707149) (xy 253.961265 -20.681648) (xy 253.915907 -20.649197) (xy 253.875758 -20.610488)
			(xy 253.841672 -20.566345) (xy 253.814376 -20.51771) (xy 253.794453 -20.465619) (xy 253.782327 -20.411182)
			(xy 253.778256 -20.35556) (xy 249.035013 -20.35556) (xy 249.027695 -20.403784) (xy 249.010644 -20.458675)
			(xy 248.985552 -20.510388) (xy 248.952987 -20.557752) (xy 248.933716 -20.57908) (xy 248.927112 -20.585938)
			(xy 248.92 -20.603972) (xy 248.92 -20.692872) (xy 248.927112 -20.710906) (xy 248.933716 -20.717764)
			(xy 248.953007 -20.739073) (xy 248.985568 -20.786439) (xy 249.010656 -20.838154) (xy 249.027702 -20.893048)
			(xy 249.036322 -20.949877) (xy 249.036319 -21.007356) (xy 249.027695 -21.064184) (xy 249.010644 -21.119075)
			(xy 248.985552 -21.170788) (xy 248.952987 -21.218152) (xy 248.933716 -21.23948) (xy 248.927112 -21.246338)
			(xy 248.92 -21.264372) (xy 248.92 -21.353272) (xy 248.927112 -21.371306) (xy 248.927357 -21.37156)
			(xy 253.778256 -21.37156) (xy 253.782327 -21.315938) (xy 253.794453 -21.261501) (xy 253.814376 -21.20941)
			(xy 253.841672 -21.160775) (xy 253.875758 -21.116632) (xy 253.915907 -21.077923) (xy 253.961265 -21.045472)
			(xy 254.010865 -21.019971) (xy 254.063649 -21.001964) (xy 254.118492 -20.991834) (xy 254.174226 -20.989797)
			(xy 254.229663 -20.995897) (xy 254.28362 -21.010003) (xy 254.334949 -21.031815) (xy 254.382555 -21.060869)
			(xy 254.425423 -21.096544) (xy 254.46264 -21.138081) (xy 254.493413 -21.184594) (xy 254.517085 -21.235091)
			(xy 254.533153 -21.288498) (xy 254.541273 -21.343674) (xy 254.541782 -21.37156) (xy 254.541273 -21.399446)
			(xy 254.533153 -21.454622) (xy 254.517085 -21.508029) (xy 254.493413 -21.558526) (xy 254.46264 -21.605039)
			(xy 254.425423 -21.646576) (xy 254.382555 -21.682251) (xy 254.334949 -21.711305) (xy 254.28362 -21.733117)
			(xy 254.229663 -21.747223) (xy 254.174226 -21.753323) (xy 254.118492 -21.751286) (xy 254.063649 -21.741156)
			(xy 254.010865 -21.723149) (xy 253.961265 -21.697648) (xy 253.915907 -21.665197) (xy 253.875758 -21.626488)
			(xy 253.841672 -21.582345) (xy 253.814376 -21.53371) (xy 253.794453 -21.481619) (xy 253.782327 -21.427182)
			(xy 253.778256 -21.37156) (xy 248.927357 -21.37156) (xy 248.933716 -21.378164) (xy 248.95299 -21.399489)
			(xy 248.985557 -21.446851) (xy 249.01065 -21.498563) (xy 249.0277 -21.553454) (xy 249.036321 -21.610283)
			(xy 249.03684 -21.639022) (xy 249.036354 -21.666273) (xy 249.028598 -21.720221) (xy 249.013243 -21.772516)
			(xy 249.011801 -21.775674) (xy 258.13588 -21.775674) (xy 258.139951 -21.720052) (xy 258.152077 -21.665615)
			(xy 258.172 -21.613524) (xy 258.199296 -21.564889) (xy 258.233382 -21.520746) (xy 258.273531 -21.482037)
			(xy 258.318889 -21.449586) (xy 258.368489 -21.424085) (xy 258.421273 -21.406078) (xy 258.476116 -21.395948)
			(xy 258.53185 -21.393911) (xy 258.587287 -21.400011) (xy 258.641244 -21.414117) (xy 258.692573 -21.435929)
			(xy 258.740179 -21.464983) (xy 258.783047 -21.500658) (xy 258.820264 -21.542195) (xy 258.851037 -21.588708)
			(xy 258.874709 -21.639205) (xy 258.890777 -21.692612) (xy 258.898897 -21.747788) (xy 258.899406 -21.775674)
			(xy 258.898897 -21.80356) (xy 258.890777 -21.858736) (xy 258.874709 -21.912143) (xy 258.851037 -21.96264)
			(xy 258.820264 -22.009153) (xy 258.783047 -22.05069) (xy 258.740179 -22.086365) (xy 258.692573 -22.115419)
			(xy 258.641244 -22.137231) (xy 258.587287 -22.151337) (xy 258.53185 -22.157437) (xy 258.476116 -22.1554)
			(xy 258.421273 -22.14527) (xy 258.368489 -22.127263) (xy 258.318889 -22.101762) (xy 258.273531 -22.069311)
			(xy 258.233382 -22.030602) (xy 258.199296 -21.986459) (xy 258.172 -21.937824) (xy 258.152077 -21.885733)
			(xy 258.139951 -21.831296) (xy 258.13588 -21.775674) (xy 249.011801 -21.775674) (xy 248.990601 -21.822093)
			(xy 248.961135 -21.867943) (xy 248.925444 -21.909134) (xy 248.884253 -21.944825) (xy 248.838403 -21.974291)
			(xy 248.788826 -21.996933) (xy 248.736531 -22.012288) (xy 248.682583 -22.020044) (xy 248.628081 -22.020044)
			(xy 248.574133 -22.012288) (xy 248.521838 -21.996933) (xy 248.472261 -21.974291) (xy 248.426411 -21.944825)
			(xy 248.38522 -21.909134) (xy 248.349529 -21.867943) (xy 248.320063 -21.822093) (xy 248.297421 -21.772516)
			(xy 248.282066 -21.720221) (xy 248.27431 -21.666273) (xy 248.273824 -21.639022) (xy 244.366344 -21.639022)
			(xy 244.370613 -21.652767) (xy 244.379232 -21.709596) (xy 244.37975 -21.738336) (xy 244.379264 -21.765587)
			(xy 244.371508 -21.819535) (xy 244.356153 -21.87183) (xy 244.333511 -21.921407) (xy 244.304045 -21.967257)
			(xy 244.268354 -22.008448) (xy 244.227163 -22.044139) (xy 244.181313 -22.073605) (xy 244.131736 -22.096247)
			(xy 244.079441 -22.111602) (xy 244.025493 -22.119358) (xy 243.970991 -22.119358) (xy 243.917043 -22.111602)
			(xy 243.864748 -22.096247) (xy 243.815171 -22.073605) (xy 243.769321 -22.044139) (xy 243.72813 -22.008448)
			(xy 243.692439 -21.967257) (xy 243.662973 -21.921407) (xy 243.640331 -21.87183) (xy 243.624976 -21.819535)
			(xy 243.61722 -21.765587) (xy 243.616734 -21.738336) (xy 241.392886 -21.738336) (xy 241.369165 -21.783021)
			(xy 241.301224 -21.894082) (xy 241.226638 -22.000794) (xy 241.145685 -22.102761) (xy 241.058666 -22.199603)
			(xy 240.965905 -22.29096) (xy 240.867747 -22.376492) (xy 240.764558 -22.45588) (xy 240.656721 -22.52883)
			(xy 240.544636 -22.595071) (xy 240.428723 -22.654354) (xy 240.30941 -22.706462) (xy 240.187143 -22.751198)
			(xy 240.062376 -22.788397) (xy 239.935573 -22.817921) (xy 239.807206 -22.839659) (xy 239.677753 -22.853532)
			(xy 239.547694 -22.859486) (xy 239.417515 -22.857501) (xy 239.287699 -22.847583) (xy 239.158729 -22.829769)
			(xy 239.031084 -22.804126) (xy 238.905241 -22.770749) (xy 238.781666 -22.729762) (xy 238.66082 -22.681318)
			(xy 238.543152 -22.625596) (xy 238.4291 -22.562805) (xy 238.319088 -22.493178) (xy 238.213526 -22.416973)
			(xy 238.112806 -22.334474) (xy 238.017302 -22.245989) (xy 237.92737 -22.151846) (xy 237.843345 -22.052395)
			(xy 237.76554 -21.948007) (xy 237.694243 -21.83907) (xy 237.629719 -21.725988) (xy 237.57221 -21.609184)
			(xy 237.521928 -21.489091) (xy 237.479062 -21.366155) (xy 237.443769 -21.240836) (xy 237.416183 -21.113597)
			(xy 237.396404 -20.984914) (xy 237.384508 -20.855264) (xy 237.380538 -20.72513) (xy 233.615738 -20.72513)
			(xy 233.615738 -23.0251) (xy 243.562376 -23.0251) (xy 243.566447 -22.969478) (xy 243.578573 -22.915041)
			(xy 243.598496 -22.86295) (xy 243.625792 -22.814315) (xy 243.659878 -22.770172) (xy 243.700027 -22.731463)
			(xy 243.745385 -22.699012) (xy 243.794985 -22.673511) (xy 243.847769 -22.655504) (xy 243.902612 -22.645374)
			(xy 243.958346 -22.643337) (xy 244.013783 -22.649437) (xy 244.06774 -22.663543) (xy 244.119069 -22.685355)
			(xy 244.166675 -22.714409) (xy 244.209543 -22.750084) (xy 244.24676 -22.791621) (xy 244.277533 -22.838134)
			(xy 244.301205 -22.888631) (xy 244.317273 -22.942038) (xy 244.325393 -22.997214) (xy 244.325902 -23.0251)
			(xy 244.325393 -23.052986) (xy 244.317273 -23.108162) (xy 244.301205 -23.161569) (xy 244.277533 -23.212066)
			(xy 244.24676 -23.258579) (xy 244.209543 -23.300116) (xy 244.166675 -23.335791) (xy 244.119069 -23.364845)
			(xy 244.06774 -23.386657) (xy 244.013783 -23.400763) (xy 243.958346 -23.406863) (xy 243.902612 -23.404826)
			(xy 243.847769 -23.394696) (xy 243.794985 -23.376689) (xy 243.745385 -23.351188) (xy 243.700027 -23.318737)
			(xy 243.659878 -23.280028) (xy 243.625792 -23.235885) (xy 243.598496 -23.18725) (xy 243.578573 -23.135159)
			(xy 243.566447 -23.080722) (xy 243.562376 -23.0251) (xy 233.615738 -23.0251) (xy 233.615738 -23.556366)
			(xy 244.266023 -23.556366) (xy 244.273776 -23.502427) (xy 244.289126 -23.450141) (xy 244.311761 -23.400571)
			(xy 244.341219 -23.354726) (xy 244.376902 -23.313541) (xy 244.418082 -23.277852) (xy 244.463923 -23.248387)
			(xy 244.513489 -23.225745) (xy 244.565774 -23.210388) (xy 244.619711 -23.202627) (xy 244.646958 -23.202138)
			(xy 244.670988 -23.202497) (xy 244.718666 -23.208543) (xy 244.765207 -23.220531) (xy 244.787674 -23.229062)
			(xy 244.800811 -23.233889) (xy 244.828644 -23.236782) (xy 244.856218 -23.232022) (xy 244.881469 -23.219963)
			(xy 244.902505 -23.201511) (xy 244.91775 -23.178046) (xy 244.926063 -23.151327) (xy 244.92682 -23.123354)
			(xy 244.923818 -23.109682) (xy 244.918367 -23.086699) (xy 244.912506 -23.039828) (xy 244.912134 -23.01621)
			(xy 244.912567 -22.988959) (xy 244.920322 -22.93501) (xy 244.935676 -22.882714) (xy 244.958315 -22.833136)
			(xy 244.98778 -22.787284) (xy 245.02347 -22.746092) (xy 245.06466 -22.710399) (xy 245.110509 -22.68093)
			(xy 245.160086 -22.658286) (xy 245.21238 -22.642929) (xy 245.266328 -22.635169) (xy 245.320831 -22.635166)
			(xy 245.374779 -22.64292) (xy 245.427076 -22.658272) (xy 245.476655 -22.68091) (xy 245.522507 -22.710374)
			(xy 245.5637 -22.746063) (xy 245.599395 -22.787251) (xy 245.628865 -22.8331) (xy 245.65151 -22.882676)
			(xy 245.666869 -22.93497) (xy 245.67463 -22.988917) (xy 245.674634 -23.04342) (xy 245.666882 -23.097369)
			(xy 245.651532 -23.149666) (xy 245.628895 -23.199245) (xy 245.599433 -23.245099) (xy 245.563745 -23.286293)
			(xy 245.522558 -23.321989) (xy 245.47671 -23.35146) (xy 245.427134 -23.374106) (xy 245.374841 -23.389467)
			(xy 245.320893 -23.397229) (xy 245.293642 -23.397718) (xy 245.269612 -23.397355) (xy 245.221935 -23.39131)
			(xy 245.175394 -23.379324) (xy 245.152926 -23.370794) (xy 245.139774 -23.366019) (xy 245.111951 -23.363129)
			(xy 245.084387 -23.367888) (xy 245.059145 -23.37994) (xy 245.038114 -23.398384) (xy 245.02287 -23.421837)
			(xy 245.014553 -23.448544) (xy 245.013786 -23.476505) (xy 245.016782 -23.490174) (xy 245.022243 -23.513155)
			(xy 245.028098 -23.560028) (xy 245.028466 -23.583646) (xy 245.028351 -23.589996) (xy 248.28449 -23.589996)
			(xy 248.288561 -23.534374) (xy 248.300687 -23.479937) (xy 248.32061 -23.427846) (xy 248.347906 -23.379211)
			(xy 248.381992 -23.335068) (xy 248.422141 -23.296359) (xy 248.467499 -23.263908) (xy 248.517099 -23.238407)
			(xy 248.569883 -23.2204) (xy 248.624726 -23.21027) (xy 248.68046 -23.208233) (xy 248.735897 -23.214333)
			(xy 248.789854 -23.228439) (xy 248.841183 -23.250251) (xy 248.888789 -23.279305) (xy 248.931657 -23.31498)
			(xy 248.968011 -23.355554) (xy 257.5306 -23.355554) (xy 257.531068 -23.328743) (xy 257.538575 -23.275648)
			(xy 257.55345 -23.22413) (xy 257.575398 -23.175205) (xy 257.603985 -23.129839) (xy 257.638649 -23.088926)
			(xy 257.678704 -23.053276) (xy 257.70078 -23.038054) (xy 257.712324 -23.029768) (xy 257.730731 -23.008139)
			(xy 257.742471 -22.982278) (xy 257.746635 -22.954184) (xy 257.742902 -22.926029) (xy 257.731561 -22.89999)
			(xy 257.713488 -22.878081) (xy 257.70205 -22.869652) (xy 257.680597 -22.854295) (xy 257.641685 -22.818668)
			(xy 257.608053 -22.778019) (xy 257.580343 -22.733124) (xy 257.559082 -22.68484) (xy 257.544676 -22.634087)
			(xy 257.5374 -22.581833) (xy 257.53695 -22.555454) (xy 257.537436 -22.528203) (xy 257.545192 -22.474255)
			(xy 257.560547 -22.42196) (xy 257.583189 -22.372383) (xy 257.612655 -22.326533) (xy 257.648346 -22.285342)
			(xy 257.689537 -22.249651) (xy 257.735387 -22.220185) (xy 257.784964 -22.197543) (xy 257.837259 -22.182188)
			(xy 257.891207 -22.174432) (xy 257.945709 -22.174432) (xy 257.999657 -22.182188) (xy 258.051952 -22.197543)
			(xy 258.101529 -22.220185) (xy 258.147379 -22.249651) (xy 258.18857 -22.285342) (xy 258.224261 -22.326533)
			(xy 258.253727 -22.372383) (xy 258.276369 -22.42196) (xy 258.291724 -22.474255) (xy 258.29948 -22.528203)
			(xy 258.299966 -22.555454) (xy 258.299475 -22.582264) (xy 258.291968 -22.635356) (xy 258.277095 -22.686873)
			(xy 258.255151 -22.735797) (xy 258.226567 -22.781163) (xy 258.191908 -22.822076) (xy 258.151859 -22.85773)
			(xy 258.129786 -22.872954) (xy 258.118237 -22.881232) (xy 258.099836 -22.902864) (xy 258.088101 -22.928727)
			(xy 258.083939 -22.956821) (xy 258.087672 -22.984975) (xy 258.099011 -23.011013) (xy 258.11708 -23.032924)
			(xy 258.128516 -23.041356) (xy 258.149966 -23.056718) (xy 258.188879 -23.092344) (xy 258.222512 -23.132991)
			(xy 258.250224 -23.177885) (xy 258.271485 -23.226169) (xy 258.285891 -23.276921) (xy 258.293167 -23.329175)
			(xy 258.293616 -23.355554) (xy 258.29313 -23.382805) (xy 258.285374 -23.436753) (xy 258.270019 -23.489048)
			(xy 258.247377 -23.538625) (xy 258.217911 -23.584475) (xy 258.18222 -23.625666) (xy 258.141029 -23.661357)
			(xy 258.095179 -23.690823) (xy 258.045602 -23.713465) (xy 257.993307 -23.72882) (xy 257.939359 -23.736576)
			(xy 257.884857 -23.736576) (xy 257.830909 -23.72882) (xy 257.778614 -23.713465) (xy 257.729037 -23.690823)
			(xy 257.683187 -23.661357) (xy 257.641996 -23.625666) (xy 257.606305 -23.584475) (xy 257.576839 -23.538625)
			(xy 257.554197 -23.489048) (xy 257.538842 -23.436753) (xy 257.531086 -23.382805) (xy 257.5306 -23.355554)
			(xy 248.968011 -23.355554) (xy 248.968874 -23.356517) (xy 248.999647 -23.40303) (xy 249.023319 -23.453527)
			(xy 249.039387 -23.506934) (xy 249.047507 -23.56211) (xy 249.048016 -23.589996) (xy 249.047507 -23.617882)
			(xy 249.039387 -23.673058) (xy 249.023319 -23.726465) (xy 248.999647 -23.776962) (xy 248.968874 -23.823475)
			(xy 248.931657 -23.865012) (xy 248.913265 -23.880318) (xy 249.440698 -23.880318) (xy 249.444769 -23.824696)
			(xy 249.456895 -23.770259) (xy 249.476818 -23.718168) (xy 249.504114 -23.669533) (xy 249.5382 -23.62539)
			(xy 249.578349 -23.586681) (xy 249.623707 -23.55423) (xy 249.673307 -23.528729) (xy 249.726091 -23.510722)
			(xy 249.780934 -23.500592) (xy 249.836668 -23.498555) (xy 249.892105 -23.504655) (xy 249.946062 -23.518761)
			(xy 249.997391 -23.540573) (xy 250.044997 -23.569627) (xy 250.087865 -23.605302) (xy 250.125082 -23.646839)
			(xy 250.155855 -23.693352) (xy 250.179527 -23.743849) (xy 250.195595 -23.797256) (xy 250.203715 -23.852432)
			(xy 250.204224 -23.880318) (xy 250.456698 -23.880318) (xy 250.460769 -23.824696) (xy 250.472895 -23.770259)
			(xy 250.492818 -23.718168) (xy 250.520114 -23.669533) (xy 250.5542 -23.62539) (xy 250.594349 -23.586681)
			(xy 250.639707 -23.55423) (xy 250.689307 -23.528729) (xy 250.742091 -23.510722) (xy 250.796934 -23.500592)
			(xy 250.852668 -23.498555) (xy 250.908105 -23.504655) (xy 250.962062 -23.518761) (xy 251.013391 -23.540573)
			(xy 251.060997 -23.569627) (xy 251.103865 -23.605302) (xy 251.141082 -23.646839) (xy 251.171855 -23.693352)
			(xy 251.195527 -23.743849) (xy 251.211595 -23.797256) (xy 251.219715 -23.852432) (xy 251.220224 -23.880318)
			(xy 251.472698 -23.880318) (xy 251.476769 -23.824696) (xy 251.488895 -23.770259) (xy 251.508818 -23.718168)
			(xy 251.536114 -23.669533) (xy 251.5702 -23.62539) (xy 251.610349 -23.586681) (xy 251.655707 -23.55423)
			(xy 251.705307 -23.528729) (xy 251.758091 -23.510722) (xy 251.812934 -23.500592) (xy 251.868668 -23.498555)
			(xy 251.924105 -23.504655) (xy 251.978062 -23.518761) (xy 252.029391 -23.540573) (xy 252.076997 -23.569627)
			(xy 252.119865 -23.605302) (xy 252.157082 -23.646839) (xy 252.187855 -23.693352) (xy 252.211527 -23.743849)
			(xy 252.227595 -23.797256) (xy 252.235715 -23.852432) (xy 252.236224 -23.880318) (xy 252.490984 -23.880318)
			(xy 252.495055 -23.824696) (xy 252.507181 -23.770259) (xy 252.527104 -23.718168) (xy 252.5544 -23.669533)
			(xy 252.588486 -23.62539) (xy 252.628635 -23.586681) (xy 252.673993 -23.55423) (xy 252.723593 -23.528729)
			(xy 252.776377 -23.510722) (xy 252.83122 -23.500592) (xy 252.886954 -23.498555) (xy 252.942391 -23.504655)
			(xy 252.996348 -23.518761) (xy 253.047677 -23.540573) (xy 253.095283 -23.569627) (xy 253.138151 -23.605302)
			(xy 253.175368 -23.646839) (xy 253.206141 -23.693352) (xy 253.229813 -23.743849) (xy 253.245881 -23.797256)
			(xy 253.254001 -23.852432) (xy 253.25451 -23.880318) (xy 253.254001 -23.908204) (xy 253.245881 -23.96338)
			(xy 253.229813 -24.016787) (xy 253.206141 -24.067284) (xy 253.175368 -24.113797) (xy 253.138151 -24.155334)
			(xy 253.095283 -24.191009) (xy 253.047677 -24.220063) (xy 252.996348 -24.241875) (xy 252.942391 -24.255981)
			(xy 252.886954 -24.262081) (xy 252.83122 -24.260044) (xy 252.776377 -24.249914) (xy 252.723593 -24.231907)
			(xy 252.673993 -24.206406) (xy 252.628635 -24.173955) (xy 252.588486 -24.135246) (xy 252.5544 -24.091103)
			(xy 252.527104 -24.042468) (xy 252.507181 -23.990377) (xy 252.495055 -23.93594) (xy 252.490984 -23.880318)
			(xy 252.236224 -23.880318) (xy 252.235715 -23.908204) (xy 252.227595 -23.96338) (xy 252.211527 -24.016787)
			(xy 252.187855 -24.067284) (xy 252.157082 -24.113797) (xy 252.119865 -24.155334) (xy 252.076997 -24.191009)
			(xy 252.029391 -24.220063) (xy 251.978062 -24.241875) (xy 251.924105 -24.255981) (xy 251.868668 -24.262081)
			(xy 251.812934 -24.260044) (xy 251.758091 -24.249914) (xy 251.705307 -24.231907) (xy 251.655707 -24.206406)
			(xy 251.610349 -24.173955) (xy 251.5702 -24.135246) (xy 251.536114 -24.091103) (xy 251.508818 -24.042468)
			(xy 251.488895 -23.990377) (xy 251.476769 -23.93594) (xy 251.472698 -23.880318) (xy 251.220224 -23.880318)
			(xy 251.219715 -23.908204) (xy 251.211595 -23.96338) (xy 251.195527 -24.016787) (xy 251.171855 -24.067284)
			(xy 251.141082 -24.113797) (xy 251.103865 -24.155334) (xy 251.060997 -24.191009) (xy 251.013391 -24.220063)
			(xy 250.962062 -24.241875) (xy 250.908105 -24.255981) (xy 250.852668 -24.262081) (xy 250.796934 -24.260044)
			(xy 250.742091 -24.249914) (xy 250.689307 -24.231907) (xy 250.639707 -24.206406) (xy 250.594349 -24.173955)
			(xy 250.5542 -24.135246) (xy 250.520114 -24.091103) (xy 250.492818 -24.042468) (xy 250.472895 -23.990377)
			(xy 250.460769 -23.93594) (xy 250.456698 -23.880318) (xy 250.204224 -23.880318) (xy 250.203715 -23.908204)
			(xy 250.195595 -23.96338) (xy 250.179527 -24.016787) (xy 250.155855 -24.067284) (xy 250.125082 -24.113797)
			(xy 250.087865 -24.155334) (xy 250.044997 -24.191009) (xy 249.997391 -24.220063) (xy 249.946062 -24.241875)
			(xy 249.892105 -24.255981) (xy 249.836668 -24.262081) (xy 249.780934 -24.260044) (xy 249.726091 -24.249914)
			(xy 249.673307 -24.231907) (xy 249.623707 -24.206406) (xy 249.578349 -24.173955) (xy 249.5382 -24.135246)
			(xy 249.504114 -24.091103) (xy 249.476818 -24.042468) (xy 249.456895 -23.990377) (xy 249.444769 -23.93594)
			(xy 249.440698 -23.880318) (xy 248.913265 -23.880318) (xy 248.888789 -23.900687) (xy 248.841183 -23.929741)
			(xy 248.789854 -23.951553) (xy 248.735897 -23.965659) (xy 248.68046 -23.971759) (xy 248.624726 -23.969722)
			(xy 248.569883 -23.959592) (xy 248.517099 -23.941585) (xy 248.467499 -23.916084) (xy 248.422141 -23.883633)
			(xy 248.381992 -23.844924) (xy 248.347906 -23.800781) (xy 248.32061 -23.752146) (xy 248.300687 -23.700055)
			(xy 248.288561 -23.645618) (xy 248.28449 -23.589996) (xy 245.028351 -23.589996) (xy 245.027973 -23.610893)
			(xy 245.020211 -23.66483) (xy 245.004853 -23.717114) (xy 244.982211 -23.766681) (xy 244.952746 -23.812521)
			(xy 244.917057 -23.853701) (xy 244.875871 -23.889383) (xy 244.830026 -23.918841) (xy 244.780456 -23.941475)
			(xy 244.728169 -23.956825) (xy 244.67423 -23.964577) (xy 244.619737 -23.964575) (xy 244.565799 -23.956818)
			(xy 244.513513 -23.941464) (xy 244.463945 -23.918825) (xy 244.418103 -23.889363) (xy 244.37692 -23.853677)
			(xy 244.341234 -23.812494) (xy 244.311773 -23.766652) (xy 244.289135 -23.717083) (xy 244.273782 -23.664798)
			(xy 244.266025 -23.610859) (xy 244.266023 -23.556366) (xy 233.615738 -23.556366) (xy 233.615738 -24.158194)
			(xy 239.650776 -24.158194) (xy 239.654847 -24.102572) (xy 239.666973 -24.048135) (xy 239.686896 -23.996044)
			(xy 239.714192 -23.947409) (xy 239.748278 -23.903266) (xy 239.788427 -23.864557) (xy 239.833785 -23.832106)
			(xy 239.883385 -23.806605) (xy 239.936169 -23.788598) (xy 239.991012 -23.778468) (xy 240.046746 -23.776431)
			(xy 240.102183 -23.782531) (xy 240.15614 -23.796637) (xy 240.207469 -23.818449) (xy 240.255075 -23.847503)
			(xy 240.297943 -23.883178) (xy 240.33516 -23.924715) (xy 240.365933 -23.971228) (xy 240.389605 -24.021725)
			(xy 240.405673 -24.075132) (xy 240.413793 -24.130308) (xy 240.414302 -24.158194) (xy 240.413793 -24.18608)
			(xy 240.413224 -24.189944) (xy 243.498876 -24.189944) (xy 243.502947 -24.134322) (xy 243.515073 -24.079885)
			(xy 243.534996 -24.027794) (xy 243.562292 -23.979159) (xy 243.596378 -23.935016) (xy 243.636527 -23.896307)
			(xy 243.681885 -23.863856) (xy 243.731485 -23.838355) (xy 243.784269 -23.820348) (xy 243.839112 -23.810218)
			(xy 243.894846 -23.808181) (xy 243.950283 -23.814281) (xy 244.00424 -23.828387) (xy 244.055569 -23.850199)
			(xy 244.103175 -23.879253) (xy 244.146043 -23.914928) (xy 244.18326 -23.956465) (xy 244.214033 -24.002978)
			(xy 244.237705 -24.053475) (xy 244.253773 -24.106882) (xy 244.261893 -24.162058) (xy 244.262402 -24.189944)
			(xy 246.021858 -24.189944) (xy 246.025929 -24.134322) (xy 246.038055 -24.079885) (xy 246.057978 -24.027794)
			(xy 246.085274 -23.979159) (xy 246.11936 -23.935016) (xy 246.159509 -23.896307) (xy 246.204867 -23.863856)
			(xy 246.254467 -23.838355) (xy 246.307251 -23.820348) (xy 246.362094 -23.810218) (xy 246.417828 -23.808181)
			(xy 246.473265 -23.814281) (xy 246.527222 -23.828387) (xy 246.578551 -23.850199) (xy 246.626157 -23.879253)
			(xy 246.669025 -23.914928) (xy 246.706242 -23.956465) (xy 246.737015 -24.002978) (xy 246.760687 -24.053475)
			(xy 246.776755 -24.106882) (xy 246.784875 -24.162058) (xy 246.785384 -24.189944) (xy 246.784875 -24.21783)
			(xy 246.776755 -24.273006) (xy 246.760687 -24.326413) (xy 246.737015 -24.37691) (xy 246.706242 -24.423423)
			(xy 246.669025 -24.46496) (xy 246.626157 -24.500635) (xy 246.578551 -24.529689) (xy 246.527222 -24.551501)
			(xy 246.473265 -24.565607) (xy 246.417828 -24.571707) (xy 246.362094 -24.56967) (xy 246.307251 -24.55954)
			(xy 246.254467 -24.541533) (xy 246.204867 -24.516032) (xy 246.159509 -24.483581) (xy 246.11936 -24.444872)
			(xy 246.085274 -24.400729) (xy 246.057978 -24.352094) (xy 246.038055 -24.300003) (xy 246.025929 -24.245566)
			(xy 246.021858 -24.189944) (xy 244.262402 -24.189944) (xy 244.261893 -24.21783) (xy 244.253773 -24.273006)
			(xy 244.237705 -24.326413) (xy 244.214033 -24.37691) (xy 244.18326 -24.423423) (xy 244.146043 -24.46496)
			(xy 244.103175 -24.500635) (xy 244.055569 -24.529689) (xy 244.00424 -24.551501) (xy 243.950283 -24.565607)
			(xy 243.894846 -24.571707) (xy 243.839112 -24.56967) (xy 243.784269 -24.55954) (xy 243.731485 -24.541533)
			(xy 243.681885 -24.516032) (xy 243.636527 -24.483581) (xy 243.596378 -24.444872) (xy 243.562292 -24.400729)
			(xy 243.534996 -24.352094) (xy 243.515073 -24.300003) (xy 243.502947 -24.245566) (xy 243.498876 -24.189944)
			(xy 240.413224 -24.189944) (xy 240.405673 -24.241256) (xy 240.389605 -24.294663) (xy 240.365933 -24.34516)
			(xy 240.33516 -24.391673) (xy 240.297943 -24.43321) (xy 240.255075 -24.468885) (xy 240.207469 -24.497939)
			(xy 240.15614 -24.519751) (xy 240.102183 -24.533857) (xy 240.046746 -24.539957) (xy 239.991012 -24.53792)
			(xy 239.936169 -24.52779) (xy 239.883385 -24.509783) (xy 239.833785 -24.484282) (xy 239.788427 -24.451831)
			(xy 239.748278 -24.413122) (xy 239.714192 -24.368979) (xy 239.686896 -24.320344) (xy 239.666973 -24.268253)
			(xy 239.654847 -24.213816) (xy 239.650776 -24.158194) (xy 233.615738 -24.158194) (xy 233.615738 -24.307546)
			(xy 233.615501 -24.314498) (xy 233.611768 -24.327892) (xy 233.608372 -24.333962) (xy 233.604562 -24.340058)
			(xy 233.602784 -24.346408) (xy 233.600752 -24.360378) (xy 233.600752 -24.807418) (xy 240.820192 -24.807418)
			(xy 240.824263 -24.751796) (xy 240.836389 -24.697359) (xy 240.856312 -24.645268) (xy 240.883608 -24.596633)
			(xy 240.917694 -24.55249) (xy 240.957843 -24.513781) (xy 241.003201 -24.48133) (xy 241.052801 -24.455829)
			(xy 241.105585 -24.437822) (xy 241.160428 -24.427692) (xy 241.216162 -24.425655) (xy 241.271599 -24.431755)
			(xy 241.325556 -24.445861) (xy 241.376885 -24.467673) (xy 241.424491 -24.496727) (xy 241.467359 -24.532402)
			(xy 241.504576 -24.573939) (xy 241.535349 -24.620452) (xy 241.559021 -24.670949) (xy 241.575089 -24.724356)
			(xy 241.580136 -24.75865) (xy 253.06858 -24.75865) (xy 253.072651 -24.703028) (xy 253.084777 -24.648591)
			(xy 253.1047 -24.5965) (xy 253.131996 -24.547865) (xy 253.166082 -24.503722) (xy 253.206231 -24.465013)
			(xy 253.251589 -24.432562) (xy 253.301189 -24.407061) (xy 253.353973 -24.389054) (xy 253.408816 -24.378924)
			(xy 253.46455 -24.376887) (xy 253.519987 -24.382987) (xy 253.573944 -24.397093) (xy 253.625273 -24.418905)
			(xy 253.672879 -24.447959) (xy 253.715747 -24.483634) (xy 253.752964 -24.525171) (xy 253.783737 -24.571684)
			(xy 253.807409 -24.622181) (xy 253.823477 -24.675588) (xy 253.831597 -24.730764) (xy 253.832106 -24.75865)
			(xy 253.831597 -24.786536) (xy 253.823477 -24.841712) (xy 253.807409 -24.895119) (xy 253.783737 -24.945616)
			(xy 253.752964 -24.992129) (xy 253.715747 -25.033666) (xy 253.672879 -25.069341) (xy 253.625273 -25.098395)
			(xy 253.573944 -25.120207) (xy 253.519987 -25.134313) (xy 253.46455 -25.140413) (xy 253.408816 -25.138376)
			(xy 253.353973 -25.128246) (xy 253.301189 -25.110239) (xy 253.251589 -25.084738) (xy 253.206231 -25.052287)
			(xy 253.166082 -25.013578) (xy 253.131996 -24.969435) (xy 253.1047 -24.9208) (xy 253.084777 -24.868709)
			(xy 253.072651 -24.814272) (xy 253.06858 -24.75865) (xy 241.580136 -24.75865) (xy 241.583209 -24.779532)
			(xy 241.583718 -24.807418) (xy 241.583209 -24.835304) (xy 241.575089 -24.89048) (xy 241.559021 -24.943887)
			(xy 241.535349 -24.994384) (xy 241.504576 -25.040897) (xy 241.467359 -25.082434) (xy 241.424491 -25.118109)
			(xy 241.376885 -25.147163) (xy 241.325556 -25.168975) (xy 241.271599 -25.183081) (xy 241.216162 -25.189181)
			(xy 241.160428 -25.187144) (xy 241.105585 -25.177014) (xy 241.052801 -25.159007) (xy 241.003201 -25.133506)
			(xy 240.957843 -25.101055) (xy 240.917694 -25.062346) (xy 240.883608 -25.018203) (xy 240.856312 -24.969568)
			(xy 240.836389 -24.917477) (xy 240.824263 -24.86304) (xy 240.820192 -24.807418) (xy 233.600752 -24.807418)
			(xy 233.600752 -25.390094) (xy 246.009668 -25.390094) (xy 246.010154 -25.362843) (xy 246.01791 -25.308895)
			(xy 246.033265 -25.2566) (xy 246.055907 -25.207023) (xy 246.085373 -25.161173) (xy 246.121064 -25.119982)
			(xy 246.162255 -25.084291) (xy 246.208105 -25.054825) (xy 246.257682 -25.032183) (xy 246.309977 -25.016828)
			(xy 246.363925 -25.009072) (xy 246.418427 -25.009072) (xy 246.472375 -25.016828) (xy 246.52467 -25.032183)
			(xy 246.574247 -25.054825) (xy 246.620097 -25.084291) (xy 246.661288 -25.119982) (xy 246.696979 -25.161173)
			(xy 246.726445 -25.207023) (xy 246.749087 -25.2566) (xy 246.764442 -25.308895) (xy 246.772198 -25.362843)
			(xy 246.772684 -25.390094) (xy 246.7721 -25.419113) (xy 246.763311 -25.476482) (xy 246.745934 -25.531858)
			(xy 246.720371 -25.583964) (xy 246.687212 -25.631596) (xy 246.64722 -25.673658) (xy 246.624602 -25.691846)
			(xy 246.614057 -25.700615) (xy 246.597614 -25.72255) (xy 246.587608 -25.748071) (xy 246.584761 -25.775336)
			(xy 246.589278 -25.802374) (xy 246.600834 -25.827232) (xy 246.618594 -25.848114) (xy 246.629682 -25.856184)
			(xy 246.651317 -25.871512) (xy 246.690574 -25.907147) (xy 246.724518 -25.947877) (xy 246.752493 -25.992916)
			(xy 246.77396 -26.041395) (xy 246.788506 -26.09238) (xy 246.79585 -26.144888) (xy 246.796306 -26.171398)
			(xy 246.79582 -26.198649) (xy 246.788064 -26.252597) (xy 246.772709 -26.304892) (xy 246.750067 -26.354469)
			(xy 246.720601 -26.400319) (xy 246.68491 -26.44151) (xy 246.643719 -26.477201) (xy 246.597869 -26.506667)
			(xy 246.548292 -26.529309) (xy 246.495997 -26.544664) (xy 246.442049 -26.55242) (xy 246.387547 -26.55242)
			(xy 246.333599 -26.544664) (xy 246.281304 -26.529309) (xy 246.231727 -26.506667) (xy 246.185877 -26.477201)
			(xy 246.144686 -26.44151) (xy 246.108995 -26.400319) (xy 246.079529 -26.354469) (xy 246.056887 -26.304892)
			(xy 246.041532 -26.252597) (xy 246.033776 -26.198649) (xy 246.03329 -26.171398) (xy 246.03384 -26.142377)
			(xy 246.042632 -26.085005) (xy 246.060014 -26.029627) (xy 246.085583 -25.977521) (xy 246.11875 -25.92989)
			(xy 246.158749 -25.887832) (xy 246.181372 -25.869646) (xy 246.191929 -25.860888) (xy 246.208376 -25.838952)
			(xy 246.218384 -25.813428) (xy 246.221231 -25.786159) (xy 246.216711 -25.759118) (xy 246.20515 -25.734258)
			(xy 246.187384 -25.713376) (xy 246.176292 -25.705308) (xy 246.154648 -25.689993) (xy 246.115391 -25.654355)
			(xy 246.081449 -25.613622) (xy 246.053476 -25.568582) (xy 246.03201 -25.520101) (xy 246.017466 -25.469114)
			(xy 246.010123 -25.416604) (xy 246.009668 -25.390094) (xy 233.600752 -25.390094) (xy 233.600752 -25.971246)
			(xy 234.159804 -25.971246) (xy 234.163875 -25.915624) (xy 234.176001 -25.861187) (xy 234.195924 -25.809096)
			(xy 234.22322 -25.760461) (xy 234.257306 -25.716318) (xy 234.297455 -25.677609) (xy 234.342813 -25.645158)
			(xy 234.392413 -25.619657) (xy 234.445197 -25.60165) (xy 234.50004 -25.59152) (xy 234.555774 -25.589483)
			(xy 234.611211 -25.595583) (xy 234.665168 -25.609689) (xy 234.716497 -25.631501) (xy 234.764103 -25.660555)
			(xy 234.806971 -25.69623) (xy 234.844188 -25.737767) (xy 234.874961 -25.78428) (xy 234.898633 -25.834777)
			(xy 234.914701 -25.888184) (xy 234.922821 -25.94336) (xy 234.92333 -25.971246) (xy 235.175804 -25.971246)
			(xy 235.179875 -25.915624) (xy 235.192001 -25.861187) (xy 235.211924 -25.809096) (xy 235.23922 -25.760461)
			(xy 235.273306 -25.716318) (xy 235.313455 -25.677609) (xy 235.358813 -25.645158) (xy 235.408413 -25.619657)
			(xy 235.461197 -25.60165) (xy 235.51604 -25.59152) (xy 235.571774 -25.589483) (xy 235.627211 -25.595583)
			(xy 235.681168 -25.609689) (xy 235.732497 -25.631501) (xy 235.780103 -25.660555) (xy 235.822971 -25.69623)
			(xy 235.860188 -25.737767) (xy 235.890961 -25.78428) (xy 235.914633 -25.834777) (xy 235.930701 -25.888184)
			(xy 235.938821 -25.94336) (xy 235.93933 -25.971246) (xy 236.191804 -25.971246) (xy 236.195875 -25.915624)
			(xy 236.208001 -25.861187) (xy 236.227924 -25.809096) (xy 236.25522 -25.760461) (xy 236.289306 -25.716318)
			(xy 236.329455 -25.677609) (xy 236.374813 -25.645158) (xy 236.424413 -25.619657) (xy 236.477197 -25.60165)
			(xy 236.53204 -25.59152) (xy 236.587774 -25.589483) (xy 236.643211 -25.595583) (xy 236.697168 -25.609689)
			(xy 236.748497 -25.631501) (xy 236.796103 -25.660555) (xy 236.838971 -25.69623) (xy 236.876188 -25.737767)
			(xy 236.906961 -25.78428) (xy 236.930633 -25.834777) (xy 236.946701 -25.888184) (xy 236.954821 -25.94336)
			(xy 236.95533 -25.971246) (xy 236.954821 -25.999132) (xy 236.949729 -26.03373) (xy 237.4679 -26.03373)
			(xy 237.471971 -25.978108) (xy 237.484097 -25.923671) (xy 237.50402 -25.87158) (xy 237.531316 -25.822945)
			(xy 237.565402 -25.778802) (xy 237.605551 -25.740093) (xy 237.650909 -25.707642) (xy 237.700509 -25.682141)
			(xy 237.753293 -25.664134) (xy 237.808136 -25.654004) (xy 237.86387 -25.651967) (xy 237.919307 -25.658067)
			(xy 237.973264 -25.672173) (xy 238.024593 -25.693985) (xy 238.072199 -25.723039) (xy 238.115067 -25.758714)
			(xy 238.152284 -25.800251) (xy 238.183057 -25.846764) (xy 238.206729 -25.897261) (xy 238.222797 -25.950668)
			(xy 238.230917 -26.005844) (xy 238.231426 -26.03373) (xy 238.230917 -26.061616) (xy 238.222797 -26.116792)
			(xy 238.206729 -26.170199) (xy 238.183057 -26.220696) (xy 238.152823 -26.266394) (xy 240.720626 -26.266394)
			(xy 240.72105 -26.239139) (xy 240.728809 -26.185185) (xy 240.744167 -26.132885) (xy 240.766813 -26.083302)
			(xy 240.796285 -26.037448) (xy 240.831982 -25.996254) (xy 240.87318 -25.960561) (xy 240.919037 -25.931094)
			(xy 240.968622 -25.908453) (xy 241.020924 -25.8931) (xy 241.074879 -25.885347) (xy 241.102134 -25.884886)
			(xy 241.13146 -25.885397) (xy 241.189419 -25.894385) (xy 241.245317 -25.912143) (xy 241.297837 -25.938253)
			(xy 241.322098 -25.954736) (xy 241.3326 -25.961207) (xy 241.357022 -25.964389) (xy 241.368834 -25.960832)
			(xy 241.44732 -25.931622) (xy 241.45874 -25.926774) (xy 241.475386 -25.908416) (xy 241.47907 -25.89657)
			(xy 241.486383 -25.869475) (xy 241.507946 -25.817661) (xy 241.536869 -25.769566) (xy 241.572529 -25.726229)
			(xy 241.614155 -25.688587) (xy 241.660848 -25.657451) (xy 241.7116 -25.633496) (xy 241.765315 -25.617236)
			(xy 241.820833 -25.609025) (xy 241.848894 -25.608534) (xy 241.87615 -25.608913) (xy 241.930108 -25.61667)
			(xy 241.982412 -25.632027) (xy 242.031999 -25.654672) (xy 242.077857 -25.684143) (xy 242.119055 -25.71984)
			(xy 242.154754 -25.761038) (xy 242.184226 -25.806896) (xy 242.206871 -25.856482) (xy 242.222229 -25.908786)
			(xy 242.229987 -25.962744) (xy 242.229987 -25.990042) (xy 243.498876 -25.990042) (xy 243.502947 -25.93442)
			(xy 243.515073 -25.879983) (xy 243.534996 -25.827892) (xy 243.562292 -25.779257) (xy 243.596378 -25.735114)
			(xy 243.636527 -25.696405) (xy 243.681885 -25.663954) (xy 243.731485 -25.638453) (xy 243.784269 -25.620446)
			(xy 243.839112 -25.610316) (xy 243.894846 -25.608279) (xy 243.950283 -25.614379) (xy 244.00424 -25.628485)
			(xy 244.055569 -25.650297) (xy 244.103175 -25.679351) (xy 244.146043 -25.715026) (xy 244.18326 -25.756563)
			(xy 244.214033 -25.803076) (xy 244.237705 -25.853573) (xy 244.253773 -25.90698) (xy 244.261893 -25.962156)
			(xy 244.262402 -25.990042) (xy 244.261893 -26.017928) (xy 244.253773 -26.073104) (xy 244.237705 -26.126511)
			(xy 244.214033 -26.177008) (xy 244.18326 -26.223521) (xy 244.146043 -26.265058) (xy 244.103175 -26.300733)
			(xy 244.055569 -26.329787) (xy 244.00424 -26.351599) (xy 243.950283 -26.365705) (xy 243.894846 -26.371805)
			(xy 243.839112 -26.369768) (xy 243.784269 -26.359638) (xy 243.731485 -26.341631) (xy 243.681885 -26.31613)
			(xy 243.636527 -26.283679) (xy 243.596378 -26.24497) (xy 243.562292 -26.200827) (xy 243.534996 -26.152192)
			(xy 243.515073 -26.100101) (xy 243.502947 -26.045664) (xy 243.498876 -25.990042) (xy 242.229987 -25.990042)
			(xy 242.229987 -26.017256) (xy 242.222229 -26.071214) (xy 242.206871 -26.123518) (xy 242.184226 -26.173104)
			(xy 242.154754 -26.218962) (xy 242.119055 -26.26016) (xy 242.077857 -26.295857) (xy 242.031999 -26.325328)
			(xy 241.982412 -26.347973) (xy 241.930108 -26.36333) (xy 241.87615 -26.371087) (xy 241.848894 -26.37155)
			(xy 241.819569 -26.371018) (xy 241.761611 -26.362036) (xy 241.705713 -26.344283) (xy 241.653192 -26.31818)
			(xy 241.62893 -26.3017) (xy 241.618418 -26.295248) (xy 241.594004 -26.292052) (xy 241.582194 -26.295604)
			(xy 241.503708 -26.324814) (xy 241.492263 -26.329616) (xy 241.475631 -26.348008) (xy 241.471958 -26.359866)
			(xy 241.465174 -26.384898) (xy 241.445758 -26.432988) (xy 241.420002 -26.478002) (xy 241.38838 -26.519109)
			(xy 241.351478 -26.555549) (xy 241.330988 -26.571448) (xy 241.321319 -26.579427) (xy 241.31067 -26.60209)
			(xy 241.310668 -26.614628) (xy 241.31524 -26.698956) (xy 241.316479 -26.711393) (xy 241.329281 -26.73283)
			(xy 241.339624 -26.73985) (xy 241.363366 -26.754746) (xy 241.4066 -26.790414) (xy 241.444151 -26.832024)
			(xy 241.475209 -26.878679) (xy 241.499108 -26.929377) (xy 241.515333 -26.983025) (xy 241.523533 -27.03847)
			(xy 241.524028 -27.066494) (xy 241.523542 -27.093745) (xy 241.515786 -27.147693) (xy 241.500431 -27.199988)
			(xy 241.477789 -27.249565) (xy 241.448323 -27.295415) (xy 241.412632 -27.336606) (xy 241.371441 -27.372297)
			(xy 241.325591 -27.401763) (xy 241.276014 -27.424405) (xy 241.223719 -27.43976) (xy 241.169771 -27.447516)
			(xy 241.115269 -27.447516) (xy 241.061321 -27.43976) (xy 241.009026 -27.424405) (xy 240.959449 -27.401763)
			(xy 240.913599 -27.372297) (xy 240.872408 -27.336606) (xy 240.836717 -27.295415) (xy 240.807251 -27.249565)
			(xy 240.784609 -27.199988) (xy 240.769254 -27.147693) (xy 240.761498 -27.093745) (xy 240.761012 -27.066494)
			(xy 240.76155 -27.037006) (xy 240.770647 -26.978734) (xy 240.788608 -26.922559) (xy 240.815004 -26.869818)
			(xy 240.849205 -26.821771) (xy 240.890397 -26.779562) (xy 240.913666 -26.76144) (xy 240.923333 -26.753459)
			(xy 240.933985 -26.730797) (xy 240.933986 -26.71826) (xy 240.929414 -26.633932) (xy 240.928159 -26.621499)
			(xy 240.915366 -26.600063) (xy 240.90503 -26.593038) (xy 240.881295 -26.578131) (xy 240.838058 -26.542467)
			(xy 240.800505 -26.50086) (xy 240.769445 -26.454206) (xy 240.745545 -26.40351) (xy 240.72932 -26.349862)
			(xy 240.72112 -26.294418) (xy 240.720626 -26.266394) (xy 238.152823 -26.266394) (xy 238.152284 -26.267209)
			(xy 238.115067 -26.308746) (xy 238.072199 -26.344421) (xy 238.024593 -26.373475) (xy 237.973264 -26.395287)
			(xy 237.919307 -26.409393) (xy 237.86387 -26.415493) (xy 237.808136 -26.413456) (xy 237.753293 -26.403326)
			(xy 237.700509 -26.385319) (xy 237.650909 -26.359818) (xy 237.605551 -26.327367) (xy 237.565402 -26.288658)
			(xy 237.531316 -26.244515) (xy 237.50402 -26.19588) (xy 237.484097 -26.143789) (xy 237.471971 -26.089352)
			(xy 237.4679 -26.03373) (xy 236.949729 -26.03373) (xy 236.946701 -26.054308) (xy 236.930633 -26.107715)
			(xy 236.906961 -26.158212) (xy 236.876188 -26.204725) (xy 236.838971 -26.246262) (xy 236.796103 -26.281937)
			(xy 236.748497 -26.310991) (xy 236.697168 -26.332803) (xy 236.643211 -26.346909) (xy 236.587774 -26.353009)
			(xy 236.53204 -26.350972) (xy 236.477197 -26.340842) (xy 236.424413 -26.322835) (xy 236.374813 -26.297334)
			(xy 236.329455 -26.264883) (xy 236.289306 -26.226174) (xy 236.25522 -26.182031) (xy 236.227924 -26.133396)
			(xy 236.208001 -26.081305) (xy 236.195875 -26.026868) (xy 236.191804 -25.971246) (xy 235.93933 -25.971246)
			(xy 235.938821 -25.999132) (xy 235.930701 -26.054308) (xy 235.914633 -26.107715) (xy 235.890961 -26.158212)
			(xy 235.860188 -26.204725) (xy 235.822971 -26.246262) (xy 235.780103 -26.281937) (xy 235.732497 -26.310991)
			(xy 235.681168 -26.332803) (xy 235.627211 -26.346909) (xy 235.571774 -26.353009) (xy 235.51604 -26.350972)
			(xy 235.461197 -26.340842) (xy 235.408413 -26.322835) (xy 235.358813 -26.297334) (xy 235.313455 -26.264883)
			(xy 235.273306 -26.226174) (xy 235.23922 -26.182031) (xy 235.211924 -26.133396) (xy 235.192001 -26.081305)
			(xy 235.179875 -26.026868) (xy 235.175804 -25.971246) (xy 234.92333 -25.971246) (xy 234.922821 -25.999132)
			(xy 234.914701 -26.054308) (xy 234.898633 -26.107715) (xy 234.874961 -26.158212) (xy 234.844188 -26.204725)
			(xy 234.806971 -26.246262) (xy 234.764103 -26.281937) (xy 234.716497 -26.310991) (xy 234.665168 -26.332803)
			(xy 234.611211 -26.346909) (xy 234.555774 -26.353009) (xy 234.50004 -26.350972) (xy 234.445197 -26.340842)
			(xy 234.392413 -26.322835) (xy 234.342813 -26.297334) (xy 234.297455 -26.264883) (xy 234.257306 -26.226174)
			(xy 234.22322 -26.182031) (xy 234.195924 -26.133396) (xy 234.176001 -26.081305) (xy 234.163875 -26.026868)
			(xy 234.159804 -25.971246) (xy 233.600752 -25.971246) (xy 233.600752 -27.655012) (xy 233.600999 -27.662193)
			(xy 233.604998 -27.675987) (xy 233.608626 -27.68219) (xy 233.612436 -27.688032) (xy 233.62285 -27.69743)
			(xy 233.629708 -27.700732) (xy 233.656529 -27.714125) (xy 233.705947 -27.748058) (xy 233.715329 -27.756956)
			(xy 236.959043 -27.756956) (xy 236.959043 -27.702444) (xy 236.966801 -27.648488) (xy 236.98216 -27.596185)
			(xy 237.004806 -27.546601) (xy 237.034279 -27.500745) (xy 237.069978 -27.459549) (xy 237.111177 -27.423855)
			(xy 237.157036 -27.394387) (xy 237.206623 -27.371746) (xy 237.258927 -27.356393) (xy 237.312884 -27.34864)
			(xy 237.34014 -27.34818) (xy 237.354225 -27.34828) (xy 237.382321 -27.350315) (xy 237.396274 -27.352244)
			(xy 237.410244 -27.354276) (xy 237.435898 -27.343862) (xy 237.498128 -27.261058) (xy 237.503262 -27.253536)
			(xy 237.508327 -27.236056) (xy 237.506946 -27.21791) (xy 237.503462 -27.209496) (xy 237.503462 -27.209242)
			(xy 237.49242 -27.184112) (xy 237.476817 -27.131489) (xy 237.46891 -27.077174) (xy 237.46841 -27.04973)
			(xy 237.468896 -27.022479) (xy 237.476652 -26.968531) (xy 237.492007 -26.916236) (xy 237.514649 -26.866659)
			(xy 237.544115 -26.820809) (xy 237.579806 -26.779618) (xy 237.620997 -26.743927) (xy 237.666847 -26.714461)
			(xy 237.716424 -26.691819) (xy 237.768719 -26.676464) (xy 237.822667 -26.668708) (xy 237.877169 -26.668708)
			(xy 237.931117 -26.676464) (xy 237.983412 -26.691819) (xy 238.032989 -26.714461) (xy 238.078839 -26.743927)
			(xy 238.12003 -26.779618) (xy 238.155721 -26.820809) (xy 238.185187 -26.866659) (xy 238.207829 -26.916236)
			(xy 238.223184 -26.968531) (xy 238.23094 -27.022479) (xy 238.231426 -27.04973) (xy 238.231426 -27.050238)
			(xy 238.230767 -27.081568) (xy 238.220478 -27.143379) (xy 238.200233 -27.20268) (xy 238.18596 -27.230578)
			(xy 238.180626 -27.24023) (xy 238.179102 -27.26182) (xy 238.213392 -27.354276) (xy 238.228378 -27.369516)
			(xy 238.238538 -27.37358) (xy 238.239046 -27.37358) (xy 238.265666 -27.384368) (xy 238.315579 -27.412786)
			(xy 238.360669 -27.448365) (xy 238.399917 -27.4903) (xy 238.432436 -27.537644) (xy 238.457492 -27.589327)
			(xy 238.474517 -27.644182) (xy 238.483128 -27.70097) (xy 238.483648 -27.729688) (xy 238.483111 -27.756937)
			(xy 238.475357 -27.810881) (xy 238.460005 -27.863172) (xy 238.437368 -27.912747) (xy 238.407907 -27.958595)
			(xy 238.372221 -27.999784) (xy 238.331037 -28.035476) (xy 238.285192 -28.064944) (xy 238.235621 -28.087587)
			(xy 238.183332 -28.102946) (xy 238.129389 -28.110707) (xy 238.10214 -28.111196) (xy 238.073224 -28.11065)
			(xy 238.016054 -28.101927) (xy 237.960856 -28.084675) (xy 237.908894 -28.059288) (xy 237.861359 -28.02635)
			(xy 237.819341 -27.986613) (xy 237.80115 -27.96413) (xy 237.793523 -27.955344) (xy 237.772637 -27.945152)
			(xy 237.761018 -27.944572) (xy 237.681262 -27.944572) (xy 237.669625 -27.945079) (xy 237.648715 -27.955288)
			(xy 237.64113 -27.96413) (xy 237.62293 -27.986605) (xy 237.580911 -28.02634) (xy 237.533378 -28.059279)
			(xy 237.481418 -28.084668) (xy 237.426223 -28.101927) (xy 237.369055 -28.110659) (xy 237.34014 -28.111196)
			(xy 237.312884 -28.11076) (xy 237.258927 -28.103007) (xy 237.206623 -28.087654) (xy 237.157036 -28.065013)
			(xy 237.111177 -28.035545) (xy 237.069978 -27.999851) (xy 237.034279 -27.958655) (xy 237.004806 -27.912799)
			(xy 236.98216 -27.863215) (xy 236.966801 -27.810912) (xy 236.959043 -27.756956) (xy 233.715329 -27.756956)
			(xy 233.749442 -27.789311) (xy 233.768138 -27.812746) (xy 233.768138 -27.813) (xy 233.769916 -27.815286)
			(xy 233.771948 -27.817572) (xy 233.780584 -27.826208) (xy 233.785282 -27.829514) (xy 233.795797 -27.834138)
			(xy 233.801412 -27.835352) (xy 233.808524 -27.836622) (xy 233.879136 -27.846528) (xy 233.883035 -27.846726)
			(xy 233.890816 -27.846091) (xy 233.89463 -27.845258) (xy 233.901996 -27.843226) (xy 233.911648 -27.83586)
			(xy 233.936532 -27.817627) (xy 233.990958 -27.788592) (xy 234.049344 -27.768683) (xy 234.110171 -27.758419)
			(xy 234.14101 -27.757628) (xy 234.15117 -27.757628) (xy 234.177591 -27.758624) (xy 234.229794 -27.767005)
			(xy 234.28034 -27.782515) (xy 234.32826 -27.804857) (xy 234.372634 -27.833602) (xy 234.412614 -27.868201)
			(xy 234.447432 -27.90799) (xy 234.46232 -27.92984) (xy 234.463082 -27.930856) (xy 234.471464 -27.944064)
			(xy 234.478576 -27.9527) (xy 234.479084 -27.953208) (xy 234.48899 -27.960574) (xy 234.508294 -27.97175)
			(xy 234.509818 -27.972512) (xy 234.519978 -27.97683) (xy 234.52963 -27.978608) (xy 234.530646 -27.978608)
			(xy 234.533948 -27.978862) (xy 234.587542 -27.978862) (xy 234.5944 -27.978354) (xy 234.598718 -27.977592)
			(xy 234.602368 -27.976714) (xy 234.609379 -27.97403) (xy 234.612688 -27.972258) (xy 234.637326 -27.958288)
			(xy 234.646724 -27.949398) (xy 234.650026 -27.94381) (xy 234.657223 -27.932476) (xy 234.672986 -27.910739)
			(xy 234.681522 -27.900376) (xy 234.706922 -27.87269) (xy 234.70743 -27.872182) (xy 234.729107 -27.850895)
			(xy 234.777959 -27.814783) (xy 234.831916 -27.786868) (xy 234.889614 -27.767855) (xy 234.949597 -27.758224)
			(xy 234.979972 -27.757628) (xy 235.007225 -27.758089) (xy 235.061177 -27.765843) (xy 235.113476 -27.781197)
			(xy 235.163058 -27.803839) (xy 235.208912 -27.833307) (xy 235.250105 -27.869001) (xy 235.285798 -27.910195)
			(xy 235.315265 -27.956049) (xy 235.337905 -28.005631) (xy 235.353258 -28.057931) (xy 235.361011 -28.111883)
			(xy 235.36148 -28.139136) (xy 235.867954 -28.139136) (xy 235.872025 -28.083514) (xy 235.884151 -28.029077)
			(xy 235.904074 -27.976986) (xy 235.93137 -27.928351) (xy 235.965456 -27.884208) (xy 236.005605 -27.845499)
			(xy 236.050963 -27.813048) (xy 236.100563 -27.787547) (xy 236.153347 -27.76954) (xy 236.20819 -27.75941)
			(xy 236.263924 -27.757373) (xy 236.319361 -27.763473) (xy 236.373318 -27.777579) (xy 236.424647 -27.799391)
			(xy 236.472253 -27.828445) (xy 236.515121 -27.86412) (xy 236.552338 -27.905657) (xy 236.583111 -27.95217)
			(xy 236.606783 -28.002667) (xy 236.622851 -28.056074) (xy 236.630971 -28.11125) (xy 236.63148 -28.139136)
			(xy 236.630971 -28.167022) (xy 236.622851 -28.222198) (xy 236.606783 -28.275605) (xy 236.583111 -28.326102)
			(xy 236.552338 -28.372615) (xy 236.515121 -28.414152) (xy 236.472253 -28.449827) (xy 236.424647 -28.478881)
			(xy 236.373318 -28.500693) (xy 236.319361 -28.514799) (xy 236.263924 -28.520899) (xy 236.20819 -28.518862)
			(xy 236.153347 -28.508732) (xy 236.100563 -28.490725) (xy 236.050963 -28.465224) (xy 236.005605 -28.432773)
			(xy 235.965456 -28.394064) (xy 235.93137 -28.349921) (xy 235.904074 -28.301286) (xy 235.884151 -28.249195)
			(xy 235.872025 -28.194758) (xy 235.867954 -28.139136) (xy 235.36148 -28.139136) (xy 235.361061 -28.164503)
			(xy 235.354331 -28.21479) (xy 235.340995 -28.26374) (xy 235.321289 -28.310492) (xy 235.295559 -28.354218)
			(xy 235.26426 -28.394148) (xy 235.246418 -28.412186) (xy 235.246164 -28.41244) (xy 235.224525 -28.433508)
			(xy 235.175828 -28.469226) (xy 235.122114 -28.496829) (xy 235.064723 -28.515628) (xy 235.005088 -28.525154)
			(xy 234.974892 -28.525724) (xy 234.946216 -28.525214) (xy 234.889507 -28.516638) (xy 234.834723 -28.499667)
			(xy 234.783098 -28.474683) (xy 234.735797 -28.442249) (xy 234.693887 -28.403097) (xy 234.658313 -28.35811)
			(xy 234.643676 -28.333446) (xy 234.636593 -28.323414) (xy 234.615494 -28.310919) (xy 234.60329 -28.30957)
			(xy 234.527344 -28.30957) (xy 234.521113 -28.309781) (xy 234.509037 -28.312863) (xy 234.503468 -28.315666)
			(xy 234.472988 -28.331922) (xy 234.469178 -28.337764) (xy 234.465622 -28.343352) (xy 234.446064 -28.371292)
			(xy 234.423966 -28.397454) (xy 234.423712 -28.397962) (xy 234.422696 -28.398978) (xy 234.422188 -28.399486)
			(xy 234.421172 -28.400502) (xy 234.41025 -28.411678) (xy 234.409742 -28.412186) (xy 234.388096 -28.433299)
			(xy 234.339369 -28.4691) (xy 234.285606 -28.496769) (xy 234.228154 -28.515616) (xy 234.168448 -28.525168)
			(xy 234.138216 -28.525724) (xy 234.109058 -28.525173) (xy 234.051419 -28.516303) (xy 233.995801 -28.498767)
			(xy 233.943499 -28.472973) (xy 233.89573 -28.439522) (xy 233.853606 -28.399192) (xy 233.835448 -28.376372)
			(xy 233.833416 -28.373832) (xy 233.831638 -28.3718) (xy 233.823002 -28.363164) (xy 233.817817 -28.359519)
			(xy 233.806125 -28.354639) (xy 233.799888 -28.353512) (xy 233.729022 -28.343098) (xy 233.71972 -28.342052)
			(xy 233.701458 -28.346104) (xy 233.693462 -28.350972) (xy 233.691684 -28.352242) (xy 233.686096 -28.356306)
			(xy 233.68508 -28.356814) (xy 233.681778 -28.359354) (xy 233.679238 -28.361132) (xy 233.67365 -28.365196)
			(xy 233.670602 -28.368498) (xy 233.665268 -28.375356) (xy 233.653584 -28.396438) (xy 233.65079 -28.401518)
			(xy 233.648463 -28.40668) (xy 233.64589 -28.417703) (xy 233.64571 -28.423362) (xy 233.64571 -28.42895)
			(xy 233.645904 -28.434404) (xy 233.648331 -28.445041) (xy 233.650536 -28.450032) (xy 233.65714 -28.462732)
			(xy 233.663236 -28.47086) (xy 233.667046 -28.474924) (xy 233.673396 -28.478988) (xy 233.695913 -28.493682)
			(xy 233.736972 -28.528394) (xy 233.772756 -28.568524) (xy 233.802558 -28.613276) (xy 233.825787 -28.661765)
			(xy 233.841984 -28.713034) (xy 233.85083 -28.766068) (xy 233.851958 -28.792932) (xy 233.851958 -28.802076)
			(xy 233.851549 -28.827556) (xy 233.844798 -28.878066) (xy 233.831384 -28.927228) (xy 233.811548 -28.974168)
			(xy 233.785642 -29.018051) (xy 233.754126 -29.058096) (xy 233.736134 -29.076142) (xy 233.73588 -29.076396)
			(xy 233.712321 -29.099092) (xy 233.658938 -29.136893) (xy 233.629708 -29.15158) (xy 233.629454 -29.151834)
			(xy 233.623104 -29.155078) (xy 233.612405 -29.164495) (xy 233.608372 -29.170376) (xy 233.604562 -29.176218)
			(xy 233.60253 -29.18333) (xy 233.600752 -29.196538) (xy 233.600752 -29.223462) (xy 233.601006 -29.228034)
			(xy 233.601828 -29.233904) (xy 233.605802 -29.245067) (xy 233.60888 -29.250132) (xy 233.612944 -29.256228)
			(xy 233.623104 -29.265118) (xy 233.623358 -29.265118) (xy 233.624882 -29.26588) (xy 233.649862 -29.277479)
			(xy 233.696483 -29.306797) (xy 233.738408 -29.34251) (xy 233.774765 -29.383877) (xy 233.804802 -29.43004)
			(xy 233.827893 -29.480039) (xy 233.843559 -29.532837) (xy 233.851477 -29.587339) (xy 233.851958 -29.614876)
			(xy 233.851545 -29.640215) (xy 233.844838 -29.690447) (xy 233.831538 -29.739348) (xy 233.811881 -29.786058)
			(xy 233.786212 -29.829754) (xy 233.754983 -29.869666) (xy 233.73715 -29.887672) (xy 233.736642 -29.88818)
			(xy 233.72791 -29.896891) (xy 233.709479 -29.913286) (xy 233.699812 -29.920946) (xy 233.692432 -29.927232)
			(xy 233.682643 -29.943947) (xy 233.680762 -29.953458) (xy 233.680254 -29.960316) (xy 233.680254 -30.032198)
			(xy 233.6806 -30.040889) (xy 233.686445 -30.057259) (xy 233.691684 -30.064202) (xy 233.697526 -30.070298)
			(xy 233.720853 -30.088257) (xy 233.762212 -30.130147) (xy 233.796648 -30.177892) (xy 233.823341 -30.23036)
			(xy 233.84166 -30.286305) (xy 233.851169 -30.3444) (xy 233.851958 -30.373828) (xy 233.851958 -30.38094)
			(xy 233.851704 -30.396434) (xy 233.851704 -30.39745) (xy 233.849662 -30.425952) (xy 233.838113 -30.481915)
			(xy 233.818339 -30.535526) (xy 233.790784 -30.585585) (xy 233.756065 -30.630969) (xy 233.73588 -30.651196)
			(xy 233.735372 -30.651704) (xy 233.711909 -30.67424) (xy 233.658785 -30.711788) (xy 233.629708 -30.72638)
			(xy 233.629454 -30.726634) (xy 233.623104 -30.729878) (xy 233.612405 -30.739295) (xy 233.608372 -30.745176)
			(xy 233.604562 -30.751018) (xy 233.60253 -30.75813) (xy 233.600752 -30.771338) (xy 233.600752 -31.141416)
			(xy 233.601113 -31.150432) (xy 233.60736 -31.167348) (xy 233.612944 -31.174436) (xy 233.618786 -31.181294)
			(xy 233.634026 -31.18993) (xy 233.64317 -31.191454) (xy 233.669576 -31.196295) (xy 233.720783 -31.212415)
			(xy 233.769224 -31.235556) (xy 233.81394 -31.265262) (xy 233.854049 -31.300946) (xy 233.888757 -31.341901)
			(xy 233.917379 -31.387319) (xy 233.939349 -31.436302) (xy 233.954233 -31.487882) (xy 233.961736 -31.54104)
			(xy 233.962194 -31.567882) (xy 233.961607 -31.598258) (xy 233.951981 -31.658244) (xy 233.93297 -31.715946)
			(xy 233.931252 -31.719266) (xy 234.485432 -31.719266) (xy 234.489503 -31.663644) (xy 234.501629 -31.609207)
			(xy 234.521552 -31.557116) (xy 234.548848 -31.508481) (xy 234.582934 -31.464338) (xy 234.623083 -31.425629)
			(xy 234.668441 -31.393178) (xy 234.718041 -31.367677) (xy 234.770825 -31.34967) (xy 234.825668 -31.33954)
			(xy 234.881402 -31.337503) (xy 234.936839 -31.343603) (xy 234.990796 -31.357709) (xy 235.042125 -31.379521)
			(xy 235.089731 -31.408575) (xy 235.132599 -31.44425) (xy 235.169816 -31.485787) (xy 235.200589 -31.5323)
			(xy 235.224261 -31.582797) (xy 235.240329 -31.636204) (xy 235.244479 -31.664402) (xy 235.76102 -31.664402)
			(xy 235.765091 -31.60878) (xy 235.777217 -31.554343) (xy 235.79714 -31.502252) (xy 235.824436 -31.453617)
			(xy 235.858522 -31.409474) (xy 235.898671 -31.370765) (xy 235.944029 -31.338314) (xy 235.993629 -31.312813)
			(xy 236.046413 -31.294806) (xy 236.101256 -31.284676) (xy 236.15699 -31.282639) (xy 236.212427 -31.288739)
			(xy 236.266384 -31.302845) (xy 236.317713 -31.324657) (xy 236.365319 -31.353711) (xy 236.408187 -31.389386)
			(xy 236.445404 -31.430923) (xy 236.476177 -31.477436) (xy 236.499849 -31.527933) (xy 236.515917 -31.58134)
			(xy 236.524037 -31.636516) (xy 236.524546 -31.664402) (xy 236.524037 -31.692288) (xy 236.515917 -31.747464)
			(xy 236.506977 -31.777178) (xy 237.026194 -31.777178) (xy 237.030265 -31.721556) (xy 237.042391 -31.667119)
			(xy 237.062314 -31.615028) (xy 237.08961 -31.566393) (xy 237.123696 -31.52225) (xy 237.163845 -31.483541)
			(xy 237.209203 -31.45109) (xy 237.258803 -31.425589) (xy 237.311587 -31.407582) (xy 237.36643 -31.397452)
			(xy 237.422164 -31.395415) (xy 237.477601 -31.401515) (xy 237.531558 -31.415621) (xy 237.582887 -31.437433)
			(xy 237.630493 -31.466487) (xy 237.673361 -31.502162) (xy 237.710578 -31.543699) (xy 237.741351 -31.590212)
			(xy 237.765023 -31.640709) (xy 237.781091 -31.694116) (xy 237.789211 -31.749292) (xy 237.78972 -31.777178)
			(xy 237.789211 -31.805064) (xy 237.781091 -31.86024) (xy 237.765023 -31.913647) (xy 237.741351 -31.964144)
			(xy 237.710578 -32.010657) (xy 237.673361 -32.052194) (xy 237.630493 -32.087869) (xy 237.582887 -32.116923)
			(xy 237.531558 -32.138735) (xy 237.477601 -32.152841) (xy 237.422164 -32.158941) (xy 237.36643 -32.156904)
			(xy 237.311587 -32.146774) (xy 237.258803 -32.128767) (xy 237.209203 -32.103266) (xy 237.163845 -32.070815)
			(xy 237.123696 -32.032106) (xy 237.08961 -31.987963) (xy 237.062314 -31.939328) (xy 237.042391 -31.887237)
			(xy 237.030265 -31.8328) (xy 237.026194 -31.777178) (xy 236.506977 -31.777178) (xy 236.499849 -31.800871)
			(xy 236.476177 -31.851368) (xy 236.445404 -31.897881) (xy 236.408187 -31.939418) (xy 236.365319 -31.975093)
			(xy 236.317713 -32.004147) (xy 236.266384 -32.025959) (xy 236.212427 -32.040065) (xy 236.15699 -32.046165)
			(xy 236.101256 -32.044128) (xy 236.046413 -32.033998) (xy 235.993629 -32.015991) (xy 235.944029 -31.99049)
			(xy 235.898671 -31.958039) (xy 235.858522 -31.91933) (xy 235.824436 -31.875187) (xy 235.79714 -31.826552)
			(xy 235.777217 -31.774461) (xy 235.765091 -31.720024) (xy 235.76102 -31.664402) (xy 235.244479 -31.664402)
			(xy 235.248449 -31.69138) (xy 235.248958 -31.719266) (xy 235.248449 -31.747152) (xy 235.240329 -31.802328)
			(xy 235.224261 -31.855735) (xy 235.200589 -31.906232) (xy 235.169816 -31.952745) (xy 235.132599 -31.994282)
			(xy 235.089731 -32.029957) (xy 235.042125 -32.059011) (xy 234.990796 -32.080823) (xy 234.936839 -32.094929)
			(xy 234.881402 -32.101029) (xy 234.825668 -32.098992) (xy 234.770825 -32.088862) (xy 234.718041 -32.070855)
			(xy 234.668441 -32.045354) (xy 234.623083 -32.012903) (xy 234.582934 -31.974194) (xy 234.548848 -31.930051)
			(xy 234.521552 -31.881416) (xy 234.501629 -31.829325) (xy 234.489503 -31.774888) (xy 234.485432 -31.719266)
			(xy 233.931252 -31.719266) (xy 233.905054 -31.769905) (xy 233.868939 -31.818758) (xy 233.84764 -31.840424)
			(xy 233.841798 -31.846012) (xy 233.84129 -31.84652) (xy 233.820666 -31.865883) (xy 233.774752 -31.898931)
			(xy 233.724465 -31.924842) (xy 233.670904 -31.943047) (xy 233.64317 -31.948628) (xy 233.642662 -31.948628)
			(xy 233.638852 -31.94939) (xy 233.628846 -31.952472) (xy 233.61235 -31.965326) (xy 233.602395 -31.983717)
			(xy 233.601006 -31.994094) (xy 233.601006 -31.994602) (xy 233.600752 -31.998412) (xy 233.600752 -33.513268)
			(xy 233.601006 -33.518094) (xy 233.603546 -33.52927) (xy 233.607274 -33.538513) (xy 233.620469 -33.553422)
			(xy 233.6292 -33.558226) (xy 233.68127 -33.580578) (xy 233.717338 -33.596072) (xy 233.72437 -33.598792)
			(xy 233.739362 -33.600342) (xy 233.746802 -33.59912) (xy 233.755184 -33.597342) (xy 233.767122 -33.590992)
			(xy 233.771948 -33.58642) (xy 233.772964 -33.585404) (xy 233.794496 -33.565056) (xy 233.842682 -33.530595)
			(xy 233.895615 -33.503997) (xy 233.952024 -33.485899) (xy 234.010552 -33.476738) (xy 234.040172 -33.476184)
			(xy 234.05291 -33.476261) (xy 234.078331 -33.477913) (xy 234.090972 -33.479486) (xy 234.117987 -33.483594)
			(xy 234.170549 -33.49853) (xy 234.220446 -33.520805) (xy 234.266659 -33.549963) (xy 234.308246 -33.585409)
			(xy 234.344356 -33.62642) (xy 234.374253 -33.672159) (xy 234.397326 -33.721692) (xy 234.405678 -33.74771)
			(xy 234.408472 -33.757362) (xy 234.41406 -33.764474) (xy 234.416523 -33.76759) (xy 234.422267 -33.773075)
			(xy 234.42549 -33.775396) (xy 234.485434 -33.81121) (xy 234.493816 -33.812734) (xy 234.516377 -33.807503)
			(xy 234.562353 -33.801902) (xy 234.58551 -33.801558) (xy 234.612762 -33.802044) (xy 234.66671 -33.809802)
			(xy 234.719006 -33.825158) (xy 234.768584 -33.847799) (xy 234.783978 -33.857692) (xy 235.690154 -33.857692)
			(xy 235.694225 -33.80207) (xy 235.706351 -33.747633) (xy 235.726274 -33.695542) (xy 235.75357 -33.646907)
			(xy 235.787656 -33.602764) (xy 235.827805 -33.564055) (xy 235.873163 -33.531604) (xy 235.922763 -33.506103)
			(xy 235.975547 -33.488096) (xy 236.03039 -33.477966) (xy 236.086124 -33.475929) (xy 236.141561 -33.482029)
			(xy 236.195518 -33.496135) (xy 236.246847 -33.517947) (xy 236.294453 -33.547001) (xy 236.337321 -33.582676)
			(xy 236.374538 -33.624213) (xy 236.405311 -33.670726) (xy 236.428983 -33.721223) (xy 236.445051 -33.77463)
			(xy 236.453171 -33.829806) (xy 236.45368 -33.857692) (xy 236.453171 -33.885578) (xy 236.445051 -33.940754)
			(xy 236.428983 -33.994161) (xy 236.405311 -34.044658) (xy 236.374538 -34.091171) (xy 236.337321 -34.132708)
			(xy 236.294453 -34.168383) (xy 236.246847 -34.197437) (xy 236.195518 -34.219249) (xy 236.141561 -34.233355)
			(xy 236.086124 -34.239455) (xy 236.03039 -34.237418) (xy 235.975547 -34.227288) (xy 235.922763 -34.209281)
			(xy 235.873163 -34.18378) (xy 235.827805 -34.151329) (xy 235.787656 -34.11262) (xy 235.75357 -34.068477)
			(xy 235.726274 -34.019842) (xy 235.706351 -33.967751) (xy 235.694225 -33.913314) (xy 235.690154 -33.857692)
			(xy 234.783978 -33.857692) (xy 234.814435 -33.877265) (xy 234.855627 -33.912956) (xy 234.891321 -33.954145)
			(xy 234.92079 -33.999995) (xy 234.943434 -34.049572) (xy 234.958793 -34.101866) (xy 234.966554 -34.155814)
			(xy 234.967018 -34.183066) (xy 234.966604 -34.208435) (xy 234.959883 -34.258727) (xy 234.946555 -34.307684)
			(xy 234.926856 -34.354443) (xy 234.901132 -34.398178) (xy 234.869839 -34.438117) (xy 234.851956 -34.456116)
			(xy 234.851702 -34.45637) (xy 234.83006 -34.477432) (xy 234.781361 -34.51314) (xy 234.727646 -34.540732)
			(xy 234.670256 -34.55952) (xy 234.610624 -34.569035) (xy 234.58043 -34.569654) (xy 234.553823 -34.569194)
			(xy 234.501126 -34.561804) (xy 234.449966 -34.547163) (xy 234.401337 -34.525555) (xy 234.356183 -34.497399)
			(xy 234.315379 -34.463242) (xy 234.279717 -34.423746) (xy 234.24989 -34.379679) (xy 234.226475 -34.331893)
			(xy 234.217718 -34.306764) (xy 234.21467 -34.29762) (xy 234.209336 -34.290762) (xy 234.206395 -34.287258)
			(xy 234.199497 -34.281252) (xy 234.19562 -34.278824) (xy 234.166664 -34.261552) (xy 234.134914 -34.242756)
			(xy 234.131655 -34.241111) (xy 234.124768 -34.238691) (xy 234.121198 -34.23793) (xy 234.11307 -34.236406)
			(xy 234.103164 -34.238184) (xy 234.086354 -34.241028) (xy 234.052394 -34.244082) (xy 234.035346 -34.24428)
			(xy 234.035092 -34.24428) (xy 234.00608 -34.24374) (xy 233.948724 -34.234963) (xy 233.893356 -34.217612)
			(xy 233.841248 -34.192088) (xy 233.7936 -34.158975) (xy 233.772202 -34.139378) (xy 233.771948 -34.139124)
			(xy 233.770678 -34.138108) (xy 233.765338 -34.133621) (xy 233.752848 -34.127429) (xy 233.74604 -34.125916)
			(xy 233.738928 -34.124646) (xy 233.731562 -34.125662) (xy 233.72797 -34.126102) (xy 233.720958 -34.127889)
			(xy 233.717592 -34.129218) (xy 233.631486 -34.166302) (xy 233.622592 -34.170608) (xy 233.608727 -34.18466)
			(xy 233.601212 -34.202915) (xy 233.600752 -34.212784) (xy 233.600752 -35.264852) (xy 236.102396 -35.264852)
			(xy 236.106467 -35.20923) (xy 236.118593 -35.154793) (xy 236.138516 -35.102702) (xy 236.165812 -35.054067)
			(xy 236.199898 -35.009924) (xy 236.240047 -34.971215) (xy 236.285405 -34.938764) (xy 236.335005 -34.913263)
			(xy 236.387789 -34.895256) (xy 236.442632 -34.885126) (xy 236.498366 -34.883089) (xy 236.553803 -34.889189)
			(xy 236.60776 -34.903295) (xy 236.659089 -34.925107) (xy 236.706695 -34.954161) (xy 236.749563 -34.989836)
			(xy 236.774397 -35.017553) (xy 238.419856 -35.017553) (xy 238.419856 -34.963047) (xy 238.427613 -34.909097)
			(xy 238.442968 -34.8568) (xy 238.46561 -34.80722) (xy 238.495078 -34.761367) (xy 238.530771 -34.720175)
			(xy 238.571963 -34.684481) (xy 238.617815 -34.655013) (xy 238.667394 -34.63237) (xy 238.719691 -34.617014)
			(xy 238.773641 -34.609256) (xy 238.800894 -34.60877) (xy 238.818006 -34.608957) (xy 238.852093 -34.612012)
			(xy 238.868966 -34.614866) (xy 238.880257 -34.616244) (xy 238.902147 -34.610162) (xy 238.91113 -34.603182)
			(xy 238.935514 -34.582354) (xy 238.943944 -34.574377) (xy 238.953072 -34.553066) (xy 238.95304 -34.54146)
			(xy 238.952532 -34.52241) (xy 238.952532 -33.65881) (xy 238.95304 -33.638998) (xy 238.953009 -33.627405)
			(xy 238.943891 -33.606117) (xy 238.935514 -33.598104) (xy 238.91113 -33.577022) (xy 238.902127 -33.569951)
			(xy 238.880047 -33.563993) (xy 238.868712 -33.565592) (xy 238.851904 -33.568452) (xy 238.817943 -33.571506)
			(xy 238.800894 -33.571688) (xy 238.773642 -33.571242) (xy 238.719692 -33.563484) (xy 238.667395 -33.548128)
			(xy 238.617816 -33.525485) (xy 238.571964 -33.496017) (xy 238.530772 -33.460324) (xy 238.495079 -33.419131)
			(xy 238.465612 -33.373279) (xy 238.44297 -33.323699) (xy 238.427615 -33.271402) (xy 238.419858 -33.217452)
			(xy 238.419858 -33.162948) (xy 238.427615 -33.108998) (xy 238.44297 -33.056701) (xy 238.465612 -33.007121)
			(xy 238.495079 -32.961269) (xy 238.530772 -32.920076) (xy 238.571964 -32.884383) (xy 238.617816 -32.854915)
			(xy 238.667395 -32.832272) (xy 238.719692 -32.816916) (xy 238.773642 -32.809158) (xy 238.800894 -32.808672)
			(xy 238.827902 -32.809125) (xy 238.88138 -32.816731) (xy 238.933251 -32.831805) (xy 238.982475 -32.854046)
			(xy 239.02807 -32.883009) (xy 239.069123 -32.918115) (xy 239.104812 -32.958662) (xy 239.134425 -33.003838)
			(xy 239.157367 -33.052739) (xy 239.173182 -33.104389) (xy 239.17783 -33.130998) (xy 239.179354 -33.141666)
			(xy 239.190784 -33.159446) (xy 239.262158 -33.206944) (xy 239.271081 -33.212305) (xy 239.29155 -33.215972)
			(xy 239.301782 -33.214056) (xy 239.302544 -33.214056) (xy 239.329113 -33.207938) (xy 239.383233 -33.201317)
			(xy 239.410494 -33.200848) (xy 239.437818 -33.201311) (xy 239.492066 -33.207927) (xy 239.518698 -33.214056)
			(xy 239.519206 -33.214056) (xy 239.529438 -33.215895) (xy 239.549883 -33.212236) (xy 239.55883 -33.206944)
			(xy 239.630204 -33.159446) (xy 239.641634 -33.141666) (xy 239.643158 -33.130998) (xy 239.647769 -33.104384)
			(xy 239.663603 -33.052743) (xy 239.68656 -33.00385) (xy 239.716182 -32.958683) (xy 239.751877 -32.918144)
			(xy 239.792931 -32.883043) (xy 239.838525 -32.854082) (xy 239.887746 -32.831838) (xy 239.939613 -32.816757)
			(xy 239.993087 -32.809141) (xy 240.020094 -32.808672) (xy 240.047465 -32.809124) (xy 240.101645 -32.816943)
			(xy 240.154149 -32.832434) (xy 240.203896 -32.855279) (xy 240.249862 -32.885008) (xy 240.270792 -32.902652)
			(xy 240.271046 -32.902906) (xy 240.278143 -32.908477) (xy 240.295052 -32.914733) (xy 240.304066 -32.915098)
			(xy 240.371122 -32.915098) (xy 240.38014 -32.914752) (xy 240.397057 -32.908497) (xy 240.404142 -32.902906)
			(xy 240.404142 -32.902652) (xy 240.404396 -32.902652) (xy 240.425325 -32.885009) (xy 240.471298 -32.855296)
			(xy 240.521046 -32.83246) (xy 240.573548 -32.81697) (xy 240.627725 -32.809144) (xy 240.655094 -32.808672)
			(xy 240.672206 -32.808859) (xy 240.706293 -32.811914) (xy 240.723166 -32.814768) (xy 240.734457 -32.816145)
			(xy 240.756347 -32.810064) (xy 240.76533 -32.803084) (xy 240.789714 -32.782256) (xy 240.798143 -32.774278)
			(xy 240.807272 -32.752968) (xy 240.80724 -32.741362) (xy 240.806732 -32.722312) (xy 240.806732 -31.858712)
			(xy 240.80724 -31.8389) (xy 240.807208 -31.827307) (xy 240.79809 -31.806019) (xy 240.789714 -31.798006)
			(xy 240.76533 -31.776924) (xy 240.756327 -31.769853) (xy 240.734247 -31.763895) (xy 240.722912 -31.765494)
			(xy 240.706104 -31.768354) (xy 240.672143 -31.771408) (xy 240.655094 -31.77159) (xy 240.627724 -31.77113)
			(xy 240.573544 -31.763311) (xy 240.521041 -31.747821) (xy 240.471294 -31.724978) (xy 240.425327 -31.695252)
			(xy 240.404396 -31.67761) (xy 240.397538 -31.671514) (xy 240.38052 -31.665164) (xy 240.295176 -31.665164)
			(xy 240.277904 -31.671768) (xy 240.271046 -31.677864) (xy 240.250115 -31.695505) (xy 240.204145 -31.725225)
			(xy 240.154398 -31.748064) (xy 240.101896 -31.763554) (xy 240.047718 -31.771375) (xy 240.020348 -31.771844)
			(xy 240.020094 -31.771844) (xy 239.993116 -31.77138) (xy 239.939697 -31.763797) (xy 239.887881 -31.748758)
			(xy 239.838704 -31.72656) (xy 239.793148 -31.697649) (xy 239.752126 -31.662603) (xy 239.716456 -31.622121)
			(xy 239.686851 -31.577014) (xy 239.663904 -31.528182) (xy 239.648073 -31.476602) (xy 239.643412 -31.450026)
			(xy 239.641236 -31.439799) (xy 239.629965 -31.422218) (xy 239.621568 -31.41599) (xy 239.550194 -31.368492)
			(xy 239.529112 -31.364682) (xy 239.518952 -31.367222) (xy 239.492251 -31.373301) (xy 239.437875 -31.379791)
			(xy 239.410494 -31.380176) (xy 239.383112 -31.379799) (xy 239.328736 -31.373305) (xy 239.302036 -31.367222)
			(xy 239.291876 -31.364682) (xy 239.270794 -31.368492) (xy 239.19053 -31.421832) (xy 239.179354 -31.439358)
			(xy 239.177576 -31.450026) (xy 239.172879 -31.476591) (xy 239.157024 -31.528153) (xy 239.134063 -31.576967)
			(xy 239.104453 -31.622059) (xy 239.068786 -31.66253) (xy 239.027773 -31.697572) (xy 238.982231 -31.726486)
			(xy 238.933071 -31.748696) (xy 238.881271 -31.763757) (xy 238.827866 -31.771371) (xy 238.800894 -31.771844)
			(xy 238.773646 -31.771285) (xy 238.719704 -31.763529) (xy 238.667415 -31.748175) (xy 238.617843 -31.725535)
			(xy 238.571998 -31.696072) (xy 238.530812 -31.660384) (xy 238.495125 -31.619198) (xy 238.465662 -31.573352)
			(xy 238.443023 -31.52378) (xy 238.42767 -31.47149) (xy 238.419914 -31.417548) (xy 238.419914 -31.363052)
			(xy 238.42767 -31.30911) (xy 238.443023 -31.25682) (xy 238.465662 -31.207248) (xy 238.495125 -31.161402)
			(xy 238.530812 -31.120216) (xy 238.571998 -31.084528) (xy 238.617843 -31.055065) (xy 238.667415 -31.032425)
			(xy 238.719704 -31.017071) (xy 238.773646 -31.009315) (xy 238.800894 -31.008828) (xy 238.818006 -31.009015)
			(xy 238.852093 -31.01207) (xy 238.868966 -31.014924) (xy 238.880257 -31.016311) (xy 238.902149 -31.010225)
			(xy 238.91113 -31.00324) (xy 238.935514 -30.982412) (xy 238.943915 -30.97441) (xy 238.95306 -30.953118)
			(xy 238.95304 -30.941518) (xy 238.952532 -30.922468) (xy 238.952532 -30.058868) (xy 238.95304 -30.039056)
			(xy 238.953034 -30.027461) (xy 238.943898 -30.006172) (xy 238.935514 -29.998162) (xy 238.91113 -29.97708)
			(xy 238.902123 -29.970014) (xy 238.880046 -29.964051) (xy 238.868712 -29.96565) (xy 238.851904 -29.968511)
			(xy 238.817943 -29.971564) (xy 238.800894 -29.971746) (xy 238.773646 -29.971183) (xy 238.719704 -29.963427)
			(xy 238.667415 -29.948073) (xy 238.617844 -29.925434) (xy 238.571999 -29.89597) (xy 238.530813 -29.860282)
			(xy 238.495126 -29.819096) (xy 238.465663 -29.773251) (xy 238.443025 -29.723679) (xy 238.427672 -29.67139)
			(xy 238.419916 -29.617448) (xy 238.419916 -29.562952) (xy 238.427672 -29.50901) (xy 238.443025 -29.456721)
			(xy 238.465663 -29.407149) (xy 238.495126 -29.361304) (xy 238.530813 -29.320118) (xy 238.571999 -29.28443)
			(xy 238.617844 -29.254966) (xy 238.667415 -29.232327) (xy 238.719704 -29.216973) (xy 238.773646 -29.209217)
			(xy 238.800894 -29.20873) (xy 238.827901 -29.209218) (xy 238.881376 -29.216823) (xy 238.933243 -29.231895)
			(xy 238.982466 -29.254133) (xy 239.028059 -29.283093) (xy 239.069111 -29.318194) (xy 239.104801 -29.358736)
			(xy 239.134415 -29.403907) (xy 239.157361 -29.452804) (xy 239.173179 -29.504449) (xy 239.17783 -29.531056)
			(xy 239.179354 -29.541724) (xy 239.190784 -29.559504) (xy 239.262158 -29.607002) (xy 239.271082 -29.612361)
			(xy 239.29155 -29.61603) (xy 239.301782 -29.614114) (xy 239.302544 -29.614114) (xy 239.329119 -29.608057)
			(xy 239.38324 -29.601568) (xy 239.410494 -29.60116) (xy 239.437812 -29.601542) (xy 239.492061 -29.608039)
			(xy 239.518698 -29.614114) (xy 239.519206 -29.614114) (xy 239.529439 -29.615944) (xy 239.549881 -29.612289)
			(xy 239.55883 -29.607002) (xy 239.630204 -29.559504) (xy 239.641634 -29.541724) (xy 239.643158 -29.531056)
			(xy 239.647813 -29.50445) (xy 239.663639 -29.452809) (xy 239.68659 -29.403916) (xy 239.716206 -29.358748)
			(xy 239.751895 -29.318208) (xy 239.792945 -29.283105) (xy 239.838535 -29.254142) (xy 239.887753 -29.231898)
			(xy 239.939616 -29.216816) (xy 239.993088 -29.209199) (xy 240.020094 -29.20873) (xy 240.047464 -29.209192)
			(xy 240.101644 -29.21701) (xy 240.154147 -29.232499) (xy 240.203894 -29.255342) (xy 240.249861 -29.285068)
			(xy 240.270792 -29.30271) (xy 240.271046 -29.302964) (xy 240.278138 -29.308542) (xy 240.295051 -29.314792)
			(xy 240.304066 -29.315156) (xy 240.371122 -29.315156) (xy 240.380141 -29.314819) (xy 240.397058 -29.308559)
			(xy 240.404142 -29.302964) (xy 240.404142 -29.30271) (xy 240.404396 -29.30271) (xy 240.42532 -29.285061)
			(xy 240.471295 -29.25535) (xy 240.521044 -29.232516) (xy 240.573547 -29.217027) (xy 240.627724 -29.209202)
			(xy 240.655094 -29.20873) (xy 240.672206 -29.208917) (xy 240.706293 -29.211972) (xy 240.723166 -29.214826)
			(xy 240.734457 -29.216213) (xy 240.756349 -29.210127) (xy 240.76533 -29.203142) (xy 240.789714 -29.182314)
			(xy 240.798114 -29.174311) (xy 240.807259 -29.15302) (xy 240.80724 -29.14142) (xy 240.806732 -29.12237)
			(xy 240.806732 -28.25877) (xy 240.80724 -28.238958) (xy 240.807233 -28.227363) (xy 240.798098 -28.206075)
			(xy 240.789714 -28.198064) (xy 240.76533 -28.176982) (xy 240.756322 -28.169916) (xy 240.734246 -28.163953)
			(xy 240.722912 -28.165552) (xy 240.706104 -28.168413) (xy 240.672143 -28.171466) (xy 240.655094 -28.171648)
			(xy 240.627846 -28.171081) (xy 240.573905 -28.163325) (xy 240.521616 -28.147971) (xy 240.472045 -28.125332)
			(xy 240.4262 -28.095869) (xy 240.385015 -28.060181) (xy 240.349328 -28.018995) (xy 240.319865 -27.97315)
			(xy 240.297227 -27.923578) (xy 240.281874 -27.87129) (xy 240.274118 -27.817348) (xy 240.274118 -27.762852)
			(xy 240.281874 -27.70891) (xy 240.297227 -27.656622) (xy 240.319865 -27.60705) (xy 240.349328 -27.561205)
			(xy 240.385015 -27.520019) (xy 240.4262 -27.484331) (xy 240.472045 -27.454868) (xy 240.521616 -27.432229)
			(xy 240.573905 -27.416875) (xy 240.627846 -27.409119) (xy 240.655094 -27.408632) (xy 240.682101 -27.409119)
			(xy 240.735576 -27.416723) (xy 240.787443 -27.431796) (xy 240.836666 -27.454034) (xy 240.88226 -27.482994)
			(xy 240.923312 -27.518095) (xy 240.959002 -27.558637) (xy 240.988616 -27.603809) (xy 241.011561 -27.652706)
			(xy 241.027379 -27.704351) (xy 241.03203 -27.730958) (xy 241.033554 -27.741626) (xy 241.044984 -27.759406)
			(xy 241.116358 -27.806904) (xy 241.125282 -27.812263) (xy 241.14575 -27.815933) (xy 241.155982 -27.814016)
			(xy 241.156744 -27.814016) (xy 241.183313 -27.807898) (xy 241.237433 -27.801277) (xy 241.264694 -27.800808)
			(xy 241.286872 -27.80111) (xy 241.331018 -27.805431) (xy 241.352832 -27.809444) (xy 241.362992 -27.811476)
			(xy 241.383058 -27.807412) (xy 241.451384 -27.760168) (xy 241.459553 -27.753961) (xy 241.47056 -27.736669)
			(xy 241.47272 -27.72664) (xy 241.477649 -27.700308) (xy 241.493863 -27.649252) (xy 241.51706 -27.600965)
			(xy 241.546785 -27.556399) (xy 241.582452 -27.51643) (xy 241.623361 -27.481844) (xy 241.668705 -27.453322)
			(xy 241.717595 -27.431424) (xy 241.769067 -27.416581) (xy 241.822109 -27.409086) (xy 241.848894 -27.408632)
			(xy 241.87615 -27.409015) (xy 241.930107 -27.416772) (xy 241.982411 -27.432129) (xy 242.031998 -27.454773)
			(xy 242.077856 -27.484244) (xy 242.119054 -27.519942) (xy 242.154752 -27.561139) (xy 242.184224 -27.606997)
			(xy 242.206869 -27.656583) (xy 242.222227 -27.708887) (xy 242.229985 -27.762844) (xy 242.229985 -27.817356)
			(xy 242.222227 -27.871313) (xy 242.206869 -27.923617) (xy 242.184224 -27.973203) (xy 242.154752 -28.019061)
			(xy 242.119054 -28.060258) (xy 242.077856 -28.095956) (xy 242.031998 -28.125427) (xy 241.982411 -28.148071)
			(xy 241.930107 -28.163428) (xy 241.87615 -28.171185) (xy 241.848894 -28.171648) (xy 241.848132 -28.171648)
			(xy 241.8368 -28.171534) (xy 241.81418 -28.170135) (xy 241.80292 -28.168854) (xy 241.792006 -28.168101)
			(xy 241.771208 -28.174823) (xy 241.762788 -28.181808) (xy 241.738912 -28.203398) (xy 241.731074 -28.211322)
			(xy 241.722517 -28.231876) (xy 241.722402 -28.243022) (xy 241.722656 -28.25877) (xy 241.722656 -29.12237)
			(xy 241.722402 -29.137356) (xy 241.722482 -29.148506) (xy 241.731058 -29.169064) (xy 241.738912 -29.17698)
			(xy 241.762788 -29.198316) (xy 241.771215 -29.205289) (xy 241.792007 -29.212006) (xy 241.80292 -29.21127)
			(xy 241.814179 -29.209981) (xy 241.8368 -29.20858) (xy 241.848132 -29.208476) (xy 241.848894 -29.208476)
			(xy 241.876146 -29.208971) (xy 241.930095 -29.216727) (xy 241.982392 -29.232082) (xy 242.03197 -29.254723)
			(xy 242.077822 -29.28419) (xy 242.119014 -29.319882) (xy 242.154707 -29.361073) (xy 242.184174 -29.406924)
			(xy 242.206816 -29.456503) (xy 242.222172 -29.508799) (xy 242.229929 -29.562748) (xy 242.229929 -29.617252)
			(xy 242.222172 -29.671201) (xy 242.206816 -29.723497) (xy 242.184174 -29.773076) (xy 242.154707 -29.818927)
			(xy 242.119014 -29.860118) (xy 242.077822 -29.89581) (xy 242.03197 -29.925277) (xy 241.982392 -29.947918)
			(xy 241.930095 -29.963273) (xy 241.876146 -29.971029) (xy 241.848894 -29.971492) (xy 241.822147 -29.971028)
			(xy 241.769179 -29.963533) (xy 241.717775 -29.94872) (xy 241.668942 -29.926878) (xy 241.623635 -29.898435)
			(xy 241.582741 -29.863947) (xy 241.54706 -29.824089) (xy 241.51729 -29.779642) (xy 241.494016 -29.731475)
			(xy 241.47769 -29.680532) (xy 241.47272 -29.654246) (xy 241.470942 -29.643832) (xy 241.460274 -29.627068)
			(xy 241.383312 -29.573728) (xy 241.363246 -29.569664) (xy 241.353086 -29.571696) (xy 241.331212 -29.57574)
			(xy 241.286937 -29.580068) (xy 241.264694 -29.580332) (xy 241.237306 -29.579893) (xy 241.18293 -29.573269)
			(xy 241.156236 -29.567124) (xy 241.146076 -29.564584) (xy 241.124994 -29.568394) (xy 241.04473 -29.621734)
			(xy 241.033554 -29.63926) (xy 241.031776 -29.649928) (xy 241.02708 -29.676493) (xy 241.011225 -29.728055)
			(xy 240.988264 -29.776869) (xy 240.958654 -29.821962) (xy 240.922987 -29.862432) (xy 240.881973 -29.897474)
			(xy 240.836432 -29.926388) (xy 240.787271 -29.948598) (xy 240.735471 -29.963659) (xy 240.682066 -29.971273)
			(xy 240.655094 -29.971746) (xy 240.627723 -29.971297) (xy 240.573543 -29.963477) (xy 240.521039 -29.947985)
			(xy 240.471292 -29.925139) (xy 240.425327 -29.89541) (xy 240.404396 -29.877766) (xy 240.404142 -29.877512)
			(xy 240.397047 -29.871938) (xy 240.380137 -29.865683) (xy 240.371122 -29.86532) (xy 240.304066 -29.86532)
			(xy 240.295047 -29.865656) (xy 240.27813 -29.871918) (xy 240.271046 -29.877512) (xy 240.271046 -29.877766)
			(xy 240.270792 -29.877766) (xy 240.249869 -29.895417) (xy 240.203895 -29.925128) (xy 240.154145 -29.947962)
			(xy 240.101642 -29.963451) (xy 240.047464 -29.971275) (xy 240.020094 -29.971746) (xy 240.003046 -29.971542)
			(xy 239.969087 -29.968492) (xy 239.952276 -29.96565) (xy 239.940947 -29.964248) (xy 239.918934 -29.970161)
			(xy 239.909858 -29.97708) (xy 239.885474 -29.998162) (xy 239.877035 -30.006131) (xy 239.867913 -30.027448)
			(xy 239.867948 -30.039056) (xy 239.868456 -30.058868) (xy 239.868456 -30.922468) (xy 239.867948 -30.941518)
			(xy 239.867973 -30.953111) (xy 239.877096 -30.974399) (xy 239.885474 -30.982412) (xy 239.909858 -31.00324)
			(xy 239.91882 -31.010253) (xy 239.940726 -31.016313) (xy 239.952022 -31.014924) (xy 239.968892 -31.012049)
			(xy 240.002981 -31.009) (xy 240.020094 -31.008828) (xy 240.047464 -31.009291) (xy 240.101644 -31.017108)
			(xy 240.154147 -31.032598) (xy 240.203894 -31.05544) (xy 240.249861 -31.085166) (xy 240.270792 -31.102808)
			(xy 240.27765 -31.108904) (xy 240.294668 -31.115254) (xy 240.380012 -31.115254) (xy 240.397284 -31.10865)
			(xy 240.404142 -31.102554) (xy 240.42508 -31.084921) (xy 240.471047 -31.0552) (xy 240.520793 -31.032359)
			(xy 240.573294 -31.016867) (xy 240.627471 -31.009044) (xy 240.65484 -31.008574) (xy 240.655094 -31.008574)
			(xy 240.682102 -31.009025) (xy 240.735581 -31.016631) (xy 240.787451 -31.031705) (xy 240.836676 -31.053947)
			(xy 240.882271 -31.08291) (xy 240.923323 -31.118016) (xy 240.959013 -31.158563) (xy 240.988625 -31.203739)
			(xy 241.011568 -31.252641) (xy 241.027382 -31.304291) (xy 241.03203 -31.3309) (xy 241.033554 -31.341568)
			(xy 241.044984 -31.359348) (xy 241.116358 -31.406846) (xy 241.125281 -31.412207) (xy 241.14575 -31.415874)
			(xy 241.155982 -31.413958) (xy 241.156744 -31.413958) (xy 241.18332 -31.407902) (xy 241.23744 -31.401412)
			(xy 241.264694 -31.401004) (xy 241.286867 -31.401234) (xy 241.331013 -31.405431) (xy 241.352832 -31.409386)
			(xy 241.362992 -31.411418) (xy 241.383058 -31.407354) (xy 241.451384 -31.36011) (xy 241.459573 -31.353926)
			(xy 241.470569 -31.336617) (xy 241.47272 -31.326582) (xy 241.477605 -31.300242) (xy 241.493826 -31.249185)
			(xy 241.517031 -31.200899) (xy 241.546761 -31.156334) (xy 241.582434 -31.116366) (xy 241.623347 -31.081782)
			(xy 241.668696 -31.053261) (xy 241.717588 -31.031364) (xy 241.769063 -31.016522) (xy 241.822108 -31.009027)
			(xy 241.848894 -31.008574) (xy 241.876146 -31.009073) (xy 241.930095 -31.016829) (xy 241.982391 -31.032184)
			(xy 242.03197 -31.054825) (xy 242.077821 -31.084291) (xy 242.119013 -31.119983) (xy 242.154705 -31.161174)
			(xy 242.184172 -31.207025) (xy 242.206814 -31.256603) (xy 242.22217 -31.308899) (xy 242.229927 -31.362848)
			(xy 242.229927 -31.417352) (xy 242.22217 -31.471301) (xy 242.206814 -31.523597) (xy 242.184172 -31.573175)
			(xy 242.154705 -31.619026) (xy 242.119013 -31.660217) (xy 242.077821 -31.695909) (xy 242.03197 -31.725375)
			(xy 241.982391 -31.748016) (xy 241.930095 -31.763371) (xy 241.876146 -31.771127) (xy 241.848894 -31.77159)
			(xy 241.848132 -31.77159) (xy 241.8368 -31.771476) (xy 241.81418 -31.770077) (xy 241.80292 -31.768796)
			(xy 241.792006 -31.768033) (xy 241.771207 -31.77476) (xy 241.762788 -31.78175) (xy 241.738912 -31.80334)
			(xy 241.731101 -31.811287) (xy 241.722529 -31.831824) (xy 241.722402 -31.842964) (xy 241.722656 -31.858712)
			(xy 241.722656 -32.722312) (xy 241.722402 -32.737552) (xy 241.722484 -32.748702) (xy 241.731058 -32.769259)
			(xy 241.738912 -32.777176) (xy 241.762788 -32.798512) (xy 241.771215 -32.805485) (xy 241.792007 -32.812202)
			(xy 241.80292 -32.811466) (xy 241.814179 -32.810177) (xy 241.8368 -32.808776) (xy 241.848132 -32.808672)
			(xy 241.848894 -32.808672) (xy 241.876146 -32.809175) (xy 241.930094 -32.816931) (xy 241.98239 -32.832285)
			(xy 242.031969 -32.854926) (xy 242.07782 -32.884393) (xy 242.119011 -32.920084) (xy 242.154704 -32.961275)
			(xy 242.184171 -33.007126) (xy 242.206812 -33.056704) (xy 242.222168 -33.109) (xy 242.229925 -33.162948)
			(xy 242.229925 -33.217452) (xy 242.222168 -33.2714) (xy 242.206812 -33.323696) (xy 242.184171 -33.373274)
			(xy 242.154704 -33.419125) (xy 242.119011 -33.460316) (xy 242.07782 -33.496007) (xy 242.031969 -33.525474)
			(xy 241.98239 -33.548115) (xy 241.930094 -33.563469) (xy 241.876146 -33.571225) (xy 241.848894 -33.571688)
			(xy 241.822126 -33.571322) (xy 241.769115 -33.56385) (xy 241.717668 -33.54904) (xy 241.668798 -33.527181)
			(xy 241.623465 -33.498705) (xy 241.582558 -33.46417) (xy 241.546881 -33.424254) (xy 241.517136 -33.379743)
			(xy 241.493906 -33.331509) (xy 241.477649 -33.280502) (xy 241.47272 -33.254188) (xy 241.470942 -33.243774)
			(xy 241.460274 -33.22701) (xy 241.383312 -33.17367) (xy 241.363246 -33.169606) (xy 241.353086 -33.171638)
			(xy 241.331206 -33.175615) (xy 241.286931 -33.179817) (xy 241.264694 -33.18002) (xy 241.237312 -33.179644)
			(xy 241.182936 -33.17315) (xy 241.156236 -33.167066) (xy 241.146076 -33.164526) (xy 241.124994 -33.168336)
			(xy 241.04473 -33.221676) (xy 241.033554 -33.239202) (xy 241.031776 -33.24987) (xy 241.027036 -33.276427)
			(xy 241.011189 -33.327989) (xy 240.988234 -33.376803) (xy 240.95863 -33.421897) (xy 240.922968 -33.462369)
			(xy 240.881959 -33.497412) (xy 240.836422 -33.526328) (xy 240.787264 -33.548538) (xy 240.735467 -33.563601)
			(xy 240.682065 -33.571215) (xy 240.655094 -33.571688) (xy 240.627724 -33.571228) (xy 240.573544 -33.563409)
			(xy 240.521041 -33.547919) (xy 240.471294 -33.525076) (xy 240.425327 -33.49535) (xy 240.404396 -33.477708)
			(xy 240.404142 -33.477454) (xy 240.397052 -33.471873) (xy 240.380138 -33.465624) (xy 240.371122 -33.465262)
			(xy 240.304066 -33.465262) (xy 240.295048 -33.465611) (xy 240.278132 -33.471865) (xy 240.271046 -33.477454)
			(xy 240.271046 -33.477708) (xy 240.270792 -33.477708) (xy 240.249875 -33.495366) (xy 240.203898 -33.525074)
			(xy 240.154146 -33.547907) (xy 240.101643 -33.563393) (xy 240.047464 -33.571217) (xy 240.020094 -33.571688)
			(xy 240.003046 -33.571485) (xy 239.969086 -33.568435) (xy 239.952276 -33.565592) (xy 239.940948 -33.564181)
			(xy 239.918933 -33.570098) (xy 239.909858 -33.577022) (xy 239.885474 -33.598104) (xy 239.877063 -33.606097)
			(xy 239.867925 -33.627396) (xy 239.867948 -33.638998) (xy 239.868456 -33.65881) (xy 239.868456 -34.52241)
			(xy 239.867948 -34.54146) (xy 239.867949 -34.553055) (xy 239.877089 -34.574344) (xy 239.885474 -34.582354)
			(xy 239.909858 -34.603182) (xy 239.918824 -34.61019) (xy 239.940727 -34.616254) (xy 239.952022 -34.614866)
			(xy 239.968892 -34.611991) (xy 240.002981 -34.608942) (xy 240.020094 -34.60877) (xy 240.047346 -34.609277)
			(xy 240.101294 -34.617033) (xy 240.15359 -34.632387) (xy 240.203168 -34.655028) (xy 240.249019 -34.684494)
			(xy 240.29021 -34.720186) (xy 240.325902 -34.761376) (xy 240.355369 -34.807227) (xy 240.378011 -34.856805)
			(xy 240.393366 -34.9091) (xy 240.401123 -34.963048) (xy 240.401123 -34.990024) (xy 241.466876 -34.990024)
			(xy 241.470947 -34.934402) (xy 241.483073 -34.879965) (xy 241.502996 -34.827874) (xy 241.530292 -34.779239)
			(xy 241.564378 -34.735096) (xy 241.604527 -34.696387) (xy 241.649885 -34.663936) (xy 241.699485 -34.638435)
			(xy 241.752269 -34.620428) (xy 241.807112 -34.610298) (xy 241.862846 -34.608261) (xy 241.918283 -34.614361)
			(xy 241.97224 -34.628467) (xy 242.023569 -34.650279) (xy 242.071175 -34.679333) (xy 242.114043 -34.715008)
			(xy 242.15126 -34.756545) (xy 242.182033 -34.803058) (xy 242.205705 -34.853555) (xy 242.221773 -34.906962)
			(xy 242.229893 -34.962138) (xy 242.230402 -34.990024) (xy 242.229893 -35.01791) (xy 242.221773 -35.073086)
			(xy 242.205705 -35.126493) (xy 242.182033 -35.17699) (xy 242.15126 -35.223503) (xy 242.114043 -35.26504)
			(xy 242.071175 -35.300715) (xy 242.023569 -35.329769) (xy 241.97224 -35.351581) (xy 241.918283 -35.365687)
			(xy 241.862846 -35.371787) (xy 241.807112 -35.36975) (xy 241.752269 -35.35962) (xy 241.699485 -35.341613)
			(xy 241.649885 -35.316112) (xy 241.604527 -35.283661) (xy 241.564378 -35.244952) (xy 241.530292 -35.200809)
			(xy 241.502996 -35.152174) (xy 241.483073 -35.100083) (xy 241.470947 -35.045646) (xy 241.466876 -34.990024)
			(xy 240.401123 -34.990024) (xy 240.401123 -35.017552) (xy 240.393366 -35.0715) (xy 240.378011 -35.123795)
			(xy 240.355369 -35.173373) (xy 240.325902 -35.219224) (xy 240.29021 -35.260414) (xy 240.249019 -35.296106)
			(xy 240.203168 -35.325572) (xy 240.15359 -35.348213) (xy 240.101294 -35.363567) (xy 240.047346 -35.371323)
			(xy 240.020094 -35.371786) (xy 239.993118 -35.371286) (xy 239.939702 -35.363705) (xy 239.887888 -35.348667)
			(xy 239.838713 -35.326473) (xy 239.793159 -35.297566) (xy 239.752137 -35.262524) (xy 239.716467 -35.222047)
			(xy 239.686861 -35.176944) (xy 239.663911 -35.128117) (xy 239.648076 -35.076542) (xy 239.643412 -35.049968)
			(xy 239.641263 -35.039734) (xy 239.629972 -35.022156) (xy 239.621568 -35.015932) (xy 239.550194 -34.968434)
			(xy 239.529112 -34.964624) (xy 239.518952 -34.967164) (xy 239.492257 -34.973303) (xy 239.437882 -34.979925)
			(xy 239.410494 -34.980372) (xy 239.383106 -34.979932) (xy 239.32873 -34.973308) (xy 239.302036 -34.967164)
			(xy 239.291876 -34.964624) (xy 239.270794 -34.968434) (xy 239.19053 -35.021774) (xy 239.179354 -35.0393)
			(xy 239.177576 -35.049968) (xy 239.172911 -35.076539) (xy 239.15705 -35.128101) (xy 239.134084 -35.176915)
			(xy 239.10447 -35.222006) (xy 239.068799 -35.262476) (xy 239.027783 -35.297517) (xy 238.982238 -35.32643)
			(xy 238.933075 -35.348639) (xy 238.881274 -35.3637) (xy 238.827867 -35.371313) (xy 238.800894 -35.371786)
			(xy 238.773641 -35.371344) (xy 238.719691 -35.363586) (xy 238.667394 -35.34823) (xy 238.617815 -35.325587)
			(xy 238.571963 -35.296119) (xy 238.530771 -35.260425) (xy 238.495078 -35.219233) (xy 238.46561 -35.17338)
			(xy 238.442968 -35.1238) (xy 238.427613 -35.071503) (xy 238.419856 -35.017553) (xy 236.774397 -35.017553)
			(xy 236.78678 -35.031373) (xy 236.817553 -35.077886) (xy 236.841225 -35.128383) (xy 236.857293 -35.18179)
			(xy 236.865413 -35.236966) (xy 236.865922 -35.264852) (xy 236.865413 -35.292738) (xy 236.857293 -35.347914)
			(xy 236.841225 -35.401321) (xy 236.817553 -35.451818) (xy 236.78678 -35.498331) (xy 236.749563 -35.539868)
			(xy 236.706695 -35.575543) (xy 236.659089 -35.604597) (xy 236.60776 -35.626409) (xy 236.553803 -35.640515)
			(xy 236.498366 -35.646615) (xy 236.442632 -35.644578) (xy 236.387789 -35.634448) (xy 236.335005 -35.616441)
			(xy 236.285405 -35.59094) (xy 236.240047 -35.558489) (xy 236.199898 -35.51978) (xy 236.165812 -35.475637)
			(xy 236.138516 -35.427002) (xy 236.118593 -35.374911) (xy 236.106467 -35.320474) (xy 236.102396 -35.264852)
			(xy 233.600752 -35.264852) (xy 233.600752 -37.087048) (xy 237.400846 -37.087048) (xy 237.401311 -37.060444)
			(xy 237.408687 -37.007751) (xy 237.423317 -36.956595) (xy 237.444917 -36.907969) (xy 237.473066 -36.862819)
			(xy 237.507219 -36.822019) (xy 237.546712 -36.786364) (xy 237.568486 -36.771072) (xy 237.57841 -36.763541)
			(xy 237.590138 -36.741598) (xy 237.590838 -36.729162) (xy 237.590838 -36.644834) (xy 237.590166 -36.632384)
			(xy 237.578457 -36.610408) (xy 237.568486 -36.602924) (xy 237.546728 -36.587612) (xy 237.507247 -36.55195)
			(xy 237.473101 -36.51115) (xy 237.444953 -36.466003) (xy 237.423349 -36.417384) (xy 237.408707 -36.366236)
			(xy 237.40131 -36.313549) (xy 237.400846 -36.286948) (xy 237.4014 -36.259698) (xy 237.409149 -36.205753)
			(xy 237.424497 -36.15346) (xy 237.44713 -36.103883) (xy 237.476589 -36.058032) (xy 237.512273 -36.01684)
			(xy 237.553456 -35.981145) (xy 237.5993 -35.951675) (xy 237.648872 -35.92903) (xy 237.701161 -35.913669)
			(xy 237.755105 -35.905907) (xy 237.782354 -35.90544) (xy 237.786926 -35.90544) (xy 237.796135 -35.905166)
			(xy 237.813454 -35.898927) (xy 237.820708 -35.893248) (xy 237.871508 -35.84956) (xy 237.878214 -35.843323)
			(xy 237.887073 -35.827314) (xy 237.88878 -35.818318) (xy 237.88878 -35.818064) (xy 237.89313 -35.791134)
			(xy 237.90844 -35.738778) (xy 237.931051 -35.689137) (xy 237.960502 -35.643222) (xy 237.996192 -35.60197)
			(xy 238.037394 -35.566222) (xy 238.083268 -35.536707) (xy 238.132878 -35.514026) (xy 238.185212 -35.498643)
			(xy 238.239204 -35.49087) (xy 238.266478 -35.490404) (xy 238.293733 -35.490841) (xy 238.347688 -35.498596)
			(xy 238.39999 -35.513951) (xy 238.449575 -35.536593) (xy 238.495432 -35.566061) (xy 238.536629 -35.601756)
			(xy 238.572326 -35.64295) (xy 238.601797 -35.688806) (xy 238.624442 -35.738389) (xy 238.639799 -35.790691)
			(xy 238.647557 -35.844645) (xy 238.647557 -35.899155) (xy 238.639799 -35.953109) (xy 238.624442 -36.005411)
			(xy 238.601797 -36.054994) (xy 238.572326 -36.10085) (xy 238.536629 -36.142044) (xy 238.495432 -36.177739)
			(xy 238.449575 -36.207207) (xy 238.39999 -36.229849) (xy 238.347688 -36.245204) (xy 238.293733 -36.252959)
			(xy 238.266478 -36.25342) (xy 238.261906 -36.25342) (xy 238.252692 -36.253647) (xy 238.235373 -36.259918)
			(xy 238.228124 -36.265612) (xy 238.177324 -36.3093) (xy 238.170602 -36.315522) (xy 238.161751 -36.331541)
			(xy 238.160052 -36.340542) (xy 238.160052 -36.340796) (xy 238.155854 -36.366999) (xy 238.14117 -36.417994)
			(xy 238.119557 -36.466459) (xy 238.091433 -36.51146) (xy 238.088006 -36.515548) (xy 239.21415 -36.515548)
			(xy 239.218221 -36.459926) (xy 239.230347 -36.405489) (xy 239.25027 -36.353398) (xy 239.277566 -36.304763)
			(xy 239.311652 -36.26062) (xy 239.351801 -36.221911) (xy 239.397159 -36.18946) (xy 239.446759 -36.163959)
			(xy 239.499543 -36.145952) (xy 239.554386 -36.135822) (xy 239.61012 -36.133785) (xy 239.665557 -36.139885)
			(xy 239.719514 -36.153991) (xy 239.770843 -36.175803) (xy 239.818449 -36.204857) (xy 239.861317 -36.240532)
			(xy 239.898534 -36.282069) (xy 239.929307 -36.328582) (xy 239.952979 -36.379079) (xy 239.969047 -36.432486)
			(xy 239.977167 -36.487662) (xy 239.977676 -36.515548) (xy 239.977167 -36.543434) (xy 239.969047 -36.59861)
			(xy 239.952979 -36.652017) (xy 239.929307 -36.702514) (xy 239.898534 -36.749027) (xy 239.861317 -36.790564)
			(xy 239.818449 -36.826239) (xy 239.770843 -36.855293) (xy 239.719514 -36.877105) (xy 239.665557 -36.891211)
			(xy 239.61012 -36.897311) (xy 239.554386 -36.895274) (xy 239.499543 -36.885144) (xy 239.446759 -36.867137)
			(xy 239.397159 -36.841636) (xy 239.351801 -36.809185) (xy 239.311652 -36.770476) (xy 239.277566 -36.726333)
			(xy 239.25027 -36.677698) (xy 239.230347 -36.625607) (xy 239.218221 -36.57117) (xy 239.21415 -36.515548)
			(xy 238.088006 -36.515548) (xy 238.057341 -36.552127) (xy 238.01794 -36.587675) (xy 237.996222 -36.602924)
			(xy 237.986301 -36.610458) (xy 237.974571 -36.632399) (xy 237.97387 -36.644834) (xy 237.97387 -36.729162)
			(xy 237.974541 -36.741612) (xy 237.986251 -36.763588) (xy 237.996222 -36.771072) (xy 238.01798 -36.786385)
			(xy 238.057461 -36.822047) (xy 238.091606 -36.862846) (xy 238.119754 -36.907993) (xy 238.141358 -36.956612)
			(xy 238.156001 -37.00776) (xy 238.163397 -37.060447) (xy 238.163862 -37.087048) (xy 238.163862 -37.087302)
			(xy 238.163244 -37.119019) (xy 238.152743 -37.181577) (xy 238.132015 -37.241528) (xy 238.11738 -37.269674)
			(xy 238.112046 -37.27958) (xy 238.110522 -37.301678) (xy 238.142526 -37.384482) (xy 238.14702 -37.394568)
			(xy 238.162807 -37.409971) (xy 238.173006 -37.4142) (xy 238.19754 -37.423263) (xy 238.24407 -37.447146)
			(xy 238.286902 -37.477163) (xy 238.32523 -37.51275) (xy 238.358338 -37.553239) (xy 238.385604 -37.597871)
			(xy 238.406516 -37.64581) (xy 238.420684 -37.696157) (xy 238.42784 -37.747967) (xy 238.428276 -37.774118)
			(xy 238.42779 -37.801369) (xy 238.420034 -37.855317) (xy 238.404679 -37.907612) (xy 238.382037 -37.957189)
			(xy 238.352571 -38.003039) (xy 238.31688 -38.04423) (xy 238.275689 -38.079921) (xy 238.229839 -38.109387)
			(xy 238.180262 -38.132029) (xy 238.127967 -38.147384) (xy 238.074019 -38.15514) (xy 238.019517 -38.15514)
			(xy 237.965569 -38.147384) (xy 237.913274 -38.132029) (xy 237.863697 -38.109387) (xy 237.817847 -38.079921)
			(xy 237.776656 -38.04423) (xy 237.740965 -38.003039) (xy 237.711499 -37.957189) (xy 237.688857 -37.907612)
			(xy 237.673502 -37.855317) (xy 237.665746 -37.801369) (xy 237.66526 -37.774118) (xy 237.66526 -37.773864)
			(xy 237.665862 -37.742146) (xy 237.676369 -37.679588) (xy 237.697104 -37.619637) (xy 237.711742 -37.591492)
			(xy 237.717076 -37.581586) (xy 237.7186 -37.559488) (xy 237.686596 -37.476684) (xy 237.682148 -37.466573)
			(xy 237.666328 -37.451182) (xy 237.656116 -37.446966) (xy 237.631575 -37.43792) (xy 237.585043 -37.414035)
			(xy 237.542211 -37.384018) (xy 237.503881 -37.34843) (xy 237.470773 -37.307938) (xy 237.443508 -37.263303)
			(xy 237.422598 -37.215361) (xy 237.408433 -37.165012) (xy 237.40128 -37.1132) (xy 237.400846 -37.087048)
			(xy 233.600752 -37.087048) (xy 233.600752 -38.315138) (xy 238.618012 -38.315138) (xy 238.622083 -38.259516)
			(xy 238.634209 -38.205079) (xy 238.654132 -38.152988) (xy 238.681428 -38.104353) (xy 238.715514 -38.06021)
			(xy 238.755663 -38.021501) (xy 238.801021 -37.98905) (xy 238.850621 -37.963549) (xy 238.903405 -37.945542)
			(xy 238.958248 -37.935412) (xy 239.013982 -37.933375) (xy 239.069419 -37.939475) (xy 239.123376 -37.953581)
			(xy 239.174705 -37.975393) (xy 239.222311 -38.004447) (xy 239.265179 -38.040122) (xy 239.302396 -38.081659)
			(xy 239.333169 -38.128172) (xy 239.356841 -38.178669) (xy 239.372909 -38.232076) (xy 239.381029 -38.287252)
			(xy 239.381538 -38.315138) (xy 239.381029 -38.343024) (xy 239.372909 -38.3982) (xy 239.356841 -38.451607)
			(xy 239.333169 -38.502104) (xy 239.302396 -38.548617) (xy 239.265179 -38.590154) (xy 239.222311 -38.625829)
			(xy 239.174705 -38.654883) (xy 239.123376 -38.676695) (xy 239.069419 -38.690801) (xy 239.013982 -38.696901)
			(xy 238.958248 -38.694864) (xy 238.903405 -38.684734) (xy 238.850621 -38.666727) (xy 238.801021 -38.641226)
			(xy 238.755663 -38.608775) (xy 238.715514 -38.570066) (xy 238.681428 -38.525923) (xy 238.654132 -38.477288)
			(xy 238.634209 -38.425197) (xy 238.622083 -38.37076) (xy 238.618012 -38.315138) (xy 233.600752 -38.315138)
			(xy 233.600752 -45.835348) (xy 234.660216 -45.835348) (xy 234.660216 -45.780852) (xy 234.667972 -45.726911)
			(xy 234.683324 -45.674623) (xy 234.705962 -45.625051) (xy 234.735424 -45.579206) (xy 234.771111 -45.538021)
			(xy 234.812295 -45.502333) (xy 234.858139 -45.472869) (xy 234.90771 -45.450229) (xy 234.959997 -45.434874)
			(xy 235.013938 -45.427117) (xy 235.041186 -45.42663) (xy 235.068556 -45.427097) (xy 235.122736 -45.434913)
			(xy 235.175239 -45.450402) (xy 235.224986 -45.473244) (xy 235.270953 -45.502968) (xy 235.291884 -45.52061)
			(xy 235.292138 -45.520864) (xy 235.299233 -45.526438) (xy 235.316143 -45.532691) (xy 235.325158 -45.533056)
			(xy 235.392214 -45.533056) (xy 235.401233 -45.532715) (xy 235.41815 -45.526458) (xy 235.425234 -45.520864)
			(xy 235.425234 -45.52061) (xy 235.425488 -45.52061) (xy 235.446421 -45.502969) (xy 235.492389 -45.473245)
			(xy 235.542135 -45.450399) (xy 235.594637 -45.434903) (xy 235.648815 -45.427074) (xy 235.703557 -45.427074)
			(xy 235.757735 -45.434903) (xy 235.810237 -45.450399) (xy 235.859983 -45.473245) (xy 235.905951 -45.502969)
			(xy 235.926884 -45.52061) (xy 235.927138 -45.520864) (xy 235.934233 -45.526438) (xy 235.951143 -45.532691)
			(xy 235.960158 -45.533056) (xy 236.027214 -45.533056) (xy 236.036233 -45.532715) (xy 236.05315 -45.526458)
			(xy 236.060234 -45.520864) (xy 236.060234 -45.52061) (xy 236.060488 -45.52061) (xy 236.081415 -45.502965)
			(xy 236.127389 -45.473253) (xy 236.177138 -45.450418) (xy 236.22964 -45.434929) (xy 236.283816 -45.427103)
			(xy 236.311186 -45.42663) (xy 236.3375 -45.427097) (xy 236.389629 -45.434331) (xy 236.440272 -45.448649)
			(xy 236.488471 -45.469782) (xy 236.533315 -45.497328) (xy 236.573954 -45.530768) (xy 236.59211 -45.54982)
			(xy 236.599623 -45.557231) (xy 236.61891 -45.565749) (xy 236.629448 -45.56633) (xy 236.704124 -45.56633)
			(xy 236.714669 -45.565765) (xy 236.733965 -45.557254) (xy 236.741462 -45.54982) (xy 236.759598 -45.530745)
			(xy 236.800232 -45.497289) (xy 236.845076 -45.469732) (xy 236.893281 -45.448597) (xy 236.943932 -45.434284)
			(xy 236.996069 -45.427065) (xy 237.022386 -45.42663) (xy 237.049642 -45.427016) (xy 237.1036 -45.434772)
			(xy 237.155905 -45.450128) (xy 237.205492 -45.472772) (xy 237.251351 -45.502243) (xy 237.29255 -45.53794)
			(xy 237.328249 -45.579137) (xy 237.357721 -45.624996) (xy 237.380367 -45.674582) (xy 237.395725 -45.726886)
			(xy 237.403483 -45.780844) (xy 237.403483 -45.835356) (xy 237.395725 -45.889314) (xy 237.380367 -45.941618)
			(xy 237.357721 -45.991204) (xy 237.328249 -46.037063) (xy 237.29255 -46.07826) (xy 237.251351 -46.113957)
			(xy 237.205492 -46.143428) (xy 237.155905 -46.166072) (xy 237.1036 -46.181428) (xy 237.049642 -46.189184)
			(xy 237.022386 -46.189646) (xy 236.996071 -46.189205) (xy 236.943941 -46.181967) (xy 236.893297 -46.167644)
			(xy 236.845097 -46.146507) (xy 236.800255 -46.118955) (xy 236.759617 -46.085511) (xy 236.741462 -46.066456)
			(xy 236.733949 -46.059044) (xy 236.714663 -46.050524) (xy 236.704124 -46.049946) (xy 236.629448 -46.049946)
			(xy 236.618898 -46.050474) (xy 236.599602 -46.059009) (xy 236.59211 -46.066456) (xy 236.573954 -46.08551)
			(xy 236.533323 -46.118965) (xy 236.488482 -46.146523) (xy 236.440282 -46.167662) (xy 236.389635 -46.18198)
			(xy 236.337502 -46.189206) (xy 236.311186 -46.189646) (xy 236.283815 -46.189201) (xy 236.229634 -46.18138)
			(xy 236.17713 -46.165887) (xy 236.127384 -46.14304) (xy 236.081418 -46.11331) (xy 236.060488 -46.095666)
			(xy 236.060234 -46.095412) (xy 236.053141 -46.089835) (xy 236.036229 -46.083582) (xy 236.027214 -46.08322)
			(xy 235.960158 -46.08322) (xy 235.951143 -46.083601) (xy 235.934226 -46.089831) (xy 235.927138 -46.095412)
			(xy 235.927138 -46.095666) (xy 235.926884 -46.095666) (xy 235.905951 -46.113307) (xy 235.859983 -46.143031)
			(xy 235.810237 -46.165877) (xy 235.757735 -46.181373) (xy 235.703557 -46.189202) (xy 235.648815 -46.189202)
			(xy 235.594637 -46.181373) (xy 235.542135 -46.165877) (xy 235.492389 -46.143031) (xy 235.446421 -46.113307)
			(xy 235.425488 -46.095666) (xy 235.425234 -46.095412) (xy 235.418141 -46.089835) (xy 235.401229 -46.083582)
			(xy 235.392214 -46.08322) (xy 235.325158 -46.08322) (xy 235.316143 -46.083601) (xy 235.299226 -46.089831)
			(xy 235.292138 -46.095412) (xy 235.292138 -46.095666) (xy 235.291884 -46.095666) (xy 235.270927 -46.113274)
			(xy 235.224961 -46.142992) (xy 235.17522 -46.165834) (xy 235.122725 -46.181332) (xy 235.068554 -46.189168)
			(xy 235.041186 -46.189646) (xy 235.013938 -46.189083) (xy 234.959997 -46.181326) (xy 234.90771 -46.165971)
			(xy 234.858139 -46.143331) (xy 234.812295 -46.113867) (xy 234.771111 -46.078179) (xy 234.735424 -46.036994)
			(xy 234.705962 -45.991149) (xy 234.683324 -45.941577) (xy 234.667972 -45.889289) (xy 234.660216 -45.835348)
			(xy 233.600752 -45.835348) (xy 233.600752 -47.922557) (xy 234.624511 -47.922557) (xy 234.624511 -47.868043)
			(xy 234.63227 -47.814083) (xy 234.647629 -47.761777) (xy 234.670276 -47.71219) (xy 234.69975 -47.66633)
			(xy 234.73545 -47.625132) (xy 234.776651 -47.589434) (xy 234.822513 -47.559963) (xy 234.872102 -47.53732)
			(xy 234.924409 -47.521964) (xy 234.978369 -47.514209) (xy 235.005626 -47.513748) (xy 235.032997 -47.514187)
			(xy 235.087178 -47.52201) (xy 235.139682 -47.537504) (xy 235.189428 -47.560352) (xy 235.235394 -47.590083)
			(xy 235.256324 -47.607728) (xy 235.256578 -47.607982) (xy 235.263668 -47.613563) (xy 235.280582 -47.619813)
			(xy 235.289598 -47.620174) (xy 235.356654 -47.620174) (xy 235.365669 -47.619801) (xy 235.382587 -47.613565)
			(xy 235.389674 -47.607982) (xy 235.389674 -47.607728) (xy 235.389928 -47.607728) (xy 235.41088 -47.590114)
			(xy 235.456847 -47.560397) (xy 235.506589 -47.537556) (xy 235.559086 -47.522059) (xy 235.613258 -47.514225)
			(xy 235.640626 -47.513748) (xy 235.658969 -47.513987) (xy 235.695482 -47.517546) (xy 235.713524 -47.52086)
			(xy 235.724156 -47.522439) (xy 235.745073 -47.517581) (xy 235.75391 -47.511462) (xy 235.822998 -47.459138)
			(xy 235.833412 -47.440342) (xy 235.834174 -47.42942) (xy 235.837018 -47.40113) (xy 235.850067 -47.345791)
			(xy 235.871174 -47.292997) (xy 235.899874 -47.243916) (xy 235.935533 -47.199631) (xy 235.956094 -47.179992)
			(xy 235.9635 -47.172474) (xy 235.972022 -47.153191) (xy 235.972604 -47.142654) (xy 235.972604 -47.067978)
			(xy 235.972045 -47.057432) (xy 235.963531 -47.038136) (xy 235.956094 -47.03064) (xy 235.937015 -47.012508)
			(xy 235.90356 -46.971873) (xy 235.876005 -46.927028) (xy 235.85487 -46.878822) (xy 235.840558 -46.828171)
			(xy 235.833339 -46.776033) (xy 235.832904 -46.749716) (xy 235.83339 -46.722465) (xy 235.841146 -46.668517)
			(xy 235.856501 -46.616222) (xy 235.879143 -46.566645) (xy 235.908609 -46.520795) (xy 235.9443 -46.479604)
			(xy 235.985491 -46.443913) (xy 236.031341 -46.414447) (xy 236.080918 -46.391805) (xy 236.133213 -46.37645)
			(xy 236.187161 -46.368694) (xy 236.241663 -46.368694) (xy 236.295611 -46.37645) (xy 236.347906 -46.391805)
			(xy 236.397483 -46.414447) (xy 236.443333 -46.443913) (xy 236.484524 -46.479604) (xy 236.520215 -46.520795)
			(xy 236.549681 -46.566645) (xy 236.572323 -46.616222) (xy 236.587678 -46.668517) (xy 236.595434 -46.722465)
			(xy 236.59592 -46.749716) (xy 236.595457 -46.77603) (xy 236.58822 -46.828158) (xy 236.5739 -46.878801)
			(xy 236.552767 -46.927) (xy 236.52522 -46.971843) (xy 236.491781 -47.012483) (xy 236.47273 -47.03064)
			(xy 236.465313 -47.038149) (xy 236.456796 -47.057438) (xy 236.45622 -47.067978) (xy 236.45622 -47.142654)
			(xy 236.456755 -47.153203) (xy 236.465285 -47.172499) (xy 236.47273 -47.179992) (xy 236.49178 -47.198153)
			(xy 236.525237 -47.238782) (xy 236.552796 -47.283621) (xy 236.573935 -47.331821) (xy 236.588254 -47.382467)
			(xy 236.59548 -47.4346) (xy 236.59592 -47.460916) (xy 236.595437 -47.488167) (xy 236.587679 -47.542114)
			(xy 236.572322 -47.594408) (xy 236.54968 -47.643985) (xy 236.520213 -47.689835) (xy 236.484522 -47.731024)
			(xy 236.443331 -47.766716) (xy 236.397481 -47.796182) (xy 236.347905 -47.818824) (xy 236.29561 -47.83418)
			(xy 236.241663 -47.841937) (xy 236.214412 -47.842424) (xy 236.196069 -47.842193) (xy 236.159556 -47.838629)
			(xy 236.141514 -47.835312) (xy 236.130884 -47.833701) (xy 236.109964 -47.838582) (xy 236.101128 -47.84471)
			(xy 236.03204 -47.897034) (xy 236.021626 -47.91583) (xy 236.020864 -47.926752) (xy 236.017989 -47.955012)
			(xy 236.004952 -48.010297) (xy 235.983863 -48.063039) (xy 235.955189 -48.112072) (xy 235.919562 -48.156312)
			(xy 235.877771 -48.194782) (xy 235.830739 -48.226632) (xy 235.779504 -48.251157) (xy 235.7252 -48.267816)
			(xy 235.669027 -48.27624) (xy 235.640626 -48.276764) (xy 235.613256 -48.276291) (xy 235.559077 -48.268477)
			(xy 235.506573 -48.252989) (xy 235.456826 -48.230149) (xy 235.41086 -48.200425) (xy 235.389928 -48.182784)
			(xy 235.389674 -48.18253) (xy 235.382576 -48.17696) (xy 235.365668 -48.170705) (xy 235.356654 -48.170338)
			(xy 235.289598 -48.170338) (xy 235.28058 -48.170686) (xy 235.263663 -48.176939) (xy 235.256578 -48.18253)
			(xy 235.256578 -48.182784) (xy 235.256324 -48.182784) (xy 235.235392 -48.200423) (xy 235.189419 -48.230135)
			(xy 235.139672 -48.252971) (xy 235.087171 -48.268463) (xy 235.032995 -48.27629) (xy 235.005626 -48.276764)
			(xy 234.978369 -48.276391) (xy 234.924409 -48.268636) (xy 234.872102 -48.25328) (xy 234.822513 -48.230637)
			(xy 234.776651 -48.201166) (xy 234.73545 -48.165468) (xy 234.69975 -48.12427) (xy 234.670276 -48.07841)
			(xy 234.647629 -48.028823) (xy 234.63227 -47.976517) (xy 234.624511 -47.922557) (xy 233.600752 -47.922557)
			(xy 233.600752 -48.797551) (xy 236.196364 -48.797551) (xy 236.196364 -48.743049) (xy 236.20412 -48.689101)
			(xy 236.219475 -48.636806) (xy 236.242115 -48.587228) (xy 236.27158 -48.541377) (xy 236.307271 -48.500186)
			(xy 236.34846 -48.464493) (xy 236.394309 -48.435025) (xy 236.443885 -48.412382) (xy 236.496179 -48.397025)
			(xy 236.550127 -48.389265) (xy 236.577378 -48.388778) (xy 236.604749 -48.389238) (xy 236.658929 -48.397054)
			(xy 236.711433 -48.412544) (xy 236.76118 -48.435387) (xy 236.807145 -48.465115) (xy 236.828076 -48.482758)
			(xy 236.82833 -48.483012) (xy 236.835431 -48.488577) (xy 236.852337 -48.494836) (xy 236.86135 -48.495204)
			(xy 236.928406 -48.495204) (xy 236.937423 -48.494849) (xy 236.95434 -48.4886) (xy 236.961426 -48.483012)
			(xy 236.961426 -48.482758) (xy 236.96168 -48.482758) (xy 236.982603 -48.465108) (xy 237.028579 -48.435399)
			(xy 237.078329 -48.412566) (xy 237.130831 -48.397077) (xy 237.185008 -48.389251) (xy 237.212378 -48.388778)
			(xy 237.239631 -48.389268) (xy 237.293582 -48.397022) (xy 237.345881 -48.412376) (xy 237.395462 -48.435016)
			(xy 237.441316 -48.464482) (xy 237.48251 -48.500175) (xy 237.518205 -48.541366) (xy 237.547674 -48.587219)
			(xy 237.570317 -48.636799) (xy 237.585673 -48.689096) (xy 237.593431 -48.743047) (xy 237.593431 -48.797553)
			(xy 237.585673 -48.851504) (xy 237.570317 -48.903801) (xy 237.547674 -48.953381) (xy 237.518205 -48.999234)
			(xy 237.48251 -49.040425) (xy 237.441316 -49.076118) (xy 237.395462 -49.105584) (xy 237.345881 -49.128224)
			(xy 237.293582 -49.143578) (xy 237.239631 -49.151332) (xy 237.212378 -49.151794) (xy 237.185007 -49.151342)
			(xy 237.130827 -49.143521) (xy 237.078324 -49.128029) (xy 237.028578 -49.105184) (xy 236.982611 -49.075457)
			(xy 236.96168 -49.057814) (xy 236.961426 -49.05756) (xy 236.95434 -49.051973) (xy 236.937423 -49.045728)
			(xy 236.928406 -49.045368) (xy 236.86135 -49.045368) (xy 236.852336 -49.045756) (xy 236.83542 -49.051983)
			(xy 236.82833 -49.05756) (xy 236.82833 -49.057814) (xy 236.828076 -49.057814) (xy 236.807128 -49.075433)
			(xy 236.761159 -49.105147) (xy 236.711416 -49.127987) (xy 236.658919 -49.143483) (xy 236.604746 -49.151317)
			(xy 236.577378 -49.151794) (xy 236.550127 -49.151335) (xy 236.496179 -49.143575) (xy 236.443885 -49.128218)
			(xy 236.394309 -49.105575) (xy 236.34846 -49.076107) (xy 236.307271 -49.040414) (xy 236.27158 -48.999223)
			(xy 236.242115 -48.953372) (xy 236.219475 -48.903794) (xy 236.20412 -48.851499) (xy 236.196364 -48.797551)
			(xy 233.600752 -48.797551) (xy 233.600752 -50.47234) (xy 240.755168 -50.47234) (xy 240.759239 -50.416718)
			(xy 240.771365 -50.362281) (xy 240.791288 -50.31019) (xy 240.818584 -50.261555) (xy 240.85267 -50.217412)
			(xy 240.892819 -50.178703) (xy 240.938177 -50.146252) (xy 240.987777 -50.120751) (xy 241.040561 -50.102744)
			(xy 241.095404 -50.092614) (xy 241.151138 -50.090577) (xy 241.206575 -50.096677) (xy 241.260532 -50.110783)
			(xy 241.311861 -50.132595) (xy 241.359467 -50.161649) (xy 241.402335 -50.197324) (xy 241.439552 -50.238861)
			(xy 241.470325 -50.285374) (xy 241.493997 -50.335871) (xy 241.510065 -50.389278) (xy 241.518185 -50.444454)
			(xy 241.518694 -50.47234) (xy 241.518185 -50.500226) (xy 241.510065 -50.555402) (xy 241.493997 -50.608809)
			(xy 241.470325 -50.659306) (xy 241.439552 -50.705819) (xy 241.402335 -50.747356) (xy 241.359467 -50.783031)
			(xy 241.311861 -50.812085) (xy 241.260532 -50.833897) (xy 241.206575 -50.848003) (xy 241.151138 -50.854103)
			(xy 241.095404 -50.852066) (xy 241.040561 -50.841936) (xy 240.987777 -50.823929) (xy 240.938177 -50.798428)
			(xy 240.892819 -50.765977) (xy 240.85267 -50.727268) (xy 240.818584 -50.683125) (xy 240.791288 -50.63449)
			(xy 240.771365 -50.582399) (xy 240.759239 -50.527962) (xy 240.755168 -50.47234) (xy 233.600752 -50.47234)
			(xy 233.600752 -51.222449) (xy 236.270302 -51.222449) (xy 236.270302 -51.167951) (xy 236.278058 -51.114007)
			(xy 236.293412 -51.061717) (xy 236.316051 -51.012143) (xy 236.345514 -50.966296) (xy 236.381203 -50.925109)
			(xy 236.42239 -50.889419) (xy 236.468236 -50.859955) (xy 236.517809 -50.837315) (xy 236.570099 -50.82196)
			(xy 236.624043 -50.814203) (xy 236.651292 -50.813716) (xy 236.679384 -50.814201) (xy 236.734962 -50.822428)
			(xy 236.788732 -50.838719) (xy 236.83953 -50.862723) (xy 236.886257 -50.89392) (xy 236.927902 -50.931634)
			(xy 236.963562 -50.97505) (xy 236.978444 -50.998882) (xy 236.983778 -51.007772) (xy 237.000796 -51.019964)
			(xy 237.094014 -51.040284) (xy 237.114588 -51.035966) (xy 237.123224 -51.030124) (xy 237.147282 -51.014114)
			(xy 237.199215 -50.988773) (xy 237.254375 -50.97155) (xy 237.311501 -50.962838) (xy 237.340394 -50.962306)
			(xy 237.367647 -50.962761) (xy 237.421599 -50.970517) (xy 237.473898 -50.985873) (xy 237.523479 -51.008516)
			(xy 237.569333 -51.037985) (xy 237.610526 -51.07368) (xy 237.64622 -51.114873) (xy 237.675688 -51.160728)
			(xy 237.698329 -51.210309) (xy 237.713684 -51.262609) (xy 237.72144 -51.316561) (xy 237.721902 -51.343814)
			(xy 237.721444 -51.371185) (xy 237.713624 -51.425364) (xy 237.698133 -51.477867) (xy 237.67529 -51.527614)
			(xy 237.645564 -51.57358) (xy 237.627922 -51.594512) (xy 237.627668 -51.594766) (xy 237.622086 -51.601856)
			(xy 237.615838 -51.61877) (xy 237.615476 -51.627786) (xy 237.615476 -51.694842) (xy 237.615866 -51.703855)
			(xy 237.622091 -51.720772) (xy 237.627668 -51.727862) (xy 237.627922 -51.727862) (xy 237.627922 -51.728116)
			(xy 237.645574 -51.749039) (xy 237.675295 -51.795009) (xy 237.698136 -51.844758) (xy 237.713629 -51.897261)
			(xy 237.721456 -51.95144) (xy 237.721454 -52.006181) (xy 237.713625 -52.06036) (xy 237.698129 -52.112862)
			(xy 237.675285 -52.162609) (xy 237.645562 -52.208578) (xy 237.627922 -52.229512) (xy 237.627668 -52.229766)
			(xy 237.622086 -52.236856) (xy 237.615838 -52.25377) (xy 237.615476 -52.262786) (xy 237.615476 -52.329842)
			(xy 237.615866 -52.338855) (xy 237.622091 -52.355772) (xy 237.627668 -52.362862) (xy 237.627922 -52.362862)
			(xy 237.627922 -52.363116) (xy 237.645539 -52.384066) (xy 237.675253 -52.430034) (xy 237.698093 -52.479777)
			(xy 237.713589 -52.532274) (xy 237.721424 -52.586446) (xy 237.721902 -52.613814) (xy 237.721416 -52.641065)
			(xy 237.71366 -52.695013) (xy 237.698305 -52.747308) (xy 237.675663 -52.796885) (xy 237.646197 -52.842735)
			(xy 237.610506 -52.883926) (xy 237.610047 -52.884324) (xy 240.776504 -52.884324) (xy 240.780575 -52.828702)
			(xy 240.792701 -52.774265) (xy 240.812624 -52.722174) (xy 240.83992 -52.673539) (xy 240.874006 -52.629396)
			(xy 240.914155 -52.590687) (xy 240.959513 -52.558236) (xy 241.009113 -52.532735) (xy 241.061897 -52.514728)
			(xy 241.11674 -52.504598) (xy 241.172474 -52.502561) (xy 241.227911 -52.508661) (xy 241.281868 -52.522767)
			(xy 241.333197 -52.544579) (xy 241.380803 -52.573633) (xy 241.423671 -52.609308) (xy 241.460888 -52.650845)
			(xy 241.491661 -52.697358) (xy 241.515333 -52.747855) (xy 241.531401 -52.801262) (xy 241.539521 -52.856438)
			(xy 241.54003 -52.884324) (xy 241.539521 -52.91221) (xy 241.531401 -52.967386) (xy 241.515333 -53.020793)
			(xy 241.491661 -53.07129) (xy 241.460888 -53.117803) (xy 241.423671 -53.15934) (xy 241.380803 -53.195015)
			(xy 241.333197 -53.224069) (xy 241.281868 -53.245881) (xy 241.227911 -53.259987) (xy 241.172474 -53.266087)
			(xy 241.11674 -53.26405) (xy 241.061897 -53.25392) (xy 241.009113 -53.235913) (xy 240.959513 -53.210412)
			(xy 240.914155 -53.177961) (xy 240.874006 -53.139252) (xy 240.83992 -53.095109) (xy 240.812624 -53.046474)
			(xy 240.792701 -52.994383) (xy 240.780575 -52.939946) (xy 240.776504 -52.884324) (xy 237.610047 -52.884324)
			(xy 237.569315 -52.919617) (xy 237.523465 -52.949083) (xy 237.473888 -52.971725) (xy 237.421593 -52.98708)
			(xy 237.367645 -52.994836) (xy 237.313143 -52.994836) (xy 237.259195 -52.98708) (xy 237.2069 -52.971725)
			(xy 237.157323 -52.949083) (xy 237.111473 -52.919617) (xy 237.070282 -52.883926) (xy 237.034591 -52.842735)
			(xy 237.005125 -52.796885) (xy 236.982483 -52.747308) (xy 236.967128 -52.695013) (xy 236.959372 -52.641065)
			(xy 236.958886 -52.613814) (xy 236.959364 -52.586444) (xy 236.967179 -52.532266) (xy 236.982666 -52.479763)
			(xy 237.005505 -52.430016) (xy 237.035226 -52.384048) (xy 237.052866 -52.363116) (xy 237.05312 -52.362862)
			(xy 237.058689 -52.355763) (xy 237.064946 -52.338856) (xy 237.065312 -52.329842) (xy 237.065312 -52.262786)
			(xy 237.064959 -52.253769) (xy 237.058708 -52.236852) (xy 237.05312 -52.229766) (xy 237.052866 -52.229766)
			(xy 237.052866 -52.229512) (xy 237.035237 -52.208569) (xy 237.005509 -52.162604) (xy 236.98266 -52.11286)
			(xy 236.967161 -52.060359) (xy 236.959331 -52.006181) (xy 236.959329 -51.95144) (xy 236.967157 -51.897262)
			(xy 236.982653 -51.84476) (xy 237.005499 -51.795015) (xy 237.035225 -51.749048) (xy 237.052866 -51.728116)
			(xy 237.05312 -51.727862) (xy 237.058689 -51.720763) (xy 237.064946 -51.703856) (xy 237.065312 -51.694842)
			(xy 237.065312 -51.627786) (xy 237.064959 -51.618769) (xy 237.058708 -51.601852) (xy 237.05312 -51.594766)
			(xy 237.052866 -51.594258) (xy 237.041923 -51.581523) (xy 237.022081 -51.554432) (xy 237.013242 -51.540156)
			(xy 237.007908 -51.531266) (xy 236.99089 -51.519074) (xy 236.897672 -51.498754) (xy 236.877098 -51.503072)
			(xy 236.868462 -51.508914) (xy 236.844411 -51.524934) (xy 236.792475 -51.550272) (xy 236.737313 -51.567492)
			(xy 236.680186 -51.576201) (xy 236.651292 -51.576732) (xy 236.624043 -51.576197) (xy 236.570099 -51.56844)
			(xy 236.517809 -51.553085) (xy 236.468236 -51.530445) (xy 236.42239 -51.500981) (xy 236.381203 -51.465291)
			(xy 236.345514 -51.424104) (xy 236.316051 -51.378257) (xy 236.293412 -51.328683) (xy 236.278058 -51.276393)
			(xy 236.270302 -51.222449) (xy 233.600752 -51.222449) (xy 233.600752 -51.654249) (xy 234.593902 -51.654249)
			(xy 234.593902 -51.599751) (xy 234.601658 -51.545807) (xy 234.617012 -51.493517) (xy 234.639651 -51.443943)
			(xy 234.669114 -51.398096) (xy 234.704803 -51.356909) (xy 234.74599 -51.321219) (xy 234.791836 -51.291755)
			(xy 234.841409 -51.269115) (xy 234.893699 -51.25376) (xy 234.947643 -51.246003) (xy 234.974892 -51.245516)
			(xy 235.001206 -51.245984) (xy 235.053335 -51.253218) (xy 235.103978 -51.267536) (xy 235.152177 -51.288669)
			(xy 235.19702 -51.316215) (xy 235.23766 -51.349654) (xy 235.255816 -51.368706) (xy 235.263329 -51.376117)
			(xy 235.282616 -51.384636) (xy 235.293154 -51.385216) (xy 235.36783 -51.385216) (xy 235.378376 -51.384658)
			(xy 235.397672 -51.376143) (xy 235.405168 -51.368706) (xy 235.423299 -51.349626) (xy 235.463934 -51.31617)
			(xy 235.508779 -51.288615) (xy 235.556985 -51.26748) (xy 235.607637 -51.253169) (xy 235.659774 -51.245951)
			(xy 235.686092 -51.245516) (xy 235.713347 -51.24593) (xy 235.767302 -51.253687) (xy 235.819604 -51.269043)
			(xy 235.869189 -51.291687) (xy 235.915046 -51.321156) (xy 235.956242 -51.356852) (xy 235.991939 -51.398048)
			(xy 236.021409 -51.443904) (xy 236.044054 -51.493488) (xy 236.059411 -51.54579) (xy 236.067169 -51.599745)
			(xy 236.067169 -51.654255) (xy 236.059411 -51.70821) (xy 236.044054 -51.760512) (xy 236.021409 -51.810096)
			(xy 235.991939 -51.855952) (xy 235.956242 -51.897148) (xy 235.915046 -51.932844) (xy 235.869189 -51.962313)
			(xy 235.819604 -51.984957) (xy 235.767302 -52.000313) (xy 235.713347 -52.00807) (xy 235.686092 -52.008532)
			(xy 235.659778 -52.00806) (xy 235.60765 -52.000824) (xy 235.557008 -51.986506) (xy 235.508809 -51.965374)
			(xy 235.463966 -51.937829) (xy 235.423325 -51.904393) (xy 235.405168 -51.885342) (xy 235.397654 -51.877931)
			(xy 235.378369 -51.869411) (xy 235.36783 -51.868832) (xy 235.293154 -51.868832) (xy 235.282605 -51.869367)
			(xy 235.263309 -51.877897) (xy 235.255816 -51.885342) (xy 235.237654 -51.904391) (xy 235.197025 -51.937847)
			(xy 235.152185 -51.965406) (xy 235.103986 -51.986545) (xy 235.05334 -52.000864) (xy 235.001208 -52.008092)
			(xy 234.974892 -52.008532) (xy 234.947643 -52.007997) (xy 234.893699 -52.00024) (xy 234.841409 -51.984885)
			(xy 234.791836 -51.962245) (xy 234.74599 -51.932781) (xy 234.704803 -51.897091) (xy 234.669114 -51.855904)
			(xy 234.639651 -51.810057) (xy 234.617012 -51.760483) (xy 234.601658 -51.708193) (xy 234.593902 -51.654249)
			(xy 233.600752 -51.654249) (xy 233.600752 -53.718714) (xy 236.97514 -53.718714) (xy 236.979211 -53.663092)
			(xy 236.991337 -53.608655) (xy 237.01126 -53.556564) (xy 237.038556 -53.507929) (xy 237.072642 -53.463786)
			(xy 237.112791 -53.425077) (xy 237.158149 -53.392626) (xy 237.207749 -53.367125) (xy 237.260533 -53.349118)
			(xy 237.315376 -53.338988) (xy 237.37111 -53.336951) (xy 237.426547 -53.343051) (xy 237.480504 -53.357157)
			(xy 237.531833 -53.378969) (xy 237.579439 -53.408023) (xy 237.622307 -53.443698) (xy 237.659524 -53.485235)
			(xy 237.690297 -53.531748) (xy 237.713969 -53.582245) (xy 237.730037 -53.635652) (xy 237.738157 -53.690828)
			(xy 237.738666 -53.718714) (xy 237.738157 -53.7466) (xy 237.730037 -53.801776) (xy 237.713969 -53.855183)
			(xy 237.690297 -53.90568) (xy 237.659524 -53.952193) (xy 237.622307 -53.99373) (xy 237.579439 -54.029405)
			(xy 237.531833 -54.058459) (xy 237.480504 -54.080271) (xy 237.426547 -54.094377) (xy 237.37111 -54.100477)
			(xy 237.315376 -54.09844) (xy 237.260533 -54.08831) (xy 237.207749 -54.070303) (xy 237.158149 -54.044802)
			(xy 237.112791 -54.012351) (xy 237.072642 -53.973642) (xy 237.038556 -53.929499) (xy 237.01126 -53.880864)
			(xy 236.991337 -53.828773) (xy 236.979211 -53.774336) (xy 236.97514 -53.718714) (xy 233.600752 -53.718714)
			(xy 233.600752 -54.309518) (xy 237.727234 -54.309518) (xy 237.731305 -54.253896) (xy 237.743431 -54.199459)
			(xy 237.763354 -54.147368) (xy 237.79065 -54.098733) (xy 237.824736 -54.05459) (xy 237.864885 -54.015881)
			(xy 237.910243 -53.98343) (xy 237.959843 -53.957929) (xy 238.012627 -53.939922) (xy 238.06747 -53.929792)
			(xy 238.123204 -53.927755) (xy 238.178641 -53.933855) (xy 238.232598 -53.947961) (xy 238.283927 -53.969773)
			(xy 238.331533 -53.998827) (xy 238.374401 -54.034502) (xy 238.411618 -54.076039) (xy 238.442391 -54.122552)
			(xy 238.466063 -54.173049) (xy 238.47449 -54.20106) (xy 239.961418 -54.20106) (xy 239.965489 -54.145438)
			(xy 239.977615 -54.091001) (xy 239.997538 -54.03891) (xy 240.024834 -53.990275) (xy 240.05892 -53.946132)
			(xy 240.099069 -53.907423) (xy 240.144427 -53.874972) (xy 240.194027 -53.849471) (xy 240.246811 -53.831464)
			(xy 240.301654 -53.821334) (xy 240.357388 -53.819297) (xy 240.412825 -53.825397) (xy 240.466782 -53.839503)
			(xy 240.518111 -53.861315) (xy 240.565717 -53.890369) (xy 240.608585 -53.926044) (xy 240.645802 -53.967581)
			(xy 240.676575 -54.014094) (xy 240.700247 -54.064591) (xy 240.716315 -54.117998) (xy 240.724435 -54.173174)
			(xy 240.724944 -54.20106) (xy 240.724435 -54.228946) (xy 240.716315 -54.284122) (xy 240.700247 -54.337529)
			(xy 240.676575 -54.388026) (xy 240.645802 -54.434539) (xy 240.608585 -54.476076) (xy 240.565717 -54.511751)
			(xy 240.518111 -54.540805) (xy 240.466782 -54.562617) (xy 240.412825 -54.576723) (xy 240.357388 -54.582823)
			(xy 240.301654 -54.580786) (xy 240.246811 -54.570656) (xy 240.194027 -54.552649) (xy 240.144427 -54.527148)
			(xy 240.099069 -54.494697) (xy 240.05892 -54.455988) (xy 240.024834 -54.411845) (xy 239.997538 -54.36321)
			(xy 239.977615 -54.311119) (xy 239.965489 -54.256682) (xy 239.961418 -54.20106) (xy 238.47449 -54.20106)
			(xy 238.482131 -54.226456) (xy 238.490251 -54.281632) (xy 238.49076 -54.309518) (xy 238.490251 -54.337404)
			(xy 238.482131 -54.39258) (xy 238.466063 -54.445987) (xy 238.442391 -54.496484) (xy 238.411618 -54.542997)
			(xy 238.374401 -54.584534) (xy 238.331533 -54.620209) (xy 238.283927 -54.649263) (xy 238.232598 -54.671075)
			(xy 238.178641 -54.685181) (xy 238.123204 -54.691281) (xy 238.06747 -54.689244) (xy 238.012627 -54.679114)
			(xy 237.959843 -54.661107) (xy 237.910243 -54.635606) (xy 237.864885 -54.603155) (xy 237.824736 -54.564446)
			(xy 237.79065 -54.520303) (xy 237.763354 -54.471668) (xy 237.743431 -54.419577) (xy 237.731305 -54.36514)
			(xy 237.727234 -54.309518) (xy 233.600752 -54.309518) (xy 233.600752 -54.794658) (xy 238.931448 -54.794658)
			(xy 238.935519 -54.739036) (xy 238.947645 -54.684599) (xy 238.967568 -54.632508) (xy 238.994864 -54.583873)
			(xy 239.02895 -54.53973) (xy 239.069099 -54.501021) (xy 239.114457 -54.46857) (xy 239.164057 -54.443069)
			(xy 239.216841 -54.425062) (xy 239.271684 -54.414932) (xy 239.327418 -54.412895) (xy 239.382855 -54.418995)
			(xy 239.436812 -54.433101) (xy 239.488141 -54.454913) (xy 239.535747 -54.483967) (xy 239.578615 -54.519642)
			(xy 239.615832 -54.561179) (xy 239.646605 -54.607692) (xy 239.670277 -54.658189) (xy 239.686345 -54.711596)
			(xy 239.694465 -54.766772) (xy 239.694974 -54.794658) (xy 239.69496 -54.79542) (xy 240.96294 -54.79542)
			(xy 240.967011 -54.739798) (xy 240.979137 -54.685361) (xy 240.99906 -54.63327) (xy 241.026356 -54.584635)
			(xy 241.060442 -54.540492) (xy 241.100591 -54.501783) (xy 241.145949 -54.469332) (xy 241.195549 -54.443831)
			(xy 241.248333 -54.425824) (xy 241.303176 -54.415694) (xy 241.35891 -54.413657) (xy 241.414347 -54.419757)
			(xy 241.468304 -54.433863) (xy 241.519633 -54.455675) (xy 241.567239 -54.484729) (xy 241.610107 -54.520404)
			(xy 241.647324 -54.561941) (xy 241.678097 -54.608454) (xy 241.701769 -54.658951) (xy 241.717837 -54.712358)
			(xy 241.725957 -54.767534) (xy 241.726466 -54.79542) (xy 241.725957 -54.823306) (xy 241.717837 -54.878482)
			(xy 241.701769 -54.931889) (xy 241.678097 -54.982386) (xy 241.647324 -55.028899) (xy 241.610107 -55.070436)
			(xy 241.567239 -55.106111) (xy 241.519633 -55.135165) (xy 241.468304 -55.156977) (xy 241.414347 -55.171083)
			(xy 241.35891 -55.177183) (xy 241.303176 -55.175146) (xy 241.248333 -55.165016) (xy 241.195549 -55.147009)
			(xy 241.145949 -55.121508) (xy 241.100591 -55.089057) (xy 241.060442 -55.050348) (xy 241.026356 -55.006205)
			(xy 240.99906 -54.95757) (xy 240.979137 -54.905479) (xy 240.967011 -54.851042) (xy 240.96294 -54.79542)
			(xy 239.69496 -54.79542) (xy 239.694465 -54.822544) (xy 239.686345 -54.87772) (xy 239.670277 -54.931127)
			(xy 239.646605 -54.981624) (xy 239.615832 -55.028137) (xy 239.578615 -55.069674) (xy 239.535747 -55.105349)
			(xy 239.488141 -55.134403) (xy 239.436812 -55.156215) (xy 239.382855 -55.170321) (xy 239.327418 -55.176421)
			(xy 239.271684 -55.174384) (xy 239.216841 -55.164254) (xy 239.164057 -55.146247) (xy 239.114457 -55.120746)
			(xy 239.069099 -55.088295) (xy 239.02895 -55.049586) (xy 238.994864 -55.005443) (xy 238.967568 -54.956808)
			(xy 238.947645 -54.904717) (xy 238.935519 -54.85028) (xy 238.931448 -54.794658) (xy 233.600752 -54.794658)
			(xy 233.600752 -56.208168) (xy 237.456218 -56.208168) (xy 237.456668 -56.181342) (xy 237.464184 -56.128218)
			(xy 237.479063 -56.076669) (xy 237.501014 -56.027712) (xy 237.529602 -55.982309) (xy 237.564265 -55.941357)
			(xy 237.604321 -55.905661) (xy 237.626398 -55.890414) (xy 237.637934 -55.882155) (xy 237.656341 -55.860586)
			(xy 237.668098 -55.834782) (xy 237.672298 -55.806738) (xy 237.668615 -55.778622) (xy 237.657334 -55.752607)
			(xy 237.639327 -55.730702) (xy 237.627922 -55.722266) (xy 237.606422 -55.706971) (xy 237.567513 -55.671333)
			(xy 237.533886 -55.630673) (xy 237.506181 -55.585767) (xy 237.484928 -55.537473) (xy 237.470531 -55.486711)
			(xy 237.463266 -55.43445) (xy 237.462822 -55.408068) (xy 237.463308 -55.380817) (xy 237.471064 -55.326869)
			(xy 237.486419 -55.274574) (xy 237.509061 -55.224997) (xy 237.538527 -55.179147) (xy 237.574218 -55.137956)
			(xy 237.615409 -55.102265) (xy 237.661259 -55.072799) (xy 237.710836 -55.050157) (xy 237.763131 -55.034802)
			(xy 237.817079 -55.027046) (xy 237.871581 -55.027046) (xy 237.925529 -55.034802) (xy 237.977824 -55.050157)
			(xy 238.027401 -55.072799) (xy 238.073251 -55.102265) (xy 238.114442 -55.137956) (xy 238.150133 -55.179147)
			(xy 238.179599 -55.224997) (xy 238.202241 -55.274574) (xy 238.217596 -55.326869) (xy 238.225352 -55.380817)
			(xy 238.225838 -55.408068) (xy 238.225391 -55.434894) (xy 238.217871 -55.488017) (xy 238.202989 -55.539565)
			(xy 238.181038 -55.588521) (xy 238.15245 -55.633923) (xy 238.117788 -55.674876) (xy 238.077734 -55.710574)
			(xy 238.055658 -55.725822) (xy 238.044091 -55.734038) (xy 238.025691 -55.75562) (xy 238.013941 -55.781432)
			(xy 238.009747 -55.809482) (xy 238.013435 -55.837602) (xy 238.024719 -55.863622) (xy 238.042728 -55.885531)
			(xy 238.054134 -55.89397) (xy 238.075594 -55.909318) (xy 238.114506 -55.944946) (xy 238.148138 -55.985596)
			(xy 238.175848 -56.030493) (xy 238.197108 -56.078779) (xy 238.211512 -56.129533) (xy 238.218786 -56.181789)
			(xy 238.219234 -56.208168) (xy 238.218748 -56.235419) (xy 238.210992 -56.289367) (xy 238.195637 -56.341662)
			(xy 238.172995 -56.391239) (xy 238.143529 -56.437089) (xy 238.107838 -56.47828) (xy 238.066647 -56.513971)
			(xy 238.020797 -56.543437) (xy 237.97122 -56.566079) (xy 237.918925 -56.581434) (xy 237.864977 -56.58919)
			(xy 237.810475 -56.58919) (xy 237.756527 -56.581434) (xy 237.704232 -56.566079) (xy 237.654655 -56.543437)
			(xy 237.608805 -56.513971) (xy 237.567614 -56.47828) (xy 237.531923 -56.437089) (xy 237.502457 -56.391239)
			(xy 237.479815 -56.341662) (xy 237.46446 -56.289367) (xy 237.456704 -56.235419) (xy 237.456218 -56.208168)
			(xy 233.600752 -56.208168) (xy 233.600752 -56.86044) (xy 239.090452 -56.86044) (xy 239.094523 -56.804818)
			(xy 239.106649 -56.750381) (xy 239.126572 -56.69829) (xy 239.153868 -56.649655) (xy 239.187954 -56.605512)
			(xy 239.228103 -56.566803) (xy 239.273461 -56.534352) (xy 239.323061 -56.508851) (xy 239.375845 -56.490844)
			(xy 239.430688 -56.480714) (xy 239.486422 -56.478677) (xy 239.541859 -56.484777) (xy 239.595816 -56.498883)
			(xy 239.647145 -56.520695) (xy 239.694751 -56.549749) (xy 239.737619 -56.585424) (xy 239.774836 -56.626961)
			(xy 239.805609 -56.673474) (xy 239.829281 -56.723971) (xy 239.845349 -56.777378) (xy 239.853469 -56.832554)
			(xy 239.853978 -56.86044) (xy 239.853862 -56.86679) (xy 241.182142 -56.86679) (xy 241.186213 -56.811168)
			(xy 241.198339 -56.756731) (xy 241.218262 -56.70464) (xy 241.245558 -56.656005) (xy 241.279644 -56.611862)
			(xy 241.319793 -56.573153) (xy 241.365151 -56.540702) (xy 241.414751 -56.515201) (xy 241.467535 -56.497194)
			(xy 241.522378 -56.487064) (xy 241.578112 -56.485027) (xy 241.633549 -56.491127) (xy 241.687506 -56.505233)
			(xy 241.738835 -56.527045) (xy 241.786441 -56.556099) (xy 241.829309 -56.591774) (xy 241.866526 -56.633311)
			(xy 241.897299 -56.679824) (xy 241.920971 -56.730321) (xy 241.937039 -56.783728) (xy 241.945159 -56.838904)
			(xy 241.945668 -56.86679) (xy 241.945159 -56.894676) (xy 241.937039 -56.949852) (xy 241.920971 -57.003259)
			(xy 241.897299 -57.053756) (xy 241.866526 -57.100269) (xy 241.829309 -57.141806) (xy 241.786441 -57.177481)
			(xy 241.738835 -57.206535) (xy 241.687506 -57.228347) (xy 241.633549 -57.242453) (xy 241.578112 -57.248553)
			(xy 241.522378 -57.246516) (xy 241.467535 -57.236386) (xy 241.414751 -57.218379) (xy 241.365151 -57.192878)
			(xy 241.319793 -57.160427) (xy 241.279644 -57.121718) (xy 241.245558 -57.077575) (xy 241.218262 -57.02894)
			(xy 241.198339 -56.976849) (xy 241.186213 -56.922412) (xy 241.182142 -56.86679) (xy 239.853862 -56.86679)
			(xy 239.853469 -56.888326) (xy 239.845349 -56.943502) (xy 239.829281 -56.996909) (xy 239.805609 -57.047406)
			(xy 239.774836 -57.093919) (xy 239.737619 -57.135456) (xy 239.694751 -57.171131) (xy 239.647145 -57.200185)
			(xy 239.595816 -57.221997) (xy 239.541859 -57.236103) (xy 239.486422 -57.242203) (xy 239.430688 -57.240166)
			(xy 239.375845 -57.230036) (xy 239.323061 -57.212029) (xy 239.273461 -57.186528) (xy 239.228103 -57.154077)
			(xy 239.187954 -57.115368) (xy 239.153868 -57.071225) (xy 239.126572 -57.02259) (xy 239.106649 -56.970499)
			(xy 239.094523 -56.916062) (xy 239.090452 -56.86044) (xy 233.600752 -56.86044) (xy 233.600752 -57.638692)
			(xy 233.790741 -57.638692) (xy 233.790741 -57.561484) (xy 233.798811 -57.4847) (xy 233.814864 -57.409179)
			(xy 233.838722 -57.335751) (xy 233.870125 -57.265218) (xy 233.908729 -57.198355) (xy 233.95411 -57.135892)
			(xy 234.005772 -57.078516) (xy 234.063148 -57.026854) (xy 234.125611 -56.981473) (xy 234.192474 -56.942869)
			(xy 234.263007 -56.911466) (xy 234.336435 -56.887608) (xy 234.411956 -56.871555) (xy 234.48874 -56.863485)
			(xy 234.565948 -56.863485) (xy 234.642732 -56.871555) (xy 234.718253 -56.887608) (xy 234.791681 -56.911466)
			(xy 234.862214 -56.942869) (xy 234.929077 -56.981473) (xy 234.99154 -57.026854) (xy 235.048916 -57.078516)
			(xy 235.100578 -57.135892) (xy 235.145959 -57.198355) (xy 235.184563 -57.265218) (xy 235.215966 -57.335751)
			(xy 235.239824 -57.409179) (xy 235.255877 -57.4847) (xy 235.263947 -57.561484) (xy 235.264452 -57.600088)
			(xy 235.263947 -57.638692) (xy 235.255877 -57.715476) (xy 235.239824 -57.790997) (xy 235.215966 -57.864425)
			(xy 235.184563 -57.934958) (xy 235.145959 -58.001821) (xy 235.100578 -58.064284) (xy 235.048916 -58.12166)
			(xy 234.99154 -58.173322) (xy 234.929077 -58.218703) (xy 234.862214 -58.257307) (xy 234.791681 -58.28871)
			(xy 234.718253 -58.312568) (xy 234.642732 -58.328621) (xy 234.565948 -58.336691) (xy 234.48874 -58.336691)
			(xy 234.411956 -58.328621) (xy 234.336435 -58.312568) (xy 234.263007 -58.28871) (xy 234.192474 -58.257307)
			(xy 234.125611 -58.218703) (xy 234.063148 -58.173322) (xy 234.005772 -58.12166) (xy 233.95411 -58.064284)
			(xy 233.908729 -58.001821) (xy 233.870125 -57.934958) (xy 233.838722 -57.864425) (xy 233.814864 -57.790997)
			(xy 233.798811 -57.715476) (xy 233.790741 -57.638692) (xy 233.600752 -57.638692) (xy 233.600752 -58.245756)
			(xy 233.601124 -58.254862) (xy 233.607497 -58.271921) (xy 233.613198 -58.27903) (xy 233.618786 -58.284618)
			(xy 233.623635 -58.288589) (xy 233.634809 -58.294255) (xy 233.640884 -58.295794) (xy 233.644948 -58.296302)
			(xy 233.671908 -58.300586) (xy 233.724318 -58.315858) (xy 233.774016 -58.338443) (xy 233.819989 -58.36788)
			(xy 233.861297 -58.403568) (xy 233.897097 -58.444779) (xy 233.926659 -58.490671) (xy 233.949379 -58.540307)
			(xy 233.964793 -58.592675) (xy 233.972531 -58.646314) (xy 237.901732 -58.646314) (xy 237.905803 -58.590692)
			(xy 237.917929 -58.536255) (xy 237.937852 -58.484164) (xy 237.965148 -58.435529) (xy 237.999234 -58.391386)
			(xy 238.039383 -58.352677) (xy 238.084741 -58.320226) (xy 238.134341 -58.294725) (xy 238.187125 -58.276718)
			(xy 238.241968 -58.266588) (xy 238.297702 -58.264551) (xy 238.353139 -58.270651) (xy 238.407096 -58.284757)
			(xy 238.407367 -58.284872) (xy 240.598196 -58.284872) (xy 240.602267 -58.22925) (xy 240.614393 -58.174813)
			(xy 240.634316 -58.122722) (xy 240.661612 -58.074087) (xy 240.695698 -58.029944) (xy 240.735847 -57.991235)
			(xy 240.781205 -57.958784) (xy 240.830805 -57.933283) (xy 240.883589 -57.915276) (xy 240.938432 -57.905146)
			(xy 240.994166 -57.903109) (xy 241.049603 -57.909209) (xy 241.10356 -57.923315) (xy 241.154889 -57.945127)
			(xy 241.202495 -57.974181) (xy 241.245363 -58.009856) (xy 241.28258 -58.051393) (xy 241.313353 -58.097906)
			(xy 241.337025 -58.148403) (xy 241.353093 -58.20181) (xy 241.361213 -58.256986) (xy 241.361722 -58.284872)
			(xy 241.361213 -58.312758) (xy 241.353093 -58.367934) (xy 241.337025 -58.421341) (xy 241.313353 -58.471838)
			(xy 241.28258 -58.518351) (xy 241.245363 -58.559888) (xy 241.202495 -58.595563) (xy 241.154889 -58.624617)
			(xy 241.10356 -58.646429) (xy 241.049603 -58.660535) (xy 240.994166 -58.666635) (xy 240.938432 -58.664598)
			(xy 240.883589 -58.654468) (xy 240.830805 -58.636461) (xy 240.781205 -58.61096) (xy 240.735847 -58.578509)
			(xy 240.695698 -58.5398) (xy 240.661612 -58.495657) (xy 240.634316 -58.447022) (xy 240.614393 -58.394931)
			(xy 240.602267 -58.340494) (xy 240.598196 -58.284872) (xy 238.407367 -58.284872) (xy 238.458425 -58.306569)
			(xy 238.506031 -58.335623) (xy 238.548899 -58.371298) (xy 238.586116 -58.412835) (xy 238.616889 -58.459348)
			(xy 238.640561 -58.509845) (xy 238.656629 -58.563252) (xy 238.664749 -58.618428) (xy 238.665258 -58.646314)
			(xy 238.664749 -58.6742) (xy 238.656629 -58.729376) (xy 238.640561 -58.782783) (xy 238.616889 -58.83328)
			(xy 238.586116 -58.879793) (xy 238.548899 -58.92133) (xy 238.506031 -58.957005) (xy 238.458425 -58.986059)
			(xy 238.407096 -59.007871) (xy 238.353139 -59.021977) (xy 238.297702 -59.028077) (xy 238.241968 -59.02604)
			(xy 238.187125 -59.01591) (xy 238.134341 -58.997903) (xy 238.084741 -58.972402) (xy 238.039383 -58.939951)
			(xy 237.999234 -58.901242) (xy 237.965148 -58.857099) (xy 237.937852 -58.808464) (xy 237.917929 -58.756373)
			(xy 237.905803 -58.701936) (xy 237.901732 -58.646314) (xy 233.972531 -58.646314) (xy 233.972587 -58.646705)
			(xy 233.973116 -58.674) (xy 233.972608 -58.701893) (xy 233.964493 -58.757084) (xy 233.948434 -58.810508)
			(xy 233.924774 -58.861027) (xy 233.894016 -58.907566) (xy 233.856814 -58.949135) (xy 233.835702 -58.96737)
			(xy 233.835194 -58.967624) (xy 233.82732 -58.974482) (xy 233.82224 -58.984134) (xy 233.819914 -58.98917)
			(xy 233.81723 -58.999932) (xy 233.816906 -59.00547) (xy 233.81462 -59.081416) (xy 233.814605 -59.086959)
			(xy 233.816648 -59.097851) (xy 233.818684 -59.103006) (xy 233.822494 -59.111388) (xy 233.83113 -59.119262)
			(xy 233.850159 -59.137403) (xy 233.883555 -59.178008) (xy 233.911059 -59.222813) (xy 233.932152 -59.27097)
			(xy 233.946434 -59.321566) (xy 233.953634 -59.373645) (xy 233.954066 -59.399932) (xy 233.953547 -59.428242)
			(xy 233.945169 -59.484238) (xy 233.928602 -59.538379) (xy 233.904211 -59.589475) (xy 233.872531 -59.636402)
			(xy 233.83426 -59.678127) (xy 233.812588 -59.69635) (xy 233.806492 -59.70143) (xy 233.800142 -59.709558)
			(xy 233.79811 -59.714384) (xy 233.795884 -59.719823) (xy 233.793699 -59.731368) (xy 233.793792 -59.737244)
			(xy 233.796078 -59.783218) (xy 233.797856 -59.821318) (xy 233.798516 -59.826936) (xy 233.80198 -59.837702)
			(xy 233.804714 -59.842654) (xy 233.807508 -59.84748) (xy 233.814874 -59.855354) (xy 233.820716 -59.859164)
			(xy 233.842966 -59.874387) (xy 233.883354 -59.910096) (xy 233.918317 -59.951131) (xy 233.947159 -59.996677)
			(xy 233.969307 -60.045827) (xy 233.98432 -60.097604) (xy 233.991899 -60.150979) (xy 233.99242 -60.177934)
			(xy 233.991951 -60.204929) (xy 233.984338 -60.258381) (xy 233.96927 -60.310226) (xy 233.947047 -60.359431)
			(xy 233.918112 -60.405013) (xy 233.883043 -60.446064) (xy 233.842539 -60.481764) (xy 233.79741 -60.5114)
			(xy 233.748554 -60.534381) (xy 233.696948 -60.550249) (xy 233.670348 -60.55487) (xy 233.667046 -60.555378)
			(xy 233.66476 -60.555886) (xy 233.639868 -60.56884) (xy 233.636648 -60.570792) (xy 233.630779 -60.575509)
			(xy 233.628184 -60.578238) (xy 233.62285 -60.583826) (xy 233.612182 -60.59551) (xy 233.609772 -60.598597)
			(xy 233.605817 -60.605357) (xy 233.604308 -60.608972) (xy 233.604308 -60.60948) (xy 233.602709 -60.613885)
			(xy 233.600926 -60.623085) (xy 233.600752 -60.627768) (xy 233.600752 -60.775342) (xy 233.601163 -60.78411)
			(xy 233.607134 -60.800605) (xy 233.612436 -60.8076) (xy 233.618024 -60.814458) (xy 233.632248 -60.823094)
			(xy 233.642154 -60.824872) (xy 233.668105 -60.830146) (xy 233.718335 -60.846912) (xy 233.765763 -60.870465)
			(xy 233.809477 -60.900353) (xy 233.831473 -60.920376) (xy 239.456974 -60.920376) (xy 239.461045 -60.864754)
			(xy 239.473171 -60.810317) (xy 239.493094 -60.758226) (xy 239.52039 -60.709591) (xy 239.554476 -60.665448)
			(xy 239.594625 -60.626739) (xy 239.639983 -60.594288) (xy 239.689583 -60.568787) (xy 239.742367 -60.55078)
			(xy 239.79721 -60.54065) (xy 239.852944 -60.538613) (xy 239.908381 -60.544713) (xy 239.962338 -60.558819)
			(xy 240.013667 -60.580631) (xy 240.061273 -60.609685) (xy 240.104141 -60.64536) (xy 240.141358 -60.686897)
			(xy 240.172131 -60.73341) (xy 240.195803 -60.783907) (xy 240.211871 -60.837314) (xy 240.219991 -60.89249)
			(xy 240.2205 -60.920376) (xy 240.219991 -60.948262) (xy 240.211871 -61.003438) (xy 240.195803 -61.056845)
			(xy 240.172131 -61.107342) (xy 240.141358 -61.153855) (xy 240.104141 -61.195392) (xy 240.061273 -61.231067)
			(xy 240.013667 -61.260121) (xy 239.962338 -61.281933) (xy 239.908381 -61.296039) (xy 239.852944 -61.302139)
			(xy 239.79721 -61.300102) (xy 239.742367 -61.289972) (xy 239.689583 -61.271965) (xy 239.639983 -61.246464)
			(xy 239.594625 -61.214013) (xy 239.554476 -61.175304) (xy 239.52039 -61.131161) (xy 239.493094 -61.082526)
			(xy 239.473171 -61.030435) (xy 239.461045 -60.975998) (xy 239.456974 -60.920376) (xy 233.831473 -60.920376)
			(xy 233.848636 -60.936) (xy 233.882488 -60.976721) (xy 233.910381 -61.021734) (xy 233.931779 -61.070172)
			(xy 233.946272 -61.121105) (xy 233.953579 -61.173553) (xy 233.954066 -61.20003) (xy 233.953519 -61.22908)
			(xy 233.944704 -61.286507) (xy 233.927283 -61.341934) (xy 233.901658 -61.394077) (xy 233.885486 -61.418216)
			(xy 233.880152 -61.425836) (xy 233.878377 -61.430017) (xy 233.876201 -61.438835) (xy 233.875834 -61.443362)
			(xy 233.875072 -61.457078) (xy 233.897678 -61.500258) (xy 233.925618 -61.553344) (xy 233.930737 -61.560764)
			(xy 233.945051 -61.571699) (xy 233.953558 -61.57468) (xy 238.77524 -61.57468) (xy 238.780066 -61.576712)
			(xy 238.992918 -61.576712)
		)
		(stroke
			(width 0)
			(type solid)
		)
		(fill yes)
		(layer "In9.Cu")
		(net "P3V3_SSD8")
	)
	(gr_poly
		(pts
			(xy 289.228784 -61.576712) (xy 289.263328 -61.57468) (xy 290.397184 -61.57468) (xy 290.406328 -61.573918)
			(xy 290.410646 -61.573156) (xy 290.417954 -61.571552) (xy 290.431247 -61.5647) (xy 290.436808 -61.559694)
			(xy 290.484814 -61.51372) (xy 290.491442 -61.50675) (xy 290.499407 -61.489259) (xy 290.500308 -61.479684)
			(xy 290.500308 -61.478668) (xy 290.501814 -61.451595) (xy 290.511521 -61.398249) (xy 290.528676 -61.346813)
			(xy 290.552935 -61.298321) (xy 290.583808 -61.253747) (xy 290.601908 -61.233558) (xy 290.602416 -61.23305)
			(xy 290.603178 -61.232288) (xy 290.604702 -61.23051) (xy 290.60521 -61.230002) (xy 290.60648 -61.228478)
			(xy 290.62461 -61.209567) (xy 290.665153 -61.176388) (xy 290.709852 -61.149064) (xy 290.757867 -61.128108)
			(xy 290.808297 -61.113915) (xy 290.860194 -61.10675) (xy 290.886388 -61.106304) (xy 290.9134 -61.106772)
			(xy 290.966884 -61.114389) (xy 291.018759 -61.129474) (xy 291.067988 -61.151725) (xy 291.113586 -61.180696)
			(xy 291.154643 -61.215809) (xy 291.190337 -61.256361) (xy 291.219955 -61.301543) (xy 291.242904 -61.35045)
			(xy 291.258726 -61.402105) (xy 291.267105 -61.455475) (xy 291.267896 -61.482478) (xy 291.26815 -61.492892)
			(xy 291.276024 -61.51118) (xy 291.32022 -61.553852) (xy 291.326062 -61.55944) (xy 291.33166 -61.564539)
			(xy 291.345085 -61.571523) (xy 291.352478 -61.573156) (xy 291.361368 -61.57468) (xy 292.343078 -61.57468)
			(xy 292.352052 -61.574729) (xy 292.36997 -61.575744) (xy 292.378892 -61.576712) (xy 293.243 -61.576712)
			(xy 293.251922 -61.575744) (xy 293.26984 -61.574725) (xy 293.278814 -61.57468) (xy 294.953182 -61.57468)
			(xy 294.959477 -61.574494) (xy 294.971685 -61.571413) (xy 294.977312 -61.568584) (xy 294.983916 -61.565028)
			(xy 295.612312 -60.936632) (xy 295.61536 -60.93333) (xy 295.625774 -60.922916) (xy 295.628448 -60.917445)
			(xy 295.631403 -60.905634) (xy 295.631616 -60.899548) (xy 295.631616 -38.90645) (xy 295.630854 -38.897306)
			(xy 295.62806 -38.882574) (xy 295.619678 -38.867842) (xy 295.613074 -38.862) (xy 295.580415 -38.83269)
			(xy 295.520108 -38.768934) (xy 295.466005 -38.699836) (xy 295.418577 -38.625996) (xy 295.378237 -38.548057)
			(xy 295.345336 -38.466699) (xy 295.32016 -38.382628) (xy 295.302928 -38.296577) (xy 295.29379 -38.209295)
			(xy 295.292827 -38.121541) (xy 295.300045 -38.034078) (xy 295.315383 -37.94767) (xy 295.338707 -37.863067)
			(xy 295.369814 -37.781005) (xy 295.408433 -37.7022) (xy 295.454228 -37.627336) (xy 295.506801 -37.557066)
			(xy 295.535858 -37.524182) (xy 295.54043 -37.519102) (xy 295.540684 -37.518594) (xy 295.552352 -37.505892)
			(xy 295.576488 -37.481248) (xy 295.588944 -37.469318) (xy 295.602406 -37.457126) (xy 295.60266 -37.456872)
			(xy 295.606978 -37.452808) (xy 295.611042 -37.448998) (xy 295.617138 -37.440616) (xy 295.627298 -37.417248)
			(xy 295.6293 -37.412408) (xy 295.631476 -37.402164) (xy 295.631616 -37.396928) (xy 295.631616 -31.777432)
			(xy 295.628822 -31.769304) (xy 295.618666 -31.738539) (xy 295.607688 -31.674694) (xy 295.606978 -31.642304)
			(xy 295.607688 -31.609914) (xy 295.618675 -31.546072) (xy 295.628822 -31.515304) (xy 295.631616 -31.507176)
			(xy 295.631616 -31.238444) (xy 295.63173 -31.233489) (xy 295.633642 -31.223764) (xy 295.635426 -31.21914)
			(xy 295.640506 -31.207202) (xy 295.642304 -31.202515) (xy 295.644223 -31.192663) (xy 295.644316 -31.187644)
			(xy 295.644316 -29.841952) (xy 295.644054 -29.834014) (xy 295.63927 -29.818878) (xy 295.634918 -29.812234)
			(xy 295.618066 -29.787795) (xy 295.591326 -29.734798) (xy 295.573113 -29.6783) (xy 295.563865 -29.619664)
			(xy 295.56329 -29.589984) (xy 295.563872 -29.560303) (xy 295.573105 -29.501664) (xy 295.591313 -29.445163)
			(xy 295.618057 -29.392167) (xy 295.634918 -29.367734) (xy 295.639283 -29.361094) (xy 295.644086 -29.345958)
			(xy 295.644316 -29.338016) (xy 295.644316 -28.112974) (xy 295.644436 -28.108426) (xy 295.646089 -28.099479)
			(xy 295.647618 -28.095194) (xy 295.649383 -28.090051) (xy 295.650916 -28.07929) (xy 295.650666 -28.073858)
			(xy 295.64838 -28.044394) (xy 295.647645 -28.037201) (xy 295.642611 -28.023654) (xy 295.638474 -28.017724)
			(xy 295.620787 -27.992879) (xy 295.5927 -27.938748) (xy 295.573573 -27.880842) (xy 295.563891 -27.820632)
			(xy 295.56329 -27.79014) (xy 295.563751 -27.762885) (xy 295.571503 -27.70893) (xy 295.586855 -27.656627)
			(xy 295.609496 -27.607042) (xy 295.638963 -27.561184) (xy 295.674656 -27.519986) (xy 295.71585 -27.484288)
			(xy 295.761705 -27.454816) (xy 295.811288 -27.43217) (xy 295.863589 -27.416812) (xy 295.917543 -27.409054)
			(xy 295.944798 -27.408632) (xy 295.970346 -27.409041) (xy 296.020985 -27.415856) (xy 296.070262 -27.429364)
			(xy 296.117297 -27.449325) (xy 296.16125 -27.475381) (xy 296.181526 -27.490928) (xy 296.19702 -27.50312)
			(xy 296.23512 -27.501088) (xy 296.388536 -27.347672) (xy 296.395933 -27.340823) (xy 296.414532 -27.333091)
			(xy 296.424604 -27.332686) (xy 296.570908 -27.332686) (xy 296.575226 -27.331924) (xy 296.595546 -27.32913)
			(xy 296.5958 -27.32913) (xy 296.627296 -27.327352) (xy 300.672754 -27.327352) (xy 300.682732 -27.326942)
			(xy 300.701173 -27.319319) (xy 300.71529 -27.305216) (xy 300.722932 -27.286783) (xy 300.7233 -27.276806)
			(xy 300.7233 -26.479246) (xy 300.723472 -26.463316) (xy 300.72576 -26.431537) (xy 300.727872 -26.415746)
			(xy 300.727872 -26.415238) (xy 300.728888 -26.409396) (xy 300.728888 -26.408888) (xy 300.731428 -26.39441)
			(xy 300.732698 -26.387044) (xy 300.731174 -26.372566) (xy 300.72838 -26.365708) (xy 300.725394 -26.358991)
			(xy 300.716235 -26.3475) (xy 300.710346 -26.343102) (xy 300.702726 -26.337768) (xy 300.676564 -26.31948)
			(xy 300.653865 -26.333025) (xy 300.605521 -26.354399) (xy 300.554685 -26.368877) (xy 300.502333 -26.37618)
			(xy 300.475904 -26.37663) (xy 300.448652 -26.376145) (xy 300.394703 -26.368389) (xy 300.342406 -26.353034)
			(xy 300.292827 -26.330393) (xy 300.246975 -26.300928) (xy 300.205782 -26.265236) (xy 300.170088 -26.224046)
			(xy 300.140619 -26.178196) (xy 300.117975 -26.128618) (xy 300.102617 -26.076323) (xy 300.094857 -26.022374)
			(xy 300.094396 -25.995122) (xy 300.094936 -25.965825) (xy 300.103902 -25.907922) (xy 300.121612 -25.852068)
			(xy 300.147648 -25.799577) (xy 300.181401 -25.751682) (xy 300.20133 -25.7302) (xy 300.202092 -25.729438)
			(xy 300.2026 -25.72893) (xy 300.220703 -25.710287) (xy 300.261083 -25.677578) (xy 300.305528 -25.650652)
			(xy 300.353216 -25.630006) (xy 300.403264 -25.616023) (xy 300.454747 -25.608961) (xy 300.48073 -25.608534)
			(xy 300.509679 -25.609073) (xy 300.566913 -25.617825) (xy 300.622167 -25.635123) (xy 300.674174 -25.660571)
			(xy 300.721739 -25.693584) (xy 300.76377 -25.733404) (xy 300.799303 -25.779117) (xy 300.827521 -25.829674)
			(xy 300.82841 -25.832054) (xy 302.38776 -25.832054) (xy 302.391831 -25.776432) (xy 302.403957 -25.721995)
			(xy 302.42388 -25.669904) (xy 302.451176 -25.621269) (xy 302.485262 -25.577126) (xy 302.525411 -25.538417)
			(xy 302.570769 -25.505966) (xy 302.620369 -25.480465) (xy 302.673153 -25.462458) (xy 302.727996 -25.452328)
			(xy 302.78373 -25.450291) (xy 302.839167 -25.456391) (xy 302.893124 -25.470497) (xy 302.944453 -25.492309)
			(xy 302.992059 -25.521363) (xy 303.034927 -25.557038) (xy 303.036461 -25.55875) (xy 306.84216 -25.55875)
			(xy 306.842646 -25.531499) (xy 306.850402 -25.477551) (xy 306.865757 -25.425256) (xy 306.888399 -25.375679)
			(xy 306.917865 -25.329829) (xy 306.953556 -25.288638) (xy 306.994747 -25.252947) (xy 307.040597 -25.223481)
			(xy 307.090174 -25.200839) (xy 307.142469 -25.185484) (xy 307.196417 -25.177728) (xy 307.250919 -25.177728)
			(xy 307.304867 -25.185484) (xy 307.357162 -25.200839) (xy 307.406739 -25.223481) (xy 307.452589 -25.252947)
			(xy 307.49378 -25.288638) (xy 307.529471 -25.329829) (xy 307.558937 -25.375679) (xy 307.581579 -25.425256)
			(xy 307.596934 -25.477551) (xy 307.60469 -25.531499) (xy 307.605176 -25.55875) (xy 307.604613 -25.589012)
			(xy 307.595061 -25.648778) (xy 307.576191 -25.706285) (xy 307.548474 -25.76009) (xy 307.531008 -25.78481)
			(xy 307.522704 -25.796942) (xy 307.512749 -25.824591) (xy 307.51108 -25.85393) (xy 307.517835 -25.882529)
			(xy 307.532456 -25.90802) (xy 307.55373 -25.928292) (xy 307.579897 -25.941665) (xy 307.594254 -25.94483)
			(xy 307.620155 -25.950135) (xy 307.670278 -25.966958) (xy 307.717597 -25.990542) (xy 307.761204 -26.020437)
			(xy 307.800265 -26.056068) (xy 307.83403 -26.096752) (xy 307.861852 -26.14171) (xy 307.883198 -26.19008)
			(xy 307.897658 -26.240934) (xy 307.904956 -26.293299) (xy 307.905404 -26.319734) (xy 309.041798 -26.319734)
			(xy 309.045869 -26.264112) (xy 309.057995 -26.209675) (xy 309.077918 -26.157584) (xy 309.105214 -26.108949)
			(xy 309.1393 -26.064806) (xy 309.179449 -26.026097) (xy 309.224807 -25.993646) (xy 309.274407 -25.968145)
			(xy 309.327191 -25.950138) (xy 309.382034 -25.940008) (xy 309.437768 -25.937971) (xy 309.493205 -25.944071)
			(xy 309.547162 -25.958177) (xy 309.598491 -25.979989) (xy 309.646097 -26.009043) (xy 309.688965 -26.044718)
			(xy 309.726182 -26.086255) (xy 309.756955 -26.132768) (xy 309.780627 -26.183265) (xy 309.796695 -26.236672)
			(xy 309.804815 -26.291848) (xy 309.805324 -26.319734) (xy 309.804815 -26.34762) (xy 309.796695 -26.402796)
			(xy 309.780627 -26.456203) (xy 309.756955 -26.5067) (xy 309.726182 -26.553213) (xy 309.688965 -26.59475)
			(xy 309.646097 -26.630425) (xy 309.598491 -26.659479) (xy 309.547162 -26.681291) (xy 309.493205 -26.695397)
			(xy 309.437768 -26.701497) (xy 309.382034 -26.69946) (xy 309.327191 -26.68933) (xy 309.274407 -26.671323)
			(xy 309.224807 -26.645822) (xy 309.179449 -26.613371) (xy 309.1393 -26.574662) (xy 309.105214 -26.530519)
			(xy 309.077918 -26.481884) (xy 309.057995 -26.429793) (xy 309.045869 -26.375356) (xy 309.041798 -26.319734)
			(xy 307.905404 -26.319734) (xy 307.904918 -26.346985) (xy 307.897162 -26.400933) (xy 307.881807 -26.453228)
			(xy 307.859165 -26.502805) (xy 307.829699 -26.548655) (xy 307.794008 -26.589846) (xy 307.752817 -26.625537)
			(xy 307.706967 -26.655003) (xy 307.65739 -26.677645) (xy 307.605095 -26.693) (xy 307.551147 -26.700756)
			(xy 307.496645 -26.700756) (xy 307.442697 -26.693) (xy 307.390402 -26.677645) (xy 307.340825 -26.655003)
			(xy 307.294975 -26.625537) (xy 307.253784 -26.589846) (xy 307.218093 -26.548655) (xy 307.188627 -26.502805)
			(xy 307.165985 -26.453228) (xy 307.15063 -26.400933) (xy 307.142874 -26.346985) (xy 307.142388 -26.319734)
			(xy 307.142931 -26.289471) (xy 307.152486 -26.229704) (xy 307.171363 -26.172196) (xy 307.199086 -26.118392)
			(xy 307.216556 -26.093674) (xy 307.22484 -26.081533) (xy 307.234784 -26.053888) (xy 307.236447 -26.024557)
			(xy 307.229692 -25.995965) (xy 307.215079 -25.970479) (xy 307.193815 -25.950207) (xy 307.167661 -25.936826)
			(xy 307.15331 -25.933654) (xy 307.127415 -25.928317) (xy 307.077292 -25.911502) (xy 307.029971 -25.887923)
			(xy 306.986362 -25.858034) (xy 306.947299 -25.822407) (xy 306.913533 -25.781726) (xy 306.88571 -25.73677)
			(xy 306.864364 -25.688401) (xy 306.849904 -25.637548) (xy 306.842607 -25.585185) (xy 306.84216 -25.55875)
			(xy 303.036461 -25.55875) (xy 303.072144 -25.598575) (xy 303.102917 -25.645088) (xy 303.126589 -25.695585)
			(xy 303.142657 -25.748992) (xy 303.150777 -25.804168) (xy 303.151286 -25.832054) (xy 303.150777 -25.85994)
			(xy 303.142657 -25.915116) (xy 303.126589 -25.968523) (xy 303.102917 -26.01902) (xy 303.072144 -26.065533)
			(xy 303.034927 -26.10707) (xy 302.992059 -26.142745) (xy 302.944453 -26.171799) (xy 302.893124 -26.193611)
			(xy 302.839167 -26.207717) (xy 302.78373 -26.213817) (xy 302.727996 -26.21178) (xy 302.673153 -26.20165)
			(xy 302.620369 -26.183643) (xy 302.570769 -26.158142) (xy 302.525411 -26.125691) (xy 302.485262 -26.086982)
			(xy 302.451176 -26.042839) (xy 302.42388 -25.994204) (xy 302.403957 -25.942113) (xy 302.391831 -25.887676)
			(xy 302.38776 -25.832054) (xy 300.82841 -25.832054) (xy 300.847777 -25.883914) (xy 300.859607 -25.940591)
			(xy 300.86173 -25.969468) (xy 300.86173 -25.969976) (xy 300.863165 -25.982102) (xy 300.875643 -26.003047)
			(xy 300.885606 -26.010108) (xy 300.920912 -26.031952) (xy 300.966632 -26.0604) (xy 300.99127 -26.062432)
			(xy 301.0027 -26.057606) (xy 301.030695 -26.046253) (xy 301.08893 -26.030178) (xy 301.148773 -26.021909)
			(xy 301.178976 -26.021284) (xy 301.181262 -26.021284) (xy 301.211248 -26.021751) (xy 301.270708 -26.029575)
			(xy 301.328638 -26.045094) (xy 301.384046 -26.068042) (xy 301.435984 -26.098027) (xy 301.483563 -26.134536)
			(xy 301.52597 -26.176943) (xy 301.562477 -26.224523) (xy 301.592462 -26.276462) (xy 301.615409 -26.33187)
			(xy 301.623181 -26.360882) (xy 304.30546 -26.360882) (xy 304.309531 -26.30526) (xy 304.321657 -26.250823)
			(xy 304.34158 -26.198732) (xy 304.368876 -26.150097) (xy 304.402962 -26.105954) (xy 304.443111 -26.067245)
			(xy 304.488469 -26.034794) (xy 304.538069 -26.009293) (xy 304.590853 -25.991286) (xy 304.645696 -25.981156)
			(xy 304.70143 -25.979119) (xy 304.756867 -25.985219) (xy 304.810824 -25.999325) (xy 304.862153 -26.021137)
			(xy 304.909759 -26.050191) (xy 304.952627 -26.085866) (xy 304.989844 -26.127403) (xy 305.020617 -26.173916)
			(xy 305.044289 -26.224413) (xy 305.060357 -26.27782) (xy 305.068477 -26.332996) (xy 305.068986 -26.360882)
			(xy 305.068477 -26.388768) (xy 305.060357 -26.443944) (xy 305.044289 -26.497351) (xy 305.020617 -26.547848)
			(xy 304.989844 -26.594361) (xy 304.952627 -26.635898) (xy 304.909759 -26.671573) (xy 304.862153 -26.700627)
			(xy 304.810824 -26.722439) (xy 304.756867 -26.736545) (xy 304.70143 -26.742645) (xy 304.645696 -26.740608)
			(xy 304.590853 -26.730478) (xy 304.538069 -26.712471) (xy 304.488469 -26.68697) (xy 304.443111 -26.654519)
			(xy 304.402962 -26.61581) (xy 304.368876 -26.571667) (xy 304.34158 -26.523032) (xy 304.321657 -26.470941)
			(xy 304.309531 -26.416504) (xy 304.30546 -26.360882) (xy 301.623181 -26.360882) (xy 301.630927 -26.3898)
			(xy 301.63875 -26.44926) (xy 301.639224 -26.479246) (xy 301.639224 -27.276806) (xy 301.639611 -27.28679)
			(xy 301.647214 -27.305252) (xy 301.661328 -27.319373) (xy 301.679786 -27.326985) (xy 301.68977 -27.327352)
			(xy 310.895746 -27.327352) (xy 310.905622 -27.326888) (xy 310.923918 -27.319443) (xy 310.931306 -27.312874)
			(xy 310.93156 -27.31262) (xy 311.290716 -26.953464) (xy 311.297566 -26.946068) (xy 311.305301 -26.927469)
			(xy 311.305702 -26.917396) (xy 311.305702 -25.139396) (xy 311.305111 -25.128863) (xy 311.296576 -25.109594)
			(xy 311.289192 -25.102058) (xy 311.225946 -25.044146) (xy 311.205626 -25.037288) (xy 311.194958 -25.038304)
			(xy 311.160414 -25.039828) (xy 311.133162 -25.039343) (xy 311.079211 -25.031588) (xy 311.026914 -25.016235)
			(xy 310.977333 -24.993595) (xy 310.93148 -24.964129) (xy 310.890286 -24.928438) (xy 310.854591 -24.887247)
			(xy 310.825122 -24.841396) (xy 310.802477 -24.791818) (xy 310.787119 -24.739522) (xy 310.779359 -24.685572)
			(xy 310.778906 -24.65832) (xy 310.779496 -24.629) (xy 310.788505 -24.571054) (xy 310.806253 -24.515162)
			(xy 310.818784 -24.488648) (xy 310.825134 -24.475948) (xy 310.822848 -24.447754) (xy 310.753506 -24.351742)
			(xy 310.727344 -24.34082) (xy 310.713374 -24.342852) (xy 310.699921 -24.344653) (xy 310.672844 -24.346561)
			(xy 310.659272 -24.346662) (xy 310.632025 -24.346174) (xy 310.578087 -24.338415) (xy 310.525801 -24.323059)
			(xy 310.476234 -24.300419) (xy 310.430392 -24.270955) (xy 310.38921 -24.235268) (xy 310.353526 -24.194083)
			(xy 310.324066 -24.148239) (xy 310.30143 -24.098669) (xy 310.286078 -24.046383) (xy 310.278324 -23.992443)
			(xy 310.278324 -23.93795) (xy 310.28608 -23.884011) (xy 310.301432 -23.831725) (xy 310.324069 -23.782155)
			(xy 310.35353 -23.736312) (xy 310.389215 -23.695128) (xy 310.430397 -23.659441) (xy 310.476239 -23.629978)
			(xy 310.525808 -23.607338) (xy 310.578093 -23.591984) (xy 310.632032 -23.584226) (xy 310.686526 -23.584223)
			(xy 310.740465 -23.591974) (xy 310.792752 -23.607324) (xy 310.842323 -23.629957) (xy 310.888168 -23.659415)
			(xy 310.929355 -23.695097) (xy 310.965044 -23.736278) (xy 310.99451 -23.782118) (xy 311.017153 -23.831685)
			(xy 311.032511 -23.883969) (xy 311.040273 -23.937907) (xy 311.04078 -23.965154) (xy 311.040192 -23.994475)
			(xy 311.031187 -24.052422) (xy 311.013441 -24.108315) (xy 311.000902 -24.134826) (xy 310.994552 -24.147526)
			(xy 310.996838 -24.17572) (xy 311.06618 -24.271732) (xy 311.092342 -24.282654) (xy 311.106312 -24.280622)
			(xy 311.119765 -24.278821) (xy 311.146842 -24.276912) (xy 311.160414 -24.276812) (xy 311.194958 -24.278336)
			(xy 311.205626 -24.279352) (xy 311.225946 -24.272494) (xy 311.289192 -24.214582) (xy 311.296633 -24.207087)
			(xy 311.305156 -24.187792) (xy 311.305702 -24.177244) (xy 311.305702 -24.082756) (xy 311.302654 -24.074374)
			(xy 311.29312 -24.045781) (xy 311.282167 -23.986516) (xy 311.280679 -23.926264) (xy 311.284112 -23.89632)
			(xy 311.290462 -23.860252) (xy 311.290716 -23.859998) (xy 311.293206 -23.849699) (xy 311.299177 -23.829367)
			(xy 311.302654 -23.819358) (xy 311.305702 -23.810976) (xy 311.305702 -22.239478) (xy 311.288684 -22.214078)
			(xy 311.27446 -22.207982) (xy 311.248695 -22.196774) (xy 311.200498 -22.167897) (xy 311.157061 -22.132259)
			(xy 311.119324 -22.090633) (xy 311.088105 -22.043919) (xy 311.06408 -21.99313) (xy 311.047768 -21.939364)
			(xy 311.039523 -21.883787) (xy 311.039524 -21.827601) (xy 311.047771 -21.772024) (xy 311.064084 -21.718259)
			(xy 311.088111 -21.66747) (xy 311.119332 -21.620757) (xy 311.15707 -21.579132) (xy 311.200508 -21.543496)
			(xy 311.248706 -21.51462) (xy 311.27446 -21.503386) (xy 311.288684 -21.49729) (xy 311.305702 -21.47189)
			(xy 311.305702 -15.83563) (xy 311.305702 -15.832074) (xy 311.303924 -15.808198) (xy 311.276238 -15.783306)
			(xy 311.274206 -15.781274) (xy 311.23382 -15.740634) (xy 311.215786 -15.733014) (xy 311.205626 -15.73276)
			(xy 311.179908 -15.73191) (xy 311.129041 -15.724149) (xy 311.079676 -15.709626) (xy 311.03271 -15.688605)
			(xy 310.988992 -15.661467) (xy 310.949315 -15.628702) (xy 310.93156 -15.610078) (xy 310.92394 -15.60195)
			(xy 310.903874 -15.593568) (xy 310.805322 -15.596108) (xy 310.785764 -15.605506) (xy 310.778652 -15.614142)
			(xy 310.760441 -15.635291) (xy 310.718893 -15.672554) (xy 310.672362 -15.703368) (xy 310.621838 -15.727076)
			(xy 310.5684 -15.743172) (xy 310.513187 -15.751313) (xy 310.485282 -15.75181) (xy 310.458031 -15.751323)
			(xy 310.404085 -15.743564) (xy 310.351793 -15.728208) (xy 310.302217 -15.705565) (xy 310.256369 -15.676098)
			(xy 310.215181 -15.640407) (xy 310.179491 -15.599217) (xy 310.150026 -15.553367) (xy 310.127386 -15.503791)
			(xy 310.112032 -15.451497) (xy 310.104276 -15.397551) (xy 310.104276 -15.343049) (xy 310.112032 -15.289103)
			(xy 310.127386 -15.236809) (xy 310.150026 -15.187233) (xy 310.179491 -15.141383) (xy 310.215181 -15.100193)
			(xy 310.256369 -15.064502) (xy 310.302217 -15.035035) (xy 310.351793 -15.012392) (xy 310.404085 -14.997036)
			(xy 310.458031 -14.989277) (xy 310.485282 -14.988794) (xy 310.511519 -14.98923) (xy 310.563497 -14.996425)
			(xy 310.613998 -15.010681) (xy 310.662066 -15.031729) (xy 310.706792 -15.059171) (xy 310.747332 -15.092489)
			(xy 310.765444 -15.111476) (xy 310.773064 -15.119604) (xy 310.79313 -15.127986) (xy 310.891682 -15.125446)
			(xy 310.91124 -15.116048) (xy 310.918352 -15.107412) (xy 310.936232 -15.086649) (xy 310.976927 -15.049958)
			(xy 311.022447 -15.01946) (xy 311.071859 -14.99578) (xy 311.124149 -14.979404) (xy 311.178241 -14.97067)
			(xy 311.205626 -14.969744) (xy 311.215532 -14.969744) (xy 311.234074 -14.96187) (xy 311.278524 -14.916912)
			(xy 311.29097 -14.904212) (xy 311.297027 -14.897551) (xy 311.304435 -14.881155) (xy 311.305448 -14.872208)
			(xy 311.305702 -14.868652) (xy 311.305702 -13.73124) (xy 311.305268 -13.721175) (xy 311.297538 -13.702586)
			(xy 311.290716 -13.695172) (xy 310.985408 -13.389864) (xy 310.978013 -13.383009) (xy 310.959414 -13.375262)
			(xy 310.94934 -13.374878) (xy 306.24272 -13.374878) (xy 306.23267 -13.375384) (xy 306.214109 -13.383106)
			(xy 306.206652 -13.389864) (xy 305.496214 -14.100302) (xy 310.242964 -14.100302) (xy 310.247035 -14.04468)
			(xy 310.259161 -13.990243) (xy 310.279084 -13.938152) (xy 310.30638 -13.889517) (xy 310.340466 -13.845374)
			(xy 310.380615 -13.806665) (xy 310.425973 -13.774214) (xy 310.475573 -13.748713) (xy 310.528357 -13.730706)
			(xy 310.5832 -13.720576) (xy 310.638934 -13.718539) (xy 310.694371 -13.724639) (xy 310.748328 -13.738745)
			(xy 310.799657 -13.760557) (xy 310.847263 -13.789611) (xy 310.890131 -13.825286) (xy 310.927348 -13.866823)
			(xy 310.958121 -13.913336) (xy 310.981793 -13.963833) (xy 310.997861 -14.01724) (xy 311.005981 -14.072416)
			(xy 311.00649 -14.100302) (xy 311.005981 -14.128188) (xy 310.997861 -14.183364) (xy 310.981793 -14.236771)
			(xy 310.958121 -14.287268) (xy 310.927348 -14.333781) (xy 310.890131 -14.375318) (xy 310.847263 -14.410993)
			(xy 310.799657 -14.440047) (xy 310.748328 -14.461859) (xy 310.694371 -14.475965) (xy 310.638934 -14.482065)
			(xy 310.5832 -14.480028) (xy 310.528357 -14.469898) (xy 310.475573 -14.451891) (xy 310.425973 -14.42639)
			(xy 310.380615 -14.393939) (xy 310.340466 -14.35523) (xy 310.30638 -14.311087) (xy 310.279084 -14.262452)
			(xy 310.259161 -14.210361) (xy 310.247035 -14.155924) (xy 310.242964 -14.100302) (xy 305.496214 -14.100302)
			(xy 304.900838 -14.695678) (xy 304.895624 -14.700587) (xy 304.883121 -14.707556) (xy 304.8762 -14.709394)
			(xy 304.866548 -14.71168) (xy 304.851054 -14.722348) (xy 304.793904 -14.807184) (xy 304.791364 -14.832076)
			(xy 304.79619 -14.844014) (xy 304.820504 -14.904939) (xy 304.862506 -15.029225) (xy 304.896792 -15.155857)
			(xy 304.923232 -15.284357) (xy 304.941726 -15.414238) (xy 304.952204 -15.545011) (xy 304.953924 -15.610586)
			(xy 304.954178 -15.64894) (xy 304.954178 -15.649956) (xy 304.953682 -15.71498) (xy 304.94576 -15.844785)
			(xy 304.929948 -15.973868) (xy 304.906305 -16.101748) (xy 304.874919 -16.227951) (xy 304.835907 -16.352008)
			(xy 304.789412 -16.47346) (xy 304.735608 -16.591855) (xy 304.674695 -16.706755) (xy 304.606898 -16.817731)
			(xy 304.532469 -16.924374) (xy 304.451685 -17.026286) (xy 304.364845 -17.123091) (xy 304.318924 -17.16913)
			(xy 304.273041 -17.214029) (xy 304.176676 -17.298866) (xy 304.075385 -17.377757) (xy 303.969535 -17.450416)
			(xy 303.859508 -17.51658) (xy 303.745703 -17.576011) (xy 303.628531 -17.628492) (xy 303.508415 -17.673834)
			(xy 303.385792 -17.711874) (xy 303.261103 -17.742473) (xy 303.1348 -17.765522) (xy 303.00734 -17.780935)
			(xy 302.879184 -17.788659) (xy 302.81499 -17.789144) (xy 302.750519 -17.788657) (xy 302.621811 -17.780871)
			(xy 302.493808 -17.765328) (xy 302.366978 -17.742085) (xy 302.241782 -17.711227) (xy 302.118677 -17.672866)
			(xy 301.998113 -17.627142) (xy 301.88053 -17.574223) (xy 301.766357 -17.5143) (xy 301.65601 -17.447594)
			(xy 301.549892 -17.374346) (xy 301.44839 -17.294825) (xy 301.351874 -17.209321) (xy 301.260697 -17.118145)
			(xy 301.175192 -17.02163) (xy 301.095669 -16.920129) (xy 301.022421 -16.814012) (xy 300.955713 -16.703666)
			(xy 300.895789 -16.589493) (xy 300.842867 -16.471911) (xy 300.797142 -16.351347) (xy 300.75878 -16.228243)
			(xy 300.72792 -16.103048) (xy 300.704676 -15.976217) (xy 300.689131 -15.848215) (xy 300.681344 -15.719507)
			(xy 300.680882 -15.655036) (xy 300.681434 -15.586705) (xy 300.690193 -15.450325) (xy 300.707666 -15.314786)
			(xy 300.73378 -15.180643) (xy 300.768428 -15.048447) (xy 300.811469 -14.91874) (xy 300.836584 -14.85519)
			(xy 300.838362 -14.850618) (xy 300.840394 -14.83995) (xy 300.841948 -14.830042) (xy 300.838031 -14.810389)
			(xy 300.832774 -14.80185) (xy 300.786292 -14.733016) (xy 300.778761 -14.722999) (xy 300.756645 -14.711279)
			(xy 300.744128 -14.710664) (xy 298.929298 -14.710664) (xy 298.919952 -14.711131) (xy 298.902522 -14.717899)
			(xy 298.888651 -14.730437) (xy 298.884086 -14.738604) (xy 298.840144 -14.825218) (xy 298.84243 -14.853666)
			(xy 298.850812 -14.86535) (xy 298.877187 -14.902352) (xy 298.923497 -14.98054) (xy 298.962054 -15.062827)
			(xy 298.992498 -15.148449) (xy 299.014547 -15.236606) (xy 299.027993 -15.326479) (xy 299.030898 -15.371826)
			(xy 299.03166 -15.389352) (xy 299.032478 -15.423761) (xy 299.029681 -15.492537) (xy 299.026072 -15.526766)
			(xy 299.022584 -15.555337) (xy 299.012546 -15.61202) (xy 299.006006 -15.64005) (xy 298.99737 -15.673324)
			(xy 298.99737 -15.673578) (xy 298.9961 -15.677642) (xy 298.981471 -15.726548) (xy 298.943028 -15.821119)
			(xy 298.919392 -15.866364) (xy 298.913296 -15.877794) (xy 298.913296 -15.903194) (xy 298.961556 -15.992602)
			(xy 298.982892 -16.006572) (xy 298.995846 -16.007588) (xy 299.039237 -16.011726) (xy 299.125087 -16.026839)
			(xy 299.209227 -16.049627) (xy 299.29097 -16.079905) (xy 299.369652 -16.117426) (xy 299.444633 -16.161884)
			(xy 299.515302 -16.212919) (xy 299.581084 -16.270115) (xy 299.641445 -16.333006) (xy 299.695892 -16.401081)
			(xy 299.743983 -16.473786) (xy 299.785327 -16.550528) (xy 299.819586 -16.630684) (xy 299.846483 -16.713601)
			(xy 299.865798 -16.798605) (xy 299.877374 -16.885003) (xy 299.881117 -16.972093) (xy 299.876997 -17.059166)
			(xy 299.865046 -17.145514) (xy 299.845363 -17.230433) (xy 299.818108 -17.313233) (xy 299.783501 -17.393239)
			(xy 299.741826 -17.469802) (xy 299.69342 -17.542297) (xy 299.638678 -17.610136) (xy 299.608748 -17.641824)
			(xy 299.608494 -17.642078) (xy 299.577207 -17.67411) (xy 299.509634 -17.732871) (xy 299.436912 -17.785124)
			(xy 299.359664 -17.830419) (xy 299.278555 -17.868367) (xy 299.194281 -17.898644) (xy 299.107565 -17.920988)
			(xy 299.019153 -17.935208) (xy 298.929805 -17.941181) (xy 298.840287 -17.938856) (xy 298.751369 -17.928254)
			(xy 298.663814 -17.909465) (xy 298.578375 -17.88265) (xy 298.536868 -17.865852) (xy 298.495806 -17.848109)
			(xy 298.416843 -17.806071) (xy 298.342106 -17.756908) (xy 298.272238 -17.701042) (xy 298.207838 -17.638953)
			(xy 298.149457 -17.571173) (xy 298.097596 -17.498283) (xy 298.0527 -17.420908) (xy 298.015154 -17.339712)
			(xy 297.985281 -17.255391) (xy 297.963335 -17.168668) (xy 297.949506 -17.080286) (xy 297.943912 -16.991005)
			(xy 297.9466 -16.901588) (xy 297.957549 -16.812804) (xy 297.976664 -16.725413) (xy 298.00378 -16.640166)
			(xy 298.038666 -16.557792) (xy 298.059348 -16.518128) (xy 298.059602 -16.517366) (xy 298.061126 -16.514318)
			(xy 298.06265 -16.510762) (xy 298.067 -16.499101) (xy 298.065015 -16.474322) (xy 298.05884 -16.463518)
			(xy 298.058078 -16.462502) (xy 298.014898 -16.390112) (xy 298.0101 -16.382736) (xy 297.996546 -16.371534)
			(xy 297.980002 -16.36558) (xy 297.97121 -16.36522) (xy 296.232834 -16.36522) (xy 296.189395 -16.364735)
			(xy 296.102887 -16.356722) (xy 296.017487 -16.34076) (xy 295.933924 -16.316987) (xy 295.852912 -16.285604)
			(xy 295.775141 -16.24688) (xy 295.701275 -16.201145) (xy 295.631944 -16.14879) (xy 295.56774 -16.09026)
			(xy 295.50921 -16.026056) (xy 295.456855 -15.956725) (xy 295.41112 -15.882859) (xy 295.372396 -15.805088)
			(xy 295.341013 -15.724076) (xy 295.31724 -15.640513) (xy 295.301278 -15.555113) (xy 295.293265 -15.468605)
			(xy 295.29278 -15.425166) (xy 295.29278 -15.424658) (xy 295.293264 -15.382462) (xy 295.300877 -15.298413)
			(xy 295.315995 -15.215385) (xy 295.338493 -15.134046) (xy 295.368193 -15.055052) (xy 295.404854 -14.979038)
			(xy 295.448182 -14.906616) (xy 295.472612 -14.872208) (xy 295.480994 -14.860524) (xy 295.48328 -14.831822)
			(xy 295.471088 -14.8082) (xy 295.436036 -14.738858) (xy 295.432308 -14.732255) (xy 295.421718 -14.721412)
			(xy 295.415208 -14.717522) (xy 295.4147 -14.717014) (xy 295.408916 -14.714036) (xy 295.396312 -14.710828)
			(xy 295.389808 -14.710664) (xy 286.069532 -14.710664) (xy 286.059469 -14.711101) (xy 286.040888 -14.71884)
			(xy 286.033464 -14.72565) (xy 285.839154 -14.91996) (xy 285.832283 -14.927516) (xy 285.82466 -14.946443)
			(xy 285.825002 -14.966846) (xy 285.82874 -14.976348) (xy 285.82874 -14.976602) (xy 285.86684 -15.062708)
			(xy 285.87029 -15.069802) (xy 285.880761 -15.081587) (xy 285.887414 -15.085822) (xy 285.894526 -15.09014)
			(xy 285.90875 -15.093696) (xy 285.916116 -15.093188) (xy 285.91764 -15.093188) (xy 285.93669 -15.09268)
			(xy 285.963944 -15.093142) (xy 286.017898 -15.100898) (xy 286.070199 -15.116254) (xy 286.119782 -15.138897)
			(xy 286.165638 -15.168365) (xy 286.206833 -15.20406) (xy 286.242529 -15.245254) (xy 286.271999 -15.291109)
			(xy 286.294643 -15.340692) (xy 286.31 -15.392992) (xy 286.317757 -15.446946) (xy 286.317757 -15.501454)
			(xy 286.31 -15.555408) (xy 286.294643 -15.607708) (xy 286.271999 -15.657291) (xy 286.242529 -15.703146)
			(xy 286.206833 -15.74434) (xy 286.165638 -15.780035) (xy 286.119782 -15.809503) (xy 286.070199 -15.832146)
			(xy 286.017898 -15.847502) (xy 285.963944 -15.855258) (xy 285.93669 -15.855696) (xy 285.9067 -15.855141)
			(xy 285.84746 -15.845747) (xy 285.790427 -15.827177) (xy 285.763462 -15.81404) (xy 285.751524 -15.807944)
			(xy 285.725362 -15.80896) (xy 285.640018 -15.861284) (xy 285.632852 -15.866113) (xy 285.622007 -15.879553)
			(xy 285.616235 -15.89583) (xy 285.615888 -15.904464) (xy 285.615888 -18.44421) (xy 306.476144 -18.44421)
			(xy 306.480215 -18.388588) (xy 306.492341 -18.334151) (xy 306.512264 -18.28206) (xy 306.53956 -18.233425)
			(xy 306.573646 -18.189282) (xy 306.613795 -18.150573) (xy 306.659153 -18.118122) (xy 306.708753 -18.092621)
			(xy 306.761537 -18.074614) (xy 306.81638 -18.064484) (xy 306.872114 -18.062447) (xy 306.927551 -18.068547)
			(xy 306.981508 -18.082653) (xy 307.032837 -18.104465) (xy 307.080443 -18.133519) (xy 307.123311 -18.169194)
			(xy 307.160528 -18.210731) (xy 307.191301 -18.257244) (xy 307.214973 -18.307741) (xy 307.231041 -18.361148)
			(xy 307.239161 -18.416324) (xy 307.23967 -18.44421) (xy 307.239161 -18.472096) (xy 307.231041 -18.527272)
			(xy 307.214973 -18.580679) (xy 307.191301 -18.631176) (xy 307.160528 -18.677689) (xy 307.123311 -18.719226)
			(xy 307.080443 -18.754901) (xy 307.032837 -18.783955) (xy 306.981508 -18.805767) (xy 306.927551 -18.819873)
			(xy 306.872114 -18.825973) (xy 306.81638 -18.823936) (xy 306.761537 -18.813806) (xy 306.708753 -18.795799)
			(xy 306.659153 -18.770298) (xy 306.613795 -18.737847) (xy 306.573646 -18.699138) (xy 306.53956 -18.654995)
			(xy 306.512264 -18.60636) (xy 306.492341 -18.554269) (xy 306.480215 -18.499832) (xy 306.476144 -18.44421)
			(xy 285.615888 -18.44421) (xy 285.615888 -20.72513) (xy 289.380434 -20.72513) (xy 289.384404 -20.594996)
			(xy 289.3963 -20.465346) (xy 289.416079 -20.336663) (xy 289.443665 -20.209424) (xy 289.478958 -20.084105)
			(xy 289.521824 -19.961169) (xy 289.572106 -19.841076) (xy 289.629615 -19.724272) (xy 289.694139 -19.61119)
			(xy 289.765436 -19.502253) (xy 289.843241 -19.397865) (xy 289.927266 -19.298414) (xy 290.017198 -19.204271)
			(xy 290.112702 -19.115786) (xy 290.213422 -19.033287) (xy 290.318984 -18.957082) (xy 290.428996 -18.887455)
			(xy 290.543048 -18.824664) (xy 290.660716 -18.768942) (xy 290.781562 -18.720498) (xy 290.905137 -18.679511)
			(xy 291.03098 -18.646134) (xy 291.158625 -18.620491) (xy 291.287595 -18.602677) (xy 291.417411 -18.592759)
			(xy 291.54759 -18.590774) (xy 291.677649 -18.596728) (xy 291.807102 -18.610601) (xy 291.935469 -18.632339)
			(xy 292.062272 -18.661863) (xy 292.187039 -18.699062) (xy 292.309306 -18.743798) (xy 292.428619 -18.795906)
			(xy 292.544532 -18.855189) (xy 292.656617 -18.92143) (xy 292.764454 -18.99438) (xy 292.867643 -19.073768)
			(xy 292.965801 -19.1593) (xy 293.058562 -19.250657) (xy 293.145581 -19.347499) (xy 293.226534 -19.449466)
			(xy 293.30112 -19.556178) (xy 293.369061 -19.667239) (xy 293.430106 -19.782235) (xy 293.484027 -19.900739)
			(xy 293.530622 -20.02231) (xy 293.56972 -20.146495) (xy 293.601174 -20.272833) (xy 293.624868 -20.400854)
			(xy 293.640712 -20.53008) (xy 293.64865 -20.660033) (xy 293.649146 -20.72513) (xy 293.64865 -20.790227)
			(xy 293.640712 -20.92018) (xy 293.624868 -21.049406) (xy 293.601174 -21.177427) (xy 293.56972 -21.303765)
			(xy 293.530622 -21.42795) (xy 293.484027 -21.549521) (xy 293.430106 -21.668025) (xy 293.392782 -21.738336)
			(xy 295.61663 -21.738336) (xy 295.617134 -21.709597) (xy 295.625764 -21.652769) (xy 295.64282 -21.597879)
			(xy 295.667915 -21.546168) (xy 295.700483 -21.498805) (xy 295.719754 -21.477478) (xy 295.726358 -21.470366)
			(xy 295.73347 -21.45284) (xy 295.73347 -21.363432) (xy 295.726358 -21.345906) (xy 295.719754 -21.338794)
			(xy 295.700518 -21.317437) (xy 295.667949 -21.270081) (xy 295.642853 -21.218374) (xy 295.625799 -21.163487)
			(xy 295.617172 -21.106664) (xy 295.617168 -21.049189) (xy 295.625787 -20.992364) (xy 295.642834 -20.937475)
			(xy 295.667922 -20.885765) (xy 295.700485 -20.838404) (xy 295.719754 -20.817078) (xy 295.726358 -20.809966)
			(xy 295.73347 -20.79244) (xy 295.73347 -20.703032) (xy 295.726358 -20.685506) (xy 295.719754 -20.678394)
			(xy 295.700518 -20.657037) (xy 295.667949 -20.609681) (xy 295.642853 -20.557974) (xy 295.625799 -20.503087)
			(xy 295.617172 -20.446264) (xy 295.617168 -20.388789) (xy 295.625787 -20.331964) (xy 295.642834 -20.277075)
			(xy 295.667922 -20.225365) (xy 295.700485 -20.178004) (xy 295.719754 -20.156678) (xy 295.726358 -20.149566)
			(xy 295.73347 -20.13204) (xy 295.73347 -20.042632) (xy 295.726358 -20.025106) (xy 295.719754 -20.017994)
			(xy 295.700518 -19.996637) (xy 295.667949 -19.949281) (xy 295.642853 -19.897574) (xy 295.625799 -19.842687)
			(xy 295.617172 -19.785864) (xy 295.617168 -19.728389) (xy 295.625787 -19.671564) (xy 295.642834 -19.616675)
			(xy 295.667922 -19.564965) (xy 295.700485 -19.517604) (xy 295.719754 -19.496278) (xy 295.726358 -19.489166)
			(xy 295.73347 -19.47164) (xy 295.73347 -19.382232) (xy 295.726358 -19.364706) (xy 295.719754 -19.357594)
			(xy 295.700503 -19.33625) (xy 295.667933 -19.288893) (xy 295.642837 -19.237186) (xy 295.625782 -19.182298)
			(xy 295.617154 -19.125474) (xy 295.61663 -19.096736) (xy 295.617116 -19.069485) (xy 295.624872 -19.015537)
			(xy 295.640227 -18.963242) (xy 295.662869 -18.913665) (xy 295.692335 -18.867815) (xy 295.728026 -18.826624)
			(xy 295.769217 -18.790933) (xy 295.815067 -18.761467) (xy 295.864644 -18.738825) (xy 295.916939 -18.72347)
			(xy 295.970887 -18.715714) (xy 296.025389 -18.715714) (xy 296.079337 -18.72347) (xy 296.131632 -18.738825)
			(xy 296.181209 -18.761467) (xy 296.227059 -18.790933) (xy 296.26825 -18.826624) (xy 296.303941 -18.867815)
			(xy 296.333407 -18.913665) (xy 296.356049 -18.963242) (xy 296.371404 -19.015537) (xy 296.37916 -19.069485)
			(xy 296.379646 -19.096736) (xy 296.379132 -19.125475) (xy 296.370505 -19.182302) (xy 296.353452 -19.237193)
			(xy 296.328359 -19.288904) (xy 296.295793 -19.336267) (xy 296.276522 -19.357594) (xy 296.269918 -19.364706)
			(xy 296.262806 -19.382232) (xy 296.262806 -19.47164) (xy 296.269918 -19.489166) (xy 296.276522 -19.496278)
			(xy 296.295826 -19.517575) (xy 296.328387 -19.564944) (xy 296.353473 -19.616661) (xy 296.370518 -19.671556)
			(xy 296.379136 -19.728386) (xy 296.379133 -19.785866) (xy 296.370507 -19.842696) (xy 296.353454 -19.897588)
			(xy 296.32836 -19.949302) (xy 296.295793 -19.996666) (xy 296.276522 -20.017994) (xy 296.269918 -20.025106)
			(xy 296.262806 -20.042632) (xy 296.262806 -20.13204) (xy 296.269918 -20.149566) (xy 296.276522 -20.156678)
			(xy 296.295826 -20.177975) (xy 296.328387 -20.225344) (xy 296.353473 -20.277061) (xy 296.370518 -20.331956)
			(xy 296.379136 -20.388786) (xy 296.379133 -20.446266) (xy 296.370507 -20.503096) (xy 296.353454 -20.557988)
			(xy 296.32836 -20.609702) (xy 296.295793 -20.657066) (xy 296.276522 -20.678394) (xy 296.269918 -20.685506)
			(xy 296.262806 -20.703032) (xy 296.262806 -20.79244) (xy 296.269918 -20.809966) (xy 296.276522 -20.817078)
			(xy 296.295826 -20.838375) (xy 296.328387 -20.885744) (xy 296.353473 -20.937461) (xy 296.370518 -20.992356)
			(xy 296.379136 -21.049186) (xy 296.379133 -21.106666) (xy 296.370507 -21.163496) (xy 296.353454 -21.218388)
			(xy 296.32836 -21.270102) (xy 296.295793 -21.317466) (xy 296.276522 -21.338794) (xy 296.269918 -21.345906)
			(xy 296.262806 -21.363432) (xy 296.262806 -21.45284) (xy 296.269918 -21.470366) (xy 296.276522 -21.477478)
			(xy 296.295803 -21.498796) (xy 296.328369 -21.54616) (xy 296.353461 -21.597874) (xy 296.36624 -21.639022)
			(xy 300.27372 -21.639022) (xy 300.274279 -21.610285) (xy 300.282896 -21.55346) (xy 300.299939 -21.49857)
			(xy 300.325022 -21.446858) (xy 300.357578 -21.399493) (xy 300.376844 -21.378164) (xy 300.383448 -21.371052)
			(xy 300.39056 -21.353526) (xy 300.39056 -21.264118) (xy 300.383448 -21.246592) (xy 300.376844 -21.23948)
			(xy 300.357594 -21.218135) (xy 300.325026 -21.170776) (xy 300.299932 -21.119067) (xy 300.28288 -21.064179)
			(xy 300.274255 -21.007354) (xy 300.274252 -20.949878) (xy 300.282873 -20.893052) (xy 300.299921 -20.838162)
			(xy 300.32501 -20.786452) (xy 300.357574 -20.73909) (xy 300.376844 -20.717764) (xy 300.383448 -20.710652)
			(xy 300.39056 -20.693126) (xy 300.39056 -20.603718) (xy 300.383448 -20.586192) (xy 300.376844 -20.57908)
			(xy 300.357594 -20.557735) (xy 300.325026 -20.510376) (xy 300.299932 -20.458667) (xy 300.28288 -20.403779)
			(xy 300.274255 -20.346954) (xy 300.274252 -20.289478) (xy 300.282873 -20.232652) (xy 300.299921 -20.177762)
			(xy 300.32501 -20.126052) (xy 300.357574 -20.07869) (xy 300.376844 -20.057364) (xy 300.383448 -20.050252)
			(xy 300.39056 -20.032726) (xy 300.39056 -19.943318) (xy 300.383448 -19.925792) (xy 300.376844 -19.91868)
			(xy 300.357594 -19.897335) (xy 300.325026 -19.849976) (xy 300.299932 -19.798267) (xy 300.28288 -19.743379)
			(xy 300.274255 -19.686554) (xy 300.274252 -19.629078) (xy 300.282873 -19.572252) (xy 300.299921 -19.517362)
			(xy 300.32501 -19.465652) (xy 300.357574 -19.41829) (xy 300.376844 -19.396964) (xy 300.383448 -19.389852)
			(xy 300.39056 -19.372326) (xy 300.39056 -19.282918) (xy 300.383448 -19.265392) (xy 300.376844 -19.25828)
			(xy 300.357585 -19.236943) (xy 300.325017 -19.189584) (xy 300.299922 -19.137875) (xy 300.282869 -19.082986)
			(xy 300.274243 -19.02616) (xy 300.27372 -18.997422) (xy 300.274206 -18.970171) (xy 300.281962 -18.916223)
			(xy 300.297317 -18.863928) (xy 300.319959 -18.814351) (xy 300.349425 -18.768501) (xy 300.385116 -18.72731)
			(xy 300.426307 -18.691619) (xy 300.472157 -18.662153) (xy 300.521734 -18.639511) (xy 300.574029 -18.624156)
			(xy 300.627977 -18.6164) (xy 300.682479 -18.6164) (xy 300.736427 -18.624156) (xy 300.788722 -18.639511)
			(xy 300.838299 -18.662153) (xy 300.884149 -18.691619) (xy 300.92534 -18.72731) (xy 300.961031 -18.768501)
			(xy 300.990497 -18.814351) (xy 301.013139 -18.863928) (xy 301.028494 -18.916223) (xy 301.03625 -18.970171)
			(xy 301.036736 -18.997422) (xy 301.036216 -19.026161) (xy 301.027591 -19.082988) (xy 301.01054 -19.137878)
			(xy 300.985447 -19.18959) (xy 300.952882 -19.236953) (xy 300.933612 -19.25828) (xy 300.927008 -19.265392)
			(xy 300.919896 -19.282918) (xy 300.919896 -19.366853) (xy 305.779138 -19.366853) (xy 305.779138 -19.312347)
			(xy 305.786894 -19.258397) (xy 305.80225 -19.206099) (xy 305.824891 -19.156518) (xy 305.854357 -19.110664)
			(xy 305.890049 -19.069471) (xy 305.93124 -19.033775) (xy 305.977092 -19.004305) (xy 306.026671 -18.98166)
			(xy 306.078967 -18.966301) (xy 306.132917 -18.95854) (xy 306.16017 -18.958052) (xy 306.18694 -18.95855)
			(xy 306.239953 -18.966044) (xy 306.291399 -18.980874) (xy 306.340266 -19.002749) (xy 306.385596 -19.031241)
			(xy 306.426498 -19.065789) (xy 306.46217 -19.105715) (xy 306.477416 -19.127724) (xy 306.483512 -19.136614)
			(xy 306.501038 -19.148044) (xy 306.595526 -19.163284) (xy 306.615846 -19.158204) (xy 306.624228 -19.1516)
			(xy 306.644368 -19.136466) (xy 306.687894 -19.111095) (xy 306.734383 -19.091682) (xy 306.783025 -19.078564)
			(xy 306.832972 -19.071972) (xy 306.858162 -19.07159) (xy 306.885416 -19.072055) (xy 306.939371 -19.079807)
			(xy 306.991673 -19.09516) (xy 307.041258 -19.1178) (xy 307.087116 -19.147267) (xy 307.128313 -19.18296)
			(xy 307.16401 -19.224154) (xy 307.193482 -19.270009) (xy 307.216127 -19.319591) (xy 307.231485 -19.371892)
			(xy 307.239243 -19.425846) (xy 307.239243 -19.480354) (xy 307.231485 -19.534308) (xy 307.216127 -19.586609)
			(xy 307.193482 -19.636191) (xy 307.16401 -19.682046) (xy 307.128313 -19.72324) (xy 307.087116 -19.758933)
			(xy 307.041258 -19.7884) (xy 306.991673 -19.81104) (xy 306.939371 -19.826393) (xy 306.885416 -19.834145)
			(xy 306.858162 -19.834606) (xy 306.831389 -19.834178) (xy 306.778372 -19.826674) (xy 306.726924 -19.811833)
			(xy 306.678056 -19.789947) (xy 306.632727 -19.761444) (xy 306.591827 -19.726885) (xy 306.556159 -19.686948)
			(xy 306.540916 -19.664934) (xy 306.53482 -19.656044) (xy 306.517294 -19.644614) (xy 306.422806 -19.629374)
			(xy 306.402486 -19.634454) (xy 306.394104 -19.641058) (xy 306.373949 -19.656172) (xy 306.330428 -19.681547)
			(xy 306.283943 -19.700965) (xy 306.235304 -19.714087) (xy 306.185359 -19.720684) (xy 306.16017 -19.721068)
			(xy 306.132917 -19.72066) (xy 306.078967 -19.712899) (xy 306.026671 -19.69754) (xy 305.977092 -19.674895)
			(xy 305.93124 -19.645425) (xy 305.890049 -19.609729) (xy 305.854357 -19.568536) (xy 305.824891 -19.522682)
			(xy 305.80225 -19.473101) (xy 305.786894 -19.420803) (xy 305.779138 -19.366853) (xy 300.919896 -19.366853)
			(xy 300.919896 -19.372326) (xy 300.927008 -19.389852) (xy 300.933612 -19.396964) (xy 300.952903 -19.418273)
			(xy 300.985465 -19.465639) (xy 301.010552 -19.517354) (xy 301.027599 -19.572247) (xy 301.036219 -19.629076)
			(xy 301.036216 -19.686556) (xy 301.027592 -19.743384) (xy 301.010541 -19.798276) (xy 300.985448 -19.849989)
			(xy 300.952883 -19.897352) (xy 300.933612 -19.91868) (xy 300.927008 -19.925792) (xy 300.919896 -19.943318)
			(xy 300.919896 -20.032726) (xy 300.927008 -20.050252) (xy 300.933612 -20.057364) (xy 300.952903 -20.078673)
			(xy 300.985465 -20.126039) (xy 301.010552 -20.177754) (xy 301.027599 -20.232647) (xy 301.036219 -20.289476)
			(xy 301.036216 -20.346956) (xy 301.03491 -20.35556) (xy 305.778152 -20.35556) (xy 305.782223 -20.299938)
			(xy 305.794349 -20.245501) (xy 305.814272 -20.19341) (xy 305.841568 -20.144775) (xy 305.875654 -20.100632)
			(xy 305.915803 -20.061923) (xy 305.961161 -20.029472) (xy 306.010761 -20.003971) (xy 306.063545 -19.985964)
			(xy 306.118388 -19.975834) (xy 306.174122 -19.973797) (xy 306.229559 -19.979897) (xy 306.283516 -19.994003)
			(xy 306.334845 -20.015815) (xy 306.382451 -20.044869) (xy 306.425319 -20.080544) (xy 306.462536 -20.122081)
			(xy 306.493309 -20.168594) (xy 306.516981 -20.219091) (xy 306.533049 -20.272498) (xy 306.541169 -20.327674)
			(xy 306.541678 -20.35556) (xy 306.541169 -20.383446) (xy 306.533049 -20.438622) (xy 306.516981 -20.492029)
			(xy 306.493309 -20.542526) (xy 306.462536 -20.589039) (xy 306.425319 -20.630576) (xy 306.382451 -20.666251)
			(xy 306.334845 -20.695305) (xy 306.283516 -20.717117) (xy 306.229559 -20.731223) (xy 306.174122 -20.737323)
			(xy 306.118388 -20.735286) (xy 306.063545 -20.725156) (xy 306.010761 -20.707149) (xy 305.961161 -20.681648)
			(xy 305.915803 -20.649197) (xy 305.875654 -20.610488) (xy 305.841568 -20.566345) (xy 305.814272 -20.51771)
			(xy 305.794349 -20.465619) (xy 305.782223 -20.411182) (xy 305.778152 -20.35556) (xy 301.03491 -20.35556)
			(xy 301.027592 -20.403784) (xy 301.010541 -20.458676) (xy 300.985448 -20.510389) (xy 300.952883 -20.557752)
			(xy 300.933612 -20.57908) (xy 300.927008 -20.586192) (xy 300.919896 -20.603718) (xy 300.919896 -20.693126)
			(xy 300.927008 -20.710652) (xy 300.933612 -20.717764) (xy 300.952903 -20.739073) (xy 300.985465 -20.786439)
			(xy 301.010552 -20.838154) (xy 301.027599 -20.893047) (xy 301.036219 -20.949876) (xy 301.036216 -21.007356)
			(xy 301.027592 -21.064184) (xy 301.010541 -21.119076) (xy 300.985448 -21.170789) (xy 300.952883 -21.218152)
			(xy 300.933612 -21.23948) (xy 300.927008 -21.246592) (xy 300.919896 -21.264118) (xy 300.919896 -21.353526)
			(xy 300.927008 -21.371052) (xy 300.92748 -21.37156) (xy 305.778152 -21.37156) (xy 305.782223 -21.315938)
			(xy 305.794349 -21.261501) (xy 305.814272 -21.20941) (xy 305.841568 -21.160775) (xy 305.875654 -21.116632)
			(xy 305.915803 -21.077923) (xy 305.961161 -21.045472) (xy 306.010761 -21.019971) (xy 306.063545 -21.001964)
			(xy 306.118388 -20.991834) (xy 306.174122 -20.989797) (xy 306.229559 -20.995897) (xy 306.283516 -21.010003)
			(xy 306.334845 -21.031815) (xy 306.382451 -21.060869) (xy 306.425319 -21.096544) (xy 306.462536 -21.138081)
			(xy 306.493309 -21.184594) (xy 306.516981 -21.235091) (xy 306.533049 -21.288498) (xy 306.541169 -21.343674)
			(xy 306.541678 -21.37156) (xy 306.541169 -21.399446) (xy 306.533049 -21.454622) (xy 306.516981 -21.508029)
			(xy 306.493309 -21.558526) (xy 306.462536 -21.605039) (xy 306.425319 -21.646576) (xy 306.382451 -21.682251)
			(xy 306.334845 -21.711305) (xy 306.283516 -21.733117) (xy 306.229559 -21.747223) (xy 306.174122 -21.753323)
			(xy 306.118388 -21.751286) (xy 306.063545 -21.741156) (xy 306.010761 -21.723149) (xy 305.961161 -21.697648)
			(xy 305.915803 -21.665197) (xy 305.875654 -21.626488) (xy 305.841568 -21.582345) (xy 305.814272 -21.53371)
			(xy 305.794349 -21.481619) (xy 305.782223 -21.427182) (xy 305.778152 -21.37156) (xy 300.92748 -21.37156)
			(xy 300.933612 -21.378164) (xy 300.952885 -21.399489) (xy 300.985453 -21.446851) (xy 301.010546 -21.498563)
			(xy 301.027596 -21.553454) (xy 301.036217 -21.610283) (xy 301.036736 -21.639022) (xy 301.03625 -21.666273)
			(xy 301.028494 -21.720221) (xy 301.013139 -21.772516) (xy 301.011697 -21.775674) (xy 310.135776 -21.775674)
			(xy 310.139847 -21.720052) (xy 310.151973 -21.665615) (xy 310.171896 -21.613524) (xy 310.199192 -21.564889)
			(xy 310.233278 -21.520746) (xy 310.273427 -21.482037) (xy 310.318785 -21.449586) (xy 310.368385 -21.424085)
			(xy 310.421169 -21.406078) (xy 310.476012 -21.395948) (xy 310.531746 -21.393911) (xy 310.587183 -21.400011)
			(xy 310.64114 -21.414117) (xy 310.692469 -21.435929) (xy 310.740075 -21.464983) (xy 310.782943 -21.500658)
			(xy 310.82016 -21.542195) (xy 310.850933 -21.588708) (xy 310.874605 -21.639205) (xy 310.890673 -21.692612)
			(xy 310.898793 -21.747788) (xy 310.899302 -21.775674) (xy 310.898793 -21.80356) (xy 310.890673 -21.858736)
			(xy 310.874605 -21.912143) (xy 310.850933 -21.96264) (xy 310.82016 -22.009153) (xy 310.782943 -22.05069)
			(xy 310.740075 -22.086365) (xy 310.692469 -22.115419) (xy 310.64114 -22.137231) (xy 310.587183 -22.151337)
			(xy 310.531746 -22.157437) (xy 310.476012 -22.1554) (xy 310.421169 -22.14527) (xy 310.368385 -22.127263)
			(xy 310.318785 -22.101762) (xy 310.273427 -22.069311) (xy 310.233278 -22.030602) (xy 310.199192 -21.986459)
			(xy 310.171896 -21.937824) (xy 310.151973 -21.885733) (xy 310.139847 -21.831296) (xy 310.135776 -21.775674)
			(xy 301.011697 -21.775674) (xy 300.990497 -21.822093) (xy 300.961031 -21.867943) (xy 300.92534 -21.909134)
			(xy 300.884149 -21.944825) (xy 300.838299 -21.974291) (xy 300.788722 -21.996933) (xy 300.736427 -22.012288)
			(xy 300.682479 -22.020044) (xy 300.627977 -22.020044) (xy 300.574029 -22.012288) (xy 300.521734 -21.996933)
			(xy 300.472157 -21.974291) (xy 300.426307 -21.944825) (xy 300.385116 -21.909134) (xy 300.349425 -21.867943)
			(xy 300.319959 -21.822093) (xy 300.297317 -21.772516) (xy 300.281962 -21.720221) (xy 300.274206 -21.666273)
			(xy 300.27372 -21.639022) (xy 296.36624 -21.639022) (xy 296.370509 -21.652767) (xy 296.379128 -21.709596)
			(xy 296.379646 -21.738336) (xy 296.37916 -21.765587) (xy 296.371404 -21.819535) (xy 296.356049 -21.87183)
			(xy 296.333407 -21.921407) (xy 296.303941 -21.967257) (xy 296.26825 -22.008448) (xy 296.227059 -22.044139)
			(xy 296.181209 -22.073605) (xy 296.131632 -22.096247) (xy 296.079337 -22.111602) (xy 296.025389 -22.119358)
			(xy 295.970887 -22.119358) (xy 295.916939 -22.111602) (xy 295.864644 -22.096247) (xy 295.815067 -22.073605)
			(xy 295.769217 -22.044139) (xy 295.728026 -22.008448) (xy 295.692335 -21.967257) (xy 295.662869 -21.921407)
			(xy 295.640227 -21.87183) (xy 295.624872 -21.819535) (xy 295.617116 -21.765587) (xy 295.61663 -21.738336)
			(xy 293.392782 -21.738336) (xy 293.369061 -21.783021) (xy 293.30112 -21.894082) (xy 293.226534 -22.000794)
			(xy 293.145581 -22.102761) (xy 293.058562 -22.199603) (xy 292.965801 -22.29096) (xy 292.867643 -22.376492)
			(xy 292.764454 -22.45588) (xy 292.656617 -22.52883) (xy 292.544532 -22.595071) (xy 292.428619 -22.654354)
			(xy 292.309306 -22.706462) (xy 292.187039 -22.751198) (xy 292.062272 -22.788397) (xy 291.935469 -22.817921)
			(xy 291.807102 -22.839659) (xy 291.677649 -22.853532) (xy 291.54759 -22.859486) (xy 291.417411 -22.857501)
			(xy 291.287595 -22.847583) (xy 291.158625 -22.829769) (xy 291.03098 -22.804126) (xy 290.905137 -22.770749)
			(xy 290.781562 -22.729762) (xy 290.660716 -22.681318) (xy 290.543048 -22.625596) (xy 290.428996 -22.562805)
			(xy 290.318984 -22.493178) (xy 290.213422 -22.416973) (xy 290.112702 -22.334474) (xy 290.017198 -22.245989)
			(xy 289.927266 -22.151846) (xy 289.843241 -22.052395) (xy 289.765436 -21.948007) (xy 289.694139 -21.83907)
			(xy 289.629615 -21.725988) (xy 289.572106 -21.609184) (xy 289.521824 -21.489091) (xy 289.478958 -21.366155)
			(xy 289.443665 -21.240836) (xy 289.416079 -21.113597) (xy 289.3963 -20.984914) (xy 289.384404 -20.855264)
			(xy 289.380434 -20.72513) (xy 285.615888 -20.72513) (xy 285.615888 -21.487892) (xy 285.616061 -21.494044)
			(xy 285.619022 -21.505987) (xy 285.62173 -21.511514) (xy 285.634938 -21.53666) (xy 285.642304 -21.545296)
			(xy 285.646876 -21.548598) (xy 285.668708 -21.565279) (xy 285.707807 -21.603879) (xy 285.740964 -21.647689)
			(xy 285.767493 -21.695802) (xy 285.786844 -21.747224) (xy 285.798618 -21.80089) (xy 285.801948 -21.847048)
			(xy 286.27273 -21.847048) (xy 286.276801 -21.791426) (xy 286.288927 -21.736989) (xy 286.30885 -21.684898)
			(xy 286.336146 -21.636263) (xy 286.370232 -21.59212) (xy 286.410381 -21.553411) (xy 286.455739 -21.52096)
			(xy 286.505339 -21.495459) (xy 286.558123 -21.477452) (xy 286.612966 -21.467322) (xy 286.6687 -21.465285)
			(xy 286.724137 -21.471385) (xy 286.778094 -21.485491) (xy 286.829423 -21.507303) (xy 286.877029 -21.536357)
			(xy 286.919897 -21.572032) (xy 286.957114 -21.613569) (xy 286.987887 -21.660082) (xy 287.011559 -21.710579)
			(xy 287.027627 -21.763986) (xy 287.035747 -21.819162) (xy 287.036256 -21.847048) (xy 287.035747 -21.874934)
			(xy 287.027627 -21.93011) (xy 287.011559 -21.983517) (xy 286.987887 -22.034014) (xy 286.957114 -22.080527)
			(xy 286.919897 -22.122064) (xy 286.877029 -22.157739) (xy 286.829423 -22.186793) (xy 286.778094 -22.208605)
			(xy 286.724137 -22.222711) (xy 286.6687 -22.228811) (xy 286.612966 -22.226774) (xy 286.558123 -22.216644)
			(xy 286.505339 -22.198637) (xy 286.455739 -22.173136) (xy 286.410381 -22.140685) (xy 286.370232 -22.101976)
			(xy 286.336146 -22.057833) (xy 286.30885 -22.009198) (xy 286.288927 -21.957107) (xy 286.276801 -21.90267)
			(xy 286.27273 -21.847048) (xy 285.801948 -21.847048) (xy 285.802571 -21.85569) (xy 285.798621 -21.910491)
			(xy 285.78685 -21.964158) (xy 285.767501 -22.01558) (xy 285.740974 -22.063695) (xy 285.70782 -22.107507)
			(xy 285.668722 -22.146108) (xy 285.646876 -22.16277) (xy 285.642304 -22.166072) (xy 285.634938 -22.174708)
			(xy 285.62173 -22.199854) (xy 285.61903 -22.205384) (xy 285.616067 -22.217325) (xy 285.615888 -22.223476)
			(xy 285.615888 -23.052344) (xy 295.563288 -23.052344) (xy 295.563289 -22.997843) (xy 295.571046 -22.943897)
			(xy 295.586401 -22.891604) (xy 295.609042 -22.842029) (xy 295.638508 -22.796181) (xy 295.674199 -22.754992)
			(xy 295.715389 -22.719302) (xy 295.761238 -22.689838) (xy 295.810814 -22.667198) (xy 295.863107 -22.651844)
			(xy 295.917053 -22.644088) (xy 295.971554 -22.644088) (xy 296.0255 -22.651845) (xy 296.077792 -22.6672)
			(xy 296.127368 -22.689841) (xy 296.173217 -22.719306) (xy 296.214405 -22.754997) (xy 296.250096 -22.796186)
			(xy 296.279561 -22.842035) (xy 296.302201 -22.891611) (xy 296.317556 -22.943904) (xy 296.325312 -22.99785)
			(xy 296.325639 -23.01621) (xy 296.91152 -23.01621) (xy 296.915591 -22.960588) (xy 296.927717 -22.906151)
			(xy 296.94764 -22.85406) (xy 296.974936 -22.805425) (xy 297.009022 -22.761282) (xy 297.049171 -22.722573)
			(xy 297.094529 -22.690122) (xy 297.144129 -22.664621) (xy 297.196913 -22.646614) (xy 297.251756 -22.636484)
			(xy 297.30749 -22.634447) (xy 297.362927 -22.640547) (xy 297.416884 -22.654653) (xy 297.468213 -22.676465)
			(xy 297.515819 -22.705519) (xy 297.558687 -22.741194) (xy 297.595904 -22.782731) (xy 297.626677 -22.829244)
			(xy 297.650349 -22.879741) (xy 297.666417 -22.933148) (xy 297.674537 -22.988324) (xy 297.675046 -23.01621)
			(xy 297.674537 -23.044096) (xy 297.666417 -23.099272) (xy 297.650349 -23.152679) (xy 297.626677 -23.203176)
			(xy 297.595904 -23.249689) (xy 297.558687 -23.291226) (xy 297.515819 -23.326901) (xy 297.468213 -23.355955)
			(xy 297.416884 -23.377767) (xy 297.362927 -23.391873) (xy 297.30749 -23.397973) (xy 297.251756 -23.395936)
			(xy 297.196913 -23.385806) (xy 297.144129 -23.367799) (xy 297.094529 -23.342298) (xy 297.049171 -23.309847)
			(xy 297.009022 -23.271138) (xy 296.974936 -23.226995) (xy 296.94764 -23.17836) (xy 296.927717 -23.126269)
			(xy 296.915591 -23.071832) (xy 296.91152 -23.01621) (xy 296.325639 -23.01621) (xy 296.325798 -23.0251)
			(xy 296.325571 -23.04202) (xy 296.322522 -23.075725) (xy 296.319702 -23.09241) (xy 296.317704 -23.105972)
			(xy 296.320253 -23.133259) (xy 296.329961 -23.158887) (xy 296.346132 -23.181013) (xy 296.367602 -23.198045)
			(xy 296.392827 -23.208759) (xy 296.419991 -23.212383) (xy 296.447142 -23.208657) (xy 296.45991 -23.203662)
			(xy 296.483729 -23.193941) (xy 296.533322 -23.18026) (xy 296.584301 -23.173352) (xy 296.610024 -23.172928)
			(xy 296.637273 -23.173404) (xy 296.691215 -23.181163) (xy 296.743503 -23.196519) (xy 296.793075 -23.219161)
			(xy 296.838919 -23.248626) (xy 296.880104 -23.284316) (xy 296.915791 -23.325503) (xy 296.945253 -23.37135)
			(xy 296.967891 -23.420923) (xy 296.983243 -23.473213) (xy 296.990998 -23.527155) (xy 296.990998 -23.581653)
			(xy 296.989798 -23.589996) (xy 300.284386 -23.589996) (xy 300.288457 -23.534374) (xy 300.300583 -23.479937)
			(xy 300.320506 -23.427846) (xy 300.347802 -23.379211) (xy 300.381888 -23.335068) (xy 300.422037 -23.296359)
			(xy 300.467395 -23.263908) (xy 300.516995 -23.238407) (xy 300.569779 -23.2204) (xy 300.624622 -23.21027)
			(xy 300.680356 -23.208233) (xy 300.735793 -23.214333) (xy 300.78975 -23.228439) (xy 300.841079 -23.250251)
			(xy 300.888685 -23.279305) (xy 300.931553 -23.31498) (xy 300.967907 -23.355554) (xy 309.530496 -23.355554)
			(xy 309.530966 -23.328743) (xy 309.538473 -23.275649) (xy 309.553347 -23.22413) (xy 309.575295 -23.175205)
			(xy 309.603882 -23.129839) (xy 309.638546 -23.088927) (xy 309.6786 -23.053276) (xy 309.700676 -23.038054)
			(xy 309.71222 -23.029768) (xy 309.730628 -23.00814) (xy 309.742368 -22.982278) (xy 309.746533 -22.954184)
			(xy 309.7428 -22.926028) (xy 309.731458 -22.89999) (xy 309.713384 -22.878081) (xy 309.701946 -22.869652)
			(xy 309.680492 -22.854296) (xy 309.641581 -22.818668) (xy 309.607949 -22.77802) (xy 309.580238 -22.733125)
			(xy 309.558978 -22.68484) (xy 309.544572 -22.634087) (xy 309.537296 -22.581833) (xy 309.536846 -22.555454)
			(xy 309.537332 -22.528203) (xy 309.545088 -22.474255) (xy 309.560443 -22.42196) (xy 309.583085 -22.372383)
			(xy 309.612551 -22.326533) (xy 309.648242 -22.285342) (xy 309.689433 -22.249651) (xy 309.735283 -22.220185)
			(xy 309.78486 -22.197543) (xy 309.837155 -22.182188) (xy 309.891103 -22.174432) (xy 309.945605 -22.174432)
			(xy 309.999553 -22.182188) (xy 310.051848 -22.197543) (xy 310.101425 -22.220185) (xy 310.147275 -22.249651)
			(xy 310.188466 -22.285342) (xy 310.224157 -22.326533) (xy 310.253623 -22.372383) (xy 310.276265 -22.42196)
			(xy 310.29162 -22.474255) (xy 310.299376 -22.528203) (xy 310.299862 -22.555454) (xy 310.299373 -22.582264)
			(xy 310.291866 -22.635356) (xy 310.276993 -22.686873) (xy 310.255048 -22.735797) (xy 310.226464 -22.781163)
			(xy 310.191805 -22.822077) (xy 310.151755 -22.85773) (xy 310.129682 -22.872954) (xy 310.118134 -22.881232)
			(xy 310.099733 -22.902865) (xy 310.087998 -22.928727) (xy 310.083837 -22.956821) (xy 310.087569 -22.984975)
			(xy 310.098908 -23.011013) (xy 310.116977 -23.032924) (xy 310.128412 -23.041356) (xy 310.149861 -23.05672)
			(xy 310.188774 -23.092345) (xy 310.222407 -23.132992) (xy 310.250119 -23.177885) (xy 310.271381 -23.226169)
			(xy 310.285787 -23.276922) (xy 310.293063 -23.329175) (xy 310.293512 -23.355554) (xy 310.293026 -23.382805)
			(xy 310.28527 -23.436753) (xy 310.269915 -23.489048) (xy 310.247273 -23.538625) (xy 310.217807 -23.584475)
			(xy 310.182116 -23.625666) (xy 310.140925 -23.661357) (xy 310.095075 -23.690823) (xy 310.045498 -23.713465)
			(xy 309.993203 -23.72882) (xy 309.939255 -23.736576) (xy 309.884753 -23.736576) (xy 309.830805 -23.72882)
			(xy 309.77851 -23.713465) (xy 309.728933 -23.690823) (xy 309.683083 -23.661357) (xy 309.641892 -23.625666)
			(xy 309.606201 -23.584475) (xy 309.576735 -23.538625) (xy 309.554093 -23.489048) (xy 309.538738 -23.436753)
			(xy 309.530982 -23.382805) (xy 309.530496 -23.355554) (xy 300.967907 -23.355554) (xy 300.96877 -23.356517)
			(xy 300.999543 -23.40303) (xy 301.023215 -23.453527) (xy 301.039283 -23.506934) (xy 301.047403 -23.56211)
			(xy 301.047912 -23.589996) (xy 301.047403 -23.617882) (xy 301.039283 -23.673058) (xy 301.023215 -23.726465)
			(xy 300.999543 -23.776962) (xy 300.96877 -23.823475) (xy 300.931553 -23.865012) (xy 300.913161 -23.880318)
			(xy 301.440594 -23.880318) (xy 301.444665 -23.824696) (xy 301.456791 -23.770259) (xy 301.476714 -23.718168)
			(xy 301.50401 -23.669533) (xy 301.538096 -23.62539) (xy 301.578245 -23.586681) (xy 301.623603 -23.55423)
			(xy 301.673203 -23.528729) (xy 301.725987 -23.510722) (xy 301.78083 -23.500592) (xy 301.836564 -23.498555)
			(xy 301.892001 -23.504655) (xy 301.945958 -23.518761) (xy 301.997287 -23.540573) (xy 302.044893 -23.569627)
			(xy 302.087761 -23.605302) (xy 302.124978 -23.646839) (xy 302.155751 -23.693352) (xy 302.179423 -23.743849)
			(xy 302.195491 -23.797256) (xy 302.203611 -23.852432) (xy 302.20412 -23.880318) (xy 302.456594 -23.880318)
			(xy 302.460665 -23.824696) (xy 302.472791 -23.770259) (xy 302.492714 -23.718168) (xy 302.52001 -23.669533)
			(xy 302.554096 -23.62539) (xy 302.594245 -23.586681) (xy 302.639603 -23.55423) (xy 302.689203 -23.528729)
			(xy 302.741987 -23.510722) (xy 302.79683 -23.500592) (xy 302.852564 -23.498555) (xy 302.908001 -23.504655)
			(xy 302.961958 -23.518761) (xy 303.013287 -23.540573) (xy 303.060893 -23.569627) (xy 303.103761 -23.605302)
			(xy 303.140978 -23.646839) (xy 303.171751 -23.693352) (xy 303.195423 -23.743849) (xy 303.211491 -23.797256)
			(xy 303.219611 -23.852432) (xy 303.22012 -23.880318) (xy 303.472594 -23.880318) (xy 303.476665 -23.824696)
			(xy 303.488791 -23.770259) (xy 303.508714 -23.718168) (xy 303.53601 -23.669533) (xy 303.570096 -23.62539)
			(xy 303.610245 -23.586681) (xy 303.655603 -23.55423) (xy 303.705203 -23.528729) (xy 303.757987 -23.510722)
			(xy 303.81283 -23.500592) (xy 303.868564 -23.498555) (xy 303.924001 -23.504655) (xy 303.977958 -23.518761)
			(xy 304.029287 -23.540573) (xy 304.076893 -23.569627) (xy 304.119761 -23.605302) (xy 304.156978 -23.646839)
			(xy 304.187751 -23.693352) (xy 304.211423 -23.743849) (xy 304.227491 -23.797256) (xy 304.235611 -23.852432)
			(xy 304.23612 -23.880318) (xy 304.49088 -23.880318) (xy 304.494951 -23.824696) (xy 304.507077 -23.770259)
			(xy 304.527 -23.718168) (xy 304.554296 -23.669533) (xy 304.588382 -23.62539) (xy 304.628531 -23.586681)
			(xy 304.673889 -23.55423) (xy 304.723489 -23.528729) (xy 304.776273 -23.510722) (xy 304.831116 -23.500592)
			(xy 304.88685 -23.498555) (xy 304.942287 -23.504655) (xy 304.996244 -23.518761) (xy 305.047573 -23.540573)
			(xy 305.095179 -23.569627) (xy 305.138047 -23.605302) (xy 305.175264 -23.646839) (xy 305.206037 -23.693352)
			(xy 305.229709 -23.743849) (xy 305.245777 -23.797256) (xy 305.253897 -23.852432) (xy 305.254406 -23.880318)
			(xy 305.253897 -23.908204) (xy 305.245777 -23.96338) (xy 305.229709 -24.016787) (xy 305.206037 -24.067284)
			(xy 305.175264 -24.113797) (xy 305.138047 -24.155334) (xy 305.095179 -24.191009) (xy 305.047573 -24.220063)
			(xy 304.996244 -24.241875) (xy 304.942287 -24.255981) (xy 304.88685 -24.262081) (xy 304.831116 -24.260044)
			(xy 304.776273 -24.249914) (xy 304.723489 -24.231907) (xy 304.673889 -24.206406) (xy 304.628531 -24.173955)
			(xy 304.588382 -24.135246) (xy 304.554296 -24.091103) (xy 304.527 -24.042468) (xy 304.507077 -23.990377)
			(xy 304.494951 -23.93594) (xy 304.49088 -23.880318) (xy 304.23612 -23.880318) (xy 304.235611 -23.908204)
			(xy 304.227491 -23.96338) (xy 304.211423 -24.016787) (xy 304.187751 -24.067284) (xy 304.156978 -24.113797)
			(xy 304.119761 -24.155334) (xy 304.076893 -24.191009) (xy 304.029287 -24.220063) (xy 303.977958 -24.241875)
			(xy 303.924001 -24.255981) (xy 303.868564 -24.262081) (xy 303.81283 -24.260044) (xy 303.757987 -24.249914)
			(xy 303.705203 -24.231907) (xy 303.655603 -24.206406) (xy 303.610245 -24.173955) (xy 303.570096 -24.135246)
			(xy 303.53601 -24.091103) (xy 303.508714 -24.042468) (xy 303.488791 -23.990377) (xy 303.476665 -23.93594)
			(xy 303.472594 -23.880318) (xy 303.22012 -23.880318) (xy 303.219611 -23.908204) (xy 303.211491 -23.96338)
			(xy 303.195423 -24.016787) (xy 303.171751 -24.067284) (xy 303.140978 -24.113797) (xy 303.103761 -24.155334)
			(xy 303.060893 -24.191009) (xy 303.013287 -24.220063) (xy 302.961958 -24.241875) (xy 302.908001 -24.255981)
			(xy 302.852564 -24.262081) (xy 302.79683 -24.260044) (xy 302.741987 -24.249914) (xy 302.689203 -24.231907)
			(xy 302.639603 -24.206406) (xy 302.594245 -24.173955) (xy 302.554096 -24.135246) (xy 302.52001 -24.091103)
			(xy 302.492714 -24.042468) (xy 302.472791 -23.990377) (xy 302.460665 -23.93594) (xy 302.456594 -23.880318)
			(xy 302.20412 -23.880318) (xy 302.203611 -23.908204) (xy 302.195491 -23.96338) (xy 302.179423 -24.016787)
			(xy 302.155751 -24.067284) (xy 302.124978 -24.113797) (xy 302.087761 -24.155334) (xy 302.044893 -24.191009)
			(xy 301.997287 -24.220063) (xy 301.945958 -24.241875) (xy 301.892001 -24.255981) (xy 301.836564 -24.262081)
			(xy 301.78083 -24.260044) (xy 301.725987 -24.249914) (xy 301.673203 -24.231907) (xy 301.623603 -24.206406)
			(xy 301.578245 -24.173955) (xy 301.538096 -24.135246) (xy 301.50401 -24.091103) (xy 301.476714 -24.042468)
			(xy 301.456791 -23.990377) (xy 301.444665 -23.93594) (xy 301.440594 -23.880318) (xy 300.913161 -23.880318)
			(xy 300.888685 -23.900687) (xy 300.841079 -23.929741) (xy 300.78975 -23.951553) (xy 300.735793 -23.965659)
			(xy 300.680356 -23.971759) (xy 300.624622 -23.969722) (xy 300.569779 -23.959592) (xy 300.516995 -23.941585)
			(xy 300.467395 -23.916084) (xy 300.422037 -23.883633) (xy 300.381888 -23.844924) (xy 300.347802 -23.800781)
			(xy 300.320506 -23.752146) (xy 300.300583 -23.700055) (xy 300.288457 -23.645618) (xy 300.284386 -23.589996)
			(xy 296.989798 -23.589996) (xy 296.983241 -23.635595) (xy 296.967888 -23.687885) (xy 296.945249 -23.737457)
			(xy 296.915786 -23.783303) (xy 296.880099 -23.82449) (xy 296.838913 -23.860179) (xy 296.793068 -23.889643)
			(xy 296.743496 -23.912284) (xy 296.691207 -23.927639) (xy 296.637265 -23.935397) (xy 296.582767 -23.935399)
			(xy 296.528825 -23.927646) (xy 296.476534 -23.912295) (xy 296.42696 -23.889659) (xy 296.381113 -23.860198)
			(xy 296.339924 -23.824513) (xy 296.304233 -23.783329) (xy 296.274766 -23.737485) (xy 296.252123 -23.687915)
			(xy 296.236765 -23.635626) (xy 296.229005 -23.581685) (xy 296.228516 -23.554436) (xy 296.228734 -23.537515)
			(xy 296.231789 -23.503811) (xy 296.234612 -23.487126) (xy 296.236556 -23.473557) (xy 296.234016 -23.446276)
			(xy 296.224315 -23.420651) (xy 296.208152 -23.398527) (xy 296.18669 -23.381495) (xy 296.161472 -23.370781)
			(xy 296.134314 -23.367156) (xy 296.107169 -23.37088) (xy 296.094404 -23.375874) (xy 296.070584 -23.385593)
			(xy 296.020992 -23.399275) (xy 295.970013 -23.406184) (xy 295.94429 -23.406608) (xy 295.91704 -23.406111)
			(xy 295.863094 -23.398353) (xy 295.810801 -23.382998) (xy 295.761226 -23.360356) (xy 295.715378 -23.33089)
			(xy 295.67419 -23.295198) (xy 295.6385 -23.254009) (xy 295.609036 -23.208159) (xy 295.586397 -23.158583)
			(xy 295.571043 -23.10629) (xy 295.563288 -23.052344) (xy 285.615888 -23.052344) (xy 285.615888 -23.504144)
			(xy 285.623508 -23.522178) (xy 285.63062 -23.529544) (xy 285.65856 -23.557738) (xy 285.675324 -23.565358)
			(xy 285.684976 -23.56612) (xy 285.713735 -23.568362) (xy 285.770143 -23.580418) (xy 285.824093 -23.600827)
			(xy 285.874357 -23.629125) (xy 285.919789 -23.664667) (xy 285.959353 -23.706641) (xy 285.992148 -23.754093)
			(xy 286.017427 -23.805941) (xy 286.034613 -23.861003) (xy 286.043316 -23.918025) (xy 286.043878 -23.946866)
			(xy 286.044132 -23.946866) (xy 286.043694 -23.970996) (xy 286.27273 -23.970996) (xy 286.276801 -23.915374)
			(xy 286.288927 -23.860937) (xy 286.30885 -23.808846) (xy 286.336146 -23.760211) (xy 286.370232 -23.716068)
			(xy 286.410381 -23.677359) (xy 286.455739 -23.644908) (xy 286.505339 -23.619407) (xy 286.558123 -23.6014)
			(xy 286.612966 -23.59127) (xy 286.6687 -23.589233) (xy 286.724137 -23.595333) (xy 286.778094 -23.609439)
			(xy 286.829423 -23.631251) (xy 286.877029 -23.660305) (xy 286.919897 -23.69598) (xy 286.957114 -23.737517)
			(xy 286.987887 -23.78403) (xy 287.011559 -23.834527) (xy 287.027627 -23.887934) (xy 287.035747 -23.94311)
			(xy 287.036256 -23.970996) (xy 287.035747 -23.998882) (xy 287.027627 -24.054058) (xy 287.011559 -24.107465)
			(xy 286.987887 -24.157962) (xy 286.987734 -24.158194) (xy 291.650672 -24.158194) (xy 291.654743 -24.102572)
			(xy 291.666869 -24.048135) (xy 291.686792 -23.996044) (xy 291.714088 -23.947409) (xy 291.748174 -23.903266)
			(xy 291.788323 -23.864557) (xy 291.833681 -23.832106) (xy 291.883281 -23.806605) (xy 291.936065 -23.788598)
			(xy 291.990908 -23.778468) (xy 292.046642 -23.776431) (xy 292.102079 -23.782531) (xy 292.156036 -23.796637)
			(xy 292.207365 -23.818449) (xy 292.254971 -23.847503) (xy 292.297839 -23.883178) (xy 292.335056 -23.924715)
			(xy 292.365829 -23.971228) (xy 292.389501 -24.021725) (xy 292.405569 -24.075132) (xy 292.413689 -24.130308)
			(xy 292.414198 -24.158194) (xy 292.413689 -24.18608) (xy 292.41312 -24.189944) (xy 295.498772 -24.189944)
			(xy 295.502843 -24.134322) (xy 295.514969 -24.079885) (xy 295.534892 -24.027794) (xy 295.562188 -23.979159)
			(xy 295.596274 -23.935016) (xy 295.636423 -23.896307) (xy 295.681781 -23.863856) (xy 295.731381 -23.838355)
			(xy 295.784165 -23.820348) (xy 295.839008 -23.810218) (xy 295.894742 -23.808181) (xy 295.950179 -23.814281)
			(xy 296.004136 -23.828387) (xy 296.055465 -23.850199) (xy 296.103071 -23.879253) (xy 296.145939 -23.914928)
			(xy 296.183156 -23.956465) (xy 296.213929 -24.002978) (xy 296.237601 -24.053475) (xy 296.253669 -24.106882)
			(xy 296.261789 -24.162058) (xy 296.262298 -24.189944) (xy 298.021754 -24.189944) (xy 298.025825 -24.134322)
			(xy 298.037951 -24.079885) (xy 298.057874 -24.027794) (xy 298.08517 -23.979159) (xy 298.119256 -23.935016)
			(xy 298.159405 -23.896307) (xy 298.204763 -23.863856) (xy 298.254363 -23.838355) (xy 298.307147 -23.820348)
			(xy 298.36199 -23.810218) (xy 298.417724 -23.808181) (xy 298.473161 -23.814281) (xy 298.527118 -23.828387)
			(xy 298.578447 -23.850199) (xy 298.626053 -23.879253) (xy 298.668921 -23.914928) (xy 298.706138 -23.956465)
			(xy 298.736911 -24.002978) (xy 298.760583 -24.053475) (xy 298.776651 -24.106882) (xy 298.784771 -24.162058)
			(xy 298.78528 -24.189944) (xy 298.784771 -24.21783) (xy 298.776651 -24.273006) (xy 298.760583 -24.326413)
			(xy 298.736911 -24.37691) (xy 298.706138 -24.423423) (xy 298.668921 -24.46496) (xy 298.626053 -24.500635)
			(xy 298.578447 -24.529689) (xy 298.527118 -24.551501) (xy 298.473161 -24.565607) (xy 298.417724 -24.571707)
			(xy 298.36199 -24.56967) (xy 298.307147 -24.55954) (xy 298.254363 -24.541533) (xy 298.204763 -24.516032)
			(xy 298.159405 -24.483581) (xy 298.119256 -24.444872) (xy 298.08517 -24.400729) (xy 298.057874 -24.352094)
			(xy 298.037951 -24.300003) (xy 298.025825 -24.245566) (xy 298.021754 -24.189944) (xy 296.262298 -24.189944)
			(xy 296.261789 -24.21783) (xy 296.253669 -24.273006) (xy 296.237601 -24.326413) (xy 296.213929 -24.37691)
			(xy 296.183156 -24.423423) (xy 296.145939 -24.46496) (xy 296.103071 -24.500635) (xy 296.055465 -24.529689)
			(xy 296.004136 -24.551501) (xy 295.950179 -24.565607) (xy 295.894742 -24.571707) (xy 295.839008 -24.56967)
			(xy 295.784165 -24.55954) (xy 295.731381 -24.541533) (xy 295.681781 -24.516032) (xy 295.636423 -24.483581)
			(xy 295.596274 -24.444872) (xy 295.562188 -24.400729) (xy 295.534892 -24.352094) (xy 295.514969 -24.300003)
			(xy 295.502843 -24.245566) (xy 295.498772 -24.189944) (xy 292.41312 -24.189944) (xy 292.405569 -24.241256)
			(xy 292.389501 -24.294663) (xy 292.365829 -24.34516) (xy 292.335056 -24.391673) (xy 292.297839 -24.43321)
			(xy 292.254971 -24.468885) (xy 292.207365 -24.497939) (xy 292.156036 -24.519751) (xy 292.102079 -24.533857)
			(xy 292.046642 -24.539957) (xy 291.990908 -24.53792) (xy 291.936065 -24.52779) (xy 291.883281 -24.509783)
			(xy 291.833681 -24.484282) (xy 291.788323 -24.451831) (xy 291.748174 -24.413122) (xy 291.714088 -24.368979)
			(xy 291.686792 -24.320344) (xy 291.666869 -24.268253) (xy 291.654743 -24.213816) (xy 291.650672 -24.158194)
			(xy 286.987734 -24.158194) (xy 286.957114 -24.204475) (xy 286.919897 -24.246012) (xy 286.877029 -24.281687)
			(xy 286.829423 -24.310741) (xy 286.778094 -24.332553) (xy 286.724137 -24.346659) (xy 286.6687 -24.352759)
			(xy 286.612966 -24.350722) (xy 286.558123 -24.340592) (xy 286.505339 -24.322585) (xy 286.455739 -24.297084)
			(xy 286.410381 -24.264633) (xy 286.370232 -24.225924) (xy 286.336146 -24.181781) (xy 286.30885 -24.133146)
			(xy 286.288927 -24.081055) (xy 286.276801 -24.026618) (xy 286.27273 -23.970996) (xy 286.043694 -23.970996)
			(xy 286.043618 -23.975196) (xy 286.035246 -24.031232) (xy 286.018681 -24.085416) (xy 285.994287 -24.136555)
			(xy 285.962601 -24.183525) (xy 285.924318 -24.225294) (xy 285.88028 -24.260944) (xy 285.831456 -24.289691)
			(xy 285.778917 -24.310904) (xy 285.72382 -24.324115) (xy 285.695644 -24.327104) (xy 285.684468 -24.327866)
			(xy 285.67507 -24.332692) (xy 285.671184 -24.3348) (xy 285.664157 -24.340166) (xy 285.6611 -24.34336)
			(xy 285.614364 -24.393906) (xy 285.608179 -24.401165) (xy 285.601258 -24.41892) (xy 285.600902 -24.42845)
			(xy 285.600902 -24.807418) (xy 292.820088 -24.807418) (xy 292.824159 -24.751796) (xy 292.836285 -24.697359)
			(xy 292.856208 -24.645268) (xy 292.883504 -24.596633) (xy 292.91759 -24.55249) (xy 292.957739 -24.513781)
			(xy 293.003097 -24.48133) (xy 293.052697 -24.455829) (xy 293.105481 -24.437822) (xy 293.160324 -24.427692)
			(xy 293.216058 -24.425655) (xy 293.271495 -24.431755) (xy 293.325452 -24.445861) (xy 293.376781 -24.467673)
			(xy 293.424387 -24.496727) (xy 293.467255 -24.532402) (xy 293.504472 -24.573939) (xy 293.535245 -24.620452)
			(xy 293.558917 -24.670949) (xy 293.574985 -24.724356) (xy 293.580032 -24.75865) (xy 305.068476 -24.75865)
			(xy 305.072547 -24.703028) (xy 305.084673 -24.648591) (xy 305.104596 -24.5965) (xy 305.131892 -24.547865)
			(xy 305.165978 -24.503722) (xy 305.206127 -24.465013) (xy 305.251485 -24.432562) (xy 305.301085 -24.407061)
			(xy 305.353869 -24.389054) (xy 305.408712 -24.378924) (xy 305.464446 -24.376887) (xy 305.519883 -24.382987)
			(xy 305.57384 -24.397093) (xy 305.625169 -24.418905) (xy 305.672775 -24.447959) (xy 305.715643 -24.483634)
			(xy 305.75286 -24.525171) (xy 305.783633 -24.571684) (xy 305.807305 -24.622181) (xy 305.823373 -24.675588)
			(xy 305.831493 -24.730764) (xy 305.832002 -24.75865) (xy 305.831493 -24.786536) (xy 305.823373 -24.841712)
			(xy 305.807305 -24.895119) (xy 305.783633 -24.945616) (xy 305.75286 -24.992129) (xy 305.715643 -25.033666)
			(xy 305.672775 -25.069341) (xy 305.625169 -25.098395) (xy 305.57384 -25.120207) (xy 305.519883 -25.134313)
			(xy 305.464446 -25.140413) (xy 305.408712 -25.138376) (xy 305.353869 -25.128246) (xy 305.301085 -25.110239)
			(xy 305.251485 -25.084738) (xy 305.206127 -25.052287) (xy 305.165978 -25.013578) (xy 305.131892 -24.969435)
			(xy 305.104596 -24.9208) (xy 305.084673 -24.868709) (xy 305.072547 -24.814272) (xy 305.068476 -24.75865)
			(xy 293.580032 -24.75865) (xy 293.583105 -24.779532) (xy 293.583614 -24.807418) (xy 293.583105 -24.835304)
			(xy 293.574985 -24.89048) (xy 293.558917 -24.943887) (xy 293.535245 -24.994384) (xy 293.504472 -25.040897)
			(xy 293.467255 -25.082434) (xy 293.424387 -25.118109) (xy 293.376781 -25.147163) (xy 293.325452 -25.168975)
			(xy 293.271495 -25.183081) (xy 293.216058 -25.189181) (xy 293.160324 -25.187144) (xy 293.105481 -25.177014)
			(xy 293.052697 -25.159007) (xy 293.003097 -25.133506) (xy 292.957739 -25.101055) (xy 292.91759 -25.062346)
			(xy 292.883504 -25.018203) (xy 292.856208 -24.969568) (xy 292.836285 -24.917477) (xy 292.824159 -24.86304)
			(xy 292.820088 -24.807418) (xy 285.600902 -24.807418) (xy 285.600902 -25.390094) (xy 298.009564 -25.390094)
			(xy 298.01005 -25.362843) (xy 298.017806 -25.308895) (xy 298.033161 -25.2566) (xy 298.055803 -25.207023)
			(xy 298.085269 -25.161173) (xy 298.12096 -25.119982) (xy 298.162151 -25.084291) (xy 298.208001 -25.054825)
			(xy 298.257578 -25.032183) (xy 298.309873 -25.016828) (xy 298.363821 -25.009072) (xy 298.418323 -25.009072)
			(xy 298.472271 -25.016828) (xy 298.524566 -25.032183) (xy 298.574143 -25.054825) (xy 298.619993 -25.084291)
			(xy 298.661184 -25.119982) (xy 298.696875 -25.161173) (xy 298.726341 -25.207023) (xy 298.748983 -25.2566)
			(xy 298.764338 -25.308895) (xy 298.772094 -25.362843) (xy 298.77258 -25.390094) (xy 298.771997 -25.419113)
			(xy 298.763208 -25.476482) (xy 298.745831 -25.531858) (xy 298.720268 -25.583964) (xy 298.687108 -25.631597)
			(xy 298.647117 -25.673658) (xy 298.624498 -25.691846) (xy 298.613953 -25.700616) (xy 298.597511 -25.72255)
			(xy 298.587506 -25.748071) (xy 298.584659 -25.775336) (xy 298.589176 -25.802374) (xy 298.600731 -25.827232)
			(xy 298.61849 -25.848114) (xy 298.629578 -25.856184) (xy 298.651212 -25.871513) (xy 298.69047 -25.907148)
			(xy 298.724414 -25.947878) (xy 298.752389 -25.992916) (xy 298.773856 -26.041395) (xy 298.788402 -26.09238)
			(xy 298.795746 -26.144888) (xy 298.796202 -26.171398) (xy 298.795716 -26.198649) (xy 298.78796 -26.252597)
			(xy 298.772605 -26.304892) (xy 298.749963 -26.354469) (xy 298.720497 -26.400319) (xy 298.684806 -26.44151)
			(xy 298.643615 -26.477201) (xy 298.597765 -26.506667) (xy 298.548188 -26.529309) (xy 298.495893 -26.544664)
			(xy 298.441945 -26.55242) (xy 298.387443 -26.55242) (xy 298.333495 -26.544664) (xy 298.2812 -26.529309)
			(xy 298.231623 -26.506667) (xy 298.185773 -26.477201) (xy 298.144582 -26.44151) (xy 298.108891 -26.400319)
			(xy 298.079425 -26.354469) (xy 298.056783 -26.304892) (xy 298.041428 -26.252597) (xy 298.033672 -26.198649)
			(xy 298.033186 -26.171398) (xy 298.033738 -26.142377) (xy 298.04253 -26.085006) (xy 298.059911 -26.029628)
			(xy 298.08548 -25.977522) (xy 298.118647 -25.92989) (xy 298.158646 -25.887832) (xy 298.181268 -25.869646)
			(xy 298.191825 -25.860889) (xy 298.208273 -25.838953) (xy 298.218282 -25.813428) (xy 298.221129 -25.786159)
			(xy 298.216608 -25.759118) (xy 298.205047 -25.734257) (xy 298.18728 -25.713376) (xy 298.176188 -25.705308)
			(xy 298.154543 -25.689995) (xy 298.115287 -25.654355) (xy 298.081345 -25.613623) (xy 298.053372 -25.568582)
			(xy 298.031906 -25.520101) (xy 298.017362 -25.469114) (xy 298.010019 -25.416604) (xy 298.009564 -25.390094)
			(xy 285.600902 -25.390094) (xy 285.600902 -25.971246) (xy 286.1597 -25.971246) (xy 286.163771 -25.915624)
			(xy 286.175897 -25.861187) (xy 286.19582 -25.809096) (xy 286.223116 -25.760461) (xy 286.257202 -25.716318)
			(xy 286.297351 -25.677609) (xy 286.342709 -25.645158) (xy 286.392309 -25.619657) (xy 286.445093 -25.60165)
			(xy 286.499936 -25.59152) (xy 286.55567 -25.589483) (xy 286.611107 -25.595583) (xy 286.665064 -25.609689)
			(xy 286.716393 -25.631501) (xy 286.763999 -25.660555) (xy 286.806867 -25.69623) (xy 286.844084 -25.737767)
			(xy 286.874857 -25.78428) (xy 286.898529 -25.834777) (xy 286.914597 -25.888184) (xy 286.922717 -25.94336)
			(xy 286.923226 -25.971246) (xy 287.1757 -25.971246) (xy 287.179771 -25.915624) (xy 287.191897 -25.861187)
			(xy 287.21182 -25.809096) (xy 287.239116 -25.760461) (xy 287.273202 -25.716318) (xy 287.313351 -25.677609)
			(xy 287.358709 -25.645158) (xy 287.408309 -25.619657) (xy 287.461093 -25.60165) (xy 287.515936 -25.59152)
			(xy 287.57167 -25.589483) (xy 287.627107 -25.595583) (xy 287.681064 -25.609689) (xy 287.732393 -25.631501)
			(xy 287.779999 -25.660555) (xy 287.822867 -25.69623) (xy 287.860084 -25.737767) (xy 287.890857 -25.78428)
			(xy 287.914529 -25.834777) (xy 287.930597 -25.888184) (xy 287.938717 -25.94336) (xy 287.939226 -25.971246)
			(xy 288.1917 -25.971246) (xy 288.195771 -25.915624) (xy 288.207897 -25.861187) (xy 288.22782 -25.809096)
			(xy 288.255116 -25.760461) (xy 288.289202 -25.716318) (xy 288.329351 -25.677609) (xy 288.374709 -25.645158)
			(xy 288.424309 -25.619657) (xy 288.477093 -25.60165) (xy 288.531936 -25.59152) (xy 288.58767 -25.589483)
			(xy 288.643107 -25.595583) (xy 288.697064 -25.609689) (xy 288.748393 -25.631501) (xy 288.795999 -25.660555)
			(xy 288.838867 -25.69623) (xy 288.876084 -25.737767) (xy 288.906857 -25.78428) (xy 288.930529 -25.834777)
			(xy 288.946597 -25.888184) (xy 288.954717 -25.94336) (xy 288.955226 -25.971246) (xy 288.954717 -25.999132)
			(xy 288.949625 -26.03373) (xy 289.467796 -26.03373) (xy 289.471867 -25.978108) (xy 289.483993 -25.923671)
			(xy 289.503916 -25.87158) (xy 289.531212 -25.822945) (xy 289.565298 -25.778802) (xy 289.605447 -25.740093)
			(xy 289.650805 -25.707642) (xy 289.700405 -25.682141) (xy 289.753189 -25.664134) (xy 289.808032 -25.654004)
			(xy 289.863766 -25.651967) (xy 289.919203 -25.658067) (xy 289.97316 -25.672173) (xy 290.024489 -25.693985)
			(xy 290.072095 -25.723039) (xy 290.114963 -25.758714) (xy 290.15218 -25.800251) (xy 290.182953 -25.846764)
			(xy 290.206625 -25.897261) (xy 290.222693 -25.950668) (xy 290.230813 -26.005844) (xy 290.231322 -26.03373)
			(xy 290.230813 -26.061616) (xy 290.222693 -26.116792) (xy 290.206625 -26.170199) (xy 290.182953 -26.220696)
			(xy 290.152719 -26.266394) (xy 292.720522 -26.266394) (xy 292.72095 -26.23914) (xy 292.728708 -26.185186)
			(xy 292.744067 -26.132886) (xy 292.766712 -26.083303) (xy 292.796184 -26.037449) (xy 292.831881 -25.996255)
			(xy 292.873078 -25.960562) (xy 292.918935 -25.931095) (xy 292.968519 -25.908454) (xy 293.020821 -25.893101)
			(xy 293.074776 -25.885347) (xy 293.10203 -25.884886) (xy 293.131356 -25.885399) (xy 293.189315 -25.894387)
			(xy 293.245213 -25.912144) (xy 293.297733 -25.938253) (xy 293.321994 -25.954736) (xy 293.332408 -25.961848)
			(xy 293.356792 -25.96515) (xy 293.459154 -25.927304) (xy 293.475918 -25.908762) (xy 293.478966 -25.89657)
			(xy 293.486283 -25.869476) (xy 293.507845 -25.817662) (xy 293.536768 -25.769567) (xy 293.572427 -25.726231)
			(xy 293.614053 -25.688588) (xy 293.660745 -25.657453) (xy 293.711497 -25.633497) (xy 293.765212 -25.617237)
			(xy 293.820729 -25.609025) (xy 293.84879 -25.608534) (xy 293.876046 -25.608912) (xy 293.930004 -25.616669)
			(xy 293.982309 -25.632026) (xy 294.031896 -25.65467) (xy 294.077756 -25.684141) (xy 294.118954 -25.719839)
			(xy 294.154653 -25.761036) (xy 294.184125 -25.806895) (xy 294.206771 -25.856481) (xy 294.222129 -25.908786)
			(xy 294.229887 -25.962744) (xy 294.229887 -25.990042) (xy 295.498772 -25.990042) (xy 295.502843 -25.93442)
			(xy 295.514969 -25.879983) (xy 295.534892 -25.827892) (xy 295.562188 -25.779257) (xy 295.596274 -25.735114)
			(xy 295.636423 -25.696405) (xy 295.681781 -25.663954) (xy 295.731381 -25.638453) (xy 295.784165 -25.620446)
			(xy 295.839008 -25.610316) (xy 295.894742 -25.608279) (xy 295.950179 -25.614379) (xy 296.004136 -25.628485)
			(xy 296.055465 -25.650297) (xy 296.103071 -25.679351) (xy 296.145939 -25.715026) (xy 296.183156 -25.756563)
			(xy 296.213929 -25.803076) (xy 296.237601 -25.853573) (xy 296.253669 -25.90698) (xy 296.261789 -25.962156)
			(xy 296.262298 -25.990042) (xy 296.261789 -26.017928) (xy 296.253669 -26.073104) (xy 296.237601 -26.126511)
			(xy 296.213929 -26.177008) (xy 296.183156 -26.223521) (xy 296.145939 -26.265058) (xy 296.103071 -26.300733)
			(xy 296.055465 -26.329787) (xy 296.004136 -26.351599) (xy 295.950179 -26.365705) (xy 295.894742 -26.371805)
			(xy 295.839008 -26.369768) (xy 295.784165 -26.359638) (xy 295.731381 -26.341631) (xy 295.681781 -26.31613)
			(xy 295.636423 -26.283679) (xy 295.596274 -26.24497) (xy 295.562188 -26.200827) (xy 295.534892 -26.152192)
			(xy 295.514969 -26.100101) (xy 295.502843 -26.045664) (xy 295.498772 -25.990042) (xy 294.229887 -25.990042)
			(xy 294.229887 -26.017256) (xy 294.222129 -26.071214) (xy 294.206771 -26.123519) (xy 294.184125 -26.173105)
			(xy 294.154653 -26.218964) (xy 294.118954 -26.260161) (xy 294.077756 -26.295859) (xy 294.031896 -26.32533)
			(xy 293.982309 -26.347974) (xy 293.930004 -26.363331) (xy 293.876046 -26.371088) (xy 293.84879 -26.37155)
			(xy 293.819465 -26.37102) (xy 293.761507 -26.362037) (xy 293.705609 -26.344284) (xy 293.653088 -26.31818)
			(xy 293.628826 -26.3017) (xy 293.618412 -26.294588) (xy 293.594028 -26.291286) (xy 293.491666 -26.329132)
			(xy 293.474902 -26.347674) (xy 293.471854 -26.359866) (xy 293.465071 -26.384898) (xy 293.445655 -26.432989)
			(xy 293.419899 -26.478003) (xy 293.388277 -26.519109) (xy 293.351374 -26.555549) (xy 293.330884 -26.571448)
			(xy 293.320724 -26.579322) (xy 293.310056 -26.601928) (xy 293.315644 -26.711656) (xy 293.328598 -26.733246)
			(xy 293.33952 -26.73985) (xy 293.363261 -26.754748) (xy 293.406495 -26.790415) (xy 293.444046 -26.832024)
			(xy 293.475105 -26.87868) (xy 293.499004 -26.929377) (xy 293.515228 -26.983025) (xy 293.523429 -27.03847)
			(xy 293.523924 -27.066494) (xy 293.523438 -27.093745) (xy 293.515682 -27.147693) (xy 293.500327 -27.199988)
			(xy 293.477685 -27.249565) (xy 293.448219 -27.295415) (xy 293.412528 -27.336606) (xy 293.371337 -27.372297)
			(xy 293.325487 -27.401763) (xy 293.27591 -27.424405) (xy 293.223615 -27.43976) (xy 293.169667 -27.447516)
			(xy 293.115165 -27.447516) (xy 293.061217 -27.43976) (xy 293.008922 -27.424405) (xy 292.959345 -27.401763)
			(xy 292.913495 -27.372297) (xy 292.872304 -27.336606) (xy 292.836613 -27.295415) (xy 292.807147 -27.249565)
			(xy 292.784505 -27.199988) (xy 292.76915 -27.147693) (xy 292.761394 -27.093745) (xy 292.760908 -27.066494)
			(xy 292.761448 -27.037006) (xy 292.770545 -26.978735) (xy 292.788505 -26.922559) (xy 292.814901 -26.869818)
			(xy 292.849102 -26.821771) (xy 292.890293 -26.779562) (xy 292.913562 -26.76144) (xy 292.923722 -26.753566)
			(xy 292.93439 -26.73096) (xy 292.928802 -26.621232) (xy 292.915848 -26.599642) (xy 292.904926 -26.593038)
			(xy 292.88119 -26.578132) (xy 292.837953 -26.542468) (xy 292.800401 -26.500861) (xy 292.76934 -26.454207)
			(xy 292.74544 -26.40351) (xy 292.729216 -26.349862) (xy 292.721016 -26.294418) (xy 292.720522 -26.266394)
			(xy 290.152719 -26.266394) (xy 290.15218 -26.267209) (xy 290.114963 -26.308746) (xy 290.072095 -26.344421)
			(xy 290.024489 -26.373475) (xy 289.97316 -26.395287) (xy 289.919203 -26.409393) (xy 289.863766 -26.415493)
			(xy 289.808032 -26.413456) (xy 289.753189 -26.403326) (xy 289.700405 -26.385319) (xy 289.650805 -26.359818)
			(xy 289.605447 -26.327367) (xy 289.565298 -26.288658) (xy 289.531212 -26.244515) (xy 289.503916 -26.19588)
			(xy 289.483993 -26.143789) (xy 289.471867 -26.089352) (xy 289.467796 -26.03373) (xy 288.949625 -26.03373)
			(xy 288.946597 -26.054308) (xy 288.930529 -26.107715) (xy 288.906857 -26.158212) (xy 288.876084 -26.204725)
			(xy 288.838867 -26.246262) (xy 288.795999 -26.281937) (xy 288.748393 -26.310991) (xy 288.697064 -26.332803)
			(xy 288.643107 -26.346909) (xy 288.58767 -26.353009) (xy 288.531936 -26.350972) (xy 288.477093 -26.340842)
			(xy 288.424309 -26.322835) (xy 288.374709 -26.297334) (xy 288.329351 -26.264883) (xy 288.289202 -26.226174)
			(xy 288.255116 -26.182031) (xy 288.22782 -26.133396) (xy 288.207897 -26.081305) (xy 288.195771 -26.026868)
			(xy 288.1917 -25.971246) (xy 287.939226 -25.971246) (xy 287.938717 -25.999132) (xy 287.930597 -26.054308)
			(xy 287.914529 -26.107715) (xy 287.890857 -26.158212) (xy 287.860084 -26.204725) (xy 287.822867 -26.246262)
			(xy 287.779999 -26.281937) (xy 287.732393 -26.310991) (xy 287.681064 -26.332803) (xy 287.627107 -26.346909)
			(xy 287.57167 -26.353009) (xy 287.515936 -26.350972) (xy 287.461093 -26.340842) (xy 287.408309 -26.322835)
			(xy 287.358709 -26.297334) (xy 287.313351 -26.264883) (xy 287.273202 -26.226174) (xy 287.239116 -26.182031)
			(xy 287.21182 -26.133396) (xy 287.191897 -26.081305) (xy 287.179771 -26.026868) (xy 287.1757 -25.971246)
			(xy 286.923226 -25.971246) (xy 286.922717 -25.999132) (xy 286.914597 -26.054308) (xy 286.898529 -26.107715)
			(xy 286.874857 -26.158212) (xy 286.844084 -26.204725) (xy 286.806867 -26.246262) (xy 286.763999 -26.281937)
			(xy 286.716393 -26.310991) (xy 286.665064 -26.332803) (xy 286.611107 -26.346909) (xy 286.55567 -26.353009)
			(xy 286.499936 -26.350972) (xy 286.445093 -26.340842) (xy 286.392309 -26.322835) (xy 286.342709 -26.297334)
			(xy 286.297351 -26.264883) (xy 286.257202 -26.226174) (xy 286.223116 -26.182031) (xy 286.19582 -26.133396)
			(xy 286.175897 -26.081305) (xy 286.163771 -26.026868) (xy 286.1597 -25.971246) (xy 285.600902 -25.971246)
			(xy 285.600902 -27.654758) (xy 285.601261 -27.664322) (xy 285.608194 -27.682144) (xy 285.621183 -27.69618)
			(xy 285.629604 -27.700732) (xy 285.629858 -27.700732) (xy 285.656661 -27.714211) (xy 285.706069 -27.74824)
			(xy 285.715243 -27.756955) (xy 288.958943 -27.756955) (xy 288.958943 -27.702445) (xy 288.966701 -27.648489)
			(xy 288.982059 -27.596186) (xy 289.004705 -27.546602) (xy 289.034178 -27.500746) (xy 289.069876 -27.459551)
			(xy 289.111075 -27.423856) (xy 289.156934 -27.394388) (xy 289.20652 -27.371747) (xy 289.258824 -27.356393)
			(xy 289.312781 -27.34864) (xy 289.340036 -27.34818) (xy 289.354121 -27.34828) (xy 289.382217 -27.350315)
			(xy 289.39617 -27.352244) (xy 289.409886 -27.354276) (xy 289.435794 -27.343862) (xy 289.506152 -27.249882)
			(xy 289.5092 -27.221942) (xy 289.503358 -27.209242) (xy 289.492316 -27.184113) (xy 289.476713 -27.131489)
			(xy 289.468806 -27.077174) (xy 289.468306 -27.04973) (xy 289.468792 -27.022479) (xy 289.476548 -26.968531)
			(xy 289.491903 -26.916236) (xy 289.514545 -26.866659) (xy 289.544011 -26.820809) (xy 289.579702 -26.779618)
			(xy 289.620893 -26.743927) (xy 289.666743 -26.714461) (xy 289.71632 -26.691819) (xy 289.768615 -26.676464)
			(xy 289.822563 -26.668708) (xy 289.877065 -26.668708) (xy 289.931013 -26.676464) (xy 289.983308 -26.691819)
			(xy 290.032885 -26.714461) (xy 290.078735 -26.743927) (xy 290.119926 -26.779618) (xy 290.155617 -26.820809)
			(xy 290.185083 -26.866659) (xy 290.207725 -26.916236) (xy 290.22308 -26.968531) (xy 290.230836 -27.022479)
			(xy 290.231322 -27.04973) (xy 290.230699 -27.081146) (xy 290.220437 -27.143133) (xy 290.200163 -27.202602)
			(xy 290.185856 -27.230578) (xy 290.180522 -27.24023) (xy 290.178998 -27.262074) (xy 290.213288 -27.354022)
			(xy 290.228528 -27.369516) (xy 290.238688 -27.37358) (xy 290.26533 -27.384352) (xy 290.315297 -27.412729)
			(xy 290.360441 -27.448284) (xy 290.399736 -27.490212) (xy 290.432295 -27.537562) (xy 290.457378 -27.589262)
			(xy 290.474418 -27.644141) (xy 290.483029 -27.700956) (xy 290.483544 -27.729688) (xy 290.483011 -27.756937)
			(xy 290.475257 -27.810881) (xy 290.459905 -27.863173) (xy 290.437268 -27.912748) (xy 290.407806 -27.958596)
			(xy 290.37212 -27.999786) (xy 290.330935 -28.035477) (xy 290.28509 -28.064945) (xy 290.235518 -28.087588)
			(xy 290.183228 -28.102947) (xy 290.129285 -28.110707) (xy 290.102036 -28.111196) (xy 290.07312 -28.110653)
			(xy 290.01595 -28.10193) (xy 289.960751 -28.084676) (xy 289.90879 -28.059289) (xy 289.861255 -28.02635)
			(xy 289.819237 -27.986613) (xy 289.801046 -27.96413) (xy 289.793472 -27.955382) (xy 289.772722 -27.945194)
			(xy 289.761168 -27.944572) (xy 289.680904 -27.944572) (xy 289.669333 -27.94512) (xy 289.64856 -27.955328)
			(xy 289.641026 -27.96413) (xy 289.622828 -27.986607) (xy 289.580809 -28.026342) (xy 289.533275 -28.05928)
			(xy 289.481315 -28.084669) (xy 289.426119 -28.101928) (xy 289.368951 -28.110659) (xy 289.340036 -28.111196)
			(xy 289.312781 -28.11076) (xy 289.258824 -28.103007) (xy 289.20652 -28.087653) (xy 289.156934 -28.065012)
			(xy 289.111075 -28.035544) (xy 289.069876 -27.999849) (xy 289.034178 -27.958654) (xy 289.004705 -27.912798)
			(xy 288.982059 -27.863214) (xy 288.966701 -27.810911) (xy 288.958943 -27.756955) (xy 285.715243 -27.756955)
			(xy 285.749565 -27.789558) (xy 285.768288 -27.813) (xy 285.770574 -27.816048) (xy 285.773114 -27.818588)
			(xy 285.776162 -27.821636) (xy 285.782121 -27.827146) (xy 285.796625 -27.83441) (xy 285.80461 -27.83586)
			(xy 285.815786 -27.837638) (xy 285.883604 -27.847544) (xy 285.903162 -27.842464) (xy 285.91129 -27.836114)
			(xy 285.93134 -27.821289) (xy 285.974556 -27.796414) (xy 286.020644 -27.777379) (xy 286.068819 -27.764511)
			(xy 286.11826 -27.758027) (xy 286.143192 -27.757628) (xy 286.171242 -27.758123) (xy 286.226737 -27.766336)
			(xy 286.280432 -27.782587) (xy 286.331169 -27.806524) (xy 286.377854 -27.837632) (xy 286.419481 -27.87524)
			(xy 286.455152 -27.918538) (xy 286.47009 -27.942286) (xy 286.473646 -27.947874) (xy 286.482282 -27.956764)
			(xy 286.50819 -27.97175) (xy 286.51835 -27.976322) (xy 286.527748 -27.978608) (xy 286.533844 -27.978862)
			(xy 286.587438 -27.978862) (xy 286.593875 -27.978656) (xy 286.606343 -27.975445) (xy 286.612076 -27.972512)
			(xy 286.63773 -27.958288) (xy 286.646874 -27.949398) (xy 286.65043 -27.94381) (xy 286.661501 -27.926394)
			(xy 286.686829 -27.893811) (xy 286.700976 -27.878786) (xy 286.701484 -27.878278) (xy 286.701992 -27.87777)
			(xy 286.720092 -27.859166) (xy 286.760451 -27.82653) (xy 286.80486 -27.799663) (xy 286.852501 -27.779063)
			(xy 286.902494 -27.765108) (xy 286.953916 -27.758056) (xy 286.979868 -27.757628) (xy 287.007121 -27.758089)
			(xy 287.061074 -27.765843) (xy 287.113374 -27.781196) (xy 287.162955 -27.803837) (xy 287.20881 -27.833305)
			(xy 287.250003 -27.868999) (xy 287.285697 -27.910193) (xy 287.315164 -27.956048) (xy 287.337805 -28.00563)
			(xy 287.353158 -28.05793) (xy 287.360911 -28.111883) (xy 287.361376 -28.139136) (xy 287.86785 -28.139136)
			(xy 287.871921 -28.083514) (xy 287.884047 -28.029077) (xy 287.90397 -27.976986) (xy 287.931266 -27.928351)
			(xy 287.965352 -27.884208) (xy 288.005501 -27.845499) (xy 288.050859 -27.813048) (xy 288.100459 -27.787547)
			(xy 288.153243 -27.76954) (xy 288.208086 -27.75941) (xy 288.26382 -27.757373) (xy 288.319257 -27.763473)
			(xy 288.373214 -27.777579) (xy 288.424543 -27.799391) (xy 288.472149 -27.828445) (xy 288.515017 -27.86412)
			(xy 288.552234 -27.905657) (xy 288.583007 -27.95217) (xy 288.606679 -28.002667) (xy 288.622747 -28.056074)
			(xy 288.630867 -28.11125) (xy 288.631376 -28.139136) (xy 288.630867 -28.167022) (xy 288.622747 -28.222198)
			(xy 288.606679 -28.275605) (xy 288.583007 -28.326102) (xy 288.552234 -28.372615) (xy 288.515017 -28.414152)
			(xy 288.472149 -28.449827) (xy 288.424543 -28.478881) (xy 288.373214 -28.500693) (xy 288.319257 -28.514799)
			(xy 288.26382 -28.520899) (xy 288.208086 -28.518862) (xy 288.153243 -28.508732) (xy 288.100459 -28.490725)
			(xy 288.050859 -28.465224) (xy 288.005501 -28.432773) (xy 287.965352 -28.394064) (xy 287.931266 -28.349921)
			(xy 287.90397 -28.301286) (xy 287.884047 -28.249195) (xy 287.871921 -28.194758) (xy 287.86785 -28.139136)
			(xy 287.361376 -28.139136) (xy 287.36084 -28.168435) (xy 287.351881 -28.226343) (xy 287.334179 -28.282202)
			(xy 287.308149 -28.334701) (xy 287.274404 -28.382606) (xy 287.254442 -28.404058) (xy 287.25368 -28.40482)
			(xy 287.251902 -28.406598) (xy 287.233829 -28.42506) (xy 287.193567 -28.457432) (xy 287.149302 -28.484071)
			(xy 287.101844 -28.504487) (xy 287.052064 -28.518306) (xy 287.000873 -28.525276) (xy 286.975042 -28.525724)
			(xy 286.946489 -28.525187) (xy 286.890022 -28.516671) (xy 286.835453 -28.499838) (xy 286.784001 -28.475064)
			(xy 286.736814 -28.442901) (xy 286.694945 -28.404067) (xy 286.659328 -28.35943) (xy 286.644588 -28.33497)
			(xy 286.639809 -28.327476) (xy 286.626205 -28.316059) (xy 286.609525 -28.30996) (xy 286.600646 -28.30957)
			(xy 286.51454 -28.30957) (xy 286.505747 -28.309933) (xy 286.489198 -28.315879) (xy 286.475643 -28.327081)
			(xy 286.470852 -28.334462) (xy 286.459999 -28.352116) (xy 286.435055 -28.385211) (xy 286.421068 -28.400502)
			(xy 286.420306 -28.401264) (xy 286.41929 -28.402534) (xy 286.418528 -28.403296) (xy 286.418274 -28.40355)
			(xy 286.400144 -28.422463) (xy 286.359602 -28.455645) (xy 286.314903 -28.482974) (xy 286.266888 -28.503934)
			(xy 286.216459 -28.518134) (xy 286.164561 -28.525305) (xy 286.138366 -28.525724) (xy 286.109209 -28.525169)
			(xy 286.051575 -28.516292) (xy 285.995962 -28.498751) (xy 285.943666 -28.472953) (xy 285.895902 -28.439499)
			(xy 285.853785 -28.399168) (xy 285.835598 -28.376372) (xy 285.833312 -28.373324) (xy 285.830772 -28.370784)
			(xy 285.827724 -28.367736) (xy 285.821763 -28.36223) (xy 285.807258 -28.354974) (xy 285.799276 -28.353512)
			(xy 285.729172 -28.343098) (xy 285.719167 -28.342001) (xy 285.699644 -28.346831) (xy 285.691326 -28.352496)
			(xy 285.679388 -28.361132) (xy 285.674562 -28.364434) (xy 285.666434 -28.373324) (xy 285.65221 -28.398978)
			(xy 285.649248 -28.404701) (xy 285.646028 -28.417174) (xy 285.64586 -28.423616) (xy 285.64586 -28.428696)
			(xy 285.646044 -28.435136) (xy 285.649248 -28.447613) (xy 285.65221 -28.453334) (xy 285.656528 -28.460954)
			(xy 285.659715 -28.466304) (xy 285.668186 -28.475425) (xy 285.673292 -28.478988) (xy 285.6738 -28.479242)
			(xy 285.674054 -28.479242) (xy 285.697025 -28.494339) (xy 285.738785 -28.53008) (xy 285.774992 -28.571437)
			(xy 285.804899 -28.617556) (xy 285.827887 -28.667485) (xy 285.843483 -28.720193) (xy 285.851364 -28.774593)
			(xy 285.851854 -28.802076) (xy 285.851338 -28.83078) (xy 285.842741 -28.887541) (xy 285.825737 -28.942374)
			(xy 285.80071 -28.994041) (xy 285.768226 -29.041375) (xy 285.748984 -29.06268) (xy 285.748476 -29.063188)
			(xy 285.747714 -29.064204) (xy 285.746444 -29.065474) (xy 285.745936 -29.065982) (xy 285.729252 -29.083504)
			(xy 285.692207 -29.114626) (xy 285.651529 -29.140822) (xy 285.629858 -29.15158) (xy 285.616396 -29.15793)
			(xy 285.600902 -29.182568) (xy 285.600902 -29.222446) (xy 285.601342 -29.232121) (xy 285.60851 -29.250098)
			(xy 285.621786 -29.26418) (xy 285.630366 -29.268674) (xy 285.654811 -29.280478) (xy 285.700379 -29.309979)
			(xy 285.7413 -29.345647) (xy 285.776747 -29.386758) (xy 285.806004 -29.432483) (xy 285.828477 -29.481896)
			(xy 285.843713 -29.533998) (xy 285.851404 -29.587734) (xy 285.851854 -29.614876) (xy 285.851324 -29.644139)
			(xy 285.842391 -29.701978) (xy 285.82473 -29.757776) (xy 285.798756 -29.810222) (xy 285.765078 -29.858087)
			(xy 285.745174 -29.879544) (xy 285.744666 -29.880052) (xy 285.744158 -29.88056) (xy 285.733816 -29.891405)
			(xy 285.711695 -29.911624) (xy 285.699962 -29.920946) (xy 285.691132 -29.928537) (xy 285.680943 -29.949446)
			(xy 285.680404 -29.961078) (xy 285.680404 -30.02026) (xy 285.680586 -30.026063) (xy 285.683274 -30.037355)
			(xy 285.685738 -30.042612) (xy 285.697676 -30.066996) (xy 285.704534 -30.075632) (xy 285.708852 -30.078934)
			(xy 285.73076 -30.097164) (xy 285.769444 -30.139017) (xy 285.801471 -30.186159) (xy 285.82613 -30.23754)
			(xy 285.842871 -30.292018) (xy 285.851322 -30.34838) (xy 285.851854 -30.376876) (xy 285.851338 -30.40558)
			(xy 285.842741 -30.462341) (xy 285.825737 -30.517174) (xy 285.80071 -30.568841) (xy 285.768226 -30.616175)
			(xy 285.748984 -30.63748) (xy 285.748476 -30.637988) (xy 285.747714 -30.639004) (xy 285.746444 -30.640274)
			(xy 285.745936 -30.640782) (xy 285.729252 -30.658304) (xy 285.692207 -30.689426) (xy 285.651529 -30.715622)
			(xy 285.629858 -30.72638) (xy 285.616396 -30.73273) (xy 285.600902 -30.757368) (xy 285.600902 -31.159958)
			(xy 285.625032 -31.188406) (xy 285.64332 -31.191454) (xy 285.670458 -31.196471) (xy 285.723019 -31.213291)
			(xy 285.772609 -31.237508) (xy 285.818192 -31.268618) (xy 285.858817 -31.30597) (xy 285.893637 -31.348785)
			(xy 285.921926 -31.396171) (xy 285.943092 -31.447137) (xy 285.956694 -31.500622) (xy 285.962449 -31.555508)
			(xy 285.960236 -31.61065) (xy 285.950102 -31.664899) (xy 285.932258 -31.717121) (xy 285.931158 -31.719266)
			(xy 286.485328 -31.719266) (xy 286.489399 -31.663644) (xy 286.501525 -31.609207) (xy 286.521448 -31.557116)
			(xy 286.548744 -31.508481) (xy 286.58283 -31.464338) (xy 286.622979 -31.425629) (xy 286.668337 -31.393178)
			(xy 286.717937 -31.367677) (xy 286.770721 -31.34967) (xy 286.825564 -31.33954) (xy 286.881298 -31.337503)
			(xy 286.936735 -31.343603) (xy 286.990692 -31.357709) (xy 287.042021 -31.379521) (xy 287.089627 -31.408575)
			(xy 287.132495 -31.44425) (xy 287.169712 -31.485787) (xy 287.200485 -31.5323) (xy 287.224157 -31.582797)
			(xy 287.240225 -31.636204) (xy 287.244375 -31.664402) (xy 287.760916 -31.664402) (xy 287.764987 -31.60878)
			(xy 287.777113 -31.554343) (xy 287.797036 -31.502252) (xy 287.824332 -31.453617) (xy 287.858418 -31.409474)
			(xy 287.898567 -31.370765) (xy 287.943925 -31.338314) (xy 287.993525 -31.312813) (xy 288.046309 -31.294806)
			(xy 288.101152 -31.284676) (xy 288.156886 -31.282639) (xy 288.212323 -31.288739) (xy 288.26628 -31.302845)
			(xy 288.317609 -31.324657) (xy 288.365215 -31.353711) (xy 288.408083 -31.389386) (xy 288.4453 -31.430923)
			(xy 288.476073 -31.477436) (xy 288.499745 -31.527933) (xy 288.515813 -31.58134) (xy 288.523933 -31.636516)
			(xy 288.524442 -31.664402) (xy 288.523933 -31.692288) (xy 288.515813 -31.747464) (xy 288.506873 -31.777178)
			(xy 289.02609 -31.777178) (xy 289.030161 -31.721556) (xy 289.042287 -31.667119) (xy 289.06221 -31.615028)
			(xy 289.089506 -31.566393) (xy 289.123592 -31.52225) (xy 289.163741 -31.483541) (xy 289.209099 -31.45109)
			(xy 289.258699 -31.425589) (xy 289.311483 -31.407582) (xy 289.366326 -31.397452) (xy 289.42206 -31.395415)
			(xy 289.477497 -31.401515) (xy 289.531454 -31.415621) (xy 289.582783 -31.437433) (xy 289.630389 -31.466487)
			(xy 289.673257 -31.502162) (xy 289.710474 -31.543699) (xy 289.741247 -31.590212) (xy 289.764919 -31.640709)
			(xy 289.780987 -31.694116) (xy 289.789107 -31.749292) (xy 289.789616 -31.777178) (xy 289.789107 -31.805064)
			(xy 289.780987 -31.86024) (xy 289.764919 -31.913647) (xy 289.741247 -31.964144) (xy 289.710474 -32.010657)
			(xy 289.673257 -32.052194) (xy 289.630389 -32.087869) (xy 289.582783 -32.116923) (xy 289.531454 -32.138735)
			(xy 289.477497 -32.152841) (xy 289.42206 -32.158941) (xy 289.366326 -32.156904) (xy 289.311483 -32.146774)
			(xy 289.258699 -32.128767) (xy 289.209099 -32.103266) (xy 289.163741 -32.070815) (xy 289.123592 -32.032106)
			(xy 289.089506 -31.987963) (xy 289.06221 -31.939328) (xy 289.042287 -31.887237) (xy 289.030161 -31.8328)
			(xy 289.02609 -31.777178) (xy 288.506873 -31.777178) (xy 288.499745 -31.800871) (xy 288.476073 -31.851368)
			(xy 288.4453 -31.897881) (xy 288.408083 -31.939418) (xy 288.365215 -31.975093) (xy 288.317609 -32.004147)
			(xy 288.26628 -32.025959) (xy 288.212323 -32.040065) (xy 288.156886 -32.046165) (xy 288.101152 -32.044128)
			(xy 288.046309 -32.033998) (xy 287.993525 -32.015991) (xy 287.943925 -31.99049) (xy 287.898567 -31.958039)
			(xy 287.858418 -31.91933) (xy 287.824332 -31.875187) (xy 287.797036 -31.826552) (xy 287.777113 -31.774461)
			(xy 287.764987 -31.720024) (xy 287.760916 -31.664402) (xy 287.244375 -31.664402) (xy 287.248345 -31.69138)
			(xy 287.248854 -31.719266) (xy 287.248345 -31.747152) (xy 287.240225 -31.802328) (xy 287.224157 -31.855735)
			(xy 287.200485 -31.906232) (xy 287.169712 -31.952745) (xy 287.132495 -31.994282) (xy 287.089627 -32.029957)
			(xy 287.042021 -32.059011) (xy 286.990692 -32.080823) (xy 286.936735 -32.094929) (xy 286.881298 -32.101029)
			(xy 286.825564 -32.098992) (xy 286.770721 -32.088862) (xy 286.717937 -32.070855) (xy 286.668337 -32.045354)
			(xy 286.622979 -32.012903) (xy 286.58283 -31.974194) (xy 286.548744 -31.930051) (xy 286.521448 -31.881416)
			(xy 286.501525 -31.829325) (xy 286.489399 -31.774888) (xy 286.485328 -31.719266) (xy 285.931158 -31.719266)
			(xy 285.907076 -31.766228) (xy 285.875081 -31.811194) (xy 285.856426 -31.831534) (xy 285.855918 -31.832042)
			(xy 285.85541 -31.832804) (xy 285.833992 -31.854964) (xy 285.785313 -31.892755) (xy 285.731195 -31.922234)
			(xy 285.673042 -31.942633) (xy 285.642812 -31.948628) (xy 285.624524 -31.95193) (xy 285.600902 -31.97987)
			(xy 285.600902 -33.512506) (xy 285.601282 -33.521932) (xy 285.608108 -33.539506) (xy 285.620832 -33.553417)
			(xy 285.629096 -33.557972) (xy 285.630366 -33.558734) (xy 285.716726 -33.595818) (xy 285.723862 -33.59865)
			(xy 285.739116 -33.600332) (xy 285.746698 -33.59912) (xy 285.754572 -33.597596) (xy 285.767526 -33.590738)
			(xy 285.77286 -33.585404) (xy 285.794392 -33.565056) (xy 285.842578 -33.530595) (xy 285.895511 -33.503995)
			(xy 285.95192 -33.485897) (xy 286.010448 -33.476736) (xy 286.040068 -33.476184) (xy 286.067171 -33.476658)
			(xy 286.120833 -33.48433) (xy 286.172867 -33.499524) (xy 286.222224 -33.521934) (xy 286.267911 -33.551108)
			(xy 286.309005 -33.586459) (xy 286.344679 -33.627272) (xy 286.374214 -33.672726) (xy 286.397014 -33.721905)
			(xy 286.40532 -33.74771) (xy 286.408114 -33.756854) (xy 286.419544 -33.771586) (xy 286.485584 -33.81121)
			(xy 286.493712 -33.812734) (xy 286.516273 -33.807503) (xy 286.562248 -33.801901) (xy 286.585406 -33.801558)
			(xy 286.612658 -33.802044) (xy 286.666607 -33.809801) (xy 286.718903 -33.825156) (xy 286.768481 -33.847798)
			(xy 286.783878 -33.857692) (xy 287.69005 -33.857692) (xy 287.694121 -33.80207) (xy 287.706247 -33.747633)
			(xy 287.72617 -33.695542) (xy 287.753466 -33.646907) (xy 287.787552 -33.602764) (xy 287.827701 -33.564055)
			(xy 287.873059 -33.531604) (xy 287.922659 -33.506103) (xy 287.975443 -33.488096) (xy 288.030286 -33.477966)
			(xy 288.08602 -33.475929) (xy 288.141457 -33.482029) (xy 288.195414 -33.496135) (xy 288.246743 -33.517947)
			(xy 288.294349 -33.547001) (xy 288.337217 -33.582676) (xy 288.374434 -33.624213) (xy 288.405207 -33.670726)
			(xy 288.428879 -33.721223) (xy 288.444947 -33.77463) (xy 288.453067 -33.829806) (xy 288.453576 -33.857692)
			(xy 288.453067 -33.885578) (xy 288.444947 -33.940754) (xy 288.428879 -33.994161) (xy 288.405207 -34.044658)
			(xy 288.374434 -34.091171) (xy 288.337217 -34.132708) (xy 288.294349 -34.168383) (xy 288.246743 -34.197437)
			(xy 288.195414 -34.219249) (xy 288.141457 -34.233355) (xy 288.08602 -34.239455) (xy 288.030286 -34.237418)
			(xy 287.975443 -34.227288) (xy 287.922659 -34.209281) (xy 287.873059 -34.18378) (xy 287.827701 -34.151329)
			(xy 287.787552 -34.11262) (xy 287.753466 -34.068477) (xy 287.72617 -34.019842) (xy 287.706247 -33.967751)
			(xy 287.694121 -33.913314) (xy 287.69005 -33.857692) (xy 286.783878 -33.857692) (xy 286.814333 -33.877263)
			(xy 286.855526 -33.912954) (xy 286.89122 -33.954144) (xy 286.920689 -33.999994) (xy 286.943334 -34.049571)
			(xy 286.958693 -34.101866) (xy 286.966454 -34.155814) (xy 286.966914 -34.183066) (xy 286.966375 -34.212363)
			(xy 286.957411 -34.270268) (xy 286.939703 -34.326123) (xy 286.913668 -34.378615) (xy 286.879916 -34.426513)
			(xy 286.85998 -34.447988) (xy 286.859218 -34.44875) (xy 286.85744 -34.450528) (xy 286.83937 -34.468994)
			(xy 286.799111 -34.501377) (xy 286.754846 -34.528025) (xy 286.707388 -34.548449) (xy 286.657607 -34.562276)
			(xy 286.606413 -34.569253) (xy 286.58058 -34.569654) (xy 286.553971 -34.569198) (xy 286.501269 -34.561813)
			(xy 286.450104 -34.547177) (xy 286.40147 -34.525572) (xy 286.356309 -34.497418) (xy 286.3155 -34.463262)
			(xy 286.279833 -34.423766) (xy 286.250001 -34.379697) (xy 286.226582 -34.33191) (xy 286.217868 -34.306764)
			(xy 286.217614 -34.306256) (xy 286.214443 -34.297742) (xy 286.203109 -34.28356) (xy 286.195516 -34.27857)
			(xy 286.130238 -34.239708) (xy 286.112458 -34.236406) (xy 286.103314 -34.238184) (xy 286.086503 -34.241026)
			(xy 286.052544 -34.244076) (xy 286.035496 -34.24428) (xy 286.035242 -34.24428) (xy 286.006232 -34.243736)
			(xy 285.94888 -34.234953) (xy 285.893516 -34.217596) (xy 285.841413 -34.192067) (xy 285.793771 -34.158952)
			(xy 285.772352 -34.139378) (xy 285.761176 -34.128964) (xy 285.731458 -34.12363) (xy 285.631636 -34.166302)
			(xy 285.622714 -34.170638) (xy 285.608827 -34.184775) (xy 285.60135 -34.203128) (xy 285.600902 -34.213038)
			(xy 285.600902 -35.264852) (xy 288.102292 -35.264852) (xy 288.106363 -35.20923) (xy 288.118489 -35.154793)
			(xy 288.138412 -35.102702) (xy 288.165708 -35.054067) (xy 288.199794 -35.009924) (xy 288.239943 -34.971215)
			(xy 288.285301 -34.938764) (xy 288.334901 -34.913263) (xy 288.387685 -34.895256) (xy 288.442528 -34.885126)
			(xy 288.498262 -34.883089) (xy 288.553699 -34.889189) (xy 288.607656 -34.903295) (xy 288.658985 -34.925107)
			(xy 288.706591 -34.954161) (xy 288.749459 -34.989836) (xy 288.774292 -35.017552) (xy 290.419756 -35.017552)
			(xy 290.419756 -34.963048) (xy 290.427513 -34.909098) (xy 290.442868 -34.856801) (xy 290.46551 -34.807221)
			(xy 290.494977 -34.761369) (xy 290.530669 -34.720176) (xy 290.571861 -34.684483) (xy 290.617713 -34.655015)
			(xy 290.667291 -34.632372) (xy 290.719588 -34.617015) (xy 290.773538 -34.609257) (xy 290.80079 -34.60877)
			(xy 290.817902 -34.608957) (xy 290.851989 -34.612012) (xy 290.868862 -34.614866) (xy 290.880126 -34.616292)
			(xy 290.902012 -34.610343) (xy 290.911026 -34.603436) (xy 290.93541 -34.582354) (xy 290.943805 -34.574435)
			(xy 290.952923 -34.553256) (xy 290.952936 -34.541714) (xy 290.952428 -34.52241) (xy 290.952428 -33.65881)
			(xy 290.952936 -33.638744) (xy 290.952765 -33.627235) (xy 290.943662 -33.606128) (xy 290.93541 -33.598104)
			(xy 290.911026 -33.577022) (xy 290.902022 -33.570095) (xy 290.88013 -33.564153) (xy 290.868862 -33.565592)
			(xy 290.85199 -33.568455) (xy 290.817902 -33.571512) (xy 290.80079 -33.571688) (xy 290.773538 -33.571241)
			(xy 290.719588 -33.563483) (xy 290.667292 -33.548127) (xy 290.617713 -33.525484) (xy 290.571862 -33.496016)
			(xy 290.530671 -33.460322) (xy 290.494978 -33.41913) (xy 290.465511 -33.373278) (xy 290.44287 -33.323699)
			(xy 290.427514 -33.271402) (xy 290.419758 -33.217452) (xy 290.419758 -33.162948) (xy 290.427514 -33.108998)
			(xy 290.44287 -33.056701) (xy 290.465511 -33.007122) (xy 290.494978 -32.96127) (xy 290.530671 -32.920078)
			(xy 290.571862 -32.884384) (xy 290.617713 -32.854916) (xy 290.667292 -32.832273) (xy 290.719588 -32.816917)
			(xy 290.773538 -32.809159) (xy 290.80079 -32.808672) (xy 290.827798 -32.809129) (xy 290.881276 -32.816734)
			(xy 290.933146 -32.831807) (xy 290.982371 -32.854048) (xy 291.027966 -32.883011) (xy 291.069019 -32.918116)
			(xy 291.104708 -32.958663) (xy 291.13432 -33.003838) (xy 291.157263 -33.05274) (xy 291.173078 -33.104389)
			(xy 291.177726 -33.130998) (xy 291.17925 -33.141666) (xy 291.19068 -33.159446) (xy 291.270944 -33.212786)
			(xy 291.291518 -33.216596) (xy 291.302186 -33.214056) (xy 291.328817 -33.207922) (xy 291.383066 -33.201304)
			(xy 291.41039 -33.200848) (xy 291.437714 -33.201312) (xy 291.491962 -33.207927) (xy 291.518594 -33.214056)
			(xy 291.529262 -33.216596) (xy 291.549836 -33.212786) (xy 291.6301 -33.159446) (xy 291.64153 -33.141666)
			(xy 291.643054 -33.130998) (xy 291.647668 -33.104385) (xy 291.663502 -33.052744) (xy 291.68646 -33.003852)
			(xy 291.716081 -32.958685) (xy 291.751776 -32.918146) (xy 291.792829 -32.883045) (xy 291.838422 -32.854083)
			(xy 291.887643 -32.831839) (xy 291.939509 -32.816758) (xy 291.992983 -32.809141) (xy 292.01999 -32.808672)
			(xy 292.047361 -32.809126) (xy 292.101541 -32.816944) (xy 292.154045 -32.832435) (xy 292.203792 -32.85528)
			(xy 292.249757 -32.885009) (xy 292.270688 -32.902652) (xy 292.2778 -32.908748) (xy 292.294818 -32.915098)
			(xy 292.380162 -32.915098) (xy 292.39718 -32.908748) (xy 292.404292 -32.902652) (xy 292.425223 -32.885011)
			(xy 292.471195 -32.855298) (xy 292.520943 -32.832461) (xy 292.573444 -32.816971) (xy 292.627621 -32.809145)
			(xy 292.65499 -32.808672) (xy 292.672102 -32.808859) (xy 292.706189 -32.811914) (xy 292.723062 -32.814768)
			(xy 292.734326 -32.816193) (xy 292.756212 -32.810244) (xy 292.765226 -32.803338) (xy 292.78961 -32.782256)
			(xy 292.798004 -32.774336) (xy 292.807123 -32.753158) (xy 292.807136 -32.741616) (xy 292.806628 -32.722312)
			(xy 292.806628 -31.858712) (xy 292.807136 -31.838646) (xy 292.806964 -31.827137) (xy 292.797862 -31.80603)
			(xy 292.78961 -31.798006) (xy 292.765226 -31.776924) (xy 292.756222 -31.769998) (xy 292.73433 -31.764055)
			(xy 292.723062 -31.765494) (xy 292.70619 -31.768357) (xy 292.672102 -31.771414) (xy 292.65499 -31.77159)
			(xy 292.627619 -31.771132) (xy 292.57344 -31.763313) (xy 292.520937 -31.747822) (xy 292.47119 -31.724978)
			(xy 292.425223 -31.695252) (xy 292.404292 -31.67761) (xy 292.39718 -31.671514) (xy 292.380416 -31.665164)
			(xy 292.294818 -31.665164) (xy 292.2778 -31.671514) (xy 292.270942 -31.677864) (xy 292.249992 -31.695523)
			(xy 292.203976 -31.725263) (xy 292.154176 -31.74811) (xy 292.101618 -31.763593) (xy 292.047386 -31.771392)
			(xy 292.01999 -31.771844) (xy 291.993012 -31.771383) (xy 291.939593 -31.763801) (xy 291.887776 -31.74876)
			(xy 291.838599 -31.726562) (xy 291.793044 -31.697651) (xy 291.752021 -31.662604) (xy 291.716351 -31.622122)
			(xy 291.686747 -31.577014) (xy 291.6638 -31.528182) (xy 291.647969 -31.476602) (xy 291.643308 -31.450026)
			(xy 291.64153 -31.439358) (xy 291.6301 -31.421832) (xy 291.549836 -31.368238) (xy 291.529262 -31.364682)
			(xy 291.518848 -31.367222) (xy 291.492148 -31.373301) (xy 291.437771 -31.379791) (xy 291.41039 -31.380176)
			(xy 291.383008 -31.379799) (xy 291.328632 -31.373306) (xy 291.301932 -31.367222) (xy 291.291518 -31.364682)
			(xy 291.270944 -31.368238) (xy 291.19068 -31.421832) (xy 291.17925 -31.439358) (xy 291.177472 -31.450026)
			(xy 291.172778 -31.476591) (xy 291.156923 -31.528154) (xy 291.133962 -31.576968) (xy 291.104352 -31.622061)
			(xy 291.068684 -31.662532) (xy 291.027671 -31.697574) (xy 290.982129 -31.726488) (xy 290.932968 -31.748697)
			(xy 290.881168 -31.763758) (xy 290.827762 -31.771371) (xy 290.80079 -31.771844) (xy 290.773542 -31.771285)
			(xy 290.7196 -31.763528) (xy 290.667312 -31.748174) (xy 290.617741 -31.725534) (xy 290.571896 -31.69607)
			(xy 290.530711 -31.660382) (xy 290.495024 -31.619196) (xy 290.465561 -31.573351) (xy 290.442923 -31.523779)
			(xy 290.42757 -31.47149) (xy 290.419814 -31.417548) (xy 290.419814 -31.363052) (xy 290.42757 -31.30911)
			(xy 290.442923 -31.256821) (xy 290.465561 -31.207249) (xy 290.495024 -31.161404) (xy 290.530711 -31.120218)
			(xy 290.571896 -31.08453) (xy 290.617741 -31.055066) (xy 290.667312 -31.032426) (xy 290.7196 -31.017072)
			(xy 290.773542 -31.009315) (xy 290.80079 -31.008828) (xy 290.817902 -31.009016) (xy 290.851989 -31.01207)
			(xy 290.868862 -31.014924) (xy 290.880126 -31.016359) (xy 290.902014 -31.010405) (xy 290.911026 -31.003494)
			(xy 290.93541 -30.982412) (xy 290.943778 -30.974468) (xy 290.952911 -30.953309) (xy 290.952936 -30.941772)
			(xy 290.952428 -30.922468) (xy 290.952428 -30.058868) (xy 290.952936 -30.038802) (xy 290.952732 -30.027296)
			(xy 290.943652 -30.00619) (xy 290.93541 -29.998162) (xy 290.911026 -29.97708) (xy 290.902025 -29.97015)
			(xy 290.88013 -29.964212) (xy 290.868862 -29.96565) (xy 290.85199 -29.968514) (xy 290.817902 -29.97157)
			(xy 290.80079 -29.971746) (xy 290.773542 -29.971183) (xy 290.719601 -29.963426) (xy 290.667312 -29.948072)
			(xy 290.617742 -29.925432) (xy 290.571897 -29.895969) (xy 290.530712 -29.860281) (xy 290.495025 -29.819095)
			(xy 290.465563 -29.77325) (xy 290.442925 -29.723678) (xy 290.427572 -29.671389) (xy 290.419816 -29.617448)
			(xy 290.419816 -29.562952) (xy 290.427572 -29.509011) (xy 290.442925 -29.456722) (xy 290.465563 -29.40715)
			(xy 290.495025 -29.361305) (xy 290.530712 -29.320119) (xy 290.571897 -29.284431) (xy 290.617742 -29.254968)
			(xy 290.667312 -29.232328) (xy 290.719601 -29.216974) (xy 290.773542 -29.209217) (xy 290.80079 -29.20873)
			(xy 290.827797 -29.209222) (xy 290.881271 -29.216826) (xy 290.933139 -29.231898) (xy 290.982361 -29.254135)
			(xy 291.027955 -29.283095) (xy 291.069007 -29.318196) (xy 291.104697 -29.358737) (xy 291.134311 -29.403908)
			(xy 291.157257 -29.452804) (xy 291.173075 -29.504449) (xy 291.177726 -29.531056) (xy 291.17925 -29.541724)
			(xy 291.19068 -29.559504) (xy 291.270944 -29.612844) (xy 291.291518 -29.616654) (xy 291.302186 -29.614114)
			(xy 291.328826 -29.608056) (xy 291.383073 -29.60156) (xy 291.41039 -29.60116) (xy 291.437708 -29.601542)
			(xy 291.491957 -29.60804) (xy 291.518594 -29.614114) (xy 291.529262 -29.616654) (xy 291.549836 -29.612844)
			(xy 291.6301 -29.559504) (xy 291.64153 -29.541724) (xy 291.643054 -29.531056) (xy 291.647713 -29.504451)
			(xy 291.663539 -29.45281) (xy 291.686489 -29.403917) (xy 291.716105 -29.35875) (xy 291.751794 -29.318209)
			(xy 291.792843 -29.283107) (xy 291.838432 -29.254144) (xy 291.88765 -29.231899) (xy 291.939513 -29.216817)
			(xy 291.992984 -29.209199) (xy 292.01999 -29.20873) (xy 292.04736 -29.209195) (xy 292.10154 -29.217012)
			(xy 292.154043 -29.232501) (xy 292.20379 -29.255343) (xy 292.249757 -29.285068) (xy 292.270688 -29.30271)
			(xy 292.2778 -29.308806) (xy 292.294818 -29.315156) (xy 292.380162 -29.315156) (xy 292.39718 -29.308806)
			(xy 292.404292 -29.30271) (xy 292.425218 -29.285063) (xy 292.471192 -29.255352) (xy 292.520941 -29.232517)
			(xy 292.573443 -29.217028) (xy 292.62762 -29.209203) (xy 292.65499 -29.20873) (xy 292.672102 -29.208918)
			(xy 292.706189 -29.211972) (xy 292.723062 -29.214826) (xy 292.734326 -29.216261) (xy 292.756214 -29.210307)
			(xy 292.765226 -29.203396) (xy 292.78961 -29.182314) (xy 292.797977 -29.17437) (xy 292.807111 -29.153211)
			(xy 292.807136 -29.141674) (xy 292.806628 -29.12237) (xy 292.806628 -28.25877) (xy 292.807136 -28.238704)
			(xy 292.806931 -28.227198) (xy 292.797852 -28.206092) (xy 292.78961 -28.198064) (xy 292.765226 -28.176982)
			(xy 292.756225 -28.170052) (xy 292.73433 -28.164114) (xy 292.723062 -28.165552) (xy 292.70619 -28.168416)
			(xy 292.672102 -28.171472) (xy 292.65499 -28.171648) (xy 292.627742 -28.171081) (xy 292.573801 -28.163324)
			(xy 292.521513 -28.14797) (xy 292.471942 -28.125331) (xy 292.426098 -28.095867) (xy 292.384913 -28.060179)
			(xy 292.349227 -28.018994) (xy 292.319765 -27.973149) (xy 292.297127 -27.923577) (xy 292.281774 -27.871289)
			(xy 292.274018 -27.817348) (xy 292.274018 -27.762852) (xy 292.281774 -27.708911) (xy 292.297127 -27.656623)
			(xy 292.319765 -27.607051) (xy 292.349227 -27.561206) (xy 292.384913 -27.520021) (xy 292.426098 -27.484333)
			(xy 292.471942 -27.454869) (xy 292.521513 -27.43223) (xy 292.573801 -27.416876) (xy 292.627742 -27.409119)
			(xy 292.65499 -27.408632) (xy 292.681997 -27.409122) (xy 292.735472 -27.416726) (xy 292.787339 -27.431798)
			(xy 292.836562 -27.454036) (xy 292.882155 -27.482995) (xy 292.923207 -27.518097) (xy 292.958897 -27.558638)
			(xy 292.988511 -27.603809) (xy 293.011457 -27.652706) (xy 293.027275 -27.704351) (xy 293.031926 -27.730958)
			(xy 293.03345 -27.741626) (xy 293.04488 -27.759406) (xy 293.125144 -27.812746) (xy 293.145718 -27.816556)
			(xy 293.156386 -27.814016) (xy 293.183017 -27.807881) (xy 293.237265 -27.801264) (xy 293.26459 -27.800808)
			(xy 293.286769 -27.801096) (xy 293.330914 -27.805426) (xy 293.352728 -27.809444) (xy 293.363142 -27.811476)
			(xy 293.382954 -27.807412) (xy 293.459916 -27.754072) (xy 293.470838 -27.737054) (xy 293.472616 -27.72664)
			(xy 293.477549 -27.700309) (xy 293.493762 -27.649253) (xy 293.516959 -27.600967) (xy 293.546684 -27.556401)
			(xy 293.582351 -27.516432) (xy 293.623259 -27.481846) (xy 293.668603 -27.453323) (xy 293.717492 -27.431425)
			(xy 293.768963 -27.416582) (xy 293.822005 -27.409086) (xy 293.84879 -27.408632) (xy 293.876046 -27.409014)
			(xy 293.930004 -27.416771) (xy 293.982309 -27.432128) (xy 294.031895 -27.454772) (xy 294.077754 -27.484243)
			(xy 294.118953 -27.51994) (xy 294.154651 -27.561138) (xy 294.184123 -27.606996) (xy 294.206769 -27.656582)
			(xy 294.222127 -27.708886) (xy 294.229885 -27.762844) (xy 294.229885 -27.817356) (xy 294.222127 -27.871314)
			(xy 294.206769 -27.923618) (xy 294.184123 -27.973204) (xy 294.154651 -28.019062) (xy 294.118953 -28.06026)
			(xy 294.077754 -28.095957) (xy 294.031895 -28.125428) (xy 293.982309 -28.148072) (xy 293.930004 -28.163429)
			(xy 293.876046 -28.171186) (xy 293.84879 -28.171648) (xy 293.837268 -28.171552) (xy 293.814265 -28.170155)
			(xy 293.802816 -28.168854) (xy 293.791902 -28.168099) (xy 293.771104 -28.174822) (xy 293.762684 -28.181808)
			(xy 293.738808 -28.203398) (xy 293.730945 -28.211242) (xy 293.722265 -28.231663) (xy 293.722044 -28.242768)
			(xy 293.722552 -28.25877) (xy 293.722552 -29.12237) (xy 293.722298 -29.137356) (xy 293.722444 -29.14844)
			(xy 293.731 -29.168859) (xy 293.738808 -29.176726) (xy 293.762684 -29.198316) (xy 293.771112 -29.205287)
			(xy 293.791904 -29.212005) (xy 293.802816 -29.21127) (xy 293.814264 -29.20996) (xy 293.837267 -29.208561)
			(xy 293.84879 -29.208476) (xy 293.876042 -29.208971) (xy 293.929992 -29.216726) (xy 293.982289 -29.232081)
			(xy 294.031868 -29.254722) (xy 294.077721 -29.284188) (xy 294.118913 -29.31988) (xy 294.154606 -29.361071)
			(xy 294.184074 -29.406923) (xy 294.206716 -29.456502) (xy 294.222072 -29.508798) (xy 294.229829 -29.562748)
			(xy 294.229829 -29.617252) (xy 294.222072 -29.671202) (xy 294.206716 -29.723498) (xy 294.184074 -29.773077)
			(xy 294.154606 -29.818929) (xy 294.118913 -29.86012) (xy 294.077721 -29.895812) (xy 294.031868 -29.925278)
			(xy 293.982289 -29.947919) (xy 293.929992 -29.963274) (xy 293.876042 -29.971029) (xy 293.84879 -29.971492)
			(xy 293.822042 -29.971032) (xy 293.769074 -29.963537) (xy 293.717671 -29.948723) (xy 293.668837 -29.926881)
			(xy 293.62353 -29.898437) (xy 293.582636 -29.863949) (xy 293.546955 -29.824091) (xy 293.517186 -29.779643)
			(xy 293.493911 -29.731476) (xy 293.477586 -29.680532) (xy 293.472616 -29.654246) (xy 293.470838 -29.643832)
			(xy 293.46017 -29.626814) (xy 293.382954 -29.573728) (xy 293.363142 -29.569664) (xy 293.352982 -29.571696)
			(xy 293.331108 -29.575741) (xy 293.286833 -29.580069) (xy 293.26459 -29.580332) (xy 293.237202 -29.579894)
			(xy 293.182826 -29.573269) (xy 293.156132 -29.567124) (xy 293.145718 -29.564584) (xy 293.125144 -29.56814)
			(xy 293.04488 -29.621734) (xy 293.03345 -29.63926) (xy 293.031672 -29.649928) (xy 293.02698 -29.676494)
			(xy 293.011125 -29.728056) (xy 292.988163 -29.776871) (xy 292.958553 -29.821963) (xy 292.922885 -29.862434)
			(xy 292.881871 -29.897476) (xy 292.836329 -29.92639) (xy 292.787168 -29.948599) (xy 292.735368 -29.96366)
			(xy 292.681962 -29.971273) (xy 292.65499 -29.971746) (xy 292.627619 -29.971299) (xy 292.573438 -29.963479)
			(xy 292.520935 -29.947986) (xy 292.471188 -29.925139) (xy 292.425223 -29.89541) (xy 292.404292 -29.877766)
			(xy 292.39718 -29.87167) (xy 292.380162 -29.86532) (xy 292.294818 -29.86532) (xy 292.2778 -29.87167)
			(xy 292.270688 -29.877766) (xy 292.249729 -29.895372) (xy 292.203764 -29.92509) (xy 292.154024 -29.947933)
			(xy 292.101529 -29.963432) (xy 292.047357 -29.971268) (xy 292.01999 -29.971746) (xy 292.002878 -29.971561)
			(xy 291.968791 -29.968505) (xy 291.951918 -29.96565) (xy 291.940651 -29.96427) (xy 291.91877 -29.970187)
			(xy 291.909754 -29.97708) (xy 291.88537 -29.998162) (xy 291.876964 -30.006071) (xy 291.867853 -30.027257)
			(xy 291.867844 -30.038802) (xy 291.868352 -30.058868) (xy 291.868352 -30.922468) (xy 291.867844 -30.941772)
			(xy 291.868011 -30.953281) (xy 291.877118 -30.974387) (xy 291.88537 -30.982412) (xy 291.909754 -31.003494)
			(xy 291.918764 -31.010411) (xy 291.940651 -31.016358) (xy 291.951918 -31.014924) (xy 291.968788 -31.012049)
			(xy 292.002877 -31.009) (xy 292.01999 -31.008828) (xy 292.04736 -31.009293) (xy 292.10154 -31.01711)
			(xy 292.154043 -31.032599) (xy 292.20379 -31.055441) (xy 292.249757 -31.085166) (xy 292.270688 -31.102808)
			(xy 292.2778 -31.108904) (xy 292.294564 -31.115254) (xy 292.380162 -31.115254) (xy 292.39718 -31.108904)
			(xy 292.404038 -31.102554) (xy 292.424998 -31.084908) (xy 292.471011 -31.055165) (xy 292.520808 -31.032315)
			(xy 292.573364 -31.01683) (xy 292.627595 -31.009027) (xy 292.65499 -31.008574) (xy 292.681998 -31.009029)
			(xy 292.735476 -31.016634) (xy 292.787347 -31.031708) (xy 292.836572 -31.053949) (xy 292.882166 -31.082912)
			(xy 292.923219 -31.118017) (xy 292.958909 -31.158564) (xy 292.988521 -31.20374) (xy 293.011464 -31.252641)
			(xy 293.027278 -31.304291) (xy 293.031926 -31.3309) (xy 293.03345 -31.341568) (xy 293.04488 -31.359348)
			(xy 293.125144 -31.412688) (xy 293.145718 -31.416498) (xy 293.156386 -31.413958) (xy 293.183026 -31.407901)
			(xy 293.237273 -31.401404) (xy 293.26459 -31.401004) (xy 293.286763 -31.401234) (xy 293.330909 -31.405431)
			(xy 293.352728 -31.409386) (xy 293.363142 -31.411418) (xy 293.382954 -31.407354) (xy 293.459916 -31.354014)
			(xy 293.470838 -31.336996) (xy 293.472616 -31.326582) (xy 293.477505 -31.300243) (xy 293.493726 -31.249186)
			(xy 293.51693 -31.2009) (xy 293.54666 -31.156335) (xy 293.582332 -31.116368) (xy 293.623245 -31.081783)
			(xy 293.668593 -31.053262) (xy 293.717485 -31.031365) (xy 293.76896 -31.016523) (xy 293.822004 -31.009027)
			(xy 293.84879 -31.008574) (xy 293.876042 -31.009073) (xy 293.929991 -31.016828) (xy 293.982288 -31.032183)
			(xy 294.031867 -31.054823) (xy 294.077719 -31.08429) (xy 294.118911 -31.119982) (xy 294.154604 -31.161173)
			(xy 294.184072 -31.207024) (xy 294.206714 -31.256603) (xy 294.22207 -31.308899) (xy 294.229827 -31.362848)
			(xy 294.229827 -31.417352) (xy 294.22207 -31.471301) (xy 294.206714 -31.523597) (xy 294.184072 -31.573176)
			(xy 294.154604 -31.619027) (xy 294.118911 -31.660218) (xy 294.077719 -31.69591) (xy 294.031867 -31.725377)
			(xy 293.982288 -31.748017) (xy 293.929991 -31.763372) (xy 293.876042 -31.771127) (xy 293.84879 -31.77159)
			(xy 293.837268 -31.771492) (xy 293.814265 -31.770095) (xy 293.802816 -31.768796) (xy 293.791902 -31.768031)
			(xy 293.771102 -31.774759) (xy 293.762684 -31.78175) (xy 293.738808 -31.80334) (xy 293.730972 -31.811207)
			(xy 293.722277 -31.83161) (xy 293.722044 -31.84271) (xy 293.722552 -31.858712) (xy 293.722552 -32.722312)
			(xy 293.722044 -32.737552) (xy 293.722212 -32.748666) (xy 293.730918 -32.769091) (xy 293.738808 -32.776922)
			(xy 293.762684 -32.798512) (xy 293.771113 -32.805483) (xy 293.791904 -32.812201) (xy 293.802816 -32.811466)
			(xy 293.814264 -32.810156) (xy 293.837267 -32.808757) (xy 293.84879 -32.808672) (xy 293.876042 -32.809175)
			(xy 293.929991 -32.81693) (xy 293.982287 -32.832284) (xy 294.031866 -32.854925) (xy 294.077718 -32.884391)
			(xy 294.11891 -32.920083) (xy 294.154603 -32.961274) (xy 294.18407 -33.007125) (xy 294.206712 -33.056703)
			(xy 294.222068 -33.108999) (xy 294.229825 -33.162948) (xy 294.229825 -33.217452) (xy 294.222068 -33.271401)
			(xy 294.206712 -33.323697) (xy 294.18407 -33.373275) (xy 294.154603 -33.419126) (xy 294.11891 -33.460317)
			(xy 294.077718 -33.496009) (xy 294.031866 -33.525475) (xy 293.982287 -33.548116) (xy 293.929991 -33.56347)
			(xy 293.876042 -33.571225) (xy 293.84879 -33.571688) (xy 293.822025 -33.571234) (xy 293.769017 -33.563775)
			(xy 293.717572 -33.548977) (xy 293.668703 -33.52713) (xy 293.623369 -33.498664) (xy 293.582461 -33.464138)
			(xy 293.546783 -33.424231) (xy 293.517036 -33.379727) (xy 293.493805 -33.331501) (xy 293.477545 -33.280499)
			(xy 293.472616 -33.254188) (xy 293.470838 -33.243774) (xy 293.46017 -33.226756) (xy 293.382954 -33.17367)
			(xy 293.363142 -33.169606) (xy 293.352982 -33.171638) (xy 293.331102 -33.175615) (xy 293.286827 -33.179817)
			(xy 293.26459 -33.18002) (xy 293.237208 -33.179645) (xy 293.182832 -33.17315) (xy 293.156132 -33.167066)
			(xy 293.145718 -33.164526) (xy 293.125144 -33.168082) (xy 293.04488 -33.221676) (xy 293.03345 -33.239202)
			(xy 293.031672 -33.24987) (xy 293.026936 -33.276428) (xy 293.011088 -33.32799) (xy 292.988133 -33.376805)
			(xy 292.958529 -33.421898) (xy 292.922867 -33.46237) (xy 292.881857 -33.497414) (xy 292.836319 -33.526329)
			(xy 292.787161 -33.548539) (xy 292.735364 -33.563602) (xy 292.681961 -33.571215) (xy 292.65499 -33.571688)
			(xy 292.627619 -33.571231) (xy 292.57344 -33.563411) (xy 292.520937 -33.54792) (xy 292.47119 -33.525077)
			(xy 292.425223 -33.49535) (xy 292.404292 -33.477708) (xy 292.39718 -33.471612) (xy 292.380162 -33.465262)
			(xy 292.294818 -33.465262) (xy 292.2778 -33.471612) (xy 292.270688 -33.477708) (xy 292.249735 -33.495321)
			(xy 292.203768 -33.525036) (xy 292.154025 -33.547877) (xy 292.10153 -33.563374) (xy 292.047358 -33.57121)
			(xy 292.01999 -33.571688) (xy 292.002878 -33.571502) (xy 291.968791 -33.568446) (xy 291.951918 -33.565592)
			(xy 291.940651 -33.564202) (xy 291.918769 -33.570124) (xy 291.909754 -33.577022) (xy 291.88537 -33.598104)
			(xy 291.876992 -33.606038) (xy 291.867865 -33.627205) (xy 291.867844 -33.638744) (xy 291.868352 -33.65881)
			(xy 291.868352 -34.52241) (xy 291.867844 -34.541714) (xy 291.868045 -34.55322) (xy 291.877128 -34.574326)
			(xy 291.88537 -34.582354) (xy 291.909754 -34.603436) (xy 291.918768 -34.610348) (xy 291.940652 -34.6163)
			(xy 291.951918 -34.614866) (xy 291.968788 -34.611992) (xy 292.002877 -34.608942) (xy 292.01999 -34.60877)
			(xy 292.047242 -34.609277) (xy 292.101191 -34.617032) (xy 292.153487 -34.632386) (xy 292.203065 -34.655027)
			(xy 292.248917 -34.684493) (xy 292.290108 -34.720184) (xy 292.325801 -34.761375) (xy 292.355268 -34.807226)
			(xy 292.37791 -34.856804) (xy 292.393266 -34.9091) (xy 292.401023 -34.963048) (xy 292.401023 -34.990024)
			(xy 293.466772 -34.990024) (xy 293.470843 -34.934402) (xy 293.482969 -34.879965) (xy 293.502892 -34.827874)
			(xy 293.530188 -34.779239) (xy 293.564274 -34.735096) (xy 293.604423 -34.696387) (xy 293.649781 -34.663936)
			(xy 293.699381 -34.638435) (xy 293.752165 -34.620428) (xy 293.807008 -34.610298) (xy 293.862742 -34.608261)
			(xy 293.918179 -34.614361) (xy 293.972136 -34.628467) (xy 294.023465 -34.650279) (xy 294.071071 -34.679333)
			(xy 294.113939 -34.715008) (xy 294.151156 -34.756545) (xy 294.181929 -34.803058) (xy 294.205601 -34.853555)
			(xy 294.221669 -34.906962) (xy 294.229789 -34.962138) (xy 294.230298 -34.990024) (xy 294.229789 -35.01791)
			(xy 294.221669 -35.073086) (xy 294.205601 -35.126493) (xy 294.181929 -35.17699) (xy 294.151156 -35.223503)
			(xy 294.113939 -35.26504) (xy 294.071071 -35.300715) (xy 294.023465 -35.329769) (xy 293.972136 -35.351581)
			(xy 293.918179 -35.365687) (xy 293.862742 -35.371787) (xy 293.807008 -35.36975) (xy 293.752165 -35.35962)
			(xy 293.699381 -35.341613) (xy 293.649781 -35.316112) (xy 293.604423 -35.283661) (xy 293.564274 -35.244952)
			(xy 293.530188 -35.200809) (xy 293.502892 -35.152174) (xy 293.482969 -35.100083) (xy 293.470843 -35.045646)
			(xy 293.466772 -34.990024) (xy 292.401023 -34.990024) (xy 292.401023 -35.017552) (xy 292.393266 -35.0715)
			(xy 292.37791 -35.123796) (xy 292.355268 -35.173374) (xy 292.325801 -35.219225) (xy 292.290108 -35.260416)
			(xy 292.248917 -35.296107) (xy 292.203065 -35.325573) (xy 292.153487 -35.348214) (xy 292.101191 -35.363568)
			(xy 292.047242 -35.371323) (xy 292.01999 -35.371786) (xy 291.993014 -35.37129) (xy 291.939597 -35.363708)
			(xy 291.887784 -35.34867) (xy 291.838609 -35.326475) (xy 291.793055 -35.297567) (xy 291.752033 -35.262525)
			(xy 291.716363 -35.222048) (xy 291.686757 -35.176945) (xy 291.663807 -35.128117) (xy 291.647972 -35.076542)
			(xy 291.643308 -35.049968) (xy 291.64153 -35.0393) (xy 291.6301 -35.021774) (xy 291.549836 -34.96818)
			(xy 291.529262 -34.964624) (xy 291.518848 -34.967164) (xy 291.492153 -34.973303) (xy 291.437778 -34.979926)
			(xy 291.41039 -34.980372) (xy 291.383002 -34.979933) (xy 291.328626 -34.973308) (xy 291.301932 -34.967164)
			(xy 291.291518 -34.964624) (xy 291.270944 -34.96818) (xy 291.19068 -35.021774) (xy 291.17925 -35.0393)
			(xy 291.177472 -35.049968) (xy 291.17281 -35.076539) (xy 291.15695 -35.128102) (xy 291.133983 -35.176916)
			(xy 291.104369 -35.222008) (xy 291.068698 -35.262478) (xy 291.027681 -35.297519) (xy 290.982136 -35.326431)
			(xy 290.932972 -35.34864) (xy 290.88117 -35.3637) (xy 290.827763 -35.371313) (xy 290.80079 -35.371786)
			(xy 290.773538 -35.371343) (xy 290.719588 -35.363585) (xy 290.667291 -35.348228) (xy 290.617713 -35.325585)
			(xy 290.571861 -35.296117) (xy 290.530669 -35.260424) (xy 290.494977 -35.219231) (xy 290.46551 -35.173379)
			(xy 290.442868 -35.123799) (xy 290.427513 -35.071502) (xy 290.419756 -35.017552) (xy 288.774292 -35.017552)
			(xy 288.786676 -35.031373) (xy 288.817449 -35.077886) (xy 288.841121 -35.128383) (xy 288.857189 -35.18179)
			(xy 288.865309 -35.236966) (xy 288.865818 -35.264852) (xy 288.865309 -35.292738) (xy 288.857189 -35.347914)
			(xy 288.841121 -35.401321) (xy 288.817449 -35.451818) (xy 288.786676 -35.498331) (xy 288.749459 -35.539868)
			(xy 288.706591 -35.575543) (xy 288.658985 -35.604597) (xy 288.607656 -35.626409) (xy 288.553699 -35.640515)
			(xy 288.498262 -35.646615) (xy 288.442528 -35.644578) (xy 288.387685 -35.634448) (xy 288.334901 -35.616441)
			(xy 288.285301 -35.59094) (xy 288.239943 -35.558489) (xy 288.199794 -35.51978) (xy 288.165708 -35.475637)
			(xy 288.138412 -35.427002) (xy 288.118489 -35.374911) (xy 288.106363 -35.320474) (xy 288.102292 -35.264852)
			(xy 285.600902 -35.264852) (xy 285.600902 -37.087048) (xy 289.400742 -37.087048) (xy 289.401209 -37.060444)
			(xy 289.408585 -37.007751) (xy 289.423215 -36.956595) (xy 289.444814 -36.90797) (xy 289.472963 -36.862819)
			(xy 289.507116 -36.82202) (xy 289.546608 -36.786364) (xy 289.568382 -36.771072) (xy 289.578305 -36.76354)
			(xy 289.590034 -36.741598) (xy 289.590734 -36.729162) (xy 289.590734 -36.644834) (xy 289.590063 -36.632384)
			(xy 289.578353 -36.610408) (xy 289.568382 -36.602924) (xy 289.546623 -36.587613) (xy 289.507142 -36.551951)
			(xy 289.472997 -36.511151) (xy 289.444849 -36.466003) (xy 289.423245 -36.417384) (xy 289.408602 -36.366236)
			(xy 289.401206 -36.313549) (xy 289.400742 -36.286948) (xy 289.4012 -36.259694) (xy 289.408952 -36.20574)
			(xy 289.424304 -36.153439) (xy 289.446945 -36.103856) (xy 289.476413 -36.058) (xy 289.512107 -36.016806)
			(xy 289.553302 -35.981111) (xy 289.599158 -35.951644) (xy 289.648741 -35.929004) (xy 289.701042 -35.913651)
			(xy 289.754996 -35.9059) (xy 289.78225 -35.90544) (xy 289.786822 -35.90544) (xy 289.796474 -35.905694)
			(xy 289.813238 -35.899344) (xy 289.87877 -35.843464) (xy 289.887406 -35.827462) (xy 289.888676 -35.818064)
			(xy 289.893029 -35.791135) (xy 289.908339 -35.738779) (xy 289.93095 -35.689138) (xy 289.960401 -35.643223)
			(xy 289.996091 -35.601971) (xy 290.037292 -35.566223) (xy 290.083165 -35.536708) (xy 290.132775 -35.514027)
			(xy 290.185109 -35.498644) (xy 290.2391 -35.490871) (xy 290.266374 -35.490404) (xy 290.293629 -35.490841)
			(xy 290.347584 -35.498595) (xy 290.399887 -35.51395) (xy 290.449472 -35.536591) (xy 290.49533 -35.56606)
			(xy 290.536527 -35.601754) (xy 290.572225 -35.642949) (xy 290.601696 -35.688805) (xy 290.624341 -35.738388)
			(xy 290.639699 -35.79069) (xy 290.647457 -35.844645) (xy 290.647457 -35.899155) (xy 290.639699 -35.95311)
			(xy 290.624341 -36.005412) (xy 290.601696 -36.054995) (xy 290.572225 -36.100851) (xy 290.536527 -36.142046)
			(xy 290.49533 -36.17774) (xy 290.449472 -36.207209) (xy 290.399887 -36.22985) (xy 290.347584 -36.245205)
			(xy 290.293629 -36.252959) (xy 290.266374 -36.25342) (xy 290.261802 -36.25342) (xy 290.25215 -36.253166)
			(xy 290.235386 -36.259516) (xy 290.169854 -36.315396) (xy 290.161218 -36.331398) (xy 290.159948 -36.340796)
			(xy 290.155752 -36.367) (xy 290.141067 -36.417994) (xy 290.119454 -36.46646) (xy 290.09133 -36.511461)
			(xy 290.087904 -36.515548) (xy 291.214046 -36.515548) (xy 291.218117 -36.459926) (xy 291.230243 -36.405489)
			(xy 291.250166 -36.353398) (xy 291.277462 -36.304763) (xy 291.311548 -36.26062) (xy 291.351697 -36.221911)
			(xy 291.397055 -36.18946) (xy 291.446655 -36.163959) (xy 291.499439 -36.145952) (xy 291.554282 -36.135822)
			(xy 291.610016 -36.133785) (xy 291.665453 -36.139885) (xy 291.71941 -36.153991) (xy 291.770739 -36.175803)
			(xy 291.818345 -36.204857) (xy 291.861213 -36.240532) (xy 291.89843 -36.282069) (xy 291.929203 -36.328582)
			(xy 291.952875 -36.379079) (xy 291.968943 -36.432486) (xy 291.977063 -36.487662) (xy 291.977572 -36.515548)
			(xy 291.977063 -36.543434) (xy 291.968943 -36.59861) (xy 291.952875 -36.652017) (xy 291.929203 -36.702514)
			(xy 291.89843 -36.749027) (xy 291.861213 -36.790564) (xy 291.818345 -36.826239) (xy 291.770739 -36.855293)
			(xy 291.71941 -36.877105) (xy 291.665453 -36.891211) (xy 291.610016 -36.897311) (xy 291.554282 -36.895274)
			(xy 291.499439 -36.885144) (xy 291.446655 -36.867137) (xy 291.397055 -36.841636) (xy 291.351697 -36.809185)
			(xy 291.311548 -36.770476) (xy 291.277462 -36.726333) (xy 291.250166 -36.677698) (xy 291.230243 -36.625607)
			(xy 291.218117 -36.57117) (xy 291.214046 -36.515548) (xy 290.087904 -36.515548) (xy 290.057238 -36.552128)
			(xy 290.017836 -36.587675) (xy 289.996118 -36.602924) (xy 289.986196 -36.610457) (xy 289.974467 -36.632399)
			(xy 289.973766 -36.644834) (xy 289.973766 -36.729162) (xy 289.974439 -36.741612) (xy 289.986148 -36.763588)
			(xy 289.996118 -36.771072) (xy 290.017875 -36.786386) (xy 290.057356 -36.822047) (xy 290.091502 -36.862847)
			(xy 290.11965 -36.907994) (xy 290.141254 -36.956612) (xy 290.155897 -37.007761) (xy 290.163293 -37.060447)
			(xy 290.163758 -37.087048) (xy 290.163158 -37.118808) (xy 290.152671 -37.181454) (xy 290.131928 -37.24149)
			(xy 290.117276 -37.269674) (xy 290.111942 -37.27958) (xy 290.110418 -37.301678) (xy 290.146232 -37.394896)
			(xy 290.162234 -37.41039) (xy 290.172902 -37.4142) (xy 290.197435 -37.423265) (xy 290.243966 -37.447148)
			(xy 290.286797 -37.477164) (xy 290.325126 -37.512751) (xy 290.358234 -37.55324) (xy 290.385499 -37.597872)
			(xy 290.406412 -37.645811) (xy 290.42058 -37.696157) (xy 290.427736 -37.747967) (xy 290.428172 -37.774118)
			(xy 290.427686 -37.801369) (xy 290.41993 -37.855317) (xy 290.404575 -37.907612) (xy 290.381933 -37.957189)
			(xy 290.352467 -38.003039) (xy 290.316776 -38.04423) (xy 290.275585 -38.079921) (xy 290.229735 -38.109387)
			(xy 290.180158 -38.132029) (xy 290.127863 -38.147384) (xy 290.073915 -38.15514) (xy 290.019413 -38.15514)
			(xy 289.965465 -38.147384) (xy 289.91317 -38.132029) (xy 289.863593 -38.109387) (xy 289.817743 -38.079921)
			(xy 289.776552 -38.04423) (xy 289.740861 -38.003039) (xy 289.711395 -37.957189) (xy 289.688753 -37.907612)
			(xy 289.673398 -37.855317) (xy 289.665642 -37.801369) (xy 289.665156 -37.774118) (xy 289.665741 -37.742358)
			(xy 289.676234 -37.679711) (xy 289.696983 -37.619676) (xy 289.711638 -37.591492) (xy 289.716972 -37.581586)
			(xy 289.718496 -37.559488) (xy 289.682682 -37.46627) (xy 289.66668 -37.450776) (xy 289.656012 -37.446966)
			(xy 289.63147 -37.437922) (xy 289.584938 -37.414037) (xy 289.542106 -37.384019) (xy 289.503777 -37.348431)
			(xy 289.470669 -37.307939) (xy 289.443404 -37.263304) (xy 289.422493 -37.215362) (xy 289.408329 -37.165012)
			(xy 289.401176 -37.1132) (xy 289.400742 -37.087048) (xy 285.600902 -37.087048) (xy 285.600902 -38.315138)
			(xy 290.617908 -38.315138) (xy 290.621979 -38.259516) (xy 290.634105 -38.205079) (xy 290.654028 -38.152988)
			(xy 290.681324 -38.104353) (xy 290.71541 -38.06021) (xy 290.755559 -38.021501) (xy 290.800917 -37.98905)
			(xy 290.850517 -37.963549) (xy 290.903301 -37.945542) (xy 290.958144 -37.935412) (xy 291.013878 -37.933375)
			(xy 291.069315 -37.939475) (xy 291.123272 -37.953581) (xy 291.174601 -37.975393) (xy 291.222207 -38.004447)
			(xy 291.265075 -38.040122) (xy 291.302292 -38.081659) (xy 291.333065 -38.128172) (xy 291.356737 -38.178669)
			(xy 291.372805 -38.232076) (xy 291.380925 -38.287252) (xy 291.381434 -38.315138) (xy 291.380925 -38.343024)
			(xy 291.372805 -38.3982) (xy 291.356737 -38.451607) (xy 291.333065 -38.502104) (xy 291.302292 -38.548617)
			(xy 291.265075 -38.590154) (xy 291.222207 -38.625829) (xy 291.174601 -38.654883) (xy 291.123272 -38.676695)
			(xy 291.069315 -38.690801) (xy 291.013878 -38.696901) (xy 290.958144 -38.694864) (xy 290.903301 -38.684734)
			(xy 290.850517 -38.666727) (xy 290.800917 -38.641226) (xy 290.755559 -38.608775) (xy 290.71541 -38.570066)
			(xy 290.681324 -38.525923) (xy 290.654028 -38.477288) (xy 290.634105 -38.425197) (xy 290.621979 -38.37076)
			(xy 290.617908 -38.315138) (xy 285.600902 -38.315138) (xy 285.600902 -42.4307) (xy 285.601192 -42.438369)
			(xy 285.605834 -42.452988) (xy 285.610046 -42.459402) (xy 285.610046 -42.459656) (xy 285.614891 -42.466077)
			(xy 285.627693 -42.475799) (xy 285.635192 -42.478706) (xy 285.6357 -42.47896) (xy 285.660686 -42.487763)
			(xy 285.708143 -42.511302) (xy 285.751888 -42.54118) (xy 285.791078 -42.576822) (xy 285.82496 -42.617545)
			(xy 285.852882 -42.662563) (xy 285.874307 -42.711011) (xy 285.888823 -42.761958) (xy 285.896151 -42.814423)
			(xy 285.896558 -42.84091) (xy 285.896017 -42.87028) (xy 285.887016 -42.928327) (xy 285.869227 -42.984309)
			(xy 285.843071 -43.036904) (xy 285.809165 -43.084871) (xy 285.789116 -43.10634) (xy 285.788354 -43.107102)
			(xy 285.787846 -43.10761) (xy 285.766777 -43.129147) (xy 285.719083 -43.165958) (xy 285.66619 -43.194803)
			(xy 285.637986 -43.2054) (xy 285.635192 -43.206416) (xy 285.629096 -43.209464) (xy 285.620863 -43.21405)
			(xy 285.608176 -43.227963) (xy 285.601361 -43.245516) (xy 285.600902 -43.25493) (xy 285.600902 -43.4467)
			(xy 285.601192 -43.454369) (xy 285.605834 -43.468988) (xy 285.610046 -43.475402) (xy 285.610046 -43.475656)
			(xy 285.614891 -43.482077) (xy 285.627693 -43.491799) (xy 285.635192 -43.494706) (xy 285.6357 -43.49496)
			(xy 285.660686 -43.503763) (xy 285.708143 -43.527302) (xy 285.751888 -43.55718) (xy 285.791078 -43.592822)
			(xy 285.82496 -43.633545) (xy 285.852882 -43.678563) (xy 285.874307 -43.727011) (xy 285.888823 -43.777958)
			(xy 285.896151 -43.830423) (xy 285.896558 -43.85691) (xy 285.896017 -43.88628) (xy 285.887016 -43.944327)
			(xy 285.869227 -44.000309) (xy 285.843071 -44.052904) (xy 285.809165 -44.100871) (xy 285.789116 -44.12234)
			(xy 285.788354 -44.123102) (xy 285.787846 -44.12361) (xy 285.766777 -44.145147) (xy 285.719083 -44.181958)
			(xy 285.66619 -44.210803) (xy 285.637986 -44.2214) (xy 285.635192 -44.222416) (xy 285.629096 -44.225464)
			(xy 285.620863 -44.23005) (xy 285.608176 -44.243963) (xy 285.601361 -44.261516) (xy 285.600902 -44.27093)
			(xy 285.600902 -44.4627) (xy 285.601192 -44.470369) (xy 285.605834 -44.484988) (xy 285.610046 -44.491402)
			(xy 285.610046 -44.491656) (xy 285.614891 -44.498077) (xy 285.627693 -44.507799) (xy 285.635192 -44.510706)
			(xy 285.6357 -44.51096) (xy 285.660686 -44.519763) (xy 285.708143 -44.543302) (xy 285.751888 -44.57318)
			(xy 285.791078 -44.608822) (xy 285.82496 -44.649545) (xy 285.852882 -44.694563) (xy 285.874307 -44.743011)
			(xy 285.888823 -44.793958) (xy 285.896151 -44.846423) (xy 285.896558 -44.87291) (xy 285.896017 -44.90228)
			(xy 285.887016 -44.960327) (xy 285.869227 -45.016309) (xy 285.843071 -45.068904) (xy 285.809165 -45.116871)
			(xy 285.789116 -45.13834) (xy 285.788354 -45.139102) (xy 285.787846 -45.13961) (xy 285.766777 -45.161147)
			(xy 285.719083 -45.197958) (xy 285.66619 -45.226803) (xy 285.637986 -45.2374) (xy 285.635192 -45.238416)
			(xy 285.629096 -45.241464) (xy 285.620863 -45.24605) (xy 285.608176 -45.259963) (xy 285.601361 -45.277516)
			(xy 285.600902 -45.28693) (xy 285.600902 -45.4787) (xy 285.601192 -45.486369) (xy 285.605834 -45.500988)
			(xy 285.610046 -45.507402) (xy 285.610046 -45.507656) (xy 285.614891 -45.514077) (xy 285.627693 -45.523799)
			(xy 285.635192 -45.526706) (xy 285.6357 -45.52696) (xy 285.660686 -45.535763) (xy 285.708143 -45.559302)
			(xy 285.751888 -45.58918) (xy 285.791078 -45.624822) (xy 285.82496 -45.665545) (xy 285.852882 -45.710563)
			(xy 285.874307 -45.759011) (xy 285.888823 -45.809958) (xy 285.896151 -45.862423) (xy 285.896558 -45.88891)
			(xy 285.896017 -45.91828) (xy 285.887016 -45.976327) (xy 285.869227 -46.032309) (xy 285.843071 -46.084904)
			(xy 285.809165 -46.132871) (xy 285.789116 -46.15434) (xy 285.788354 -46.155102) (xy 285.787846 -46.15561)
			(xy 285.766777 -46.177147) (xy 285.719083 -46.213958) (xy 285.66619 -46.242803) (xy 285.637986 -46.2534)
			(xy 285.635192 -46.254416) (xy 285.629096 -46.257464) (xy 285.620863 -46.26205) (xy 285.608176 -46.275963)
			(xy 285.601361 -46.293516) (xy 285.600902 -46.30293) (xy 285.600902 -47.040546) (xy 285.621984 -47.067724)
			(xy 285.639002 -47.072296) (xy 285.665955 -47.079733) (xy 285.717489 -47.101418) (xy 285.765302 -47.1304)
			(xy 285.808368 -47.166056) (xy 285.845762 -47.207622) (xy 285.876681 -47.254206) (xy 285.900463 -47.304808)
			(xy 285.916596 -47.358341) (xy 285.924734 -47.413656) (xy 285.92526 -47.441612) (xy 285.925181 -47.45435)
			(xy 285.923527 -47.479771) (xy 285.921958 -47.492412) (xy 285.921704 -47.494952) (xy 285.916923 -47.524513)
			(xy 285.899362 -47.58176) (xy 285.873075 -47.63556) (xy 285.838707 -47.684594) (xy 285.818326 -47.706534)
			(xy 285.817818 -47.707042) (xy 285.81604 -47.709074) (xy 285.797763 -47.727722) (xy 285.756997 -47.76035)
			(xy 285.71216 -47.78711) (xy 285.66409 -47.807501) (xy 285.639002 -47.814738) (xy 285.638494 -47.814992)
			(xy 285.637224 -47.8155) (xy 285.626936 -47.81908) (xy 285.610501 -47.833343) (xy 285.601452 -47.853134)
			(xy 285.600902 -47.864014) (xy 285.600902 -48.5267) (xy 285.601192 -48.534369) (xy 285.605834 -48.548988)
			(xy 285.610046 -48.555402) (xy 285.610046 -48.555656) (xy 285.614891 -48.562077) (xy 285.627693 -48.571799)
			(xy 285.635192 -48.574706) (xy 285.6357 -48.57496) (xy 285.660686 -48.583763) (xy 285.708143 -48.607302)
			(xy 285.751888 -48.63718) (xy 285.791078 -48.672822) (xy 285.82496 -48.713545) (xy 285.852882 -48.758563)
			(xy 285.874307 -48.807011) (xy 285.888823 -48.857958) (xy 285.896151 -48.910423) (xy 285.896558 -48.93691)
			(xy 285.896017 -48.96628) (xy 285.887016 -49.024327) (xy 285.869227 -49.080309) (xy 285.843071 -49.132904)
			(xy 285.809165 -49.180871) (xy 285.789116 -49.20234) (xy 285.788354 -49.203102) (xy 285.787846 -49.20361)
			(xy 285.766777 -49.225147) (xy 285.719083 -49.261958) (xy 285.66619 -49.290803) (xy 285.637986 -49.3014)
			(xy 285.635192 -49.302416) (xy 285.629096 -49.305464) (xy 285.620863 -49.31005) (xy 285.608176 -49.323963)
			(xy 285.601361 -49.341516) (xy 285.600902 -49.35093) (xy 285.600902 -49.5427) (xy 285.601192 -49.550369)
			(xy 285.605834 -49.564988) (xy 285.610046 -49.571402) (xy 285.610046 -49.571656) (xy 285.614891 -49.578077)
			(xy 285.627693 -49.587799) (xy 285.635192 -49.590706) (xy 285.6357 -49.59096) (xy 285.660686 -49.599763)
			(xy 285.665101 -49.601953) (xy 286.490859 -49.601953) (xy 286.490859 -49.547447) (xy 286.498617 -49.493495)
			(xy 286.513974 -49.441196) (xy 286.536617 -49.391615) (xy 286.566086 -49.345762) (xy 286.601782 -49.304569)
			(xy 286.642976 -49.268876) (xy 286.688831 -49.239408) (xy 286.738413 -49.216767) (xy 286.790712 -49.201413)
			(xy 286.844665 -49.193658) (xy 286.871918 -49.193196) (xy 286.899289 -49.193652) (xy 286.953468 -49.201473)
			(xy 287.005971 -49.216964) (xy 287.055718 -49.239808) (xy 287.101684 -49.269534) (xy 287.122616 -49.287176)
			(xy 287.129728 -49.293272) (xy 287.146746 -49.299622) (xy 287.23209 -49.299622) (xy 287.249108 -49.293272)
			(xy 287.25622 -49.287176) (xy 287.277153 -49.269535) (xy 287.323121 -49.239811) (xy 287.372867 -49.216965)
			(xy 287.425369 -49.201469) (xy 287.479547 -49.19364) (xy 287.534289 -49.19364) (xy 287.588467 -49.201469)
			(xy 287.640969 -49.216965) (xy 287.690715 -49.239811) (xy 287.736683 -49.269535) (xy 287.757616 -49.287176)
			(xy 287.764728 -49.293272) (xy 287.781746 -49.299622) (xy 287.86709 -49.299622) (xy 287.884108 -49.293272)
			(xy 287.89122 -49.287176) (xy 287.912168 -49.269557) (xy 287.958137 -49.239843) (xy 288.00788 -49.217004)
			(xy 288.060377 -49.201508) (xy 288.11455 -49.193673) (xy 288.141918 -49.193196) (xy 288.168234 -49.193659)
			(xy 288.220367 -49.200877) (xy 288.271015 -49.215188) (xy 288.319217 -49.236321) (xy 288.364059 -49.263874)
			(xy 288.404692 -49.297327) (xy 288.422842 -49.316386) (xy 288.430348 -49.323806) (xy 288.44964 -49.33232)
			(xy 288.46018 -49.332896) (xy 288.534856 -49.332896) (xy 288.545405 -49.332358) (xy 288.5647 -49.323829)
			(xy 288.572194 -49.316386) (xy 288.590329 -49.297307) (xy 288.63095 -49.263829) (xy 288.67579 -49.236259)
			(xy 288.723998 -49.215121) (xy 288.774655 -49.200816) (xy 288.826799 -49.193617) (xy 288.853118 -49.193196)
			(xy 288.880369 -49.193675) (xy 288.934315 -49.201434) (xy 288.986608 -49.216791) (xy 289.036184 -49.239433)
			(xy 289.082032 -49.2689) (xy 289.123221 -49.304592) (xy 289.158911 -49.345782) (xy 289.188376 -49.391632)
			(xy 289.211016 -49.441209) (xy 289.22637 -49.493503) (xy 289.234126 -49.547449) (xy 289.234126 -49.601951)
			(xy 289.22637 -49.655897) (xy 289.211016 -49.708191) (xy 289.188376 -49.757768) (xy 289.158911 -49.803618)
			(xy 289.123221 -49.844808) (xy 289.082032 -49.8805) (xy 289.036184 -49.909967) (xy 288.986608 -49.932609)
			(xy 288.934315 -49.947966) (xy 288.880369 -49.955725) (xy 288.853118 -49.956212) (xy 288.826801 -49.95579)
			(xy 288.774666 -49.948563) (xy 288.724017 -49.934243) (xy 288.675815 -49.913103) (xy 288.630974 -49.885543)
			(xy 288.590343 -49.852084) (xy 288.572194 -49.833022) (xy 288.564674 -49.825619) (xy 288.545393 -49.817095)
			(xy 288.534856 -49.816512) (xy 288.46018 -49.816512) (xy 288.449633 -49.817067) (xy 288.430337 -49.825584)
			(xy 288.422842 -49.833022) (xy 288.404671 -49.852066) (xy 288.36406 -49.88555) (xy 288.319228 -49.913127)
			(xy 288.271027 -49.934273) (xy 288.220375 -49.948584) (xy 288.168236 -49.955788) (xy 288.141918 -49.956212)
			(xy 288.114548 -49.955732) (xy 288.06037 -49.947917) (xy 288.007867 -49.932431) (xy 287.95812 -49.909593)
			(xy 287.912152 -49.879872) (xy 287.89122 -49.862232) (xy 287.884108 -49.856136) (xy 287.86709 -49.849786)
			(xy 287.781746 -49.849786) (xy 287.764728 -49.856136) (xy 287.757616 -49.862232) (xy 287.736683 -49.879873)
			(xy 287.690715 -49.909597) (xy 287.640969 -49.932443) (xy 287.588467 -49.947939) (xy 287.534289 -49.955768)
			(xy 287.479547 -49.955768) (xy 287.425369 -49.947939) (xy 287.372867 -49.932443) (xy 287.323121 -49.909597)
			(xy 287.277153 -49.879873) (xy 287.25622 -49.862232) (xy 287.249108 -49.856136) (xy 287.23209 -49.849786)
			(xy 287.146746 -49.849786) (xy 287.129728 -49.856136) (xy 287.122616 -49.862232) (xy 287.101693 -49.879882)
			(xy 287.055717 -49.909591) (xy 287.005967 -49.932424) (xy 286.953465 -49.947913) (xy 286.899288 -49.955739)
			(xy 286.871918 -49.956212) (xy 286.844665 -49.955742) (xy 286.790712 -49.947987) (xy 286.738413 -49.932633)
			(xy 286.688831 -49.909992) (xy 286.642976 -49.880524) (xy 286.601782 -49.844831) (xy 286.566086 -49.803638)
			(xy 286.536617 -49.757785) (xy 286.513974 -49.708204) (xy 286.498617 -49.655905) (xy 286.490859 -49.601953)
			(xy 285.665101 -49.601953) (xy 285.708143 -49.623302) (xy 285.751888 -49.65318) (xy 285.791078 -49.688822)
			(xy 285.82496 -49.729545) (xy 285.852882 -49.774563) (xy 285.874307 -49.823011) (xy 285.888823 -49.873958)
			(xy 285.896151 -49.926423) (xy 285.896558 -49.95291) (xy 285.896017 -49.98228) (xy 285.887016 -50.040327)
			(xy 285.869227 -50.096309) (xy 285.843071 -50.148904) (xy 285.809165 -50.196871) (xy 285.789116 -50.21834)
			(xy 285.788354 -50.219102) (xy 285.787846 -50.21961) (xy 285.766777 -50.241147) (xy 285.719083 -50.277958)
			(xy 285.66619 -50.306803) (xy 285.637986 -50.3174) (xy 285.635192 -50.318416) (xy 285.629096 -50.321464)
			(xy 285.620863 -50.32605) (xy 285.608176 -50.339963) (xy 285.601361 -50.357516) (xy 285.600902 -50.36693)
			(xy 285.600902 -50.62347) (xy 285.62046 -50.65014) (xy 285.636716 -50.65522) (xy 285.66226 -50.663666)
			(xy 285.710865 -50.686734) (xy 285.755746 -50.716403) (xy 285.796013 -50.752084) (xy 285.830867 -50.793069)
			(xy 285.859616 -50.838544) (xy 285.881691 -50.887608) (xy 285.896652 -50.939287) (xy 285.904204 -50.992555)
			(xy 285.904686 -51.019456) (xy 285.904132 -51.048682) (xy 285.895224 -51.10645) (xy 285.877611 -51.162184)
			(xy 285.851704 -51.21458) (xy 285.818109 -51.262412) (xy 285.79826 -51.28387) (xy 285.797498 -51.284632)
			(xy 285.79699 -51.28514) (xy 285.774531 -51.308172) (xy 285.723335 -51.347117) (xy 285.666339 -51.376936)
			(xy 285.635954 -51.387502) (xy 285.628334 -51.390042) (xy 285.61538 -51.399186) (xy 285.610808 -51.40579)
			(xy 285.606244 -51.412428) (xy 285.601182 -51.427712) (xy 285.600902 -51.435762) (xy 285.600902 -51.63947)
			(xy 285.62046 -51.66614) (xy 285.636716 -51.67122) (xy 285.66226 -51.679666) (xy 285.682028 -51.689048)
			(xy 286.4554 -51.689048) (xy 286.4554 -51.634552) (xy 286.463155 -51.580611) (xy 286.478507 -51.528323)
			(xy 286.501144 -51.478752) (xy 286.530605 -51.432906) (xy 286.566289 -51.391719) (xy 286.607472 -51.35603)
			(xy 286.653315 -51.326564) (xy 286.702884 -51.303922) (xy 286.75517 -51.288564) (xy 286.80911 -51.280803)
			(xy 286.836358 -51.280314) (xy 286.863728 -51.280801) (xy 286.917906 -51.288613) (xy 286.970409 -51.304097)
			(xy 287.020156 -51.326934) (xy 287.066124 -51.356655) (xy 287.087056 -51.374294) (xy 287.094168 -51.38039)
			(xy 287.111186 -51.38674) (xy 287.19653 -51.38674) (xy 287.213548 -51.38039) (xy 287.22066 -51.374294)
			(xy 287.241596 -51.356659) (xy 287.287567 -51.326947) (xy 287.337314 -51.30411) (xy 287.389814 -51.288618)
			(xy 287.443989 -51.280789) (xy 287.471358 -51.280314) (xy 287.489701 -51.280549) (xy 287.526214 -51.28411)
			(xy 287.544256 -51.287426) (xy 287.555178 -51.289458) (xy 287.575752 -51.284632) (xy 287.65373 -51.225704)
			(xy 287.664144 -51.206908) (xy 287.664906 -51.195986) (xy 287.667809 -51.167703) (xy 287.680845 -51.112366)
			(xy 287.70194 -51.059573) (xy 287.730627 -51.01049) (xy 287.766272 -50.9662) (xy 287.786826 -50.946558)
			(xy 287.794237 -50.939044) (xy 287.802759 -50.919759) (xy 287.803336 -50.90922) (xy 287.803336 -50.834544)
			(xy 287.802786 -50.823997) (xy 287.794264 -50.804702) (xy 287.786826 -50.797206) (xy 287.767754 -50.779063)
			(xy 287.734275 -50.738445) (xy 287.706703 -50.693607) (xy 287.685562 -50.645401) (xy 287.671257 -50.594744)
			(xy 287.664057 -50.542601) (xy 287.663636 -50.516282) (xy 287.664122 -50.489031) (xy 287.671878 -50.435083)
			(xy 287.687233 -50.382788) (xy 287.709875 -50.333211) (xy 287.739341 -50.287361) (xy 287.775032 -50.24617)
			(xy 287.816223 -50.210479) (xy 287.862073 -50.181013) (xy 287.91165 -50.158371) (xy 287.963945 -50.143016)
			(xy 288.017893 -50.13526) (xy 288.072395 -50.13526) (xy 288.126343 -50.143016) (xy 288.178638 -50.158371)
			(xy 288.228215 -50.181013) (xy 288.274065 -50.210479) (xy 288.315256 -50.24617) (xy 288.350947 -50.287361)
			(xy 288.380413 -50.333211) (xy 288.403055 -50.382788) (xy 288.41841 -50.435083) (xy 288.426166 -50.489031)
			(xy 288.426652 -50.516282) (xy 288.426249 -50.5426) (xy 288.419021 -50.594737) (xy 288.404699 -50.645386)
			(xy 288.383555 -50.693589) (xy 288.35599 -50.738429) (xy 288.322527 -50.779058) (xy 288.303462 -50.797206)
			(xy 288.296065 -50.804732) (xy 288.287536 -50.824008) (xy 288.286952 -50.834544) (xy 288.286952 -50.90922)
			(xy 288.287525 -50.919764) (xy 288.296031 -50.939059) (xy 288.303462 -50.946558) (xy 288.322514 -50.964721)
			(xy 288.355996 -51.005334) (xy 288.383571 -51.050169) (xy 288.404714 -51.098371) (xy 288.419024 -51.149024)
			(xy 288.426228 -51.201164) (xy 288.426652 -51.227482) (xy 288.426105 -51.254731) (xy 288.418352 -51.308674)
			(xy 288.403002 -51.360965) (xy 288.380366 -51.410539) (xy 288.350906 -51.456387) (xy 288.31522 -51.497577)
			(xy 288.274037 -51.533268) (xy 288.228193 -51.562736) (xy 288.178623 -51.58538) (xy 288.126335 -51.600739)
			(xy 288.072393 -51.608501) (xy 288.045144 -51.60899) (xy 288.026801 -51.608755) (xy 287.990288 -51.605194)
			(xy 287.972246 -51.601878) (xy 287.961324 -51.599846) (xy 287.94075 -51.604672) (xy 287.862772 -51.6636)
			(xy 287.852358 -51.682396) (xy 287.851596 -51.693318) (xy 287.848661 -51.721571) (xy 287.83563 -51.776853)
			(xy 287.814548 -51.829592) (xy 287.785881 -51.878624) (xy 287.750261 -51.922864) (xy 287.708477 -51.961334)
			(xy 287.661451 -51.993185) (xy 287.610223 -52.017713) (xy 287.555925 -52.034375) (xy 287.499756 -52.042804)
			(xy 287.471358 -52.04333) (xy 287.443988 -52.042847) (xy 287.389809 -52.035036) (xy 287.337306 -52.019552)
			(xy 287.287558 -51.996713) (xy 287.241591 -51.966991) (xy 287.22066 -51.94935) (xy 287.213548 -51.943254)
			(xy 287.19653 -51.936904) (xy 287.111186 -51.936904) (xy 287.094168 -51.943254) (xy 287.087056 -51.94935)
			(xy 287.066107 -51.966969) (xy 287.02014 -51.996685) (xy 286.970397 -52.019526) (xy 286.917899 -52.035022)
			(xy 286.863726 -52.042854) (xy 286.836358 -52.04333) (xy 286.80911 -52.042797) (xy 286.75517 -52.035036)
			(xy 286.702884 -52.019678) (xy 286.653315 -51.997036) (xy 286.607472 -51.96757) (xy 286.566289 -51.931881)
			(xy 286.530605 -51.890694) (xy 286.501144 -51.844848) (xy 286.478507 -51.795277) (xy 286.463155 -51.742989)
			(xy 286.4554 -51.689048) (xy 285.682028 -51.689048) (xy 285.710865 -51.702734) (xy 285.755746 -51.732403)
			(xy 285.796013 -51.768084) (xy 285.830867 -51.809069) (xy 285.859616 -51.854544) (xy 285.881691 -51.903608)
			(xy 285.896652 -51.955287) (xy 285.904204 -52.008555) (xy 285.904686 -52.035456) (xy 285.904132 -52.064682)
			(xy 285.895224 -52.12245) (xy 285.877611 -52.178184) (xy 285.851704 -52.23058) (xy 285.818109 -52.278412)
			(xy 285.79826 -52.29987) (xy 285.797498 -52.300632) (xy 285.79699 -52.30114) (xy 285.774531 -52.324172)
			(xy 285.723335 -52.363117) (xy 285.666339 -52.392936) (xy 285.635954 -52.403502) (xy 285.628334 -52.406042)
			(xy 285.61538 -52.415186) (xy 285.610808 -52.42179) (xy 285.606244 -52.428428) (xy 285.601182 -52.443712)
			(xy 285.600902 -52.451762) (xy 285.600902 -52.564157) (xy 288.027007 -52.564157) (xy 288.027007 -52.509643)
			(xy 288.034765 -52.455685) (xy 288.050124 -52.403379) (xy 288.07277 -52.353792) (xy 288.102242 -52.307933)
			(xy 288.137942 -52.266735) (xy 288.179141 -52.231036) (xy 288.225001 -52.201565) (xy 288.274589 -52.17892)
			(xy 288.326894 -52.163563) (xy 288.380853 -52.155806) (xy 288.40811 -52.155344) (xy 288.435481 -52.155793)
			(xy 288.489661 -52.163614) (xy 288.542165 -52.179106) (xy 288.591912 -52.201952) (xy 288.637877 -52.231681)
			(xy 288.658808 -52.249324) (xy 288.66592 -52.25542) (xy 288.682938 -52.26177) (xy 288.768282 -52.26177)
			(xy 288.7853 -52.25542) (xy 288.792412 -52.249324) (xy 288.81337 -52.231716) (xy 288.859335 -52.201999)
			(xy 288.909076 -52.179157) (xy 288.961571 -52.163658) (xy 289.015743 -52.155822) (xy 289.04311 -52.155344)
			(xy 289.070357 -52.155927) (xy 289.124297 -52.163684) (xy 289.176584 -52.179038) (xy 289.226154 -52.201676)
			(xy 289.271997 -52.231139) (xy 289.313181 -52.266826) (xy 289.348867 -52.308011) (xy 289.378328 -52.353855)
			(xy 289.400966 -52.403425) (xy 289.416319 -52.455713) (xy 289.424074 -52.509653) (xy 289.424074 -52.564147)
			(xy 289.416319 -52.618087) (xy 289.400966 -52.670375) (xy 289.378328 -52.719945) (xy 289.348867 -52.765789)
			(xy 289.313181 -52.806974) (xy 289.271997 -52.842661) (xy 289.226154 -52.872124) (xy 289.176584 -52.894762)
			(xy 289.124297 -52.910116) (xy 289.070357 -52.917873) (xy 289.04311 -52.91836) (xy 289.01574 -52.917898)
			(xy 288.96156 -52.910081) (xy 288.909056 -52.894591) (xy 288.85931 -52.871748) (xy 288.813343 -52.842022)
			(xy 288.792412 -52.82438) (xy 288.7853 -52.818284) (xy 288.768282 -52.811934) (xy 288.682938 -52.811934)
			(xy 288.66592 -52.818284) (xy 288.658808 -52.82438) (xy 288.637881 -52.842026) (xy 288.591907 -52.871737)
			(xy 288.542158 -52.894572) (xy 288.489656 -52.910062) (xy 288.43548 -52.917887) (xy 288.40811 -52.91836)
			(xy 288.380853 -52.917994) (xy 288.326894 -52.910237) (xy 288.274589 -52.89488) (xy 288.225001 -52.872235)
			(xy 288.179141 -52.842764) (xy 288.137942 -52.807065) (xy 288.102242 -52.765867) (xy 288.07277 -52.720008)
			(xy 288.050124 -52.670421) (xy 288.034765 -52.618115) (xy 288.027007 -52.564157) (xy 285.600902 -52.564157)
			(xy 285.600902 -52.65547) (xy 285.62046 -52.68214) (xy 285.636716 -52.68722) (xy 285.66226 -52.695666)
			(xy 285.710865 -52.718734) (xy 285.755746 -52.748403) (xy 285.796013 -52.784084) (xy 285.830867 -52.825069)
			(xy 285.859616 -52.870544) (xy 285.881691 -52.919608) (xy 285.896652 -52.971287) (xy 285.904204 -53.024555)
			(xy 285.904686 -53.051456) (xy 285.904132 -53.080682) (xy 285.895224 -53.13845) (xy 285.877611 -53.194184)
			(xy 285.851704 -53.24658) (xy 285.818109 -53.294412) (xy 285.79826 -53.31587) (xy 285.797498 -53.316632)
			(xy 285.79699 -53.31714) (xy 285.774531 -53.340172) (xy 285.723335 -53.379117) (xy 285.666339 -53.408936)
			(xy 285.635954 -53.419502) (xy 285.628334 -53.422042) (xy 285.61538 -53.431186) (xy 285.610808 -53.43779)
			(xy 285.606244 -53.444428) (xy 285.601182 -53.459712) (xy 285.600902 -53.467762) (xy 285.600902 -53.67147)
			(xy 285.62046 -53.69814) (xy 285.636716 -53.70322) (xy 285.66226 -53.711666) (xy 285.710865 -53.734734)
			(xy 285.755746 -53.764403) (xy 285.796013 -53.800084) (xy 285.830867 -53.841069) (xy 285.859616 -53.886544)
			(xy 285.881691 -53.935608) (xy 285.896652 -53.987287) (xy 285.904204 -54.040555) (xy 285.904686 -54.067456)
			(xy 285.904132 -54.096682) (xy 285.895224 -54.15445) (xy 285.877611 -54.210184) (xy 285.86341 -54.238906)
			(xy 292.5859 -54.238906) (xy 292.589971 -54.183284) (xy 292.602097 -54.128847) (xy 292.62202 -54.076756)
			(xy 292.649316 -54.028121) (xy 292.683402 -53.983978) (xy 292.723551 -53.945269) (xy 292.768909 -53.912818)
			(xy 292.818509 -53.887317) (xy 292.871293 -53.86931) (xy 292.926136 -53.85918) (xy 292.98187 -53.857143)
			(xy 293.037307 -53.863243) (xy 293.091264 -53.877349) (xy 293.142593 -53.899161) (xy 293.190199 -53.928215)
			(xy 293.233067 -53.96389) (xy 293.270284 -54.005427) (xy 293.301057 -54.05194) (xy 293.324729 -54.102437)
			(xy 293.340797 -54.155844) (xy 293.348917 -54.21102) (xy 293.349426 -54.238906) (xy 293.348917 -54.266792)
			(xy 293.340797 -54.321968) (xy 293.324729 -54.375375) (xy 293.301057 -54.425872) (xy 293.270284 -54.472385)
			(xy 293.233067 -54.513922) (xy 293.190199 -54.549597) (xy 293.142593 -54.578651) (xy 293.091264 -54.600463)
			(xy 293.037307 -54.614569) (xy 292.98187 -54.620669) (xy 292.926136 -54.618632) (xy 292.871293 -54.608502)
			(xy 292.818509 -54.590495) (xy 292.768909 -54.564994) (xy 292.723551 -54.532543) (xy 292.683402 -54.493834)
			(xy 292.649316 -54.449691) (xy 292.62202 -54.401056) (xy 292.602097 -54.348965) (xy 292.589971 -54.294528)
			(xy 292.5859 -54.238906) (xy 285.86341 -54.238906) (xy 285.851704 -54.26258) (xy 285.818109 -54.310412)
			(xy 285.79826 -54.33187) (xy 285.797498 -54.332632) (xy 285.79699 -54.33314) (xy 285.774531 -54.356172)
			(xy 285.723335 -54.395117) (xy 285.666339 -54.424936) (xy 285.635954 -54.435502) (xy 285.628334 -54.438042)
			(xy 285.61538 -54.447186) (xy 285.610808 -54.45379) (xy 285.606244 -54.460428) (xy 285.601182 -54.475712)
			(xy 285.600902 -54.483762) (xy 285.600902 -54.68747) (xy 285.62046 -54.71414) (xy 285.636716 -54.71922)
			(xy 285.66226 -54.727666) (xy 285.710865 -54.750734) (xy 285.755746 -54.780403) (xy 285.796013 -54.816084)
			(xy 285.830867 -54.857069) (xy 285.859616 -54.902544) (xy 285.881691 -54.951608) (xy 285.892532 -54.989055)
			(xy 288.100945 -54.989055) (xy 288.100945 -54.934545) (xy 288.108703 -54.880591) (xy 288.12406 -54.82829)
			(xy 288.146705 -54.778707) (xy 288.176176 -54.732851) (xy 288.211874 -54.691657) (xy 288.25307 -54.655962)
			(xy 288.298928 -54.626494) (xy 288.348512 -54.603852) (xy 288.400814 -54.588498) (xy 288.454769 -54.580743)
			(xy 288.482024 -54.580282) (xy 288.510116 -54.580758) (xy 288.565694 -54.588988) (xy 288.619464 -54.605283)
			(xy 288.670261 -54.629289) (xy 288.716988 -54.660486) (xy 288.758632 -54.698201) (xy 288.794294 -54.741616)
			(xy 288.809176 -54.765448) (xy 288.81451 -54.774592) (xy 288.831528 -54.786784) (xy 288.924746 -54.80685)
			(xy 288.94532 -54.802786) (xy 288.953956 -54.79669) (xy 288.97803 -54.780705) (xy 289.029958 -54.755359)
			(xy 289.085113 -54.73813) (xy 289.142234 -54.729409) (xy 289.171126 -54.728872) (xy 289.198377 -54.729354)
			(xy 289.252324 -54.737113) (xy 289.304617 -54.752471) (xy 289.354193 -54.775113) (xy 289.400043 -54.80458)
			(xy 289.441232 -54.840272) (xy 289.476923 -54.881462) (xy 289.50639 -54.927312) (xy 289.529032 -54.976888)
			(xy 289.544388 -55.029182) (xy 289.552147 -55.083129) (xy 289.552634 -55.11038) (xy 289.552172 -55.137751)
			(xy 289.544356 -55.19193) (xy 289.528867 -55.244434) (xy 289.506024 -55.294181) (xy 289.476297 -55.340147)
			(xy 289.458654 -55.361078) (xy 289.452558 -55.36819) (xy 289.446208 -55.385208) (xy 289.446208 -55.470552)
			(xy 289.452558 -55.48757) (xy 289.458654 -55.494682) (xy 289.476276 -55.51563) (xy 289.506003 -55.561595)
			(xy 289.528851 -55.611338) (xy 289.544349 -55.663838) (xy 289.55218 -55.718015) (xy 289.552182 -55.772755)
			(xy 289.544356 -55.826932) (xy 289.528861 -55.879433) (xy 289.506017 -55.929179) (xy 289.476294 -55.975146)
			(xy 289.458654 -55.996078) (xy 289.452558 -56.00319) (xy 289.446208 -56.020208) (xy 289.446208 -56.105552)
			(xy 289.452558 -56.12257) (xy 289.458654 -56.129682) (xy 289.476291 -56.150616) (xy 289.506005 -56.196588)
			(xy 289.528842 -56.246334) (xy 289.544333 -56.298835) (xy 289.552161 -56.353011) (xy 289.552634 -56.38038)
			(xy 289.552148 -56.407631) (xy 289.544392 -56.461579) (xy 289.529037 -56.513874) (xy 289.506395 -56.563451)
			(xy 289.476929 -56.609301) (xy 289.441238 -56.650492) (xy 289.400047 -56.686183) (xy 289.354197 -56.715649)
			(xy 289.30462 -56.738291) (xy 289.252325 -56.753646) (xy 289.198377 -56.761402) (xy 289.143875 -56.761402)
			(xy 289.089927 -56.753646) (xy 289.037632 -56.738291) (xy 288.988055 -56.715649) (xy 288.942205 -56.686183)
			(xy 288.901014 -56.650492) (xy 288.865323 -56.609301) (xy 288.835857 -56.563451) (xy 288.813215 -56.513874)
			(xy 288.79786 -56.461579) (xy 288.790104 -56.407631) (xy 288.789618 -56.38038) (xy 288.790068 -56.353009)
			(xy 288.797889 -56.298829) (xy 288.813382 -56.246326) (xy 288.836227 -56.196579) (xy 288.865955 -56.150613)
			(xy 288.883598 -56.129682) (xy 288.889694 -56.12257) (xy 288.896044 -56.105552) (xy 288.896044 -56.020208)
			(xy 288.889694 -56.00319) (xy 288.883598 -55.996078) (xy 288.865939 -55.975161) (xy 288.836217 -55.929189)
			(xy 288.813375 -55.87944) (xy 288.797881 -55.826936) (xy 288.790055 -55.772756) (xy 288.790057 -55.718014)
			(xy 288.797888 -55.663834) (xy 288.813385 -55.611331) (xy 288.836232 -55.561584) (xy 288.865957 -55.515615)
			(xy 288.883598 -55.494682) (xy 288.889694 -55.48757) (xy 288.896044 -55.470552) (xy 288.896044 -55.385208)
			(xy 288.889694 -55.36819) (xy 288.883598 -55.361078) (xy 288.872646 -55.348283) (xy 288.852806 -55.321063)
			(xy 288.843974 -55.306722) (xy 288.83864 -55.297578) (xy 288.821622 -55.285386) (xy 288.728404 -55.26532)
			(xy 288.70783 -55.269384) (xy 288.699194 -55.27548) (xy 288.675132 -55.291483) (xy 288.6232 -55.316825)
			(xy 288.568041 -55.33405) (xy 288.510917 -55.342764) (xy 288.482024 -55.343298) (xy 288.454769 -55.342857)
			(xy 288.400814 -55.335102) (xy 288.348512 -55.319748) (xy 288.298928 -55.297106) (xy 288.25307 -55.267638)
			(xy 288.211874 -55.231943) (xy 288.176176 -55.190749) (xy 288.146705 -55.144893) (xy 288.12406 -55.09531)
			(xy 288.108703 -55.043009) (xy 288.100945 -54.989055) (xy 285.892532 -54.989055) (xy 285.896652 -55.003287)
			(xy 285.904204 -55.056555) (xy 285.904686 -55.083456) (xy 285.904132 -55.112682) (xy 285.895224 -55.17045)
			(xy 285.877611 -55.226184) (xy 285.851704 -55.27858) (xy 285.818109 -55.326412) (xy 285.79826 -55.34787)
			(xy 285.797498 -55.348632) (xy 285.79699 -55.34914) (xy 285.774531 -55.372172) (xy 285.723335 -55.411117)
			(xy 285.704722 -55.420855) (xy 286.424545 -55.420855) (xy 286.424545 -55.366345) (xy 286.432303 -55.312391)
			(xy 286.44766 -55.26009) (xy 286.470305 -55.210507) (xy 286.499776 -55.164651) (xy 286.535474 -55.123457)
			(xy 286.57667 -55.087762) (xy 286.622528 -55.058294) (xy 286.672112 -55.035652) (xy 286.724414 -55.020298)
			(xy 286.778369 -55.012543) (xy 286.805624 -55.012082) (xy 286.83194 -55.012545) (xy 286.884073 -55.019764)
			(xy 286.934721 -55.034075) (xy 286.982923 -55.055208) (xy 287.027765 -55.082761) (xy 287.068397 -55.116213)
			(xy 287.086548 -55.135272) (xy 287.094053 -55.142693) (xy 287.113346 -55.151207) (xy 287.123886 -55.151782)
			(xy 287.198562 -55.151782) (xy 287.209112 -55.151251) (xy 287.228407 -55.142718) (xy 287.2359 -55.135272)
			(xy 287.254049 -55.116206) (xy 287.294665 -55.082724) (xy 287.339502 -55.05515) (xy 287.387707 -55.034009)
			(xy 287.438362 -55.019702) (xy 287.490505 -55.012503) (xy 287.516824 -55.012082) (xy 287.544073 -55.01259)
			(xy 287.598017 -55.020349) (xy 287.650307 -55.035706) (xy 287.69988 -55.058348) (xy 287.745726 -55.087814)
			(xy 287.786913 -55.123504) (xy 287.822601 -55.164693) (xy 287.852064 -55.210541) (xy 287.874703 -55.260115)
			(xy 287.890056 -55.312406) (xy 287.897812 -55.366351) (xy 287.897812 -55.420849) (xy 287.890056 -55.474794)
			(xy 287.874703 -55.527085) (xy 287.852064 -55.576659) (xy 287.822601 -55.622507) (xy 287.786913 -55.663696)
			(xy 287.745726 -55.699386) (xy 287.69988 -55.728852) (xy 287.650307 -55.751494) (xy 287.598017 -55.766851)
			(xy 287.544073 -55.77461) (xy 287.516824 -55.775098) (xy 287.490507 -55.774676) (xy 287.438372 -55.76745)
			(xy 287.387723 -55.753131) (xy 287.339521 -55.73199) (xy 287.29468 -55.704429) (xy 287.254049 -55.670971)
			(xy 287.2359 -55.651908) (xy 287.228379 -55.644506) (xy 287.209099 -55.635981) (xy 287.198562 -55.635398)
			(xy 287.123886 -55.635398) (xy 287.113334 -55.635907) (xy 287.094039 -55.644456) (xy 287.086548 -55.651908)
			(xy 287.06844 -55.671014) (xy 287.027814 -55.704489) (xy 286.982968 -55.732056) (xy 286.934755 -55.75319)
			(xy 286.884093 -55.767489) (xy 286.831945 -55.774681) (xy 286.805624 -55.775098) (xy 286.778369 -55.774657)
			(xy 286.724414 -55.766902) (xy 286.672112 -55.751548) (xy 286.622528 -55.728906) (xy 286.57667 -55.699438)
			(xy 286.535474 -55.663743) (xy 286.499776 -55.622549) (xy 286.470305 -55.576693) (xy 286.44766 -55.52711)
			(xy 286.432303 -55.474809) (xy 286.424545 -55.420855) (xy 285.704722 -55.420855) (xy 285.666339 -55.440936)
			(xy 285.635954 -55.451502) (xy 285.628334 -55.454042) (xy 285.61538 -55.463186) (xy 285.610808 -55.46979)
			(xy 285.606244 -55.476428) (xy 285.601182 -55.491712) (xy 285.600902 -55.499762) (xy 285.600902 -55.95747)
			(xy 285.62046 -55.98414) (xy 285.636716 -55.98922) (xy 285.66226 -55.997666) (xy 285.710865 -56.020734)
			(xy 285.755746 -56.050403) (xy 285.796013 -56.086084) (xy 285.830867 -56.127069) (xy 285.859616 -56.172544)
			(xy 285.881691 -56.221608) (xy 285.896652 -56.273287) (xy 285.904204 -56.326555) (xy 285.904686 -56.353456)
			(xy 285.904132 -56.382682) (xy 285.895224 -56.44045) (xy 285.877611 -56.496184) (xy 285.851704 -56.54858)
			(xy 285.818109 -56.596412) (xy 285.79826 -56.61787) (xy 285.797498 -56.618632) (xy 285.79699 -56.61914)
			(xy 285.774531 -56.642172) (xy 285.723335 -56.681117) (xy 285.666339 -56.710936) (xy 285.635954 -56.721502)
			(xy 285.628334 -56.724042) (xy 285.61538 -56.733186) (xy 285.610808 -56.73979) (xy 285.606244 -56.746428)
			(xy 285.601182 -56.761712) (xy 285.600902 -56.769762) (xy 285.600902 -57.48528) (xy 288.805872 -57.48528)
			(xy 288.809943 -57.429658) (xy 288.822069 -57.375221) (xy 288.841992 -57.32313) (xy 288.869288 -57.274495)
			(xy 288.903374 -57.230352) (xy 288.943523 -57.191643) (xy 288.988881 -57.159192) (xy 289.038481 -57.133691)
			(xy 289.091265 -57.115684) (xy 289.146108 -57.105554) (xy 289.201842 -57.103517) (xy 289.257279 -57.109617)
			(xy 289.311236 -57.123723) (xy 289.362565 -57.145535) (xy 289.410171 -57.174589) (xy 289.453039 -57.210264)
			(xy 289.490256 -57.251801) (xy 289.521029 -57.298314) (xy 289.544701 -57.348811) (xy 289.560769 -57.402218)
			(xy 289.568889 -57.457394) (xy 289.569398 -57.48528) (xy 289.568889 -57.513166) (xy 289.560769 -57.568342)
			(xy 289.544701 -57.621749) (xy 289.521029 -57.672246) (xy 289.490256 -57.718759) (xy 289.453039 -57.760296)
			(xy 289.410171 -57.795971) (xy 289.362565 -57.825025) (xy 289.311236 -57.846837) (xy 289.257279 -57.860943)
			(xy 289.201842 -57.867043) (xy 289.146108 -57.865006) (xy 289.091265 -57.854876) (xy 289.038481 -57.836869)
			(xy 288.988881 -57.811368) (xy 288.943523 -57.778917) (xy 288.903374 -57.740208) (xy 288.869288 -57.696065)
			(xy 288.841992 -57.64743) (xy 288.822069 -57.595339) (xy 288.809943 -57.540902) (xy 288.805872 -57.48528)
			(xy 285.600902 -57.48528) (xy 285.600902 -58.076084) (xy 289.557966 -58.076084) (xy 289.562037 -58.020462)
			(xy 289.574163 -57.966025) (xy 289.594086 -57.913934) (xy 289.621382 -57.865299) (xy 289.655468 -57.821156)
			(xy 289.695617 -57.782447) (xy 289.740975 -57.749996) (xy 289.790575 -57.724495) (xy 289.843359 -57.706488)
			(xy 289.898202 -57.696358) (xy 289.953936 -57.694321) (xy 290.009373 -57.700421) (xy 290.06333 -57.714527)
			(xy 290.114659 -57.736339) (xy 290.162265 -57.765393) (xy 290.205133 -57.801068) (xy 290.24235 -57.842605)
			(xy 290.258686 -57.867296) (xy 291.842696 -57.867296) (xy 291.846769 -57.811637) (xy 291.858904 -57.757164)
			(xy 291.87884 -57.705038) (xy 291.906154 -57.65637) (xy 291.940262 -57.612198) (xy 291.980439 -57.573463)
			(xy 292.025827 -57.540991) (xy 292.075459 -57.515473) (xy 292.128279 -57.497454) (xy 292.183158 -57.487317)
			(xy 292.238929 -57.485279) (xy 292.294403 -57.491382) (xy 292.348396 -57.505498) (xy 292.399759 -57.527325)
			(xy 292.447397 -57.556398) (xy 292.490293 -57.592097) (xy 292.527535 -57.633661) (xy 292.558329 -57.680205)
			(xy 292.582017 -57.730736) (xy 292.598095 -57.784178) (xy 292.606221 -57.839392) (xy 292.60673 -57.867296)
			(xy 292.606221 -57.8952) (xy 292.598095 -57.950414) (xy 292.582017 -58.003856) (xy 292.558329 -58.054387)
			(xy 292.527535 -58.100931) (xy 292.490293 -58.142495) (xy 292.447397 -58.178194) (xy 292.399759 -58.207267)
			(xy 292.348396 -58.229094) (xy 292.294403 -58.24321) (xy 292.238929 -58.249313) (xy 292.183158 -58.247275)
			(xy 292.128279 -58.237138) (xy 292.075459 -58.219119) (xy 292.025827 -58.193601) (xy 291.980439 -58.161129)
			(xy 291.940262 -58.122394) (xy 291.906154 -58.078222) (xy 291.87884 -58.029554) (xy 291.858904 -57.977428)
			(xy 291.846769 -57.922955) (xy 291.842696 -57.867296) (xy 290.258686 -57.867296) (xy 290.273123 -57.889118)
			(xy 290.296795 -57.939615) (xy 290.312863 -57.993022) (xy 290.320983 -58.048198) (xy 290.321492 -58.076084)
			(xy 290.320983 -58.10397) (xy 290.312863 -58.159146) (xy 290.296795 -58.212553) (xy 290.273123 -58.26305)
			(xy 290.24235 -58.309563) (xy 290.205133 -58.3511) (xy 290.162265 -58.386775) (xy 290.114659 -58.415829)
			(xy 290.06333 -58.437641) (xy 290.009373 -58.451747) (xy 289.953936 -58.457847) (xy 289.898202 -58.45581)
			(xy 289.843359 -58.44568) (xy 289.790575 -58.427673) (xy 289.740975 -58.402172) (xy 289.695617 -58.369721)
			(xy 289.655468 -58.331012) (xy 289.621382 -58.286869) (xy 289.594086 -58.238234) (xy 289.574163 -58.186143)
			(xy 289.562037 -58.131706) (xy 289.557966 -58.076084) (xy 285.600902 -58.076084) (xy 285.600902 -58.561224)
			(xy 290.76218 -58.561224) (xy 290.766251 -58.505602) (xy 290.778377 -58.451165) (xy 290.7983 -58.399074)
			(xy 290.825596 -58.350439) (xy 290.859682 -58.306296) (xy 290.899831 -58.267587) (xy 290.945189 -58.235136)
			(xy 290.994789 -58.209635) (xy 291.047573 -58.191628) (xy 291.102416 -58.181498) (xy 291.15815 -58.179461)
			(xy 291.213587 -58.185561) (xy 291.267544 -58.199667) (xy 291.318873 -58.221479) (xy 291.366479 -58.250533)
			(xy 291.409347 -58.286208) (xy 291.446564 -58.327745) (xy 291.477337 -58.374258) (xy 291.501009 -58.424755)
			(xy 291.508519 -58.449718) (xy 293.00881 -58.449718) (xy 293.012881 -58.394096) (xy 293.025007 -58.339659)
			(xy 293.04493 -58.287568) (xy 293.072226 -58.238933) (xy 293.106312 -58.19479) (xy 293.146461 -58.156081)
			(xy 293.191819 -58.12363) (xy 293.241419 -58.098129) (xy 293.294203 -58.080122) (xy 293.349046 -58.069992)
			(xy 293.40478 -58.067955) (xy 293.460217 -58.074055) (xy 293.514174 -58.088161) (xy 293.565503 -58.109973)
			(xy 293.613109 -58.139027) (xy 293.655977 -58.174702) (xy 293.693194 -58.216239) (xy 293.723967 -58.262752)
			(xy 293.747639 -58.313249) (xy 293.763707 -58.366656) (xy 293.771827 -58.421832) (xy 293.772336 -58.449718)
			(xy 293.771827 -58.477604) (xy 293.763707 -58.53278) (xy 293.747639 -58.586187) (xy 293.723967 -58.636684)
			(xy 293.693194 -58.683197) (xy 293.655977 -58.724734) (xy 293.613109 -58.760409) (xy 293.565503 -58.789463)
			(xy 293.514174 -58.811275) (xy 293.460217 -58.825381) (xy 293.40478 -58.831481) (xy 293.349046 -58.829444)
			(xy 293.294203 -58.819314) (xy 293.241419 -58.801307) (xy 293.191819 -58.775806) (xy 293.146461 -58.743355)
			(xy 293.106312 -58.704646) (xy 293.072226 -58.660503) (xy 293.04493 -58.611868) (xy 293.025007 -58.559777)
			(xy 293.012881 -58.50534) (xy 293.00881 -58.449718) (xy 291.508519 -58.449718) (xy 291.517077 -58.478162)
			(xy 291.525197 -58.533338) (xy 291.525706 -58.561224) (xy 291.525197 -58.58911) (xy 291.517077 -58.644286)
			(xy 291.501009 -58.697693) (xy 291.477337 -58.74819) (xy 291.446564 -58.794703) (xy 291.409347 -58.83624)
			(xy 291.366479 -58.871915) (xy 291.318873 -58.900969) (xy 291.267544 -58.922781) (xy 291.213587 -58.936887)
			(xy 291.15815 -58.942987) (xy 291.102416 -58.94095) (xy 291.047573 -58.93082) (xy 290.994789 -58.912813)
			(xy 290.945189 -58.887312) (xy 290.899831 -58.854861) (xy 290.859682 -58.816152) (xy 290.825596 -58.772009)
			(xy 290.7983 -58.723374) (xy 290.778377 -58.671283) (xy 290.766251 -58.616846) (xy 290.76218 -58.561224)
			(xy 285.600902 -58.561224) (xy 285.600902 -59.974734) (xy 289.28695 -59.974734) (xy 289.287359 -59.947906)
			(xy 289.294881 -59.89478) (xy 289.309767 -59.84323) (xy 289.331723 -59.794272) (xy 289.360318 -59.74887)
			(xy 289.394988 -59.707919) (xy 289.43505 -59.672225) (xy 289.45713 -59.65698) (xy 289.468696 -59.648762)
			(xy 289.487098 -59.627181) (xy 289.49885 -59.601369) (xy 289.503044 -59.573319) (xy 289.499356 -59.545199)
			(xy 289.488071 -59.519179) (xy 289.470061 -59.49727) (xy 289.458654 -59.488832) (xy 289.437192 -59.473486)
			(xy 289.398281 -59.437857) (xy 289.36465 -59.397207) (xy 289.33694 -59.35231) (xy 289.31568 -59.304024)
			(xy 289.301276 -59.253269) (xy 289.294002 -59.201014) (xy 289.293554 -59.174634) (xy 289.29404 -59.147383)
			(xy 289.301796 -59.093435) (xy 289.317151 -59.04114) (xy 289.339793 -58.991563) (xy 289.369259 -58.945713)
			(xy 289.40495 -58.904522) (xy 289.446141 -58.868831) (xy 289.491991 -58.839365) (xy 289.541568 -58.816723)
			(xy 289.593863 -58.801368) (xy 289.647811 -58.793612) (xy 289.702313 -58.793612) (xy 289.756261 -58.801368)
			(xy 289.808556 -58.816723) (xy 289.858133 -58.839365) (xy 289.903983 -58.868831) (xy 289.945174 -58.904522)
			(xy 289.980865 -58.945713) (xy 290.010331 -58.991563) (xy 290.032973 -59.04114) (xy 290.048328 -59.093435)
			(xy 290.056084 -59.147383) (xy 290.05657 -59.174634) (xy 290.056127 -59.201461) (xy 290.048611 -59.254585)
			(xy 290.03373 -59.306134) (xy 290.011779 -59.355092) (xy 289.983189 -59.400494) (xy 289.948525 -59.441446)
			(xy 289.908468 -59.477142) (xy 289.88639 -59.492388) (xy 289.874853 -59.500645) (xy 289.856449 -59.522216)
			(xy 289.844692 -59.54802) (xy 289.840494 -59.576063) (xy 289.844177 -59.604178) (xy 289.855456 -59.630194)
			(xy 289.873462 -59.652099) (xy 289.884866 -59.660536) (xy 289.906364 -59.675833) (xy 289.945274 -59.711471)
			(xy 289.978902 -59.75213) (xy 290.006607 -59.797035) (xy 290.02786 -59.845329) (xy 290.042257 -59.896091)
			(xy 290.049522 -59.948352) (xy 290.049966 -59.974734) (xy 290.04948 -60.001985) (xy 290.041724 -60.055933)
			(xy 290.026369 -60.108228) (xy 290.003727 -60.157805) (xy 289.974261 -60.203655) (xy 289.93857 -60.244846)
			(xy 289.897379 -60.280537) (xy 289.851529 -60.310003) (xy 289.801952 -60.332645) (xy 289.749657 -60.348)
			(xy 289.695709 -60.355756) (xy 289.641207 -60.355756) (xy 289.587259 -60.348) (xy 289.534964 -60.332645)
			(xy 289.485387 -60.310003) (xy 289.439537 -60.280537) (xy 289.398346 -60.244846) (xy 289.362655 -60.203655)
			(xy 289.333189 -60.157805) (xy 289.310547 -60.108228) (xy 289.295192 -60.055933) (xy 289.287436 -60.001985)
			(xy 289.28695 -59.974734) (xy 285.600902 -59.974734) (xy 285.600902 -60.601606) (xy 288.533076 -60.601606)
			(xy 288.537147 -60.545984) (xy 288.549273 -60.491547) (xy 288.569196 -60.439456) (xy 288.596492 -60.390821)
			(xy 288.630578 -60.346678) (xy 288.670727 -60.307969) (xy 288.716085 -60.275518) (xy 288.765685 -60.250017)
			(xy 288.818469 -60.23201) (xy 288.873312 -60.22188) (xy 288.929046 -60.219843) (xy 288.984483 -60.225943)
			(xy 289.03844 -60.240049) (xy 289.089769 -60.261861) (xy 289.137375 -60.290915) (xy 289.180243 -60.32659)
			(xy 289.21746 -60.368127) (xy 289.248233 -60.41464) (xy 289.271905 -60.465137) (xy 289.287973 -60.518544)
			(xy 289.296093 -60.57372) (xy 289.296602 -60.601606) (xy 289.296138 -60.627006) (xy 290.921184 -60.627006)
			(xy 290.925255 -60.571384) (xy 290.937381 -60.516947) (xy 290.957304 -60.464856) (xy 290.9846 -60.416221)
			(xy 291.018686 -60.372078) (xy 291.058835 -60.333369) (xy 291.104193 -60.300918) (xy 291.153793 -60.275417)
			(xy 291.206577 -60.25741) (xy 291.26142 -60.24728) (xy 291.317154 -60.245243) (xy 291.372591 -60.251343)
			(xy 291.426548 -60.265449) (xy 291.477877 -60.287261) (xy 291.525483 -60.316315) (xy 291.568351 -60.35199)
			(xy 291.605568 -60.393527) (xy 291.636341 -60.44004) (xy 291.660013 -60.490537) (xy 291.676081 -60.543944)
			(xy 291.684201 -60.59912) (xy 291.68471 -60.627006) (xy 291.684594 -60.633356) (xy 293.012874 -60.633356)
			(xy 293.016945 -60.577734) (xy 293.029071 -60.523297) (xy 293.048994 -60.471206) (xy 293.07629 -60.422571)
			(xy 293.110376 -60.378428) (xy 293.150525 -60.339719) (xy 293.195883 -60.307268) (xy 293.245483 -60.281767)
			(xy 293.298267 -60.26376) (xy 293.35311 -60.25363) (xy 293.408844 -60.251593) (xy 293.464281 -60.257693)
			(xy 293.518238 -60.271799) (xy 293.569567 -60.293611) (xy 293.617173 -60.322665) (xy 293.660041 -60.35834)
			(xy 293.697258 -60.399877) (xy 293.728031 -60.44639) (xy 293.751703 -60.496887) (xy 293.767771 -60.550294)
			(xy 293.775891 -60.60547) (xy 293.7764 -60.633356) (xy 293.775891 -60.661242) (xy 293.767771 -60.716418)
			(xy 293.751703 -60.769825) (xy 293.728031 -60.820322) (xy 293.697258 -60.866835) (xy 293.660041 -60.908372)
			(xy 293.617173 -60.944047) (xy 293.569567 -60.973101) (xy 293.518238 -60.994913) (xy 293.464281 -61.009019)
			(xy 293.408844 -61.015119) (xy 293.35311 -61.013082) (xy 293.298267 -61.002952) (xy 293.245483 -60.984945)
			(xy 293.195883 -60.959444) (xy 293.150525 -60.926993) (xy 293.110376 -60.888284) (xy 293.07629 -60.844141)
			(xy 293.048994 -60.795506) (xy 293.029071 -60.743415) (xy 293.016945 -60.688978) (xy 293.012874 -60.633356)
			(xy 291.684594 -60.633356) (xy 291.684201 -60.654892) (xy 291.676081 -60.710068) (xy 291.660013 -60.763475)
			(xy 291.636341 -60.813972) (xy 291.605568 -60.860485) (xy 291.568351 -60.902022) (xy 291.525483 -60.937697)
			(xy 291.477877 -60.966751) (xy 291.426548 -60.988563) (xy 291.372591 -61.002669) (xy 291.317154 -61.008769)
			(xy 291.26142 -61.006732) (xy 291.206577 -60.996602) (xy 291.153793 -60.978595) (xy 291.104193 -60.953094)
			(xy 291.058835 -60.920643) (xy 291.018686 -60.881934) (xy 290.9846 -60.837791) (xy 290.957304 -60.789156)
			(xy 290.937381 -60.737065) (xy 290.925255 -60.682628) (xy 290.921184 -60.627006) (xy 289.296138 -60.627006)
			(xy 289.296093 -60.629492) (xy 289.287973 -60.684668) (xy 289.271905 -60.738075) (xy 289.248233 -60.788572)
			(xy 289.21746 -60.835085) (xy 289.180243 -60.876622) (xy 289.137375 -60.912297) (xy 289.089769 -60.941351)
			(xy 289.03844 -60.963163) (xy 288.984483 -60.977269) (xy 288.929046 -60.983369) (xy 288.873312 -60.981332)
			(xy 288.818469 -60.971202) (xy 288.765685 -60.953195) (xy 288.716085 -60.927694) (xy 288.670727 -60.895243)
			(xy 288.630578 -60.856534) (xy 288.596492 -60.812391) (xy 288.569196 -60.763756) (xy 288.549273 -60.711665)
			(xy 288.537147 -60.657228) (xy 288.533076 -60.601606) (xy 285.600902 -60.601606) (xy 285.600902 -61.333126)
			(xy 285.60133 -61.343194) (xy 285.609051 -61.361791) (xy 285.615888 -61.369194) (xy 285.81477 -61.568076)
			(xy 285.834836 -61.575696) (xy 285.845758 -61.575188) (xy 285.86176 -61.57468) (xy 288.384996 -61.57468)
			(xy 288.419794 -61.576712) (xy 288.422842 -61.576966) (xy 289.225736 -61.576966)
		)
		(stroke
			(width 0)
			(type solid)
		)
		(fill yes)
		(layer "In9.Cu")
		(net "P3V3_SSD10")
	)
	(gr_poly
		(pts
			(xy 431.32883 -61.576712) (xy 431.363374 -61.57468) (xy 432.49723 -61.57468) (xy 432.506374 -61.573918)
			(xy 432.510692 -61.573156) (xy 432.518004 -61.571558) (xy 432.531307 -61.564717) (xy 432.536854 -61.559694)
			(xy 432.58486 -61.51372) (xy 432.591493 -61.506753) (xy 432.599467 -61.489262) (xy 432.600354 -61.479684)
			(xy 432.600354 -61.478668) (xy 432.60186 -61.451595) (xy 432.611568 -61.39825) (xy 432.628725 -61.346815)
			(xy 432.652986 -61.298325) (xy 432.683862 -61.253754) (xy 432.701954 -61.233558) (xy 432.702462 -61.23305)
			(xy 432.703224 -61.232288) (xy 432.704748 -61.23051) (xy 432.705256 -61.230002) (xy 432.706526 -61.228478)
			(xy 432.724655 -61.209564) (xy 432.765197 -61.176379) (xy 432.809895 -61.149049) (xy 432.85791 -61.128087)
			(xy 432.90834 -61.113886) (xy 432.960238 -61.106714) (xy 432.986434 -61.106304) (xy 433.013444 -61.106775)
			(xy 433.066923 -61.114398) (xy 433.118792 -61.129487) (xy 433.168015 -61.15174) (xy 433.213608 -61.180712)
			(xy 433.25466 -61.215825) (xy 433.290349 -61.256377) (xy 433.319962 -61.301556) (xy 433.342908 -61.35046)
			(xy 433.358728 -61.402111) (xy 433.367105 -61.455477) (xy 433.367942 -61.482478) (xy 433.368196 -61.492892)
			(xy 433.37607 -61.51118) (xy 433.420266 -61.553852) (xy 433.426108 -61.55944) (xy 433.431708 -61.564534)
			(xy 433.445136 -61.571506) (xy 433.452524 -61.573156) (xy 433.461414 -61.57468) (xy 434.443124 -61.57468)
			(xy 434.452098 -61.57473) (xy 434.470016 -61.575748) (xy 434.478938 -61.576712) (xy 435.343046 -61.576712)
			(xy 435.351968 -61.575745) (xy 435.369886 -61.574729) (xy 435.37886 -61.57468) (xy 437.053228 -61.57468)
			(xy 437.059522 -61.574489) (xy 437.071724 -61.571398) (xy 437.077358 -61.568584) (xy 437.083962 -61.565028)
			(xy 437.712358 -60.936632) (xy 437.715406 -60.93333) (xy 437.72582 -60.922916) (xy 437.728492 -60.917444)
			(xy 437.731444 -60.905634) (xy 437.731662 -60.899548) (xy 437.731662 -38.90645) (xy 437.7309 -38.897306)
			(xy 437.728106 -38.882574) (xy 437.719724 -38.867842) (xy 437.71312 -38.862) (xy 437.68046 -38.832691)
			(xy 437.62015 -38.768936) (xy 437.566045 -38.699838) (xy 437.518614 -38.625999) (xy 437.478272 -38.548061)
			(xy 437.445369 -38.466702) (xy 437.420191 -38.38263) (xy 437.402959 -38.296578) (xy 437.393821 -38.209295)
			(xy 437.392857 -38.12154) (xy 437.400076 -38.034077) (xy 437.415415 -37.947667) (xy 437.43874 -37.863063)
			(xy 437.469849 -37.781001) (xy 437.50847 -37.702196) (xy 437.554267 -37.627332) (xy 437.606843 -37.557063)
			(xy 437.635904 -37.524182) (xy 437.640476 -37.519102) (xy 437.64073 -37.518594) (xy 437.652398 -37.505892)
			(xy 437.676532 -37.481246) (xy 437.68899 -37.469318) (xy 437.702452 -37.457126) (xy 437.702706 -37.456872)
			(xy 437.707024 -37.452808) (xy 437.711088 -37.448998) (xy 437.717184 -37.440616) (xy 437.727344 -37.417248)
			(xy 437.729348 -37.412408) (xy 437.731527 -37.402164) (xy 437.731662 -37.396928) (xy 437.731662 -31.777432)
			(xy 437.728868 -31.769304) (xy 437.718711 -31.738539) (xy 437.707732 -31.674695) (xy 437.707024 -31.642304)
			(xy 437.707734 -31.609914) (xy 437.718719 -31.546071) (xy 437.728868 -31.515304) (xy 437.731662 -31.507176)
			(xy 437.731662 -31.238444) (xy 437.731776 -31.233488) (xy 437.733686 -31.223763) (xy 437.735472 -31.21914)
			(xy 437.740552 -31.207202) (xy 437.742352 -31.202516) (xy 437.744272 -31.192663) (xy 437.744362 -31.187644)
			(xy 437.744362 -29.841952) (xy 437.744101 -29.834013) (xy 437.73932 -29.818875) (xy 437.734964 -29.812234)
			(xy 437.71811 -29.787796) (xy 437.691367 -29.734799) (xy 437.673152 -29.678301) (xy 437.663903 -29.619664)
			(xy 437.663336 -29.589984) (xy 437.663919 -29.560304) (xy 437.673152 -29.501665) (xy 437.691362 -29.445165)
			(xy 437.718109 -29.392171) (xy 437.734964 -29.367734) (xy 437.739326 -29.361093) (xy 437.744124 -29.345957)
			(xy 437.744362 -29.338016) (xy 437.744362 -28.112974) (xy 437.744482 -28.108426) (xy 437.746137 -28.09948)
			(xy 437.747664 -28.095194) (xy 437.749431 -28.090052) (xy 437.750965 -28.07929) (xy 437.750712 -28.073858)
			(xy 437.748426 -28.044394) (xy 437.74769 -28.037202) (xy 437.742652 -28.023657) (xy 437.73852 -28.017724)
			(xy 437.720831 -27.99288) (xy 437.692741 -27.93875) (xy 437.673611 -27.880843) (xy 437.663928 -27.820632)
			(xy 437.663336 -27.79014) (xy 437.663797 -27.762886) (xy 437.671549 -27.708934) (xy 437.686902 -27.656633)
			(xy 437.709543 -27.607051) (xy 437.739011 -27.561196) (xy 437.774705 -27.520002) (xy 437.815899 -27.484308)
			(xy 437.861755 -27.454841) (xy 437.911337 -27.432201) (xy 437.963637 -27.416848) (xy 438.01759 -27.409096)
			(xy 438.044844 -27.408632) (xy 438.070391 -27.409044) (xy 438.121027 -27.415864) (xy 438.170301 -27.429378)
			(xy 438.217332 -27.449343) (xy 438.261281 -27.475402) (xy 438.281572 -27.490928) (xy 438.297066 -27.50312)
			(xy 438.335166 -27.501088) (xy 438.488582 -27.347672) (xy 438.495981 -27.340831) (xy 438.514581 -27.333115)
			(xy 438.52465 -27.332686) (xy 438.671462 -27.332686) (xy 438.676542 -27.33167) (xy 438.680352 -27.330908)
			(xy 438.681114 -27.330908) (xy 438.684924 -27.3304) (xy 438.702704 -27.328368) (xy 438.727342 -27.327352)
			(xy 442.7728 -27.327352) (xy 442.782372 -27.326937) (xy 442.800183 -27.319916) (xy 442.814204 -27.306879)
			(xy 442.8225 -27.289625) (xy 442.8236 -27.280108) (xy 442.8236 -26.479246) (xy 442.823832 -26.457911)
			(xy 442.827772 -26.415423) (xy 442.831474 -26.39441) (xy 442.832744 -26.387044) (xy 442.83122 -26.372566)
			(xy 442.828426 -26.365708) (xy 442.825437 -26.358993) (xy 442.816273 -26.347511) (xy 442.810392 -26.343102)
			(xy 442.802518 -26.337768) (xy 442.79477 -26.33286) (xy 442.777003 -26.328367) (xy 442.758789 -26.3304)
			(xy 442.750448 -26.334212) (xy 442.723318 -26.347564) (xy 442.665882 -26.366459) (xy 442.606182 -26.376039)
			(xy 442.57595 -26.37663) (xy 442.548694 -26.376171) (xy 442.494737 -26.36842) (xy 442.442431 -26.353068)
			(xy 442.392844 -26.330429) (xy 442.346983 -26.300962) (xy 442.305782 -26.265269) (xy 442.270081 -26.224075)
			(xy 442.240606 -26.17822) (xy 442.217957 -26.128636) (xy 442.202596 -26.076334) (xy 442.194835 -26.022378)
			(xy 442.194442 -25.995122) (xy 442.194982 -25.965825) (xy 442.203947 -25.90792) (xy 442.221655 -25.852065)
			(xy 442.247689 -25.799572) (xy 442.281438 -25.751673) (xy 442.301376 -25.7302) (xy 442.302138 -25.729438)
			(xy 442.302646 -25.72893) (xy 442.32075 -25.710289) (xy 442.361131 -25.677585) (xy 442.405577 -25.650664)
			(xy 442.453265 -25.630024) (xy 442.503313 -25.616047) (xy 442.554794 -25.608992) (xy 442.580776 -25.608534)
			(xy 442.609723 -25.609076) (xy 442.666951 -25.617834) (xy 442.7222 -25.635136) (xy 442.7742 -25.660587)
			(xy 442.821759 -25.693601) (xy 442.863785 -25.73342) (xy 442.899312 -25.779132) (xy 442.927527 -25.829686)
			(xy 442.928411 -25.832054) (xy 444.487806 -25.832054) (xy 444.491877 -25.776432) (xy 444.504003 -25.721995)
			(xy 444.523926 -25.669904) (xy 444.551222 -25.621269) (xy 444.585308 -25.577126) (xy 444.625457 -25.538417)
			(xy 444.670815 -25.505966) (xy 444.720415 -25.480465) (xy 444.773199 -25.462458) (xy 444.828042 -25.452328)
			(xy 444.883776 -25.450291) (xy 444.939213 -25.456391) (xy 444.99317 -25.470497) (xy 445.044499 -25.492309)
			(xy 445.092105 -25.521363) (xy 445.134973 -25.557038) (xy 445.136507 -25.55875) (xy 448.942206 -25.55875)
			(xy 448.942692 -25.531499) (xy 448.950448 -25.477551) (xy 448.965803 -25.425256) (xy 448.988445 -25.375679)
			(xy 449.017911 -25.329829) (xy 449.053602 -25.288638) (xy 449.094793 -25.252947) (xy 449.140643 -25.223481)
			(xy 449.19022 -25.200839) (xy 449.242515 -25.185484) (xy 449.296463 -25.177728) (xy 449.350965 -25.177728)
			(xy 449.404913 -25.185484) (xy 449.457208 -25.200839) (xy 449.506785 -25.223481) (xy 449.552635 -25.252947)
			(xy 449.593826 -25.288638) (xy 449.629517 -25.329829) (xy 449.658983 -25.375679) (xy 449.681625 -25.425256)
			(xy 449.69698 -25.477551) (xy 449.704736 -25.531499) (xy 449.705222 -25.55875) (xy 449.704669 -25.589013)
			(xy 449.695116 -25.648779) (xy 449.676243 -25.706287) (xy 449.648522 -25.760091) (xy 449.631054 -25.78481)
			(xy 449.622783 -25.796961) (xy 449.612836 -25.824602) (xy 449.61117 -25.853932) (xy 449.617922 -25.882523)
			(xy 449.632534 -25.908008) (xy 449.653796 -25.92828) (xy 449.679949 -25.941659) (xy 449.6943 -25.94483)
			(xy 449.720193 -25.950174) (xy 449.770316 -25.96699) (xy 449.817635 -25.990569) (xy 449.861244 -26.020458)
			(xy 449.900306 -26.056084) (xy 449.934072 -26.096764) (xy 449.961895 -26.141719) (xy 449.983242 -26.190086)
			(xy 449.997703 -26.240938) (xy 450.005002 -26.2933) (xy 450.00545 -26.319734) (xy 451.141844 -26.319734)
			(xy 451.145915 -26.264112) (xy 451.158041 -26.209675) (xy 451.177964 -26.157584) (xy 451.20526 -26.108949)
			(xy 451.239346 -26.064806) (xy 451.279495 -26.026097) (xy 451.324853 -25.993646) (xy 451.374453 -25.968145)
			(xy 451.427237 -25.950138) (xy 451.48208 -25.940008) (xy 451.537814 -25.937971) (xy 451.593251 -25.944071)
			(xy 451.647208 -25.958177) (xy 451.698537 -25.979989) (xy 451.746143 -26.009043) (xy 451.789011 -26.044718)
			(xy 451.826228 -26.086255) (xy 451.857001 -26.132768) (xy 451.880673 -26.183265) (xy 451.896741 -26.236672)
			(xy 451.904861 -26.291848) (xy 451.90537 -26.319734) (xy 451.904861 -26.34762) (xy 451.896741 -26.402796)
			(xy 451.880673 -26.456203) (xy 451.857001 -26.5067) (xy 451.826228 -26.553213) (xy 451.789011 -26.59475)
			(xy 451.746143 -26.630425) (xy 451.698537 -26.659479) (xy 451.647208 -26.681291) (xy 451.593251 -26.695397)
			(xy 451.537814 -26.701497) (xy 451.48208 -26.69946) (xy 451.427237 -26.68933) (xy 451.374453 -26.671323)
			(xy 451.324853 -26.645822) (xy 451.279495 -26.613371) (xy 451.239346 -26.574662) (xy 451.20526 -26.530519)
			(xy 451.177964 -26.481884) (xy 451.158041 -26.429793) (xy 451.145915 -26.375356) (xy 451.141844 -26.319734)
			(xy 450.00545 -26.319734) (xy 450.004964 -26.346985) (xy 449.997208 -26.400933) (xy 449.981853 -26.453228)
			(xy 449.959211 -26.502805) (xy 449.929745 -26.548655) (xy 449.894054 -26.589846) (xy 449.852863 -26.625537)
			(xy 449.807013 -26.655003) (xy 449.757436 -26.677645) (xy 449.705141 -26.693) (xy 449.651193 -26.700756)
			(xy 449.596691 -26.700756) (xy 449.542743 -26.693) (xy 449.490448 -26.677645) (xy 449.440871 -26.655003)
			(xy 449.395021 -26.625537) (xy 449.35383 -26.589846) (xy 449.318139 -26.548655) (xy 449.288673 -26.502805)
			(xy 449.266031 -26.453228) (xy 449.250676 -26.400933) (xy 449.24292 -26.346985) (xy 449.242434 -26.319734)
			(xy 449.242987 -26.289471) (xy 449.252541 -26.229705) (xy 449.271415 -26.172198) (xy 449.299135 -26.118393)
			(xy 449.316602 -26.093674) (xy 449.324919 -26.081551) (xy 449.334871 -26.0539) (xy 449.336537 -26.024559)
			(xy 449.329779 -25.995959) (xy 449.315157 -25.970467) (xy 449.293881 -25.950195) (xy 449.267713 -25.93682)
			(xy 449.253356 -25.933654) (xy 449.227453 -25.928357) (xy 449.177329 -25.911534) (xy 449.13001 -25.88795)
			(xy 449.086401 -25.858055) (xy 449.04734 -25.822423) (xy 449.013575 -25.781738) (xy 448.985753 -25.736778)
			(xy 448.964408 -25.688407) (xy 448.949949 -25.637551) (xy 448.942653 -25.585186) (xy 448.942206 -25.55875)
			(xy 445.136507 -25.55875) (xy 445.17219 -25.598575) (xy 445.202963 -25.645088) (xy 445.226635 -25.695585)
			(xy 445.242703 -25.748992) (xy 445.250823 -25.804168) (xy 445.251332 -25.832054) (xy 445.250823 -25.85994)
			(xy 445.242703 -25.915116) (xy 445.226635 -25.968523) (xy 445.202963 -26.01902) (xy 445.17219 -26.065533)
			(xy 445.134973 -26.10707) (xy 445.092105 -26.142745) (xy 445.044499 -26.171799) (xy 444.99317 -26.193611)
			(xy 444.939213 -26.207717) (xy 444.883776 -26.213817) (xy 444.828042 -26.21178) (xy 444.773199 -26.20165)
			(xy 444.720415 -26.183643) (xy 444.670815 -26.158142) (xy 444.625457 -26.125691) (xy 444.585308 -26.086982)
			(xy 444.551222 -26.042839) (xy 444.523926 -25.994204) (xy 444.504003 -25.942113) (xy 444.491877 -25.887676)
			(xy 444.487806 -25.832054) (xy 442.928411 -25.832054) (xy 442.94778 -25.883922) (xy 442.959607 -25.940596)
			(xy 442.961776 -25.969468) (xy 442.961776 -25.969976) (xy 442.96327 -25.982031) (xy 442.975735 -26.00284)
			(xy 442.985652 -26.009854) (xy 443.066424 -26.060654) (xy 443.091062 -26.062432) (xy 443.102492 -26.057606)
			(xy 443.130808 -26.046145) (xy 443.189719 -26.029986) (xy 443.250257 -26.021813) (xy 443.2808 -26.021284)
			(xy 443.298834 -26.021284) (xy 443.30493 -26.022046) (xy 443.306454 -26.022046) (xy 443.337928 -26.024327)
			(xy 443.399856 -26.036452) (xy 443.459533 -26.056964) (xy 443.515828 -26.085476) (xy 443.567675 -26.121447)
			(xy 443.614093 -26.164196) (xy 443.654202 -26.212914) (xy 443.687242 -26.266676) (xy 443.712588 -26.324466)
			(xy 443.722886 -26.360882) (xy 446.405506 -26.360882) (xy 446.409577 -26.30526) (xy 446.421703 -26.250823)
			(xy 446.441626 -26.198732) (xy 446.468922 -26.150097) (xy 446.503008 -26.105954) (xy 446.543157 -26.067245)
			(xy 446.588515 -26.034794) (xy 446.638115 -26.009293) (xy 446.690899 -25.991286) (xy 446.745742 -25.981156)
			(xy 446.801476 -25.979119) (xy 446.856913 -25.985219) (xy 446.91087 -25.999325) (xy 446.962199 -26.021137)
			(xy 447.009805 -26.050191) (xy 447.052673 -26.085866) (xy 447.08989 -26.127403) (xy 447.120663 -26.173916)
			(xy 447.144335 -26.224413) (xy 447.160403 -26.27782) (xy 447.168523 -26.332996) (xy 447.169032 -26.360882)
			(xy 447.168523 -26.388768) (xy 447.160403 -26.443944) (xy 447.144335 -26.497351) (xy 447.120663 -26.547848)
			(xy 447.08989 -26.594361) (xy 447.052673 -26.635898) (xy 447.009805 -26.671573) (xy 446.962199 -26.700627)
			(xy 446.91087 -26.722439) (xy 446.856913 -26.736545) (xy 446.801476 -26.742645) (xy 446.745742 -26.740608)
			(xy 446.690899 -26.730478) (xy 446.638115 -26.712471) (xy 446.588515 -26.68697) (xy 446.543157 -26.654519)
			(xy 446.503008 -26.61581) (xy 446.468922 -26.571667) (xy 446.441626 -26.523032) (xy 446.421703 -26.470941)
			(xy 446.409577 -26.416504) (xy 446.405506 -26.360882) (xy 443.722886 -26.360882) (xy 443.729759 -26.385189)
			(xy 443.73843 -26.447694) (xy 443.739016 -26.479246) (xy 443.739016 -27.280108) (xy 443.74007 -27.289651)
			(xy 443.748314 -27.306973) (xy 443.762356 -27.320044) (xy 443.780223 -27.327029) (xy 443.789816 -27.327352)
			(xy 452.995792 -27.327352) (xy 453.005664 -27.32688) (xy 453.023949 -27.319423) (xy 453.031352 -27.312874)
			(xy 453.031606 -27.31262) (xy 453.390762 -26.953464) (xy 453.397607 -26.946065) (xy 453.405334 -26.927467)
			(xy 453.405748 -26.917396) (xy 453.405748 -24.082756) (xy 453.4027 -24.074374) (xy 453.392491 -24.043557)
			(xy 453.381515 -23.979577) (xy 453.380856 -23.94712) (xy 453.380856 -23.946866) (xy 453.38151 -23.914409)
			(xy 453.392496 -23.850431) (xy 453.4027 -23.819612) (xy 453.405748 -23.810976) (xy 453.405748 -22.239478)
			(xy 453.389238 -22.214332) (xy 453.375014 -22.208236) (xy 453.374506 -22.207982) (xy 453.372982 -22.207474)
			(xy 453.347293 -22.196184) (xy 453.299265 -22.167171) (xy 453.256007 -22.131432) (xy 453.218454 -22.089741)
			(xy 453.187415 -22.042996) (xy 453.163561 -21.992208) (xy 453.147407 -21.938472) (xy 453.139302 -21.882949)
			(xy 453.139421 -21.826838) (xy 453.147761 -21.77135) (xy 453.164142 -21.717683) (xy 453.188211 -21.666996)
			(xy 453.219447 -21.620384) (xy 453.257177 -21.578852) (xy 453.300586 -21.543297) (xy 453.348737 -21.514487)
			(xy 453.374506 -21.503386) (xy 453.38873 -21.49729) (xy 453.405748 -21.472144) (xy 453.405748 -15.810992)
			(xy 453.38365 -15.783306) (xy 453.366378 -15.779242) (xy 453.340201 -15.772697) (xy 453.289878 -15.753231)
			(xy 453.2428 -15.726869) (xy 453.199906 -15.694136) (xy 453.162052 -15.655685) (xy 453.129993 -15.612285)
			(xy 453.10437 -15.5648) (xy 453.085693 -15.514179) (xy 453.074335 -15.461431) (xy 453.070523 -15.407609)
			(xy 453.074332 -15.353787) (xy 453.085688 -15.301038) (xy 453.104362 -15.250416) (xy 453.129983 -15.20293)
			(xy 453.16204 -15.159528) (xy 453.199892 -15.121076) (xy 453.242785 -15.088341) (xy 453.289862 -15.061977)
			(xy 453.340184 -15.042509) (xy 453.366378 -15.036038) (xy 453.38365 -15.031974) (xy 453.405748 -15.004288)
			(xy 453.405748 -14.89964) (xy 453.400668 -14.884146) (xy 453.395588 -14.877288) (xy 453.379477 -14.855132)
			(xy 453.353096 -14.807123) (xy 453.333856 -14.755832) (xy 453.322152 -14.702317) (xy 453.318226 -14.647678)
			(xy 453.322159 -14.593039) (xy 453.333868 -14.539525) (xy 453.353115 -14.488237) (xy 453.379501 -14.44023)
			(xy 453.395588 -14.418056) (xy 453.400279 -14.411257) (xy 453.40545 -14.395578) (xy 453.405748 -14.387322)
			(xy 453.405748 -13.73124) (xy 453.405312 -13.721176) (xy 453.397577 -13.702592) (xy 453.390762 -13.695172)
			(xy 453.085454 -13.389864) (xy 453.078056 -13.383018) (xy 453.059457 -13.37529) (xy 453.049386 -13.374878)
			(xy 448.342766 -13.374878) (xy 448.332698 -13.375307) (xy 448.3141 -13.383027) (xy 448.306698 -13.389864)
			(xy 447.59626 -14.100302) (xy 452.34301 -14.100302) (xy 452.347081 -14.04468) (xy 452.359207 -13.990243)
			(xy 452.37913 -13.938152) (xy 452.406426 -13.889517) (xy 452.440512 -13.845374) (xy 452.480661 -13.806665)
			(xy 452.526019 -13.774214) (xy 452.575619 -13.748713) (xy 452.628403 -13.730706) (xy 452.683246 -13.720576)
			(xy 452.73898 -13.718539) (xy 452.794417 -13.724639) (xy 452.848374 -13.738745) (xy 452.899703 -13.760557)
			(xy 452.947309 -13.789611) (xy 452.990177 -13.825286) (xy 453.027394 -13.866823) (xy 453.058167 -13.913336)
			(xy 453.081839 -13.963833) (xy 453.097907 -14.01724) (xy 453.106027 -14.072416) (xy 453.106536 -14.100302)
			(xy 453.106027 -14.128188) (xy 453.097907 -14.183364) (xy 453.081839 -14.236771) (xy 453.058167 -14.287268)
			(xy 453.027394 -14.333781) (xy 452.990177 -14.375318) (xy 452.947309 -14.410993) (xy 452.899703 -14.440047)
			(xy 452.848374 -14.461859) (xy 452.794417 -14.475965) (xy 452.73898 -14.482065) (xy 452.683246 -14.480028)
			(xy 452.628403 -14.469898) (xy 452.575619 -14.451891) (xy 452.526019 -14.42639) (xy 452.480661 -14.393939)
			(xy 452.440512 -14.35523) (xy 452.406426 -14.311087) (xy 452.37913 -14.262452) (xy 452.359207 -14.210361)
			(xy 452.347081 -14.155924) (xy 452.34301 -14.100302) (xy 447.59626 -14.100302) (xy 447.000884 -14.695678)
			(xy 446.995668 -14.700582) (xy 446.983161 -14.707537) (xy 446.976246 -14.709394) (xy 446.966594 -14.71168)
			(xy 446.9511 -14.722348) (xy 446.89395 -14.807184) (xy 446.89141 -14.832076) (xy 446.896236 -14.844014)
			(xy 446.920551 -14.904939) (xy 446.962554 -15.029225) (xy 446.99684 -15.155857) (xy 447.023281 -15.284357)
			(xy 447.035519 -15.370302) (xy 452.20331 -15.370302) (xy 452.207381 -15.31468) (xy 452.219507 -15.260243)
			(xy 452.23943 -15.208152) (xy 452.266726 -15.159517) (xy 452.300812 -15.115374) (xy 452.340961 -15.076665)
			(xy 452.386319 -15.044214) (xy 452.435919 -15.018713) (xy 452.488703 -15.000706) (xy 452.543546 -14.990576)
			(xy 452.59928 -14.988539) (xy 452.654717 -14.994639) (xy 452.708674 -15.008745) (xy 452.760003 -15.030557)
			(xy 452.807609 -15.059611) (xy 452.850477 -15.095286) (xy 452.887694 -15.136823) (xy 452.918467 -15.183336)
			(xy 452.942139 -15.233833) (xy 452.958207 -15.28724) (xy 452.966327 -15.342416) (xy 452.966836 -15.370302)
			(xy 452.966327 -15.398188) (xy 452.958207 -15.453364) (xy 452.942139 -15.506771) (xy 452.918467 -15.557268)
			(xy 452.887694 -15.603781) (xy 452.850477 -15.645318) (xy 452.807609 -15.680993) (xy 452.760003 -15.710047)
			(xy 452.708674 -15.731859) (xy 452.654717 -15.745965) (xy 452.59928 -15.752065) (xy 452.543546 -15.750028)
			(xy 452.488703 -15.739898) (xy 452.435919 -15.721891) (xy 452.386319 -15.69639) (xy 452.340961 -15.663939)
			(xy 452.300812 -15.62523) (xy 452.266726 -15.581087) (xy 452.23943 -15.532452) (xy 452.219507 -15.480361)
			(xy 452.207381 -15.425924) (xy 452.20331 -15.370302) (xy 447.035519 -15.370302) (xy 447.041775 -15.414238)
			(xy 447.052254 -15.545011) (xy 447.05397 -15.610586) (xy 447.054224 -15.64894) (xy 447.054224 -15.649956)
			(xy 447.053728 -15.714979) (xy 447.045806 -15.844785) (xy 447.029993 -15.973867) (xy 447.00635 -16.101746)
			(xy 446.974964 -16.227949) (xy 446.93595 -16.352006) (xy 446.889455 -16.473457) (xy 446.83565 -16.591851)
			(xy 446.774736 -16.70675) (xy 446.706938 -16.817725) (xy 446.632508 -16.924367) (xy 446.551722 -17.026278)
			(xy 446.46488 -17.12308) (xy 446.41897 -17.16913) (xy 446.373088 -17.21403) (xy 446.276723 -17.298869)
			(xy 446.175433 -17.377762) (xy 446.069583 -17.450424) (xy 445.959557 -17.51659) (xy 445.845751 -17.576023)
			(xy 445.728579 -17.628507) (xy 445.608464 -17.673852) (xy 445.48584 -17.711894) (xy 445.361151 -17.742496)
			(xy 445.234848 -17.765547) (xy 445.107387 -17.780964) (xy 444.979231 -17.78869) (xy 444.915036 -17.789144)
			(xy 444.850564 -17.788658) (xy 444.721854 -17.780875) (xy 444.593849 -17.765335) (xy 444.467016 -17.742094)
			(xy 444.341818 -17.711237) (xy 444.218711 -17.672878) (xy 444.098145 -17.627156) (xy 443.98056 -17.574237)
			(xy 443.866384 -17.514315) (xy 443.756035 -17.447609) (xy 443.649914 -17.374362) (xy 443.548409 -17.294841)
			(xy 443.451892 -17.209337) (xy 443.360712 -17.118161) (xy 443.275205 -17.021646) (xy 443.19568 -16.920144)
			(xy 443.12243 -16.814026) (xy 443.05572 -16.703679) (xy 442.995794 -16.589505) (xy 442.942872 -16.471921)
			(xy 442.897145 -16.351357) (xy 442.858782 -16.228251) (xy 442.827921 -16.103054) (xy 442.804676 -15.976222)
			(xy 442.789132 -15.848218) (xy 442.781344 -15.719508) (xy 442.780928 -15.655036) (xy 442.781479 -15.586705)
			(xy 442.790239 -15.450325) (xy 442.807711 -15.314785) (xy 442.833824 -15.180642) (xy 442.868472 -15.048446)
			(xy 442.911511 -14.918739) (xy 442.93663 -14.85519) (xy 442.938408 -14.850618) (xy 442.94044 -14.83995)
			(xy 442.941994 -14.830042) (xy 442.93808 -14.810388) (xy 442.93282 -14.80185) (xy 442.886338 -14.733016)
			(xy 442.878803 -14.723009) (xy 442.856687 -14.711311) (xy 442.844174 -14.710664) (xy 441.029344 -14.710664)
			(xy 441.020003 -14.711139) (xy 441.002588 -14.71792) (xy 440.988732 -14.730461) (xy 440.984132 -14.738604)
			(xy 440.94019 -14.825218) (xy 440.942476 -14.853666) (xy 440.950858 -14.86535) (xy 440.977999 -14.903467)
			(xy 441.025439 -14.984128) (xy 441.064632 -15.069103) (xy 441.095191 -15.157551) (xy 441.116812 -15.248597)
			(xy 441.129283 -15.34134) (xy 441.131452 -15.388082) (xy 441.131452 -15.388336) (xy 441.132214 -15.402306)
			(xy 441.132214 -15.420086) (xy 441.131635 -15.466599) (xy 441.122423 -15.559167) (xy 441.104117 -15.650374)
			(xy 441.076895 -15.739328) (xy 441.041024 -15.82516) (xy 441.019438 -15.866364) (xy 441.013342 -15.877794)
			(xy 441.013342 -15.903194) (xy 441.061602 -15.992602) (xy 441.082938 -16.006572) (xy 441.095892 -16.007588)
			(xy 441.139281 -16.011728) (xy 441.225128 -16.026844) (xy 441.309264 -16.049635) (xy 441.391003 -16.079915)
			(xy 441.469682 -16.117437) (xy 441.544659 -16.161897) (xy 441.615324 -16.212932) (xy 441.681103 -16.270128)
			(xy 441.74146 -16.333018) (xy 441.795905 -16.401092) (xy 441.843993 -16.473795) (xy 441.885334 -16.550535)
			(xy 441.919592 -16.630689) (xy 441.946488 -16.713604) (xy 441.965802 -16.798605) (xy 441.977378 -16.885)
			(xy 441.981121 -16.972088) (xy 441.977001 -17.059158) (xy 441.965052 -17.145503) (xy 441.945371 -17.23042)
			(xy 441.918118 -17.313217) (xy 441.883514 -17.393222) (xy 441.841841 -17.469783) (xy 441.793439 -17.542278)
			(xy 441.738701 -17.610115) (xy 441.708794 -17.641824) (xy 441.70854 -17.642078) (xy 441.677253 -17.674112)
			(xy 441.609681 -17.732877) (xy 441.536959 -17.785133) (xy 441.459711 -17.830432) (xy 441.378601 -17.868385)
			(xy 441.294325 -17.898665) (xy 441.207608 -17.921013) (xy 441.119195 -17.935236) (xy 441.029844 -17.941213)
			(xy 440.940324 -17.938892) (xy 440.851403 -17.928293) (xy 440.763845 -17.909507) (xy 440.678403 -17.882696)
			(xy 440.636914 -17.865852) (xy 440.595851 -17.848111) (xy 440.516884 -17.806074) (xy 440.442144 -17.756913)
			(xy 440.372272 -17.701049) (xy 440.307869 -17.63896) (xy 440.249485 -17.57118) (xy 440.197621 -17.498289)
			(xy 440.152723 -17.420914) (xy 440.115175 -17.339716) (xy 440.0853 -17.255394) (xy 440.063354 -17.168669)
			(xy 440.049524 -17.080286) (xy 440.043929 -16.991002) (xy 440.046619 -16.901584) (xy 440.057568 -16.812798)
			(xy 440.076684 -16.725406) (xy 440.103803 -16.640156) (xy 440.138691 -16.557781) (xy 440.159394 -16.518128)
			(xy 440.159648 -16.517366) (xy 440.161172 -16.514318) (xy 440.162696 -16.510762) (xy 440.167043 -16.499101)
			(xy 440.16506 -16.474322) (xy 440.158886 -16.463518) (xy 440.158124 -16.462502) (xy 440.114944 -16.390112)
			(xy 440.110148 -16.382731) (xy 440.096596 -16.371517) (xy 440.08005 -16.365548) (xy 440.071256 -16.36522)
			(xy 438.33288 -16.36522) (xy 438.289442 -16.364732) (xy 438.202938 -16.356715) (xy 438.117542 -16.340749)
			(xy 438.033984 -16.316973) (xy 437.952976 -16.285588) (xy 437.875209 -16.246862) (xy 437.801347 -16.201126)
			(xy 437.732021 -16.14877) (xy 437.667821 -16.090241) (xy 437.609295 -16.026038) (xy 437.556943 -15.956708)
			(xy 437.511211 -15.882844) (xy 437.47249 -15.805075) (xy 437.44111 -15.724065) (xy 437.417338 -15.640505)
			(xy 437.401378 -15.555109) (xy 437.393365 -15.468604) (xy 437.392826 -15.425166) (xy 437.392826 -15.424658)
			(xy 437.393323 -15.382462) (xy 437.400936 -15.298414) (xy 437.416052 -15.215387) (xy 437.43855 -15.134049)
			(xy 437.468248 -15.055055) (xy 437.504907 -14.979041) (xy 437.548232 -14.906619) (xy 437.572658 -14.872208)
			(xy 437.58104 -14.86027) (xy 437.583326 -14.83233) (xy 437.529224 -14.725396) (xy 437.505094 -14.710664)
			(xy 428.169578 -14.710664) (xy 428.159511 -14.711093) (xy 428.140918 -14.71882) (xy 428.13351 -14.72565)
			(xy 427.9392 -14.91996) (xy 427.932335 -14.927518) (xy 427.92472 -14.946444) (xy 427.925062 -14.966842)
			(xy 427.928786 -14.976348) (xy 427.928786 -14.976602) (xy 427.966886 -15.062708) (xy 427.970339 -15.069799)
			(xy 427.980814 -15.081576) (xy 427.98746 -15.085822) (xy 427.994572 -15.09014) (xy 428.008796 -15.093696)
			(xy 428.016162 -15.093188) (xy 428.017686 -15.093188) (xy 428.036736 -15.09268) (xy 428.063986 -15.093168)
			(xy 428.117932 -15.100929) (xy 428.170224 -15.116288) (xy 428.219798 -15.138932) (xy 428.265646 -15.1684)
			(xy 428.306833 -15.204093) (xy 428.342522 -15.245283) (xy 428.371985 -15.291133) (xy 428.394625 -15.34071)
			(xy 428.409978 -15.393003) (xy 428.417734 -15.44695) (xy 428.417734 -15.50145) (xy 428.409978 -15.555397)
			(xy 428.394625 -15.60769) (xy 428.371985 -15.657267) (xy 428.342522 -15.703117) (xy 428.306833 -15.744307)
			(xy 428.265646 -15.78) (xy 428.219798 -15.809468) (xy 428.170224 -15.832112) (xy 428.117932 -15.847471)
			(xy 428.063986 -15.855232) (xy 428.036736 -15.855696) (xy 428.006745 -15.855144) (xy 427.947503 -15.845757)
			(xy 427.890466 -15.827193) (xy 427.863508 -15.81404) (xy 427.85157 -15.807944) (xy 427.825408 -15.80896)
			(xy 427.740064 -15.861284) (xy 427.732904 -15.866117) (xy 427.722071 -15.87956) (xy 427.716306 -15.895833)
			(xy 427.715934 -15.904464) (xy 427.715934 -18.44421) (xy 448.57619 -18.44421) (xy 448.580261 -18.388588)
			(xy 448.592387 -18.334151) (xy 448.61231 -18.28206) (xy 448.639606 -18.233425) (xy 448.673692 -18.189282)
			(xy 448.713841 -18.150573) (xy 448.759199 -18.118122) (xy 448.808799 -18.092621) (xy 448.861583 -18.074614)
			(xy 448.916426 -18.064484) (xy 448.97216 -18.062447) (xy 449.027597 -18.068547) (xy 449.081554 -18.082653)
			(xy 449.132883 -18.104465) (xy 449.180489 -18.133519) (xy 449.223357 -18.169194) (xy 449.260574 -18.210731)
			(xy 449.291347 -18.257244) (xy 449.315019 -18.307741) (xy 449.331087 -18.361148) (xy 449.339207 -18.416324)
			(xy 449.339716 -18.44421) (xy 449.339207 -18.472096) (xy 449.331087 -18.527272) (xy 449.315019 -18.580679)
			(xy 449.291347 -18.631176) (xy 449.260574 -18.677689) (xy 449.223357 -18.719226) (xy 449.180489 -18.754901)
			(xy 449.132883 -18.783955) (xy 449.081554 -18.805767) (xy 449.027597 -18.819873) (xy 448.97216 -18.825973)
			(xy 448.916426 -18.823936) (xy 448.861583 -18.813806) (xy 448.808799 -18.795799) (xy 448.759199 -18.770298)
			(xy 448.713841 -18.737847) (xy 448.673692 -18.699138) (xy 448.639606 -18.654995) (xy 448.61231 -18.60636)
			(xy 448.592387 -18.554269) (xy 448.580261 -18.499832) (xy 448.57619 -18.44421) (xy 427.715934 -18.44421)
			(xy 427.715934 -20.72513) (xy 431.48048 -20.72513) (xy 431.48445 -20.594996) (xy 431.496346 -20.465346)
			(xy 431.516125 -20.336663) (xy 431.543711 -20.209424) (xy 431.579004 -20.084105) (xy 431.62187 -19.961169)
			(xy 431.672152 -19.841076) (xy 431.729661 -19.724272) (xy 431.794185 -19.61119) (xy 431.865482 -19.502253)
			(xy 431.943287 -19.397865) (xy 432.027312 -19.298414) (xy 432.117244 -19.204271) (xy 432.212748 -19.115786)
			(xy 432.313468 -19.033287) (xy 432.41903 -18.957082) (xy 432.529042 -18.887455) (xy 432.643094 -18.824664)
			(xy 432.760762 -18.768942) (xy 432.881608 -18.720498) (xy 433.005183 -18.679511) (xy 433.131026 -18.646134)
			(xy 433.258671 -18.620491) (xy 433.387641 -18.602677) (xy 433.517457 -18.592759) (xy 433.647636 -18.590774)
			(xy 433.777695 -18.596728) (xy 433.907148 -18.610601) (xy 434.035515 -18.632339) (xy 434.162318 -18.661863)
			(xy 434.287085 -18.699062) (xy 434.409352 -18.743798) (xy 434.528665 -18.795906) (xy 434.644578 -18.855189)
			(xy 434.756663 -18.92143) (xy 434.8645 -18.99438) (xy 434.967689 -19.073768) (xy 435.065847 -19.1593)
			(xy 435.158608 -19.250657) (xy 435.245627 -19.347499) (xy 435.32658 -19.449466) (xy 435.401166 -19.556178)
			(xy 435.469107 -19.667239) (xy 435.530152 -19.782235) (xy 435.584073 -19.900739) (xy 435.630668 -20.02231)
			(xy 435.669766 -20.146495) (xy 435.70122 -20.272833) (xy 435.724914 -20.400854) (xy 435.740758 -20.53008)
			(xy 435.748696 -20.660033) (xy 435.749192 -20.72513) (xy 435.748696 -20.790227) (xy 435.740758 -20.92018)
			(xy 435.724914 -21.049406) (xy 435.70122 -21.177427) (xy 435.669766 -21.303765) (xy 435.630668 -21.42795)
			(xy 435.584073 -21.549521) (xy 435.530152 -21.668025) (xy 435.492828 -21.738336) (xy 437.716676 -21.738336)
			(xy 437.717167 -21.709596) (xy 437.725799 -21.652767) (xy 437.742857 -21.597877) (xy 437.767955 -21.546165)
			(xy 437.800527 -21.498804) (xy 437.8198 -21.477478) (xy 437.826404 -21.470366) (xy 437.833516 -21.45284)
			(xy 437.833516 -21.363432) (xy 437.826404 -21.345906) (xy 437.8198 -21.338794) (xy 437.800566 -21.317436)
			(xy 437.768002 -21.270078) (xy 437.74291 -21.218371) (xy 437.725858 -21.163485) (xy 437.717233 -21.106663)
			(xy 437.717229 -21.04919) (xy 437.725846 -20.992366) (xy 437.74289 -20.937478) (xy 437.767975 -20.885767)
			(xy 437.800533 -20.838405) (xy 437.8198 -20.817078) (xy 437.826404 -20.809966) (xy 437.833516 -20.79244)
			(xy 437.833516 -20.703032) (xy 437.826404 -20.685506) (xy 437.8198 -20.678394) (xy 437.800566 -20.657036)
			(xy 437.768002 -20.609678) (xy 437.74291 -20.557971) (xy 437.725858 -20.503085) (xy 437.717233 -20.446263)
			(xy 437.717229 -20.38879) (xy 437.725846 -20.331966) (xy 437.74289 -20.277078) (xy 437.767975 -20.225367)
			(xy 437.800533 -20.178005) (xy 437.8198 -20.156678) (xy 437.826404 -20.149566) (xy 437.833516 -20.13204)
			(xy 437.833516 -20.042632) (xy 437.826404 -20.025106) (xy 437.8198 -20.017994) (xy 437.800566 -19.996636)
			(xy 437.768002 -19.949278) (xy 437.74291 -19.897571) (xy 437.725858 -19.842685) (xy 437.717233 -19.785863)
			(xy 437.717229 -19.72839) (xy 437.725846 -19.671566) (xy 437.74289 -19.616678) (xy 437.767975 -19.564967)
			(xy 437.800533 -19.517605) (xy 437.8198 -19.496278) (xy 437.826404 -19.489166) (xy 437.833516 -19.47164)
			(xy 437.833516 -19.382232) (xy 437.826404 -19.364706) (xy 437.8198 -19.357594) (xy 437.800557 -19.336243)
			(xy 437.767985 -19.288888) (xy 437.742886 -19.237183) (xy 437.725829 -19.182297) (xy 437.7172 -19.125474)
			(xy 437.716676 -19.096736) (xy 437.717162 -19.069485) (xy 437.724918 -19.015537) (xy 437.740273 -18.963242)
			(xy 437.762915 -18.913665) (xy 437.792381 -18.867815) (xy 437.828072 -18.826624) (xy 437.869263 -18.790933)
			(xy 437.915113 -18.761467) (xy 437.96469 -18.738825) (xy 438.016985 -18.72347) (xy 438.070933 -18.715714)
			(xy 438.125435 -18.715714) (xy 438.179383 -18.72347) (xy 438.231678 -18.738825) (xy 438.281255 -18.761467)
			(xy 438.327105 -18.790933) (xy 438.368296 -18.826624) (xy 438.403987 -18.867815) (xy 438.433453 -18.913665)
			(xy 438.456095 -18.963242) (xy 438.47145 -19.015537) (xy 438.479206 -19.069485) (xy 438.479692 -19.096736)
			(xy 438.479192 -19.125476) (xy 438.470564 -19.182304) (xy 438.453509 -19.237195) (xy 438.428412 -19.288907)
			(xy 438.395841 -19.336268) (xy 438.376568 -19.357594) (xy 438.369964 -19.364706) (xy 438.362852 -19.382232)
			(xy 438.362852 -19.47164) (xy 438.369964 -19.489166) (xy 438.376568 -19.496278) (xy 438.395875 -19.517574)
			(xy 438.42844 -19.564941) (xy 438.45353 -19.616658) (xy 438.470577 -19.671554) (xy 438.479197 -19.728385)
			(xy 438.479193 -19.785867) (xy 438.470566 -19.842698) (xy 438.45351 -19.897591) (xy 438.428413 -19.949304)
			(xy 438.395842 -19.996667) (xy 438.376568 -20.017994) (xy 438.369964 -20.025106) (xy 438.362852 -20.042632)
			(xy 438.362852 -20.13204) (xy 438.369964 -20.149566) (xy 438.376568 -20.156678) (xy 438.395875 -20.177974)
			(xy 438.42844 -20.225341) (xy 438.45353 -20.277058) (xy 438.470577 -20.331954) (xy 438.479197 -20.388785)
			(xy 438.479193 -20.446267) (xy 438.470566 -20.503098) (xy 438.45351 -20.557991) (xy 438.428413 -20.609704)
			(xy 438.395842 -20.657067) (xy 438.376568 -20.678394) (xy 438.369964 -20.685506) (xy 438.362852 -20.703032)
			(xy 438.362852 -20.79244) (xy 438.369964 -20.809966) (xy 438.376568 -20.817078) (xy 438.395875 -20.838374)
			(xy 438.42844 -20.885741) (xy 438.45353 -20.937458) (xy 438.470577 -20.992354) (xy 438.479197 -21.049185)
			(xy 438.479193 -21.106667) (xy 438.470566 -21.163498) (xy 438.45351 -21.218391) (xy 438.428413 -21.270104)
			(xy 438.395842 -21.317467) (xy 438.376568 -21.338794) (xy 438.369964 -21.345906) (xy 438.362852 -21.363432)
			(xy 438.362852 -21.45284) (xy 438.369964 -21.470366) (xy 438.376568 -21.477478) (xy 438.395857 -21.498789)
			(xy 438.42842 -21.546156) (xy 438.453509 -21.597871) (xy 438.470556 -21.652766) (xy 438.479174 -21.709596)
			(xy 438.479486 -21.726906) (xy 442.373766 -21.726906) (xy 442.374302 -21.698168) (xy 442.382923 -21.641341)
			(xy 442.399971 -21.586451) (xy 442.425059 -21.534739) (xy 442.457621 -21.487376) (xy 442.47689 -21.466048)
			(xy 442.483494 -21.458936) (xy 442.490606 -21.44141) (xy 442.490606 -21.352002) (xy 442.483494 -21.334476)
			(xy 442.47689 -21.327364) (xy 442.457627 -21.306031) (xy 442.425064 -21.258669) (xy 442.399974 -21.206958)
			(xy 442.382926 -21.152068) (xy 442.374303 -21.095243) (xy 442.374303 -21.037766) (xy 442.382924 -20.98094)
			(xy 442.399971 -20.92605) (xy 442.42506 -20.874339) (xy 442.457621 -20.826976) (xy 442.47689 -20.805648)
			(xy 442.483494 -20.798536) (xy 442.490606 -20.78101) (xy 442.490606 -20.691602) (xy 442.483494 -20.674076)
			(xy 442.47689 -20.666964) (xy 442.457627 -20.645631) (xy 442.425064 -20.598269) (xy 442.399974 -20.546558)
			(xy 442.382926 -20.491668) (xy 442.374303 -20.434843) (xy 442.374303 -20.377366) (xy 442.382924 -20.32054)
			(xy 442.399971 -20.26565) (xy 442.42506 -20.213939) (xy 442.457621 -20.166576) (xy 442.47689 -20.145248)
			(xy 442.483494 -20.138136) (xy 442.490606 -20.12061) (xy 442.490606 -20.031202) (xy 442.483494 -20.013676)
			(xy 442.47689 -20.006564) (xy 442.457627 -19.985231) (xy 442.425064 -19.937869) (xy 442.399974 -19.886158)
			(xy 442.382926 -19.831268) (xy 442.374303 -19.774443) (xy 442.374303 -19.716966) (xy 442.382924 -19.66014)
			(xy 442.399971 -19.60525) (xy 442.42506 -19.553539) (xy 442.457621 -19.506176) (xy 442.47689 -19.484848)
			(xy 442.483494 -19.477736) (xy 442.490606 -19.46021) (xy 442.490606 -19.370802) (xy 442.483494 -19.353276)
			(xy 442.47689 -19.346164) (xy 442.457631 -19.324827) (xy 442.425061 -19.277468) (xy 442.399966 -19.225759)
			(xy 442.382913 -19.170871) (xy 442.374288 -19.114044) (xy 442.373766 -19.085306) (xy 442.374252 -19.058055)
			(xy 442.382008 -19.004107) (xy 442.397363 -18.951812) (xy 442.420005 -18.902235) (xy 442.449471 -18.856385)
			(xy 442.485162 -18.815194) (xy 442.526353 -18.779503) (xy 442.572203 -18.750037) (xy 442.62178 -18.727395)
			(xy 442.674075 -18.71204) (xy 442.728023 -18.704284) (xy 442.782525 -18.704284) (xy 442.836473 -18.71204)
			(xy 442.888768 -18.727395) (xy 442.938345 -18.750037) (xy 442.984195 -18.779503) (xy 443.025386 -18.815194)
			(xy 443.061077 -18.856385) (xy 443.090543 -18.902235) (xy 443.113185 -18.951812) (xy 443.12854 -19.004107)
			(xy 443.136296 -19.058055) (xy 443.136782 -19.085306) (xy 443.13624 -19.114044) (xy 443.127619 -19.17087)
			(xy 443.110572 -19.225759) (xy 443.085485 -19.277471) (xy 443.052925 -19.324835) (xy 443.033658 -19.346164)
			(xy 443.027054 -19.353276) (xy 443.021543 -19.366856) (xy 447.879115 -19.366856) (xy 447.879115 -19.312344)
			(xy 447.886873 -19.258385) (xy 447.902232 -19.206081) (xy 447.924878 -19.156494) (xy 447.95435 -19.110636)
			(xy 447.99005 -19.069438) (xy 448.031248 -19.033741) (xy 448.077108 -19.00427) (xy 448.126696 -18.981626)
			(xy 448.179001 -18.96627) (xy 448.23296 -18.958514) (xy 448.260216 -18.958052) (xy 448.286987 -18.958515)
			(xy 448.340002 -18.966015) (xy 448.391448 -18.980851) (xy 448.440316 -19.002733) (xy 448.485645 -19.031229)
			(xy 448.526547 -19.065782) (xy 448.562217 -19.105713) (xy 448.577462 -19.127724) (xy 448.583558 -19.136614)
			(xy 448.601084 -19.148044) (xy 448.695572 -19.163284) (xy 448.715892 -19.158204) (xy 448.724274 -19.1516)
			(xy 448.744432 -19.13649) (xy 448.787952 -19.111115) (xy 448.834437 -19.091697) (xy 448.883075 -19.078574)
			(xy 448.933019 -19.071976) (xy 448.958208 -19.07159) (xy 448.985459 -19.07208) (xy 449.039405 -19.079838)
			(xy 449.091699 -19.095193) (xy 449.141275 -19.117835) (xy 449.187124 -19.147301) (xy 449.228313 -19.182993)
			(xy 449.264004 -19.224182) (xy 449.293469 -19.270032) (xy 449.316109 -19.319609) (xy 449.331464 -19.371903)
			(xy 449.33922 -19.425849) (xy 449.33922 -19.480351) (xy 449.331464 -19.534297) (xy 449.316109 -19.586591)
			(xy 449.293469 -19.636168) (xy 449.264004 -19.682018) (xy 449.228313 -19.723207) (xy 449.187124 -19.758899)
			(xy 449.141275 -19.788365) (xy 449.091699 -19.811007) (xy 449.039405 -19.826362) (xy 448.985459 -19.83412)
			(xy 448.958208 -19.834606) (xy 448.931437 -19.834143) (xy 448.878421 -19.826646) (xy 448.826974 -19.811811)
			(xy 448.778106 -19.78993) (xy 448.732776 -19.761433) (xy 448.691875 -19.726879) (xy 448.656206 -19.686946)
			(xy 448.640962 -19.664934) (xy 448.634866 -19.656044) (xy 448.61734 -19.644614) (xy 448.522852 -19.629374)
			(xy 448.502532 -19.634454) (xy 448.49415 -19.641058) (xy 448.474013 -19.656197) (xy 448.430487 -19.681568)
			(xy 448.383997 -19.700981) (xy 448.335354 -19.714097) (xy 448.285407 -19.720687) (xy 448.260216 -19.721068)
			(xy 448.23296 -19.720686) (xy 448.179001 -19.71293) (xy 448.126696 -19.697574) (xy 448.077108 -19.67493)
			(xy 448.031248 -19.645459) (xy 447.99005 -19.609762) (xy 447.95435 -19.568564) (xy 447.924878 -19.522706)
			(xy 447.902232 -19.473119) (xy 447.886873 -19.420815) (xy 447.879115 -19.366856) (xy 443.021543 -19.366856)
			(xy 443.019942 -19.370802) (xy 443.019942 -19.46021) (xy 443.027054 -19.477736) (xy 443.033658 -19.484848)
			(xy 443.052936 -19.506169) (xy 443.085502 -19.553532) (xy 443.110595 -19.605245) (xy 443.127645 -19.660136)
			(xy 443.136267 -19.716965) (xy 443.136267 -19.774444) (xy 443.127643 -19.831272) (xy 443.110591 -19.886163)
			(xy 443.085498 -19.937875) (xy 443.05293 -19.985238) (xy 443.033658 -20.006564) (xy 443.027054 -20.013676)
			(xy 443.019942 -20.031202) (xy 443.019942 -20.12061) (xy 443.027054 -20.138136) (xy 443.033658 -20.145248)
			(xy 443.052936 -20.166569) (xy 443.085502 -20.213932) (xy 443.110595 -20.265645) (xy 443.127645 -20.320536)
			(xy 443.132959 -20.35556) (xy 447.878198 -20.35556) (xy 447.882269 -20.299938) (xy 447.894395 -20.245501)
			(xy 447.914318 -20.19341) (xy 447.941614 -20.144775) (xy 447.9757 -20.100632) (xy 448.015849 -20.061923)
			(xy 448.061207 -20.029472) (xy 448.110807 -20.003971) (xy 448.163591 -19.985964) (xy 448.218434 -19.975834)
			(xy 448.274168 -19.973797) (xy 448.329605 -19.979897) (xy 448.383562 -19.994003) (xy 448.434891 -20.015815)
			(xy 448.482497 -20.044869) (xy 448.525365 -20.080544) (xy 448.562582 -20.122081) (xy 448.593355 -20.168594)
			(xy 448.617027 -20.219091) (xy 448.633095 -20.272498) (xy 448.641215 -20.327674) (xy 448.641724 -20.35556)
			(xy 448.641215 -20.383446) (xy 448.633095 -20.438622) (xy 448.617027 -20.492029) (xy 448.593355 -20.542526)
			(xy 448.562582 -20.589039) (xy 448.525365 -20.630576) (xy 448.482497 -20.666251) (xy 448.434891 -20.695305)
			(xy 448.383562 -20.717117) (xy 448.329605 -20.731223) (xy 448.274168 -20.737323) (xy 448.218434 -20.735286)
			(xy 448.163591 -20.725156) (xy 448.110807 -20.707149) (xy 448.061207 -20.681648) (xy 448.015849 -20.649197)
			(xy 447.9757 -20.610488) (xy 447.941614 -20.566345) (xy 447.914318 -20.51771) (xy 447.894395 -20.465619)
			(xy 447.882269 -20.411182) (xy 447.878198 -20.35556) (xy 443.132959 -20.35556) (xy 443.136267 -20.377365)
			(xy 443.136267 -20.434844) (xy 443.127643 -20.491672) (xy 443.110591 -20.546563) (xy 443.085498 -20.598275)
			(xy 443.05293 -20.645638) (xy 443.033658 -20.666964) (xy 443.027054 -20.674076) (xy 443.019942 -20.691602)
			(xy 443.019942 -20.78101) (xy 443.027054 -20.798536) (xy 443.033658 -20.805648) (xy 443.052936 -20.826969)
			(xy 443.085502 -20.874332) (xy 443.110595 -20.926045) (xy 443.127645 -20.980936) (xy 443.136267 -21.037765)
			(xy 443.136267 -21.095244) (xy 443.127643 -21.152072) (xy 443.110591 -21.206963) (xy 443.085498 -21.258675)
			(xy 443.05293 -21.306038) (xy 443.033658 -21.327364) (xy 443.027054 -21.334476) (xy 443.019942 -21.352002)
			(xy 443.019942 -21.37156) (xy 447.878198 -21.37156) (xy 447.882269 -21.315938) (xy 447.894395 -21.261501)
			(xy 447.914318 -21.20941) (xy 447.941614 -21.160775) (xy 447.9757 -21.116632) (xy 448.015849 -21.077923)
			(xy 448.061207 -21.045472) (xy 448.110807 -21.019971) (xy 448.163591 -21.001964) (xy 448.218434 -20.991834)
			(xy 448.274168 -20.989797) (xy 448.329605 -20.995897) (xy 448.383562 -21.010003) (xy 448.434891 -21.031815)
			(xy 448.482497 -21.060869) (xy 448.525365 -21.096544) (xy 448.562582 -21.138081) (xy 448.593355 -21.184594)
			(xy 448.617027 -21.235091) (xy 448.633095 -21.288498) (xy 448.641215 -21.343674) (xy 448.641724 -21.37156)
			(xy 448.641215 -21.399446) (xy 448.633095 -21.454622) (xy 448.617027 -21.508029) (xy 448.593355 -21.558526)
			(xy 448.562582 -21.605039) (xy 448.525365 -21.646576) (xy 448.482497 -21.682251) (xy 448.434891 -21.711305)
			(xy 448.383562 -21.733117) (xy 448.329605 -21.747223) (xy 448.274168 -21.753323) (xy 448.218434 -21.751286)
			(xy 448.163591 -21.741156) (xy 448.110807 -21.723149) (xy 448.061207 -21.697648) (xy 448.015849 -21.665197)
			(xy 447.9757 -21.626488) (xy 447.941614 -21.582345) (xy 447.914318 -21.53371) (xy 447.894395 -21.481619)
			(xy 447.882269 -21.427182) (xy 447.878198 -21.37156) (xy 443.019942 -21.37156) (xy 443.019942 -21.44141)
			(xy 443.027054 -21.458936) (xy 443.033658 -21.466048) (xy 443.052931 -21.487373) (xy 443.085497 -21.534736)
			(xy 443.110589 -21.586448) (xy 443.127639 -21.641339) (xy 443.136261 -21.698167) (xy 443.136782 -21.726906)
			(xy 443.136296 -21.754157) (xy 443.133203 -21.775674) (xy 452.235822 -21.775674) (xy 452.239893 -21.720052)
			(xy 452.252019 -21.665615) (xy 452.271942 -21.613524) (xy 452.299238 -21.564889) (xy 452.333324 -21.520746)
			(xy 452.373473 -21.482037) (xy 452.418831 -21.449586) (xy 452.468431 -21.424085) (xy 452.521215 -21.406078)
			(xy 452.576058 -21.395948) (xy 452.631792 -21.393911) (xy 452.687229 -21.400011) (xy 452.741186 -21.414117)
			(xy 452.792515 -21.435929) (xy 452.840121 -21.464983) (xy 452.882989 -21.500658) (xy 452.920206 -21.542195)
			(xy 452.950979 -21.588708) (xy 452.974651 -21.639205) (xy 452.990719 -21.692612) (xy 452.998839 -21.747788)
			(xy 452.999348 -21.775674) (xy 452.998839 -21.80356) (xy 452.990719 -21.858736) (xy 452.974651 -21.912143)
			(xy 452.950979 -21.96264) (xy 452.920206 -22.009153) (xy 452.882989 -22.05069) (xy 452.840121 -22.086365)
			(xy 452.792515 -22.115419) (xy 452.741186 -22.137231) (xy 452.687229 -22.151337) (xy 452.631792 -22.157437)
			(xy 452.576058 -22.1554) (xy 452.521215 -22.14527) (xy 452.468431 -22.127263) (xy 452.418831 -22.101762)
			(xy 452.373473 -22.069311) (xy 452.333324 -22.030602) (xy 452.299238 -21.986459) (xy 452.271942 -21.937824)
			(xy 452.252019 -21.885733) (xy 452.239893 -21.831296) (xy 452.235822 -21.775674) (xy 443.133203 -21.775674)
			(xy 443.12854 -21.808105) (xy 443.113185 -21.8604) (xy 443.090543 -21.909977) (xy 443.061077 -21.955827)
			(xy 443.025386 -21.997018) (xy 442.984195 -22.032709) (xy 442.938345 -22.062175) (xy 442.888768 -22.084817)
			(xy 442.836473 -22.100172) (xy 442.782525 -22.107928) (xy 442.728023 -22.107928) (xy 442.674075 -22.100172)
			(xy 442.62178 -22.084817) (xy 442.572203 -22.062175) (xy 442.526353 -22.032709) (xy 442.485162 -21.997018)
			(xy 442.449471 -21.955827) (xy 442.420005 -21.909977) (xy 442.397363 -21.8604) (xy 442.382008 -21.808105)
			(xy 442.374252 -21.754157) (xy 442.373766 -21.726906) (xy 438.479486 -21.726906) (xy 438.479692 -21.738336)
			(xy 438.479206 -21.765587) (xy 438.47145 -21.819535) (xy 438.456095 -21.87183) (xy 438.433453 -21.921407)
			(xy 438.403987 -21.967257) (xy 438.368296 -22.008448) (xy 438.327105 -22.044139) (xy 438.281255 -22.073605)
			(xy 438.231678 -22.096247) (xy 438.179383 -22.111602) (xy 438.125435 -22.119358) (xy 438.070933 -22.119358)
			(xy 438.016985 -22.111602) (xy 437.96469 -22.096247) (xy 437.915113 -22.073605) (xy 437.869263 -22.044139)
			(xy 437.828072 -22.008448) (xy 437.792381 -21.967257) (xy 437.762915 -21.921407) (xy 437.740273 -21.87183)
			(xy 437.724918 -21.819535) (xy 437.717162 -21.765587) (xy 437.716676 -21.738336) (xy 435.492828 -21.738336)
			(xy 435.469107 -21.783021) (xy 435.401166 -21.894082) (xy 435.32658 -22.000794) (xy 435.245627 -22.102761)
			(xy 435.158608 -22.199603) (xy 435.065847 -22.29096) (xy 434.967689 -22.376492) (xy 434.8645 -22.45588)
			(xy 434.756663 -22.52883) (xy 434.644578 -22.595071) (xy 434.528665 -22.654354) (xy 434.409352 -22.706462)
			(xy 434.287085 -22.751198) (xy 434.162318 -22.788397) (xy 434.035515 -22.817921) (xy 433.907148 -22.839659)
			(xy 433.777695 -22.853532) (xy 433.647636 -22.859486) (xy 433.517457 -22.857501) (xy 433.387641 -22.847583)
			(xy 433.258671 -22.829769) (xy 433.131026 -22.804126) (xy 433.005183 -22.770749) (xy 432.881608 -22.729762)
			(xy 432.760762 -22.681318) (xy 432.643094 -22.625596) (xy 432.529042 -22.562805) (xy 432.41903 -22.493178)
			(xy 432.313468 -22.416973) (xy 432.212748 -22.334474) (xy 432.117244 -22.245989) (xy 432.027312 -22.151846)
			(xy 431.943287 -22.052395) (xy 431.865482 -21.948007) (xy 431.794185 -21.83907) (xy 431.729661 -21.725988)
			(xy 431.672152 -21.609184) (xy 431.62187 -21.489091) (xy 431.579004 -21.366155) (xy 431.543711 -21.240836)
			(xy 431.516125 -21.113597) (xy 431.496346 -20.984914) (xy 431.48445 -20.855264) (xy 431.48048 -20.72513)
			(xy 427.715934 -20.72513) (xy 427.715934 -21.487892) (xy 427.716106 -21.494044) (xy 427.719065 -21.505988)
			(xy 427.721776 -21.511514) (xy 427.734984 -21.53666) (xy 427.74235 -21.545296) (xy 427.746922 -21.548598)
			(xy 427.768752 -21.565281) (xy 427.807847 -21.603882) (xy 427.840999 -21.647693) (xy 427.867525 -21.695806)
			(xy 427.886874 -21.747227) (xy 427.898646 -21.800892) (xy 427.901975 -21.847048) (xy 428.372776 -21.847048)
			(xy 428.376847 -21.791426) (xy 428.388973 -21.736989) (xy 428.408896 -21.684898) (xy 428.436192 -21.636263)
			(xy 428.470278 -21.59212) (xy 428.510427 -21.553411) (xy 428.555785 -21.52096) (xy 428.605385 -21.495459)
			(xy 428.658169 -21.477452) (xy 428.713012 -21.467322) (xy 428.768746 -21.465285) (xy 428.824183 -21.471385)
			(xy 428.87814 -21.485491) (xy 428.929469 -21.507303) (xy 428.977075 -21.536357) (xy 429.019943 -21.572032)
			(xy 429.05716 -21.613569) (xy 429.087933 -21.660082) (xy 429.111605 -21.710579) (xy 429.127673 -21.763986)
			(xy 429.135793 -21.819162) (xy 429.136302 -21.847048) (xy 429.135793 -21.874934) (xy 429.127673 -21.93011)
			(xy 429.111605 -21.983517) (xy 429.087933 -22.034014) (xy 429.05716 -22.080527) (xy 429.019943 -22.122064)
			(xy 428.977075 -22.157739) (xy 428.929469 -22.186793) (xy 428.87814 -22.208605) (xy 428.824183 -22.222711)
			(xy 428.768746 -22.228811) (xy 428.713012 -22.226774) (xy 428.658169 -22.216644) (xy 428.605385 -22.198637)
			(xy 428.555785 -22.173136) (xy 428.510427 -22.140685) (xy 428.470278 -22.101976) (xy 428.436192 -22.057833)
			(xy 428.408896 -22.009198) (xy 428.388973 -21.957107) (xy 428.376847 -21.90267) (xy 428.372776 -21.847048)
			(xy 427.901975 -21.847048) (xy 427.902598 -21.85569) (xy 427.898649 -21.910489) (xy 427.886879 -21.964154)
			(xy 427.867533 -22.015576) (xy 427.84101 -22.063691) (xy 427.807859 -22.107503) (xy 427.768766 -22.146107)
			(xy 427.746922 -22.16277) (xy 427.74235 -22.166072) (xy 427.734984 -22.174708) (xy 427.721776 -22.199854)
			(xy 427.719078 -22.205385) (xy 427.716119 -22.217325) (xy 427.715934 -22.223476) (xy 427.715934 -23.0251)
			(xy 437.662318 -23.0251) (xy 437.666389 -22.969478) (xy 437.678515 -22.915041) (xy 437.698438 -22.86295)
			(xy 437.725734 -22.814315) (xy 437.75982 -22.770172) (xy 437.799969 -22.731463) (xy 437.845327 -22.699012)
			(xy 437.894927 -22.673511) (xy 437.947711 -22.655504) (xy 438.002554 -22.645374) (xy 438.058288 -22.643337)
			(xy 438.113725 -22.649437) (xy 438.167682 -22.663543) (xy 438.219011 -22.685355) (xy 438.266617 -22.714409)
			(xy 438.309485 -22.750084) (xy 438.346702 -22.791621) (xy 438.377475 -22.838134) (xy 438.401147 -22.888631)
			(xy 438.417215 -22.942038) (xy 438.425335 -22.997214) (xy 438.425844 -23.0251) (xy 438.425335 -23.052986)
			(xy 438.417215 -23.108162) (xy 438.401147 -23.161569) (xy 438.377475 -23.212066) (xy 438.346702 -23.258579)
			(xy 438.309485 -23.300116) (xy 438.266617 -23.335791) (xy 438.219011 -23.364845) (xy 438.167682 -23.386657)
			(xy 438.113725 -23.400763) (xy 438.058288 -23.406863) (xy 438.002554 -23.404826) (xy 437.947711 -23.394696)
			(xy 437.894927 -23.376689) (xy 437.845327 -23.351188) (xy 437.799969 -23.318737) (xy 437.75982 -23.280028)
			(xy 437.725734 -23.235885) (xy 437.698438 -23.18725) (xy 437.678515 -23.135159) (xy 437.666389 -23.080722)
			(xy 437.662318 -23.0251) (xy 427.715934 -23.0251) (xy 427.715934 -23.49373) (xy 427.716415 -23.503694)
			(xy 427.723997 -23.522125) (xy 427.730666 -23.529544) (xy 427.758606 -23.557738) (xy 427.77537 -23.565358)
			(xy 427.785022 -23.56612) (xy 427.813778 -23.568365) (xy 427.870181 -23.580426) (xy 427.924126 -23.600839)
			(xy 427.974383 -23.629139) (xy 428.019809 -23.664682) (xy 428.059368 -23.706656) (xy 428.092158 -23.754106)
			(xy 428.117434 -23.805951) (xy 428.134617 -23.86101) (xy 428.143319 -23.918027) (xy 428.143924 -23.946866)
			(xy 428.144178 -23.946866) (xy 428.14374 -23.970996) (xy 428.372776 -23.970996) (xy 428.376847 -23.915374)
			(xy 428.388973 -23.860937) (xy 428.408896 -23.808846) (xy 428.436192 -23.760211) (xy 428.470278 -23.716068)
			(xy 428.510427 -23.677359) (xy 428.555785 -23.644908) (xy 428.605385 -23.619407) (xy 428.658169 -23.6014)
			(xy 428.713012 -23.59127) (xy 428.768746 -23.589233) (xy 428.824183 -23.595333) (xy 428.87814 -23.609439)
			(xy 428.881418 -23.610832) (xy 438.365923 -23.610832) (xy 438.365925 -23.556337) (xy 438.373683 -23.502398)
			(xy 438.389037 -23.450111) (xy 438.411676 -23.400542) (xy 438.44114 -23.354699) (xy 438.476827 -23.313516)
			(xy 438.518012 -23.27783) (xy 438.563856 -23.248369) (xy 438.613426 -23.225732) (xy 438.665713 -23.210379)
			(xy 438.719653 -23.202624) (xy 438.7469 -23.202138) (xy 438.770929 -23.202515) (xy 438.818607 -23.208553)
			(xy 438.865148 -23.220534) (xy 438.887616 -23.229062) (xy 438.900776 -23.233822) (xy 438.9286 -23.236727)
			(xy 438.95617 -23.231977) (xy 438.981418 -23.219929) (xy 439.002452 -23.201485) (xy 439.017696 -23.178028)
			(xy 439.026007 -23.151316) (xy 439.026763 -23.123351) (xy 439.02376 -23.109682) (xy 439.018309 -23.086699)
			(xy 439.012448 -23.039828) (xy 439.012076 -23.01621) (xy 439.012544 -22.988956) (xy 439.0203 -22.935003)
			(xy 439.035656 -22.882702) (xy 439.058298 -22.83312) (xy 439.087767 -22.787264) (xy 439.123461 -22.746069)
			(xy 439.164655 -22.710373) (xy 439.21051 -22.680904) (xy 439.260092 -22.65826) (xy 439.312392 -22.642903)
			(xy 439.366345 -22.635145) (xy 439.420853 -22.635145) (xy 439.474806 -22.642902) (xy 439.527106 -22.658259)
			(xy 439.576688 -22.680902) (xy 439.622543 -22.710372) (xy 439.663737 -22.746067) (xy 439.699432 -22.787262)
			(xy 439.728901 -22.833117) (xy 439.751543 -22.8827) (xy 439.766899 -22.935) (xy 439.774656 -22.988953)
			(xy 439.774655 -23.043461) (xy 439.766896 -23.097414) (xy 439.751538 -23.149714) (xy 439.728894 -23.199296)
			(xy 439.699423 -23.24515) (xy 439.663727 -23.286343) (xy 439.622531 -23.322037) (xy 439.576675 -23.351505)
			(xy 439.527092 -23.374146) (xy 439.474791 -23.389501) (xy 439.420838 -23.397256) (xy 439.393584 -23.397718)
			(xy 439.369555 -23.397342) (xy 439.321877 -23.391303) (xy 439.275336 -23.379322) (xy 439.252868 -23.370794)
			(xy 439.239699 -23.366067) (xy 439.211883 -23.363169) (xy 439.184322 -23.36792) (xy 439.159082 -23.379965)
			(xy 439.138053 -23.398402) (xy 439.122809 -23.42185) (xy 439.114493 -23.448552) (xy 439.113728 -23.476508)
			(xy 439.116724 -23.490174) (xy 439.122184 -23.513155) (xy 439.12804 -23.560028) (xy 439.128408 -23.583646)
			(xy 439.128283 -23.589996) (xy 442.384432 -23.589996) (xy 442.388503 -23.534374) (xy 442.400629 -23.479937)
			(xy 442.420552 -23.427846) (xy 442.447848 -23.379211) (xy 442.481934 -23.335068) (xy 442.522083 -23.296359)
			(xy 442.567441 -23.263908) (xy 442.617041 -23.238407) (xy 442.669825 -23.2204) (xy 442.724668 -23.21027)
			(xy 442.780402 -23.208233) (xy 442.835839 -23.214333) (xy 442.889796 -23.228439) (xy 442.941125 -23.250251)
			(xy 442.988731 -23.279305) (xy 443.031599 -23.31498) (xy 443.067953 -23.355554) (xy 451.630542 -23.355554)
			(xy 451.631036 -23.328744) (xy 451.638542 -23.275652) (xy 451.653414 -23.224135) (xy 451.675358 -23.175211)
			(xy 451.703941 -23.129845) (xy 451.738599 -23.088931) (xy 451.778649 -23.053278) (xy 451.800722 -23.038054)
			(xy 451.812262 -23.029766) (xy 451.830662 -23.008135) (xy 451.842396 -22.982275) (xy 451.846559 -22.954184)
			(xy 451.842828 -22.926032) (xy 451.831491 -22.899995) (xy 451.813426 -22.878084) (xy 451.801992 -22.869652)
			(xy 451.780548 -22.854282) (xy 451.741634 -22.818658) (xy 451.708001 -22.778013) (xy 451.680288 -22.73312)
			(xy 451.659025 -22.684837) (xy 451.644618 -22.634085) (xy 451.637342 -22.581833) (xy 451.636892 -22.555454)
			(xy 451.637378 -22.528203) (xy 451.645134 -22.474255) (xy 451.660489 -22.42196) (xy 451.683131 -22.372383)
			(xy 451.712597 -22.326533) (xy 451.748288 -22.285342) (xy 451.789479 -22.249651) (xy 451.835329 -22.220185)
			(xy 451.884906 -22.197543) (xy 451.937201 -22.182188) (xy 451.991149 -22.174432) (xy 452.045651 -22.174432)
			(xy 452.099599 -22.182188) (xy 452.151894 -22.197543) (xy 452.201471 -22.220185) (xy 452.247321 -22.249651)
			(xy 452.288512 -22.285342) (xy 452.324203 -22.326533) (xy 452.353669 -22.372383) (xy 452.376311 -22.42196)
			(xy 452.391666 -22.474255) (xy 452.399422 -22.528203) (xy 452.399908 -22.555454) (xy 452.399443 -22.582265)
			(xy 452.391934 -22.63536) (xy 452.377059 -22.686878) (xy 452.355111 -22.735803) (xy 452.326523 -22.781169)
			(xy 452.291859 -22.822081) (xy 452.251804 -22.857732) (xy 452.229728 -22.872954) (xy 452.218176 -22.881229)
			(xy 452.199767 -22.90286) (xy 452.188027 -22.928724) (xy 452.183863 -22.956821) (xy 452.187597 -22.984978)
			(xy 452.198942 -23.011018) (xy 452.217018 -23.032927) (xy 452.228458 -23.041356) (xy 452.249917 -23.056706)
			(xy 452.288828 -23.092334) (xy 452.322459 -23.132985) (xy 452.350169 -23.17788) (xy 452.371429 -23.226166)
			(xy 452.385834 -23.27692) (xy 452.393109 -23.329175) (xy 452.393558 -23.355554) (xy 452.393072 -23.382805)
			(xy 452.385316 -23.436753) (xy 452.369961 -23.489048) (xy 452.347319 -23.538625) (xy 452.317853 -23.584475)
			(xy 452.282162 -23.625666) (xy 452.240971 -23.661357) (xy 452.195121 -23.690823) (xy 452.145544 -23.713465)
			(xy 452.093249 -23.72882) (xy 452.039301 -23.736576) (xy 451.984799 -23.736576) (xy 451.930851 -23.72882)
			(xy 451.878556 -23.713465) (xy 451.828979 -23.690823) (xy 451.783129 -23.661357) (xy 451.741938 -23.625666)
			(xy 451.706247 -23.584475) (xy 451.676781 -23.538625) (xy 451.654139 -23.489048) (xy 451.638784 -23.436753)
			(xy 451.631028 -23.382805) (xy 451.630542 -23.355554) (xy 443.067953 -23.355554) (xy 443.068816 -23.356517)
			(xy 443.099589 -23.40303) (xy 443.123261 -23.453527) (xy 443.139329 -23.506934) (xy 443.147449 -23.56211)
			(xy 443.147958 -23.589996) (xy 443.147449 -23.617882) (xy 443.139329 -23.673058) (xy 443.123261 -23.726465)
			(xy 443.099589 -23.776962) (xy 443.068816 -23.823475) (xy 443.031599 -23.865012) (xy 443.013207 -23.880318)
			(xy 443.54064 -23.880318) (xy 443.544711 -23.824696) (xy 443.556837 -23.770259) (xy 443.57676 -23.718168)
			(xy 443.604056 -23.669533) (xy 443.638142 -23.62539) (xy 443.678291 -23.586681) (xy 443.723649 -23.55423)
			(xy 443.773249 -23.528729) (xy 443.826033 -23.510722) (xy 443.880876 -23.500592) (xy 443.93661 -23.498555)
			(xy 443.992047 -23.504655) (xy 444.046004 -23.518761) (xy 444.097333 -23.540573) (xy 444.144939 -23.569627)
			(xy 444.187807 -23.605302) (xy 444.225024 -23.646839) (xy 444.255797 -23.693352) (xy 444.279469 -23.743849)
			(xy 444.295537 -23.797256) (xy 444.303657 -23.852432) (xy 444.304166 -23.880318) (xy 444.55664 -23.880318)
			(xy 444.560711 -23.824696) (xy 444.572837 -23.770259) (xy 444.59276 -23.718168) (xy 444.620056 -23.669533)
			(xy 444.654142 -23.62539) (xy 444.694291 -23.586681) (xy 444.739649 -23.55423) (xy 444.789249 -23.528729)
			(xy 444.842033 -23.510722) (xy 444.896876 -23.500592) (xy 444.95261 -23.498555) (xy 445.008047 -23.504655)
			(xy 445.062004 -23.518761) (xy 445.113333 -23.540573) (xy 445.160939 -23.569627) (xy 445.203807 -23.605302)
			(xy 445.241024 -23.646839) (xy 445.271797 -23.693352) (xy 445.295469 -23.743849) (xy 445.311537 -23.797256)
			(xy 445.319657 -23.852432) (xy 445.320166 -23.880318) (xy 445.57264 -23.880318) (xy 445.576711 -23.824696)
			(xy 445.588837 -23.770259) (xy 445.60876 -23.718168) (xy 445.636056 -23.669533) (xy 445.670142 -23.62539)
			(xy 445.710291 -23.586681) (xy 445.755649 -23.55423) (xy 445.805249 -23.528729) (xy 445.858033 -23.510722)
			(xy 445.912876 -23.500592) (xy 445.96861 -23.498555) (xy 446.024047 -23.504655) (xy 446.078004 -23.518761)
			(xy 446.129333 -23.540573) (xy 446.176939 -23.569627) (xy 446.219807 -23.605302) (xy 446.257024 -23.646839)
			(xy 446.287797 -23.693352) (xy 446.311469 -23.743849) (xy 446.327537 -23.797256) (xy 446.335657 -23.852432)
			(xy 446.336166 -23.880318) (xy 446.590926 -23.880318) (xy 446.594997 -23.824696) (xy 446.607123 -23.770259)
			(xy 446.627046 -23.718168) (xy 446.654342 -23.669533) (xy 446.688428 -23.62539) (xy 446.728577 -23.586681)
			(xy 446.773935 -23.55423) (xy 446.823535 -23.528729) (xy 446.876319 -23.510722) (xy 446.931162 -23.500592)
			(xy 446.986896 -23.498555) (xy 447.042333 -23.504655) (xy 447.09629 -23.518761) (xy 447.147619 -23.540573)
			(xy 447.195225 -23.569627) (xy 447.238093 -23.605302) (xy 447.27531 -23.646839) (xy 447.306083 -23.693352)
			(xy 447.329755 -23.743849) (xy 447.345823 -23.797256) (xy 447.353943 -23.852432) (xy 447.354452 -23.880318)
			(xy 447.353943 -23.908204) (xy 447.345823 -23.96338) (xy 447.345289 -23.965154) (xy 452.3773 -23.965154)
			(xy 452.381371 -23.909532) (xy 452.393497 -23.855095) (xy 452.41342 -23.803004) (xy 452.440716 -23.754369)
			(xy 452.474802 -23.710226) (xy 452.514951 -23.671517) (xy 452.560309 -23.639066) (xy 452.609909 -23.613565)
			(xy 452.662693 -23.595558) (xy 452.717536 -23.585428) (xy 452.77327 -23.583391) (xy 452.828707 -23.589491)
			(xy 452.882664 -23.603597) (xy 452.933993 -23.625409) (xy 452.981599 -23.654463) (xy 453.024467 -23.690138)
			(xy 453.061684 -23.731675) (xy 453.092457 -23.778188) (xy 453.116129 -23.828685) (xy 453.132197 -23.882092)
			(xy 453.140317 -23.937268) (xy 453.140826 -23.965154) (xy 453.140317 -23.99304) (xy 453.132197 -24.048216)
			(xy 453.116129 -24.101623) (xy 453.092457 -24.15212) (xy 453.061684 -24.198633) (xy 453.024467 -24.24017)
			(xy 452.981599 -24.275845) (xy 452.933993 -24.304899) (xy 452.882664 -24.326711) (xy 452.828707 -24.340817)
			(xy 452.77327 -24.346917) (xy 452.717536 -24.34488) (xy 452.662693 -24.33475) (xy 452.609909 -24.316743)
			(xy 452.560309 -24.291242) (xy 452.514951 -24.258791) (xy 452.474802 -24.220082) (xy 452.440716 -24.175939)
			(xy 452.41342 -24.127304) (xy 452.393497 -24.075213) (xy 452.381371 -24.020776) (xy 452.3773 -23.965154)
			(xy 447.345289 -23.965154) (xy 447.329755 -24.016787) (xy 447.306083 -24.067284) (xy 447.27531 -24.113797)
			(xy 447.238093 -24.155334) (xy 447.195225 -24.191009) (xy 447.147619 -24.220063) (xy 447.09629 -24.241875)
			(xy 447.042333 -24.255981) (xy 446.986896 -24.262081) (xy 446.931162 -24.260044) (xy 446.876319 -24.249914)
			(xy 446.823535 -24.231907) (xy 446.773935 -24.206406) (xy 446.728577 -24.173955) (xy 446.688428 -24.135246)
			(xy 446.654342 -24.091103) (xy 446.627046 -24.042468) (xy 446.607123 -23.990377) (xy 446.594997 -23.93594)
			(xy 446.590926 -23.880318) (xy 446.336166 -23.880318) (xy 446.335657 -23.908204) (xy 446.327537 -23.96338)
			(xy 446.311469 -24.016787) (xy 446.287797 -24.067284) (xy 446.257024 -24.113797) (xy 446.219807 -24.155334)
			(xy 446.176939 -24.191009) (xy 446.129333 -24.220063) (xy 446.078004 -24.241875) (xy 446.024047 -24.255981)
			(xy 445.96861 -24.262081) (xy 445.912876 -24.260044) (xy 445.858033 -24.249914) (xy 445.805249 -24.231907)
			(xy 445.755649 -24.206406) (xy 445.710291 -24.173955) (xy 445.670142 -24.135246) (xy 445.636056 -24.091103)
			(xy 445.60876 -24.042468) (xy 445.588837 -23.990377) (xy 445.576711 -23.93594) (xy 445.57264 -23.880318)
			(xy 445.320166 -23.880318) (xy 445.319657 -23.908204) (xy 445.311537 -23.96338) (xy 445.295469 -24.016787)
			(xy 445.271797 -24.067284) (xy 445.241024 -24.113797) (xy 445.203807 -24.155334) (xy 445.160939 -24.191009)
			(xy 445.113333 -24.220063) (xy 445.062004 -24.241875) (xy 445.008047 -24.255981) (xy 444.95261 -24.262081)
			(xy 444.896876 -24.260044) (xy 444.842033 -24.249914) (xy 444.789249 -24.231907) (xy 444.739649 -24.206406)
			(xy 444.694291 -24.173955) (xy 444.654142 -24.135246) (xy 444.620056 -24.091103) (xy 444.59276 -24.042468)
			(xy 444.572837 -23.990377) (xy 444.560711 -23.93594) (xy 444.55664 -23.880318) (xy 444.304166 -23.880318)
			(xy 444.303657 -23.908204) (xy 444.295537 -23.96338) (xy 444.279469 -24.016787) (xy 444.255797 -24.067284)
			(xy 444.225024 -24.113797) (xy 444.187807 -24.155334) (xy 444.144939 -24.191009) (xy 444.097333 -24.220063)
			(xy 444.046004 -24.241875) (xy 443.992047 -24.255981) (xy 443.93661 -24.262081) (xy 443.880876 -24.260044)
			(xy 443.826033 -24.249914) (xy 443.773249 -24.231907) (xy 443.723649 -24.206406) (xy 443.678291 -24.173955)
			(xy 443.638142 -24.135246) (xy 443.604056 -24.091103) (xy 443.57676 -24.042468) (xy 443.556837 -23.990377)
			(xy 443.544711 -23.93594) (xy 443.54064 -23.880318) (xy 443.013207 -23.880318) (xy 442.988731 -23.900687)
			(xy 442.941125 -23.929741) (xy 442.889796 -23.951553) (xy 442.835839 -23.965659) (xy 442.780402 -23.971759)
			(xy 442.724668 -23.969722) (xy 442.669825 -23.959592) (xy 442.617041 -23.941585) (xy 442.567441 -23.916084)
			(xy 442.522083 -23.883633) (xy 442.481934 -23.844924) (xy 442.447848 -23.800781) (xy 442.420552 -23.752146)
			(xy 442.400629 -23.700055) (xy 442.388503 -23.645618) (xy 442.384432 -23.589996) (xy 439.128283 -23.589996)
			(xy 439.127873 -23.610893) (xy 439.120111 -23.664832) (xy 439.104752 -23.717117) (xy 439.082109 -23.766685)
			(xy 439.052642 -23.812525) (xy 439.016952 -23.853706) (xy 438.975764 -23.889388) (xy 438.929917 -23.918846)
			(xy 438.880345 -23.941479) (xy 438.828057 -23.956827) (xy 438.774117 -23.964578) (xy 438.719622 -23.964574)
			(xy 438.665683 -23.956814) (xy 438.613397 -23.941457) (xy 438.563829 -23.918816) (xy 438.517987 -23.889351)
			(xy 438.476805 -23.853662) (xy 438.441121 -23.812476) (xy 438.411662 -23.766631) (xy 438.389026 -23.71706)
			(xy 438.373676 -23.664772) (xy 438.365923 -23.610832) (xy 428.881418 -23.610832) (xy 428.929469 -23.631251)
			(xy 428.977075 -23.660305) (xy 429.019943 -23.69598) (xy 429.05716 -23.737517) (xy 429.087933 -23.78403)
			(xy 429.111605 -23.834527) (xy 429.127673 -23.887934) (xy 429.135793 -23.94311) (xy 429.136302 -23.970996)
			(xy 429.135793 -23.998882) (xy 429.127673 -24.054058) (xy 429.111605 -24.107465) (xy 429.087933 -24.157962)
			(xy 429.08778 -24.158194) (xy 433.750718 -24.158194) (xy 433.754789 -24.102572) (xy 433.766915 -24.048135)
			(xy 433.786838 -23.996044) (xy 433.814134 -23.947409) (xy 433.84822 -23.903266) (xy 433.888369 -23.864557)
			(xy 433.933727 -23.832106) (xy 433.983327 -23.806605) (xy 434.036111 -23.788598) (xy 434.090954 -23.778468)
			(xy 434.146688 -23.776431) (xy 434.202125 -23.782531) (xy 434.256082 -23.796637) (xy 434.307411 -23.818449)
			(xy 434.355017 -23.847503) (xy 434.397885 -23.883178) (xy 434.435102 -23.924715) (xy 434.465875 -23.971228)
			(xy 434.489547 -24.021725) (xy 434.505615 -24.075132) (xy 434.513735 -24.130308) (xy 434.514244 -24.158194)
			(xy 434.513735 -24.18608) (xy 434.513166 -24.189944) (xy 437.598818 -24.189944) (xy 437.602889 -24.134322)
			(xy 437.615015 -24.079885) (xy 437.634938 -24.027794) (xy 437.662234 -23.979159) (xy 437.69632 -23.935016)
			(xy 437.736469 -23.896307) (xy 437.781827 -23.863856) (xy 437.831427 -23.838355) (xy 437.884211 -23.820348)
			(xy 437.939054 -23.810218) (xy 437.994788 -23.808181) (xy 438.050225 -23.814281) (xy 438.104182 -23.828387)
			(xy 438.155511 -23.850199) (xy 438.203117 -23.879253) (xy 438.245985 -23.914928) (xy 438.283202 -23.956465)
			(xy 438.313975 -24.002978) (xy 438.337647 -24.053475) (xy 438.353715 -24.106882) (xy 438.361835 -24.162058)
			(xy 438.362344 -24.189944) (xy 440.1218 -24.189944) (xy 440.125871 -24.134322) (xy 440.137997 -24.079885)
			(xy 440.15792 -24.027794) (xy 440.185216 -23.979159) (xy 440.219302 -23.935016) (xy 440.259451 -23.896307)
			(xy 440.304809 -23.863856) (xy 440.354409 -23.838355) (xy 440.407193 -23.820348) (xy 440.462036 -23.810218)
			(xy 440.51777 -23.808181) (xy 440.573207 -23.814281) (xy 440.627164 -23.828387) (xy 440.678493 -23.850199)
			(xy 440.726099 -23.879253) (xy 440.768967 -23.914928) (xy 440.806184 -23.956465) (xy 440.836957 -24.002978)
			(xy 440.860629 -24.053475) (xy 440.876697 -24.106882) (xy 440.884817 -24.162058) (xy 440.885326 -24.189944)
			(xy 440.884817 -24.21783) (xy 440.876697 -24.273006) (xy 440.860629 -24.326413) (xy 440.836957 -24.37691)
			(xy 440.806184 -24.423423) (xy 440.768967 -24.46496) (xy 440.726099 -24.500635) (xy 440.678493 -24.529689)
			(xy 440.627164 -24.551501) (xy 440.573207 -24.565607) (xy 440.51777 -24.571707) (xy 440.462036 -24.56967)
			(xy 440.407193 -24.55954) (xy 440.354409 -24.541533) (xy 440.304809 -24.516032) (xy 440.259451 -24.483581)
			(xy 440.219302 -24.444872) (xy 440.185216 -24.400729) (xy 440.15792 -24.352094) (xy 440.137997 -24.300003)
			(xy 440.125871 -24.245566) (xy 440.1218 -24.189944) (xy 438.362344 -24.189944) (xy 438.361835 -24.21783)
			(xy 438.353715 -24.273006) (xy 438.337647 -24.326413) (xy 438.313975 -24.37691) (xy 438.283202 -24.423423)
			(xy 438.245985 -24.46496) (xy 438.203117 -24.500635) (xy 438.155511 -24.529689) (xy 438.104182 -24.551501)
			(xy 438.050225 -24.565607) (xy 437.994788 -24.571707) (xy 437.939054 -24.56967) (xy 437.884211 -24.55954)
			(xy 437.831427 -24.541533) (xy 437.781827 -24.516032) (xy 437.736469 -24.483581) (xy 437.69632 -24.444872)
			(xy 437.662234 -24.400729) (xy 437.634938 -24.352094) (xy 437.615015 -24.300003) (xy 437.602889 -24.245566)
			(xy 437.598818 -24.189944) (xy 434.513166 -24.189944) (xy 434.505615 -24.241256) (xy 434.489547 -24.294663)
			(xy 434.465875 -24.34516) (xy 434.435102 -24.391673) (xy 434.397885 -24.43321) (xy 434.355017 -24.468885)
			(xy 434.307411 -24.497939) (xy 434.256082 -24.519751) (xy 434.202125 -24.533857) (xy 434.146688 -24.539957)
			(xy 434.090954 -24.53792) (xy 434.036111 -24.52779) (xy 433.983327 -24.509783) (xy 433.933727 -24.484282)
			(xy 433.888369 -24.451831) (xy 433.84822 -24.413122) (xy 433.814134 -24.368979) (xy 433.786838 -24.320344)
			(xy 433.766915 -24.268253) (xy 433.754789 -24.213816) (xy 433.750718 -24.158194) (xy 429.08778 -24.158194)
			(xy 429.05716 -24.204475) (xy 429.019943 -24.246012) (xy 428.977075 -24.281687) (xy 428.929469 -24.310741)
			(xy 428.87814 -24.332553) (xy 428.824183 -24.346659) (xy 428.768746 -24.352759) (xy 428.713012 -24.350722)
			(xy 428.658169 -24.340592) (xy 428.605385 -24.322585) (xy 428.555785 -24.297084) (xy 428.510427 -24.264633)
			(xy 428.470278 -24.225924) (xy 428.436192 -24.181781) (xy 428.408896 -24.133146) (xy 428.388973 -24.081055)
			(xy 428.376847 -24.026618) (xy 428.372776 -23.970996) (xy 428.14374 -23.970996) (xy 428.143664 -23.975194)
			(xy 428.135292 -24.031228) (xy 428.118726 -24.085409) (xy 428.094331 -24.136544) (xy 428.062643 -24.18351)
			(xy 428.024359 -24.225275) (xy 427.980321 -24.260919) (xy 427.931495 -24.28966) (xy 427.878957 -24.310866)
			(xy 427.823861 -24.32407) (xy 427.79569 -24.327104) (xy 427.784514 -24.327866) (xy 427.775116 -24.332692)
			(xy 427.771227 -24.334797) (xy 427.764196 -24.340159) (xy 427.761146 -24.34336) (xy 427.71441 -24.393906)
			(xy 427.70822 -24.401163) (xy 427.701292 -24.418919) (xy 427.700948 -24.42845) (xy 427.700948 -24.807418)
			(xy 434.920134 -24.807418) (xy 434.924205 -24.751796) (xy 434.936331 -24.697359) (xy 434.956254 -24.645268)
			(xy 434.98355 -24.596633) (xy 435.017636 -24.55249) (xy 435.057785 -24.513781) (xy 435.103143 -24.48133)
			(xy 435.152743 -24.455829) (xy 435.205527 -24.437822) (xy 435.26037 -24.427692) (xy 435.316104 -24.425655)
			(xy 435.371541 -24.431755) (xy 435.425498 -24.445861) (xy 435.476827 -24.467673) (xy 435.524433 -24.496727)
			(xy 435.567301 -24.532402) (xy 435.604518 -24.573939) (xy 435.635291 -24.620452) (xy 435.658963 -24.670949)
			(xy 435.675031 -24.724356) (xy 435.680078 -24.75865) (xy 447.168522 -24.75865) (xy 447.172593 -24.703028)
			(xy 447.184719 -24.648591) (xy 447.204642 -24.5965) (xy 447.231938 -24.547865) (xy 447.266024 -24.503722)
			(xy 447.306173 -24.465013) (xy 447.351531 -24.432562) (xy 447.401131 -24.407061) (xy 447.453915 -24.389054)
			(xy 447.508758 -24.378924) (xy 447.564492 -24.376887) (xy 447.619929 -24.382987) (xy 447.673886 -24.397093)
			(xy 447.725215 -24.418905) (xy 447.772821 -24.447959) (xy 447.815689 -24.483634) (xy 447.852906 -24.525171)
			(xy 447.883679 -24.571684) (xy 447.907351 -24.622181) (xy 447.923419 -24.675588) (xy 447.931539 -24.730764)
			(xy 447.932048 -24.75865) (xy 447.931539 -24.786536) (xy 447.923419 -24.841712) (xy 447.907351 -24.895119)
			(xy 447.883679 -24.945616) (xy 447.852906 -24.992129) (xy 447.815689 -25.033666) (xy 447.772821 -25.069341)
			(xy 447.725215 -25.098395) (xy 447.673886 -25.120207) (xy 447.619929 -25.134313) (xy 447.564492 -25.140413)
			(xy 447.508758 -25.138376) (xy 447.453915 -25.128246) (xy 447.401131 -25.110239) (xy 447.351531 -25.084738)
			(xy 447.306173 -25.052287) (xy 447.266024 -25.013578) (xy 447.231938 -24.969435) (xy 447.204642 -24.9208)
			(xy 447.184719 -24.868709) (xy 447.172593 -24.814272) (xy 447.168522 -24.75865) (xy 435.680078 -24.75865)
			(xy 435.683151 -24.779532) (xy 435.68366 -24.807418) (xy 435.683151 -24.835304) (xy 435.675031 -24.89048)
			(xy 435.658963 -24.943887) (xy 435.635291 -24.994384) (xy 435.604518 -25.040897) (xy 435.567301 -25.082434)
			(xy 435.524433 -25.118109) (xy 435.476827 -25.147163) (xy 435.425498 -25.168975) (xy 435.371541 -25.183081)
			(xy 435.316104 -25.189181) (xy 435.26037 -25.187144) (xy 435.205527 -25.177014) (xy 435.152743 -25.159007)
			(xy 435.103143 -25.133506) (xy 435.057785 -25.101055) (xy 435.017636 -25.062346) (xy 434.98355 -25.018203)
			(xy 434.956254 -24.969568) (xy 434.936331 -24.917477) (xy 434.924205 -24.86304) (xy 434.920134 -24.807418)
			(xy 427.700948 -24.807418) (xy 427.700948 -25.390094) (xy 440.10961 -25.390094) (xy 440.110096 -25.362843)
			(xy 440.117852 -25.308895) (xy 440.133207 -25.2566) (xy 440.155849 -25.207023) (xy 440.185315 -25.161173)
			(xy 440.221006 -25.119982) (xy 440.262197 -25.084291) (xy 440.308047 -25.054825) (xy 440.357624 -25.032183)
			(xy 440.409919 -25.016828) (xy 440.463867 -25.009072) (xy 440.518369 -25.009072) (xy 440.572317 -25.016828)
			(xy 440.624612 -25.032183) (xy 440.674189 -25.054825) (xy 440.720039 -25.084291) (xy 440.76123 -25.119982)
			(xy 440.796921 -25.161173) (xy 440.826387 -25.207023) (xy 440.849029 -25.2566) (xy 440.864384 -25.308895)
			(xy 440.87214 -25.362843) (xy 440.872626 -25.390094) (xy 440.872064 -25.419114) (xy 440.863273 -25.476485)
			(xy 440.845894 -25.531863) (xy 440.820327 -25.583969) (xy 440.787162 -25.631601) (xy 440.747165 -25.67366)
			(xy 440.724544 -25.691846) (xy 440.714005 -25.70062) (xy 440.697573 -25.722556) (xy 440.687573 -25.748075)
			(xy 440.684728 -25.775336) (xy 440.689242 -25.80237) (xy 440.700791 -25.827226) (xy 440.718541 -25.848111)
			(xy 440.729624 -25.856184) (xy 440.751268 -25.871499) (xy 440.790524 -25.907138) (xy 440.824465 -25.947871)
			(xy 440.852438 -25.992911) (xy 440.873904 -26.041392) (xy 440.888449 -26.092378) (xy 440.895792 -26.144888)
			(xy 440.896248 -26.171398) (xy 440.895762 -26.198649) (xy 440.888006 -26.252597) (xy 440.872651 -26.304892)
			(xy 440.850009 -26.354469) (xy 440.820543 -26.400319) (xy 440.784852 -26.44151) (xy 440.743661 -26.477201)
			(xy 440.697811 -26.506667) (xy 440.648234 -26.529309) (xy 440.595939 -26.544664) (xy 440.541991 -26.55242)
			(xy 440.487489 -26.55242) (xy 440.433541 -26.544664) (xy 440.381246 -26.529309) (xy 440.331669 -26.506667)
			(xy 440.285819 -26.477201) (xy 440.244628 -26.44151) (xy 440.208937 -26.400319) (xy 440.179471 -26.354469)
			(xy 440.156829 -26.304892) (xy 440.141474 -26.252597) (xy 440.133718 -26.198649) (xy 440.133232 -26.171398)
			(xy 440.133804 -26.142378) (xy 440.142595 -26.085009) (xy 440.159974 -26.029632) (xy 440.185539 -25.977526)
			(xy 440.218701 -25.929894) (xy 440.258694 -25.887834) (xy 440.281314 -25.869646) (xy 440.291866 -25.860885)
			(xy 440.308306 -25.838948) (xy 440.31831 -25.813425) (xy 440.321155 -25.786159) (xy 440.316637 -25.759121)
			(xy 440.305081 -25.734262) (xy 440.287322 -25.713378) (xy 440.276234 -25.705308) (xy 440.254599 -25.68998)
			(xy 440.215341 -25.654345) (xy 440.181397 -25.613616) (xy 440.153421 -25.568577) (xy 440.131954 -25.520098)
			(xy 440.117408 -25.469113) (xy 440.110065 -25.416604) (xy 440.10961 -25.390094) (xy 427.700948 -25.390094)
			(xy 427.700948 -25.971246) (xy 428.259746 -25.971246) (xy 428.263817 -25.915624) (xy 428.275943 -25.861187)
			(xy 428.295866 -25.809096) (xy 428.323162 -25.760461) (xy 428.357248 -25.716318) (xy 428.397397 -25.677609)
			(xy 428.442755 -25.645158) (xy 428.492355 -25.619657) (xy 428.545139 -25.60165) (xy 428.599982 -25.59152)
			(xy 428.655716 -25.589483) (xy 428.711153 -25.595583) (xy 428.76511 -25.609689) (xy 428.816439 -25.631501)
			(xy 428.864045 -25.660555) (xy 428.906913 -25.69623) (xy 428.94413 -25.737767) (xy 428.974903 -25.78428)
			(xy 428.998575 -25.834777) (xy 429.014643 -25.888184) (xy 429.022763 -25.94336) (xy 429.023272 -25.971246)
			(xy 429.275746 -25.971246) (xy 429.279817 -25.915624) (xy 429.291943 -25.861187) (xy 429.311866 -25.809096)
			(xy 429.339162 -25.760461) (xy 429.373248 -25.716318) (xy 429.413397 -25.677609) (xy 429.458755 -25.645158)
			(xy 429.508355 -25.619657) (xy 429.561139 -25.60165) (xy 429.615982 -25.59152) (xy 429.671716 -25.589483)
			(xy 429.727153 -25.595583) (xy 429.78111 -25.609689) (xy 429.832439 -25.631501) (xy 429.880045 -25.660555)
			(xy 429.922913 -25.69623) (xy 429.96013 -25.737767) (xy 429.990903 -25.78428) (xy 430.014575 -25.834777)
			(xy 430.030643 -25.888184) (xy 430.038763 -25.94336) (xy 430.039272 -25.971246) (xy 430.291746 -25.971246)
			(xy 430.295817 -25.915624) (xy 430.307943 -25.861187) (xy 430.327866 -25.809096) (xy 430.355162 -25.760461)
			(xy 430.389248 -25.716318) (xy 430.429397 -25.677609) (xy 430.474755 -25.645158) (xy 430.524355 -25.619657)
			(xy 430.577139 -25.60165) (xy 430.631982 -25.59152) (xy 430.687716 -25.589483) (xy 430.743153 -25.595583)
			(xy 430.79711 -25.609689) (xy 430.848439 -25.631501) (xy 430.896045 -25.660555) (xy 430.938913 -25.69623)
			(xy 430.97613 -25.737767) (xy 431.006903 -25.78428) (xy 431.030575 -25.834777) (xy 431.046643 -25.888184)
			(xy 431.054763 -25.94336) (xy 431.055272 -25.971246) (xy 431.054763 -25.999132) (xy 431.049671 -26.03373)
			(xy 431.567842 -26.03373) (xy 431.571913 -25.978108) (xy 431.584039 -25.923671) (xy 431.603962 -25.87158)
			(xy 431.631258 -25.822945) (xy 431.665344 -25.778802) (xy 431.705493 -25.740093) (xy 431.750851 -25.707642)
			(xy 431.800451 -25.682141) (xy 431.853235 -25.664134) (xy 431.908078 -25.654004) (xy 431.963812 -25.651967)
			(xy 432.019249 -25.658067) (xy 432.073206 -25.672173) (xy 432.124535 -25.693985) (xy 432.172141 -25.723039)
			(xy 432.215009 -25.758714) (xy 432.252226 -25.800251) (xy 432.282999 -25.846764) (xy 432.306671 -25.897261)
			(xy 432.322739 -25.950668) (xy 432.330859 -26.005844) (xy 432.331368 -26.03373) (xy 432.330859 -26.061616)
			(xy 432.322739 -26.116792) (xy 432.306671 -26.170199) (xy 432.282999 -26.220696) (xy 432.252765 -26.266394)
			(xy 434.820568 -26.266394) (xy 434.821072 -26.239144) (xy 434.828829 -26.185198) (xy 434.844184 -26.132905)
			(xy 434.866824 -26.083329) (xy 434.896288 -26.03748) (xy 434.931978 -25.996291) (xy 434.973166 -25.960599)
			(xy 435.019013 -25.931132) (xy 435.068588 -25.90849) (xy 435.12088 -25.893133) (xy 435.174826 -25.885373)
			(xy 435.202076 -25.884886) (xy 435.231401 -25.885426) (xy 435.289358 -25.894405) (xy 435.345257 -25.912155)
			(xy 435.397778 -25.938257) (xy 435.42204 -25.954736) (xy 435.432454 -25.961848) (xy 435.456838 -25.96515)
			(xy 435.5592 -25.927304) (xy 435.575964 -25.908762) (xy 435.579012 -25.89657) (xy 435.586378 -25.869491)
			(xy 435.607936 -25.81768) (xy 435.636854 -25.769587) (xy 435.672507 -25.726252) (xy 435.714126 -25.688609)
			(xy 435.760812 -25.657472) (xy 435.811557 -25.633512) (xy 435.865265 -25.617247) (xy 435.920777 -25.609029)
			(xy 435.948836 -25.608534) (xy 435.976089 -25.608938) (xy 436.030038 -25.6167) (xy 436.082335 -25.63206)
			(xy 436.131913 -25.654705) (xy 436.177764 -25.684176) (xy 436.218954 -25.719871) (xy 436.254646 -25.761065)
			(xy 436.284112 -25.806919) (xy 436.306753 -25.856499) (xy 436.322108 -25.908797) (xy 436.329864 -25.962747)
			(xy 436.329864 -25.990042) (xy 437.598818 -25.990042) (xy 437.602889 -25.93442) (xy 437.615015 -25.879983)
			(xy 437.634938 -25.827892) (xy 437.662234 -25.779257) (xy 437.69632 -25.735114) (xy 437.736469 -25.696405)
			(xy 437.781827 -25.663954) (xy 437.831427 -25.638453) (xy 437.884211 -25.620446) (xy 437.939054 -25.610316)
			(xy 437.994788 -25.608279) (xy 438.050225 -25.614379) (xy 438.104182 -25.628485) (xy 438.155511 -25.650297)
			(xy 438.203117 -25.679351) (xy 438.245985 -25.715026) (xy 438.283202 -25.756563) (xy 438.313975 -25.803076)
			(xy 438.337647 -25.853573) (xy 438.353715 -25.90698) (xy 438.361835 -25.962156) (xy 438.362344 -25.990042)
			(xy 438.361835 -26.017928) (xy 438.353715 -26.073104) (xy 438.337647 -26.126511) (xy 438.313975 -26.177008)
			(xy 438.283202 -26.223521) (xy 438.245985 -26.265058) (xy 438.203117 -26.300733) (xy 438.155511 -26.329787)
			(xy 438.104182 -26.351599) (xy 438.050225 -26.365705) (xy 437.994788 -26.371805) (xy 437.939054 -26.369768)
			(xy 437.884211 -26.359638) (xy 437.831427 -26.341631) (xy 437.781827 -26.31613) (xy 437.736469 -26.283679)
			(xy 437.69632 -26.24497) (xy 437.662234 -26.200827) (xy 437.634938 -26.152192) (xy 437.615015 -26.100101)
			(xy 437.602889 -26.045664) (xy 437.598818 -25.990042) (xy 436.329864 -25.990042) (xy 436.329864 -26.017253)
			(xy 436.322108 -26.071203) (xy 436.306753 -26.123501) (xy 436.284112 -26.173081) (xy 436.254646 -26.218935)
			(xy 436.218954 -26.260129) (xy 436.177764 -26.295824) (xy 436.131913 -26.325295) (xy 436.082335 -26.34794)
			(xy 436.030038 -26.3633) (xy 435.976089 -26.371062) (xy 435.948836 -26.37155) (xy 435.919512 -26.370997)
			(xy 435.861555 -26.362021) (xy 435.805656 -26.344275) (xy 435.753135 -26.318177) (xy 435.728872 -26.3017)
			(xy 435.718458 -26.294588) (xy 435.694074 -26.291286) (xy 435.591712 -26.329132) (xy 435.574948 -26.347674)
			(xy 435.5719 -26.359866) (xy 435.565102 -26.384894) (xy 435.545689 -26.432984) (xy 435.519935 -26.477998)
			(xy 435.488317 -26.519106) (xy 435.451418 -26.555547) (xy 435.43093 -26.571448) (xy 435.42077 -26.579322)
			(xy 435.410102 -26.601928) (xy 435.41569 -26.711656) (xy 435.428644 -26.733246) (xy 435.439566 -26.73985)
			(xy 435.463295 -26.754767) (xy 435.506532 -26.790429) (xy 435.544085 -26.832034) (xy 435.575147 -26.878686)
			(xy 435.599048 -26.929381) (xy 435.615274 -26.983027) (xy 435.623475 -27.038471) (xy 435.62397 -27.066494)
			(xy 435.623484 -27.093745) (xy 435.615728 -27.147693) (xy 435.600373 -27.199988) (xy 435.577731 -27.249565)
			(xy 435.548265 -27.295415) (xy 435.512574 -27.336606) (xy 435.471383 -27.372297) (xy 435.425533 -27.401763)
			(xy 435.375956 -27.424405) (xy 435.323661 -27.43976) (xy 435.269713 -27.447516) (xy 435.215211 -27.447516)
			(xy 435.161263 -27.43976) (xy 435.108968 -27.424405) (xy 435.059391 -27.401763) (xy 435.013541 -27.372297)
			(xy 434.97235 -27.336606) (xy 434.936659 -27.295415) (xy 434.907193 -27.249565) (xy 434.884551 -27.199988)
			(xy 434.869196 -27.147693) (xy 434.86144 -27.093745) (xy 434.860954 -27.066494) (xy 434.861515 -27.037007)
			(xy 434.870611 -26.978738) (xy 434.888568 -26.922563) (xy 434.91496 -26.869823) (xy 434.949156 -26.821775)
			(xy 434.990342 -26.779564) (xy 435.013608 -26.76144) (xy 435.023768 -26.753566) (xy 435.034436 -26.73096)
			(xy 435.028848 -26.621232) (xy 435.015894 -26.599642) (xy 435.004972 -26.593038) (xy 434.981224 -26.578151)
			(xy 434.93799 -26.542482) (xy 434.90044 -26.50087) (xy 434.869382 -26.454213) (xy 434.845484 -26.403514)
			(xy 434.829261 -26.349865) (xy 434.821062 -26.294419) (xy 434.820568 -26.266394) (xy 432.252765 -26.266394)
			(xy 432.252226 -26.267209) (xy 432.215009 -26.308746) (xy 432.172141 -26.344421) (xy 432.124535 -26.373475)
			(xy 432.073206 -26.395287) (xy 432.019249 -26.409393) (xy 431.963812 -26.415493) (xy 431.908078 -26.413456)
			(xy 431.853235 -26.403326) (xy 431.800451 -26.385319) (xy 431.750851 -26.359818) (xy 431.705493 -26.327367)
			(xy 431.665344 -26.288658) (xy 431.631258 -26.244515) (xy 431.603962 -26.19588) (xy 431.584039 -26.143789)
			(xy 431.571913 -26.089352) (xy 431.567842 -26.03373) (xy 431.049671 -26.03373) (xy 431.046643 -26.054308)
			(xy 431.030575 -26.107715) (xy 431.006903 -26.158212) (xy 430.97613 -26.204725) (xy 430.938913 -26.246262)
			(xy 430.896045 -26.281937) (xy 430.848439 -26.310991) (xy 430.79711 -26.332803) (xy 430.743153 -26.346909)
			(xy 430.687716 -26.353009) (xy 430.631982 -26.350972) (xy 430.577139 -26.340842) (xy 430.524355 -26.322835)
			(xy 430.474755 -26.297334) (xy 430.429397 -26.264883) (xy 430.389248 -26.226174) (xy 430.355162 -26.182031)
			(xy 430.327866 -26.133396) (xy 430.307943 -26.081305) (xy 430.295817 -26.026868) (xy 430.291746 -25.971246)
			(xy 430.039272 -25.971246) (xy 430.038763 -25.999132) (xy 430.030643 -26.054308) (xy 430.014575 -26.107715)
			(xy 429.990903 -26.158212) (xy 429.96013 -26.204725) (xy 429.922913 -26.246262) (xy 429.880045 -26.281937)
			(xy 429.832439 -26.310991) (xy 429.78111 -26.332803) (xy 429.727153 -26.346909) (xy 429.671716 -26.353009)
			(xy 429.615982 -26.350972) (xy 429.561139 -26.340842) (xy 429.508355 -26.322835) (xy 429.458755 -26.297334)
			(xy 429.413397 -26.264883) (xy 429.373248 -26.226174) (xy 429.339162 -26.182031) (xy 429.311866 -26.133396)
			(xy 429.291943 -26.081305) (xy 429.279817 -26.026868) (xy 429.275746 -25.971246) (xy 429.023272 -25.971246)
			(xy 429.022763 -25.999132) (xy 429.014643 -26.054308) (xy 428.998575 -26.107715) (xy 428.974903 -26.158212)
			(xy 428.94413 -26.204725) (xy 428.906913 -26.246262) (xy 428.864045 -26.281937) (xy 428.816439 -26.310991)
			(xy 428.76511 -26.332803) (xy 428.711153 -26.346909) (xy 428.655716 -26.353009) (xy 428.599982 -26.350972)
			(xy 428.545139 -26.340842) (xy 428.492355 -26.322835) (xy 428.442755 -26.297334) (xy 428.397397 -26.264883)
			(xy 428.357248 -26.226174) (xy 428.323162 -26.182031) (xy 428.295866 -26.133396) (xy 428.275943 -26.081305)
			(xy 428.263817 -26.026868) (xy 428.259746 -25.971246) (xy 427.700948 -25.971246) (xy 427.700948 -27.654758)
			(xy 427.701306 -27.664324) (xy 427.708234 -27.682153) (xy 427.721218 -27.696199) (xy 427.72965 -27.700732)
			(xy 427.729904 -27.700732) (xy 427.75671 -27.714208) (xy 427.806122 -27.748232) (xy 427.815303 -27.756951)
			(xy 431.059066 -27.756951) (xy 431.059066 -27.702449) (xy 431.066822 -27.648501) (xy 431.082177 -27.596206)
			(xy 431.104817 -27.546628) (xy 431.134283 -27.500777) (xy 431.169974 -27.459586) (xy 431.211163 -27.423894)
			(xy 431.257013 -27.394426) (xy 431.306589 -27.371783) (xy 431.358883 -27.356426) (xy 431.412831 -27.348667)
			(xy 431.440082 -27.34818) (xy 431.454167 -27.348275) (xy 431.482263 -27.350313) (xy 431.496216 -27.352244)
			(xy 431.509932 -27.354276) (xy 431.53584 -27.343862) (xy 431.606198 -27.249882) (xy 431.609246 -27.221942)
			(xy 431.603404 -27.209242) (xy 431.592365 -27.184111) (xy 431.57676 -27.131489) (xy 431.568852 -27.077173)
			(xy 431.568352 -27.04973) (xy 431.568838 -27.022479) (xy 431.576594 -26.968531) (xy 431.591949 -26.916236)
			(xy 431.614591 -26.866659) (xy 431.644057 -26.820809) (xy 431.679748 -26.779618) (xy 431.720939 -26.743927)
			(xy 431.766789 -26.714461) (xy 431.816366 -26.691819) (xy 431.868661 -26.676464) (xy 431.922609 -26.668708)
			(xy 431.977111 -26.668708) (xy 432.031059 -26.676464) (xy 432.083354 -26.691819) (xy 432.132931 -26.714461)
			(xy 432.178781 -26.743927) (xy 432.219972 -26.779618) (xy 432.255663 -26.820809) (xy 432.285129 -26.866659)
			(xy 432.307771 -26.916236) (xy 432.323126 -26.968531) (xy 432.330882 -27.022479) (xy 432.331368 -27.04973)
			(xy 432.330751 -27.081146) (xy 432.320488 -27.143133) (xy 432.300211 -27.202603) (xy 432.285902 -27.230578)
			(xy 432.280568 -27.24023) (xy 432.279044 -27.262074) (xy 432.313334 -27.354022) (xy 432.328574 -27.369516)
			(xy 432.338734 -27.37358) (xy 432.365386 -27.384327) (xy 432.415352 -27.41271) (xy 432.460493 -27.44827)
			(xy 432.499787 -27.490202) (xy 432.532344 -27.537555) (xy 432.557426 -27.589258) (xy 432.574465 -27.644139)
			(xy 432.583075 -27.700955) (xy 432.58359 -27.729688) (xy 432.583133 -27.756941) (xy 432.575378 -27.810893)
			(xy 432.560022 -27.863193) (xy 432.53738 -27.912774) (xy 432.507911 -27.958628) (xy 432.472217 -27.999821)
			(xy 432.431023 -28.035515) (xy 432.385169 -28.064983) (xy 432.335587 -28.087624) (xy 432.283288 -28.102979)
			(xy 432.229335 -28.110734) (xy 432.202082 -28.111196) (xy 432.173167 -28.11062) (xy 432.115999 -28.101904)
			(xy 432.060801 -28.084657) (xy 432.008839 -28.059276) (xy 431.961303 -28.026343) (xy 431.919284 -27.986611)
			(xy 431.901092 -27.96413) (xy 431.893541 -27.955357) (xy 431.872774 -27.945183) (xy 431.861214 -27.944572)
			(xy 431.78095 -27.944572) (xy 431.769382 -27.945146) (xy 431.748609 -27.955336) (xy 431.741072 -27.96413)
			(xy 431.722904 -27.986633) (xy 431.680879 -28.026366) (xy 431.633339 -28.059302) (xy 431.581373 -28.084686)
			(xy 431.526172 -28.101939) (xy 431.468999 -28.110663) (xy 431.440082 -28.111196) (xy 431.412831 -28.110733)
			(xy 431.358883 -28.102974) (xy 431.306589 -28.087617) (xy 431.257013 -28.064974) (xy 431.211163 -28.035506)
			(xy 431.169974 -27.999814) (xy 431.134283 -27.958623) (xy 431.104817 -27.912772) (xy 431.082177 -27.863194)
			(xy 431.066822 -27.810899) (xy 431.059066 -27.756951) (xy 427.815303 -27.756951) (xy 427.849624 -27.789547)
			(xy 427.868334 -27.813) (xy 427.87062 -27.816048) (xy 427.87316 -27.818588) (xy 427.876208 -27.821636)
			(xy 427.88217 -27.82714) (xy 427.896676 -27.834391) (xy 427.904656 -27.83586) (xy 427.915832 -27.837638)
			(xy 427.98365 -27.847544) (xy 428.003208 -27.842464) (xy 428.011336 -27.836114) (xy 428.031385 -27.821286)
			(xy 428.0746 -27.796405) (xy 428.120688 -27.777364) (xy 428.168863 -27.764488) (xy 428.218305 -27.757998)
			(xy 428.243238 -27.757628) (xy 428.27129 -27.75812) (xy 428.32679 -27.766326) (xy 428.38049 -27.782571)
			(xy 428.431233 -27.806504) (xy 428.477924 -27.837609) (xy 428.519557 -27.875216) (xy 428.555235 -27.918514)
			(xy 428.570136 -27.942286) (xy 428.573692 -27.947874) (xy 428.582328 -27.956764) (xy 428.608236 -27.97175)
			(xy 428.618396 -27.976322) (xy 428.627794 -27.978608) (xy 428.63389 -27.978862) (xy 428.687484 -27.978862)
			(xy 428.693919 -27.97865) (xy 428.706381 -27.97543) (xy 428.712122 -27.972512) (xy 428.737776 -27.958288)
			(xy 428.74692 -27.949398) (xy 428.750476 -27.94381) (xy 428.761548 -27.926395) (xy 428.786878 -27.893814)
			(xy 428.801022 -27.878786) (xy 428.80153 -27.878278) (xy 428.802038 -27.87777) (xy 428.820139 -27.859169)
			(xy 428.860499 -27.826537) (xy 428.904909 -27.799676) (xy 428.95255 -27.779081) (xy 429.002542 -27.765132)
			(xy 429.053963 -27.758087) (xy 429.079914 -27.757628) (xy 429.107165 -27.758092) (xy 429.161113 -27.765851)
			(xy 429.213407 -27.781209) (xy 429.262983 -27.803853) (xy 429.308832 -27.833321) (xy 429.35002 -27.869016)
			(xy 429.385709 -27.910208) (xy 429.415171 -27.956061) (xy 429.437809 -28.00564) (xy 429.45316 -28.057936)
			(xy 429.460911 -28.111885) (xy 429.461422 -28.139136) (xy 429.967896 -28.139136) (xy 429.971967 -28.083514)
			(xy 429.984093 -28.029077) (xy 430.004016 -27.976986) (xy 430.031312 -27.928351) (xy 430.065398 -27.884208)
			(xy 430.105547 -27.845499) (xy 430.150905 -27.813048) (xy 430.200505 -27.787547) (xy 430.253289 -27.76954)
			(xy 430.308132 -27.75941) (xy 430.363866 -27.757373) (xy 430.419303 -27.763473) (xy 430.47326 -27.777579)
			(xy 430.524589 -27.799391) (xy 430.572195 -27.828445) (xy 430.615063 -27.86412) (xy 430.65228 -27.905657)
			(xy 430.683053 -27.95217) (xy 430.706725 -28.002667) (xy 430.722793 -28.056074) (xy 430.730913 -28.11125)
			(xy 430.731422 -28.139136) (xy 430.730913 -28.167022) (xy 430.722793 -28.222198) (xy 430.706725 -28.275605)
			(xy 430.683053 -28.326102) (xy 430.65228 -28.372615) (xy 430.615063 -28.414152) (xy 430.572195 -28.449827)
			(xy 430.524589 -28.478881) (xy 430.47326 -28.500693) (xy 430.419303 -28.514799) (xy 430.363866 -28.520899)
			(xy 430.308132 -28.518862) (xy 430.253289 -28.508732) (xy 430.200505 -28.490725) (xy 430.150905 -28.465224)
			(xy 430.105547 -28.432773) (xy 430.065398 -28.394064) (xy 430.031312 -28.349921) (xy 430.004016 -28.301286)
			(xy 429.984093 -28.249195) (xy 429.971967 -28.194758) (xy 429.967896 -28.139136) (xy 429.461422 -28.139136)
			(xy 429.460885 -28.168434) (xy 429.451925 -28.226341) (xy 429.434221 -28.282199) (xy 429.408189 -28.334695)
			(xy 429.37444 -28.382597) (xy 429.354488 -28.404058) (xy 429.353726 -28.40482) (xy 429.351948 -28.406598)
			(xy 429.333876 -28.425062) (xy 429.293615 -28.45744) (xy 429.249351 -28.484083) (xy 429.201893 -28.504505)
			(xy 429.152112 -28.51833) (xy 429.10092 -28.525306) (xy 429.075088 -28.525724) (xy 429.046533 -28.52519)
			(xy 428.990062 -28.51668) (xy 428.935488 -28.499852) (xy 428.884031 -28.475081) (xy 428.836839 -28.44292)
			(xy 428.794964 -28.404088) (xy 428.759342 -28.35945) (xy 428.744634 -28.33497) (xy 428.739852 -28.327482)
			(xy 428.726246 -28.31608) (xy 428.709567 -28.309998) (xy 428.700692 -28.30957) (xy 428.614586 -28.30957)
			(xy 428.605798 -28.309942) (xy 428.589263 -28.315899) (xy 428.575722 -28.327105) (xy 428.570898 -28.334462)
			(xy 428.560047 -28.352117) (xy 428.535104 -28.385214) (xy 428.521114 -28.400502) (xy 428.520352 -28.401264)
			(xy 428.519336 -28.402534) (xy 428.518574 -28.403296) (xy 428.51832 -28.40355) (xy 428.500189 -28.42246)
			(xy 428.459645 -28.455637) (xy 428.414946 -28.482959) (xy 428.366931 -28.503913) (xy 428.316502 -28.518105)
			(xy 428.264606 -28.525269) (xy 428.238412 -28.525724) (xy 428.209254 -28.525172) (xy 428.151616 -28.516302)
			(xy 428.095998 -28.498765) (xy 428.043696 -28.472971) (xy 427.995928 -28.43952) (xy 427.953804 -28.39919)
			(xy 427.935644 -28.376372) (xy 427.933358 -28.373324) (xy 427.930818 -28.370784) (xy 427.92777 -28.367736)
			(xy 427.921806 -28.362237) (xy 427.907298 -28.354996) (xy 427.899322 -28.353512) (xy 427.834806 -28.34386)
			(xy 427.828858 -28.343125) (xy 427.81692 -28.344153) (xy 427.811184 -28.345892) (xy 427.791626 -28.352496)
			(xy 427.785784 -28.35656) (xy 427.779942 -28.36037) (xy 427.774862 -28.363926) (xy 427.770544 -28.368752)
			(xy 427.763432 -28.378658) (xy 427.752002 -28.399486) (xy 427.749179 -28.405115) (xy 427.746098 -28.417321)
			(xy 427.745906 -28.423616) (xy 427.745906 -28.428696) (xy 427.746091 -28.435136) (xy 427.749297 -28.447611)
			(xy 427.752256 -28.453334) (xy 427.756574 -28.460954) (xy 427.759763 -28.466301) (xy 427.768238 -28.475416)
			(xy 427.773338 -28.478988) (xy 427.773846 -28.479242) (xy 427.7741 -28.479242) (xy 427.797068 -28.494341)
			(xy 427.838824 -28.530084) (xy 427.875027 -28.571442) (xy 427.90493 -28.617562) (xy 427.927915 -28.66749)
			(xy 427.943509 -28.720196) (xy 427.951389 -28.774594) (xy 427.9519 -28.802076) (xy 427.951384 -28.830781)
			(xy 427.942788 -28.887543) (xy 427.925786 -28.942376) (xy 427.900761 -28.994045) (xy 427.86828 -29.041381)
			(xy 427.84903 -29.06268) (xy 427.848522 -29.063188) (xy 427.84776 -29.064204) (xy 427.84649 -29.065474)
			(xy 427.845982 -29.065982) (xy 427.829297 -29.083502) (xy 427.792249 -29.114619) (xy 427.751569 -29.14081)
			(xy 427.729904 -29.15158) (xy 427.716442 -29.15793) (xy 427.700948 -29.182568) (xy 427.700948 -29.222446)
			(xy 427.701389 -29.23212) (xy 427.70856 -29.250091) (xy 427.721841 -29.264163) (xy 427.730412 -29.268674)
			(xy 427.754855 -29.28048) (xy 427.800417 -29.309984) (xy 427.841334 -29.345653) (xy 427.876777 -29.386766)
			(xy 427.906029 -29.43249) (xy 427.9285 -29.481902) (xy 427.943734 -29.534002) (xy 427.951423 -29.587735)
			(xy 427.9519 -29.614876) (xy 427.95137 -29.644139) (xy 427.942438 -29.70198) (xy 427.924779 -29.757778)
			(xy 427.898807 -29.810226) (xy 427.865132 -29.858094) (xy 427.84522 -29.879544) (xy 427.844712 -29.880052)
			(xy 427.844204 -29.88056) (xy 427.833861 -29.891404) (xy 427.811738 -29.91162) (xy 427.800008 -29.920946)
			(xy 427.791172 -29.928533) (xy 427.780973 -29.949444) (xy 427.78045 -29.961078) (xy 427.78045 -30.02026)
			(xy 427.780631 -30.026063) (xy 427.783317 -30.037357) (xy 427.785784 -30.042612) (xy 427.797722 -30.066996)
			(xy 427.80458 -30.075632) (xy 427.808898 -30.078934) (xy 427.830804 -30.097165) (xy 427.869483 -30.13902)
			(xy 427.901506 -30.186163) (xy 427.926162 -30.237544) (xy 427.942901 -30.29202) (xy 427.951351 -30.348381)
			(xy 427.9519 -30.376876) (xy 427.951384 -30.405581) (xy 427.942788 -30.462343) (xy 427.925786 -30.517176)
			(xy 427.900761 -30.568845) (xy 427.86828 -30.616181) (xy 427.84903 -30.63748) (xy 427.848522 -30.637988)
			(xy 427.84776 -30.639004) (xy 427.84649 -30.640274) (xy 427.845982 -30.640782) (xy 427.829297 -30.658302)
			(xy 427.792249 -30.689419) (xy 427.751569 -30.71561) (xy 427.729904 -30.72638) (xy 427.716442 -30.73273)
			(xy 427.700948 -30.757368) (xy 427.700948 -31.159958) (xy 427.725078 -31.188406) (xy 427.743366 -31.191454)
			(xy 427.770507 -31.196467) (xy 427.823075 -31.213283) (xy 427.872671 -31.237497) (xy 427.918261 -31.268605)
			(xy 427.958893 -31.305957) (xy 427.993719 -31.348774) (xy 428.022011 -31.396162) (xy 428.043181 -31.447132)
			(xy 428.056785 -31.500621) (xy 428.06254 -31.555512) (xy 428.060326 -31.610659) (xy 428.050189 -31.664912)
			(xy 428.032341 -31.717138) (xy 428.03125 -31.719266) (xy 428.585374 -31.719266) (xy 428.589445 -31.663644)
			(xy 428.601571 -31.609207) (xy 428.621494 -31.557116) (xy 428.64879 -31.508481) (xy 428.682876 -31.464338)
			(xy 428.723025 -31.425629) (xy 428.768383 -31.393178) (xy 428.817983 -31.367677) (xy 428.870767 -31.34967)
			(xy 428.92561 -31.33954) (xy 428.981344 -31.337503) (xy 429.036781 -31.343603) (xy 429.090738 -31.357709)
			(xy 429.142067 -31.379521) (xy 429.189673 -31.408575) (xy 429.232541 -31.44425) (xy 429.269758 -31.485787)
			(xy 429.300531 -31.5323) (xy 429.324203 -31.582797) (xy 429.340271 -31.636204) (xy 429.344421 -31.664402)
			(xy 429.860962 -31.664402) (xy 429.865033 -31.60878) (xy 429.877159 -31.554343) (xy 429.897082 -31.502252)
			(xy 429.924378 -31.453617) (xy 429.958464 -31.409474) (xy 429.998613 -31.370765) (xy 430.043971 -31.338314)
			(xy 430.093571 -31.312813) (xy 430.146355 -31.294806) (xy 430.201198 -31.284676) (xy 430.256932 -31.282639)
			(xy 430.312369 -31.288739) (xy 430.366326 -31.302845) (xy 430.417655 -31.324657) (xy 430.465261 -31.353711)
			(xy 430.508129 -31.389386) (xy 430.545346 -31.430923) (xy 430.576119 -31.477436) (xy 430.599791 -31.527933)
			(xy 430.615859 -31.58134) (xy 430.623979 -31.636516) (xy 430.624488 -31.664402) (xy 430.623979 -31.692288)
			(xy 430.615859 -31.747464) (xy 430.606919 -31.777178) (xy 431.126136 -31.777178) (xy 431.130207 -31.721556)
			(xy 431.142333 -31.667119) (xy 431.162256 -31.615028) (xy 431.189552 -31.566393) (xy 431.223638 -31.52225)
			(xy 431.263787 -31.483541) (xy 431.309145 -31.45109) (xy 431.358745 -31.425589) (xy 431.411529 -31.407582)
			(xy 431.466372 -31.397452) (xy 431.522106 -31.395415) (xy 431.577543 -31.401515) (xy 431.6315 -31.415621)
			(xy 431.682829 -31.437433) (xy 431.730435 -31.466487) (xy 431.773303 -31.502162) (xy 431.81052 -31.543699)
			(xy 431.841293 -31.590212) (xy 431.864965 -31.640709) (xy 431.881033 -31.694116) (xy 431.889153 -31.749292)
			(xy 431.889662 -31.777178) (xy 431.889153 -31.805064) (xy 431.881033 -31.86024) (xy 431.864965 -31.913647)
			(xy 431.841293 -31.964144) (xy 431.81052 -32.010657) (xy 431.773303 -32.052194) (xy 431.730435 -32.087869)
			(xy 431.682829 -32.116923) (xy 431.6315 -32.138735) (xy 431.577543 -32.152841) (xy 431.522106 -32.158941)
			(xy 431.466372 -32.156904) (xy 431.411529 -32.146774) (xy 431.358745 -32.128767) (xy 431.309145 -32.103266)
			(xy 431.263787 -32.070815) (xy 431.223638 -32.032106) (xy 431.189552 -31.987963) (xy 431.162256 -31.939328)
			(xy 431.142333 -31.887237) (xy 431.130207 -31.8328) (xy 431.126136 -31.777178) (xy 430.606919 -31.777178)
			(xy 430.599791 -31.800871) (xy 430.576119 -31.851368) (xy 430.545346 -31.897881) (xy 430.508129 -31.939418)
			(xy 430.465261 -31.975093) (xy 430.417655 -32.004147) (xy 430.366326 -32.025959) (xy 430.312369 -32.040065)
			(xy 430.256932 -32.046165) (xy 430.201198 -32.044128) (xy 430.146355 -32.033998) (xy 430.093571 -32.015991)
			(xy 430.043971 -31.99049) (xy 429.998613 -31.958039) (xy 429.958464 -31.91933) (xy 429.924378 -31.875187)
			(xy 429.897082 -31.826552) (xy 429.877159 -31.774461) (xy 429.865033 -31.720024) (xy 429.860962 -31.664402)
			(xy 429.344421 -31.664402) (xy 429.348391 -31.69138) (xy 429.3489 -31.719266) (xy 429.348391 -31.747152)
			(xy 429.340271 -31.802328) (xy 429.324203 -31.855735) (xy 429.300531 -31.906232) (xy 429.269758 -31.952745)
			(xy 429.232541 -31.994282) (xy 429.189673 -32.029957) (xy 429.142067 -32.059011) (xy 429.090738 -32.080823)
			(xy 429.036781 -32.094929) (xy 428.981344 -32.101029) (xy 428.92561 -32.098992) (xy 428.870767 -32.088862)
			(xy 428.817983 -32.070855) (xy 428.768383 -32.045354) (xy 428.723025 -32.012903) (xy 428.682876 -31.974194)
			(xy 428.64879 -31.930051) (xy 428.621494 -31.881416) (xy 428.601571 -31.829325) (xy 428.589445 -31.774888)
			(xy 428.585374 -31.719266) (xy 428.03125 -31.719266) (xy 428.007153 -31.766247) (xy 427.975153 -31.811215)
			(xy 427.956472 -31.831534) (xy 427.955964 -31.832042) (xy 427.955456 -31.832804) (xy 427.934039 -31.854966)
			(xy 427.885362 -31.892764) (xy 427.831245 -31.922248) (xy 427.773093 -31.942654) (xy 427.742858 -31.948628)
			(xy 427.72457 -31.95193) (xy 427.700948 -31.97987) (xy 427.700948 -33.512506) (xy 427.70143 -33.522401)
			(xy 427.70894 -33.540713) (xy 427.722806 -33.554835) (xy 427.731682 -33.559242) (xy 427.831504 -33.602168)
			(xy 427.861222 -33.596834) (xy 427.872398 -33.586166) (xy 427.882559 -33.576667) (xy 427.904045 -33.559)
			(xy 427.915324 -33.55086) (xy 427.922944 -33.54578) (xy 427.928278 -33.537906) (xy 427.930817 -33.534101)
			(xy 427.934644 -33.525795) (xy 427.935898 -33.521396) (xy 427.943772 -33.489392) (xy 427.943772 -33.488884)
			(xy 427.953932 -33.447736) (xy 427.951646 -33.429702) (xy 427.947582 -33.421574) (xy 427.934376 -33.394454)
			(xy 427.915756 -33.337082) (xy 427.906422 -33.277491) (xy 427.905926 -33.24733) (xy 427.905926 -33.242504)
			(xy 427.90679 -33.215515) (xy 427.915187 -33.162173) (xy 427.931022 -33.110548) (xy 427.953977 -33.061672)
			(xy 427.983595 -33.016521) (xy 428.019284 -32.975998) (xy 428.06033 -32.940911) (xy 428.105913 -32.911963)
			(xy 428.155122 -32.889731) (xy 428.206975 -32.87466) (xy 428.260435 -32.86705) (xy 428.287434 -32.866584)
			(xy 428.314684 -32.867072) (xy 428.368628 -32.874832) (xy 428.420919 -32.89019) (xy 428.470493 -32.912833)
			(xy 428.51634 -32.942301) (xy 428.557526 -32.977992) (xy 428.593215 -33.019181) (xy 428.622679 -33.06503)
			(xy 428.645319 -33.114605) (xy 428.660673 -33.166897) (xy 428.66843 -33.220842) (xy 428.668942 -33.248092)
			(xy 428.668516 -33.274186) (xy 428.661404 -33.325888) (xy 428.647312 -33.376138) (xy 428.626502 -33.423998)
			(xy 428.599363 -33.468575) (xy 428.566401 -33.509038) (xy 428.528232 -33.54463) (xy 428.507144 -33.560004)
			(xy 428.499778 -33.565084) (xy 428.494444 -33.572958) (xy 428.491952 -33.576764) (xy 428.48825 -33.585072)
			(xy 428.487078 -33.589468) (xy 428.471076 -33.654238) (xy 428.469272 -33.663024) (xy 428.471234 -33.680842)
			(xy 428.474886 -33.689036) (xy 428.47514 -33.68929) (xy 428.47514 -33.689544) (xy 428.481782 -33.70279)
			(xy 428.493221 -33.730128) (xy 428.498 -33.744154) (xy 428.500794 -33.753044) (xy 428.512224 -33.767014)
			(xy 428.58563 -33.81121) (xy 428.593758 -33.812734) (xy 428.616319 -33.807499) (xy 428.662294 -33.801892)
			(xy 428.685452 -33.801558) (xy 428.712708 -33.802018) (xy 428.766666 -33.809769) (xy 428.818972 -33.82512)
			(xy 428.86856 -33.84776) (xy 428.884019 -33.857692) (xy 429.790096 -33.857692) (xy 429.794167 -33.80207)
			(xy 429.806293 -33.747633) (xy 429.826216 -33.695542) (xy 429.853512 -33.646907) (xy 429.887598 -33.602764)
			(xy 429.927747 -33.564055) (xy 429.973105 -33.531604) (xy 430.022705 -33.506103) (xy 430.075489 -33.488096)
			(xy 430.130332 -33.477966) (xy 430.186066 -33.475929) (xy 430.241503 -33.482029) (xy 430.29546 -33.496135)
			(xy 430.346789 -33.517947) (xy 430.394395 -33.547001) (xy 430.437263 -33.582676) (xy 430.47448 -33.624213)
			(xy 430.505253 -33.670726) (xy 430.528925 -33.721223) (xy 430.544993 -33.77463) (xy 430.553113 -33.829806)
			(xy 430.553622 -33.857692) (xy 430.553113 -33.885578) (xy 430.544993 -33.940754) (xy 430.528925 -33.994161)
			(xy 430.505253 -34.044658) (xy 430.47448 -34.091171) (xy 430.437263 -34.132708) (xy 430.394395 -34.168383)
			(xy 430.346789 -34.197437) (xy 430.29546 -34.219249) (xy 430.241503 -34.233355) (xy 430.186066 -34.239455)
			(xy 430.130332 -34.237418) (xy 430.075489 -34.227288) (xy 430.022705 -34.209281) (xy 429.973105 -34.18378)
			(xy 429.927747 -34.151329) (xy 429.887598 -34.11262) (xy 429.853512 -34.068477) (xy 429.826216 -34.019842)
			(xy 429.806293 -33.967751) (xy 429.794167 -33.913314) (xy 429.790096 -33.857692) (xy 428.884019 -33.857692)
			(xy 428.914422 -33.877226) (xy 428.955623 -33.912919) (xy 428.991325 -33.954113) (xy 429.020801 -33.999968)
			(xy 429.043451 -34.049551) (xy 429.058814 -34.101854) (xy 429.066577 -34.15581) (xy 429.06696 -34.183066)
			(xy 429.066421 -34.212364) (xy 429.057457 -34.270269) (xy 429.039751 -34.326125) (xy 429.013719 -34.37862)
			(xy 428.97997 -34.42652) (xy 428.960026 -34.447988) (xy 428.959264 -34.44875) (xy 428.957486 -34.450528)
			(xy 428.939415 -34.468992) (xy 428.899154 -34.501368) (xy 428.854889 -34.52801) (xy 428.807431 -34.548428)
			(xy 428.75765 -34.562248) (xy 428.706458 -34.569217) (xy 428.680626 -34.569654) (xy 428.654019 -34.569194)
			(xy 428.601322 -34.561803) (xy 428.550163 -34.547162) (xy 428.501535 -34.525554) (xy 428.456381 -34.497398)
			(xy 428.415577 -34.46324) (xy 428.379916 -34.423745) (xy 428.350089 -34.379677) (xy 428.326675 -34.331892)
			(xy 428.317914 -34.306764) (xy 428.31766 -34.306256) (xy 428.314492 -34.297739) (xy 428.303164 -34.283549)
			(xy 428.295562 -34.27857) (xy 428.230284 -34.239708) (xy 428.212504 -34.236406) (xy 428.20336 -34.238184)
			(xy 428.18655 -34.241028) (xy 428.15259 -34.244082) (xy 428.135542 -34.24428) (xy 428.135288 -34.24428)
			(xy 428.106276 -34.243739) (xy 428.048921 -34.234962) (xy 427.993553 -34.217611) (xy 427.941445 -34.192086)
			(xy 427.893798 -34.158973) (xy 427.872398 -34.139378) (xy 427.861222 -34.128964) (xy 427.831504 -34.12363)
			(xy 427.731682 -34.166302) (xy 427.722753 -34.170632) (xy 427.708854 -34.184768) (xy 427.701369 -34.203125)
			(xy 427.700948 -34.213038) (xy 427.700948 -35.264852) (xy 430.202338 -35.264852) (xy 430.206409 -35.20923)
			(xy 430.218535 -35.154793) (xy 430.238458 -35.102702) (xy 430.265754 -35.054067) (xy 430.29984 -35.009924)
			(xy 430.339989 -34.971215) (xy 430.385347 -34.938764) (xy 430.434947 -34.913263) (xy 430.487731 -34.895256)
			(xy 430.542574 -34.885126) (xy 430.598308 -34.883089) (xy 430.653745 -34.889189) (xy 430.707702 -34.903295)
			(xy 430.759031 -34.925107) (xy 430.806637 -34.954161) (xy 430.849505 -34.989836) (xy 430.874342 -35.017556)
			(xy 432.519733 -35.017556) (xy 432.519733 -34.963044) (xy 432.527491 -34.909087) (xy 432.54285 -34.856783)
			(xy 432.565497 -34.807197) (xy 432.59497 -34.76134) (xy 432.630669 -34.720144) (xy 432.671869 -34.684448)
			(xy 432.717729 -34.654979) (xy 432.767317 -34.632338) (xy 432.819622 -34.616984) (xy 432.87358 -34.60923)
			(xy 432.900836 -34.60877) (xy 432.917948 -34.608964) (xy 432.952035 -34.612015) (xy 432.968908 -34.614866)
			(xy 432.980174 -34.616258) (xy 433.002056 -34.610332) (xy 433.011072 -34.603436) (xy 433.035456 -34.582354)
			(xy 433.043843 -34.574427) (xy 433.052968 -34.553255) (xy 433.052982 -34.541714) (xy 433.052728 -34.52241)
			(xy 433.052728 -33.65881) (xy 433.052982 -33.638744) (xy 433.052829 -33.627233) (xy 433.043715 -33.606125)
			(xy 433.035456 -33.598104) (xy 433.011072 -33.577022) (xy 433.002087 -33.570066) (xy 432.980179 -33.564141)
			(xy 432.968908 -33.565592) (xy 432.952037 -33.568462) (xy 432.917949 -33.571515) (xy 432.900836 -33.571688)
			(xy 432.87358 -33.571268) (xy 432.819622 -33.563514) (xy 432.767317 -33.548161) (xy 432.71773 -33.525519)
			(xy 432.67187 -33.49605) (xy 432.630671 -33.460355) (xy 432.594971 -33.419159) (xy 432.565498 -33.373302)
			(xy 432.542852 -33.323716) (xy 432.527493 -33.271413) (xy 432.519735 -33.217456) (xy 432.519735 -33.162944)
			(xy 432.527493 -33.108987) (xy 432.542852 -33.056684) (xy 432.565498 -33.007098) (xy 432.594971 -32.961241)
			(xy 432.630671 -32.920045) (xy 432.67187 -32.88435) (xy 432.71773 -32.854881) (xy 432.767317 -32.832239)
			(xy 432.819622 -32.816886) (xy 432.87358 -32.809132) (xy 432.900836 -32.808672) (xy 432.927845 -32.809086)
			(xy 432.981325 -32.816698) (xy 433.033196 -32.831777) (xy 433.082421 -32.854024) (xy 433.128016 -32.882991)
			(xy 433.169068 -32.918101) (xy 433.204757 -32.958652) (xy 433.234368 -33.003831) (xy 433.25731 -33.052735)
			(xy 433.273124 -33.104388) (xy 433.277772 -33.130998) (xy 433.279296 -33.141666) (xy 433.290726 -33.159446)
			(xy 433.37099 -33.212786) (xy 433.391564 -33.216596) (xy 433.402232 -33.214056) (xy 433.428865 -33.207931)
			(xy 433.483112 -33.201307) (xy 433.510436 -33.200848) (xy 433.53776 -33.201304) (xy 433.592009 -33.207925)
			(xy 433.61864 -33.214056) (xy 433.629308 -33.216596) (xy 433.649882 -33.212786) (xy 433.730146 -33.159446)
			(xy 433.741576 -33.141666) (xy 433.7431 -33.130998) (xy 433.747766 -33.104395) (xy 433.763597 -33.052758)
			(xy 433.78655 -33.003869) (xy 433.816166 -32.958704) (xy 433.851855 -32.918166) (xy 433.892902 -32.883065)
			(xy 433.938489 -32.854101) (xy 433.987703 -32.831854) (xy 434.039563 -32.816768) (xy 434.093031 -32.809144)
			(xy 434.120036 -32.808672) (xy 434.147408 -32.809099) (xy 434.201589 -32.816924) (xy 434.254093 -32.832421)
			(xy 434.30384 -32.855272) (xy 434.349804 -32.885006) (xy 434.370734 -32.902652) (xy 434.377846 -32.908748)
			(xy 434.394864 -32.915098) (xy 434.480208 -32.915098) (xy 434.497226 -32.908748) (xy 434.504338 -32.902652)
			(xy 434.525289 -32.885037) (xy 434.571256 -32.855319) (xy 434.620999 -32.832478) (xy 434.673495 -32.816982)
			(xy 434.727668 -32.809148) (xy 434.755036 -32.808672) (xy 434.772148 -32.808866) (xy 434.806235 -32.811917)
			(xy 434.823108 -32.814768) (xy 434.834374 -32.81616) (xy 434.856256 -32.810234) (xy 434.865272 -32.803338)
			(xy 434.889656 -32.782256) (xy 434.898042 -32.774328) (xy 434.907167 -32.753157) (xy 434.907182 -32.741616)
			(xy 434.906928 -32.722312) (xy 434.906928 -31.858712) (xy 434.907182 -31.838646) (xy 434.907027 -31.827135)
			(xy 434.897915 -31.806027) (xy 434.889656 -31.798006) (xy 434.865272 -31.776924) (xy 434.856287 -31.769968)
			(xy 434.834379 -31.764043) (xy 434.823108 -31.765494) (xy 434.806237 -31.768364) (xy 434.772149 -31.771417)
			(xy 434.755036 -31.77159) (xy 434.727666 -31.771105) (xy 434.673488 -31.763292) (xy 434.620985 -31.747808)
			(xy 434.571238 -31.72497) (xy 434.52527 -31.695249) (xy 434.504338 -31.67761) (xy 434.497226 -31.671514)
			(xy 434.480462 -31.665164) (xy 434.394864 -31.665164) (xy 434.377846 -31.671514) (xy 434.370988 -31.677864)
			(xy 434.350021 -31.695501) (xy 434.304009 -31.725245) (xy 434.254214 -31.748096) (xy 434.20166 -31.763584)
			(xy 434.14743 -31.771389) (xy 434.120036 -31.771844) (xy 434.093057 -31.771433) (xy 434.039635 -31.763843)
			(xy 433.987818 -31.748795) (xy 433.93864 -31.726591) (xy 433.893085 -31.697674) (xy 433.852063 -31.662622)
			(xy 433.816394 -31.622135) (xy 433.786791 -31.577023) (xy 433.763845 -31.528187) (xy 433.748015 -31.476603)
			(xy 433.743354 -31.450026) (xy 433.741576 -31.439358) (xy 433.730146 -31.421832) (xy 433.649882 -31.368238)
			(xy 433.629308 -31.364682) (xy 433.618894 -31.367222) (xy 433.592192 -31.373293) (xy 433.537817 -31.379789)
			(xy 433.510436 -31.380176) (xy 433.483054 -31.379809) (xy 433.428678 -31.373309) (xy 433.401978 -31.367222)
			(xy 433.391564 -31.364682) (xy 433.37099 -31.368238) (xy 433.290726 -31.421832) (xy 433.279296 -31.439358)
			(xy 433.277518 -31.450026) (xy 433.272876 -31.476602) (xy 433.257018 -31.528168) (xy 433.234052 -31.576986)
			(xy 433.204437 -31.62208) (xy 433.168764 -31.662552) (xy 433.127744 -31.697594) (xy 433.082195 -31.726506)
			(xy 433.033028 -31.748712) (xy 432.981221 -31.763768) (xy 432.927811 -31.771375) (xy 432.900836 -31.771844)
			(xy 432.873584 -31.771311) (xy 432.819634 -31.763559) (xy 432.767337 -31.748208) (xy 432.717757 -31.725569)
			(xy 432.671904 -31.696105) (xy 432.630711 -31.660415) (xy 432.595016 -31.619225) (xy 432.565548 -31.573375)
			(xy 432.542905 -31.523797) (xy 432.527549 -31.471501) (xy 432.519791 -31.417552) (xy 432.519791 -31.363048)
			(xy 432.527549 -31.309099) (xy 432.542905 -31.256803) (xy 432.565548 -31.207225) (xy 432.595016 -31.161375)
			(xy 432.630711 -31.120185) (xy 432.671904 -31.084495) (xy 432.717757 -31.055031) (xy 432.767337 -31.032392)
			(xy 432.819634 -31.017041) (xy 432.873584 -31.009289) (xy 432.900836 -31.008828) (xy 432.917948 -31.009023)
			(xy 432.952035 -31.012073) (xy 432.968908 -31.014924) (xy 432.980174 -31.016326) (xy 433.002058 -31.010395)
			(xy 433.011072 -31.003494) (xy 433.035456 -30.982412) (xy 433.043815 -30.97446) (xy 433.052955 -30.953307)
			(xy 433.052982 -30.941772) (xy 433.052728 -30.922468) (xy 433.052728 -30.058868) (xy 433.052982 -30.038802)
			(xy 433.052795 -30.027294) (xy 433.043705 -30.006186) (xy 433.035456 -29.998162) (xy 433.011072 -29.97708)
			(xy 433.00209 -29.97012) (xy 432.98018 -29.9642) (xy 432.968908 -29.96565) (xy 432.952037 -29.968521)
			(xy 432.917949 -29.971573) (xy 432.900836 -29.971746) (xy 432.873584 -29.971209) (xy 432.819635 -29.963457)
			(xy 432.767338 -29.948106) (xy 432.717758 -29.925468) (xy 432.671905 -29.896004) (xy 432.630712 -29.860313)
			(xy 432.595018 -29.819124) (xy 432.56555 -29.773274) (xy 432.542907 -29.723696) (xy 432.52755 -29.6714)
			(xy 432.519793 -29.617452) (xy 432.519793 -29.562948) (xy 432.52755 -29.509) (xy 432.542907 -29.456704)
			(xy 432.56555 -29.407126) (xy 432.595018 -29.361276) (xy 432.630712 -29.320087) (xy 432.671905 -29.284396)
			(xy 432.717758 -29.254932) (xy 432.767338 -29.232294) (xy 432.819635 -29.216943) (xy 432.873584 -29.209191)
			(xy 432.900836 -29.20873) (xy 432.927844 -29.20918) (xy 432.98132 -29.21679) (xy 433.033189 -29.231868)
			(xy 433.082412 -29.254111) (xy 433.128005 -29.283075) (xy 433.169056 -29.318181) (xy 433.204746 -29.358726)
			(xy 433.234359 -29.4039) (xy 433.257304 -29.4528) (xy 433.273122 -29.504448) (xy 433.277772 -29.531056)
			(xy 433.279296 -29.541724) (xy 433.290726 -29.559504) (xy 433.37099 -29.612844) (xy 433.391564 -29.616654)
			(xy 433.402232 -29.614114) (xy 433.42887 -29.608048) (xy 433.483119 -29.601557) (xy 433.510436 -29.60116)
			(xy 433.537754 -29.601552) (xy 433.592002 -29.608043) (xy 433.61864 -29.614114) (xy 433.629308 -29.616654)
			(xy 433.649882 -29.612844) (xy 433.730146 -29.559504) (xy 433.741576 -29.541724) (xy 433.7431 -29.531056)
			(xy 433.74781 -29.504461) (xy 433.763633 -29.452825) (xy 433.786579 -29.403935) (xy 433.81619 -29.358769)
			(xy 433.851873 -29.31823) (xy 433.892916 -29.283127) (xy 433.938499 -29.254162) (xy 433.98771 -29.231914)
			(xy 434.039567 -29.216827) (xy 434.093033 -29.209203) (xy 434.120036 -29.20873) (xy 434.147407 -29.209168)
			(xy 434.201588 -29.216991) (xy 434.254092 -29.232487) (xy 434.303838 -29.255335) (xy 434.349803 -29.285066)
			(xy 434.370734 -29.30271) (xy 434.377846 -29.308806) (xy 434.394864 -29.315156) (xy 434.480208 -29.315156)
			(xy 434.497226 -29.308806) (xy 434.504338 -29.30271) (xy 434.525284 -29.285088) (xy 434.571253 -29.255373)
			(xy 434.620997 -29.232534) (xy 434.673494 -29.217039) (xy 434.727668 -29.209206) (xy 434.755036 -29.20873)
			(xy 434.772148 -29.208925) (xy 434.806235 -29.211975) (xy 434.823108 -29.214826) (xy 434.834374 -29.216228)
			(xy 434.856258 -29.210297) (xy 434.865272 -29.203396) (xy 434.889656 -29.182314) (xy 434.898014 -29.174362)
			(xy 434.907155 -29.153209) (xy 434.907182 -29.141674) (xy 434.906928 -29.12237) (xy 434.906928 -28.25877)
			(xy 434.907182 -28.238704) (xy 434.906994 -28.227196) (xy 434.897905 -28.206088) (xy 434.889656 -28.198064)
			(xy 434.865272 -28.176982) (xy 434.85629 -28.170022) (xy 434.83438 -28.164102) (xy 434.823108 -28.165552)
			(xy 434.806237 -28.168423) (xy 434.772149 -28.171475) (xy 434.755036 -28.171648) (xy 434.727784 -28.171107)
			(xy 434.673835 -28.163355) (xy 434.621538 -28.148004) (xy 434.571959 -28.125366) (xy 434.526106 -28.095902)
			(xy 434.484914 -28.060212) (xy 434.44922 -28.019023) (xy 434.419751 -27.973173) (xy 434.397109 -27.923595)
			(xy 434.381752 -27.8713) (xy 434.373995 -27.817352) (xy 434.373995 -27.762848) (xy 434.381752 -27.7089)
			(xy 434.397109 -27.656605) (xy 434.419751 -27.607027) (xy 434.44922 -27.561177) (xy 434.484914 -27.519988)
			(xy 434.526106 -27.484298) (xy 434.571959 -27.454834) (xy 434.621538 -27.432196) (xy 434.673835 -27.416845)
			(xy 434.727784 -27.409093) (xy 434.755036 -27.408632) (xy 434.782044 -27.40908) (xy 434.83552 -27.416691)
			(xy 434.887389 -27.431768) (xy 434.936612 -27.454011) (xy 434.982205 -27.482976) (xy 435.023257 -27.518082)
			(xy 435.058946 -27.558627) (xy 435.088559 -27.603802) (xy 435.111504 -27.652702) (xy 435.127322 -27.70435)
			(xy 435.131972 -27.730958) (xy 435.133496 -27.741626) (xy 435.144926 -27.759406) (xy 435.22519 -27.812746)
			(xy 435.245764 -27.816556) (xy 435.256432 -27.814016) (xy 435.283065 -27.807891) (xy 435.337312 -27.801267)
			(xy 435.364636 -27.800808) (xy 435.386814 -27.801104) (xy 435.43096 -27.805429) (xy 435.452774 -27.809444)
			(xy 435.463188 -27.811476) (xy 435.483 -27.807412) (xy 435.559962 -27.754072) (xy 435.570884 -27.737054)
			(xy 435.572662 -27.72664) (xy 435.577551 -27.7003) (xy 435.593767 -27.64924) (xy 435.616968 -27.600952)
			(xy 435.646697 -27.556384) (xy 435.682368 -27.516414) (xy 435.723282 -27.481829) (xy 435.768632 -27.453308)
			(xy 435.817526 -27.431412) (xy 435.869003 -27.416574) (xy 435.922049 -27.409083) (xy 435.948836 -27.408632)
			(xy 435.976088 -27.40904) (xy 436.030038 -27.416802) (xy 436.082334 -27.432162) (xy 436.131912 -27.454807)
			(xy 436.177762 -27.484278) (xy 436.218953 -27.519973) (xy 436.254644 -27.561166) (xy 436.28411 -27.60702)
			(xy 436.306751 -27.6566) (xy 436.322106 -27.708897) (xy 436.329862 -27.762848) (xy 436.329862 -27.817352)
			(xy 436.322106 -27.871303) (xy 436.306751 -27.9236) (xy 436.28411 -27.97318) (xy 436.254644 -28.019034)
			(xy 436.218953 -28.060227) (xy 436.177762 -28.095922) (xy 436.131912 -28.125393) (xy 436.082334 -28.148038)
			(xy 436.030038 -28.163398) (xy 435.976088 -28.17116) (xy 435.948836 -28.171648) (xy 435.937314 -28.171557)
			(xy 435.914311 -28.170157) (xy 435.902862 -28.168854) (xy 435.891948 -28.168126) (xy 435.871152 -28.17483)
			(xy 435.86273 -28.181808) (xy 435.838854 -28.203398) (xy 435.830998 -28.211248) (xy 435.822313 -28.231664)
			(xy 435.82209 -28.242768) (xy 435.822344 -28.25877) (xy 435.822344 -29.137356) (xy 435.822477 -29.148441)
			(xy 435.831041 -29.168861) (xy 435.838854 -29.176726) (xy 435.86273 -29.198316) (xy 435.871142 -29.205311)
			(xy 435.891946 -29.212015) (xy 435.902862 -29.21127) (xy 435.91431 -29.209956) (xy 435.937313 -29.20856)
			(xy 435.948836 -29.208476) (xy 435.976084 -29.208997) (xy 436.030026 -29.216757) (xy 436.082314 -29.232115)
			(xy 436.131885 -29.254757) (xy 436.177729 -29.284223) (xy 436.218913 -29.319913) (xy 436.254599 -29.3611)
			(xy 436.28406 -29.406947) (xy 436.306698 -29.45652) (xy 436.322051 -29.508809) (xy 436.329806 -29.562752)
			(xy 436.329806 -29.617248) (xy 436.322051 -29.671191) (xy 436.306698 -29.72348) (xy 436.28406 -29.773053)
			(xy 436.254599 -29.8189) (xy 436.218913 -29.860087) (xy 436.177729 -29.895777) (xy 436.131885 -29.925243)
			(xy 436.082314 -29.947885) (xy 436.030026 -29.963243) (xy 435.976084 -29.971003) (xy 435.948836 -29.971492)
			(xy 435.92209 -29.970989) (xy 435.869123 -29.963501) (xy 435.817721 -29.948693) (xy 435.768888 -29.926856)
			(xy 435.72358 -29.898417) (xy 435.682686 -29.863933) (xy 435.647004 -29.824079) (xy 435.617234 -29.779635)
			(xy 435.593959 -29.731471) (xy 435.577633 -29.68053) (xy 435.572662 -29.654246) (xy 435.570884 -29.643832)
			(xy 435.560216 -29.626814) (xy 435.483 -29.573728) (xy 435.463188 -29.569664) (xy 435.453028 -29.571696)
			(xy 435.431155 -29.575749) (xy 435.386879 -29.580071) (xy 435.364636 -29.580332) (xy 435.337248 -29.579886)
			(xy 435.282872 -29.573266) (xy 435.256178 -29.567124) (xy 435.245764 -29.564584) (xy 435.22519 -29.56814)
			(xy 435.144926 -29.621734) (xy 435.133496 -29.63926) (xy 435.131718 -29.649928) (xy 435.127077 -29.676504)
			(xy 435.111219 -29.728071) (xy 435.088253 -29.776888) (xy 435.058638 -29.821982) (xy 435.022964 -29.862454)
			(xy 434.981944 -29.897496) (xy 434.936396 -29.926408) (xy 434.887228 -29.948614) (xy 434.835422 -29.96367)
			(xy 434.782011 -29.971277) (xy 434.755036 -29.971746) (xy 434.727666 -29.971272) (xy 434.673487 -29.963458)
			(xy 434.620983 -29.947972) (xy 434.571236 -29.925131) (xy 434.525269 -29.895407) (xy 434.504338 -29.877766)
			(xy 434.497226 -29.87167) (xy 434.480208 -29.86532) (xy 434.394864 -29.86532) (xy 434.377846 -29.87167)
			(xy 434.370734 -29.877766) (xy 434.349796 -29.895397) (xy 434.303825 -29.925111) (xy 434.254079 -29.947949)
			(xy 434.20158 -29.963442) (xy 434.147405 -29.971272) (xy 434.120036 -29.971746) (xy 434.102924 -29.971555)
			(xy 434.068837 -29.968503) (xy 434.051964 -29.96565) (xy 434.040699 -29.964236) (xy 434.018814 -29.970176)
			(xy 434.0098 -29.97708) (xy 433.985416 -29.998162) (xy 433.977017 -30.006078) (xy 433.9679 -30.027259)
			(xy 433.96789 -30.038802) (xy 433.968144 -30.058868) (xy 433.968144 -30.922468) (xy 433.96789 -30.941772)
			(xy 433.968043 -30.953283) (xy 433.977158 -30.97439) (xy 433.985416 -30.982412) (xy 434.0098 -31.003494)
			(xy 434.018794 -31.010436) (xy 434.040694 -31.016368) (xy 434.051964 -31.014924) (xy 434.068835 -31.012057)
			(xy 434.102924 -31.009002) (xy 434.120036 -31.008828) (xy 434.147407 -31.009266) (xy 434.201588 -31.01709)
			(xy 434.254092 -31.032585) (xy 434.303838 -31.055433) (xy 434.349803 -31.085164) (xy 434.370734 -31.102808)
			(xy 434.377846 -31.108904) (xy 434.39461 -31.115254) (xy 434.480208 -31.115254) (xy 434.497226 -31.108904)
			(xy 434.504084 -31.102554) (xy 434.525026 -31.084886) (xy 434.571045 -31.055146) (xy 434.620846 -31.032301)
			(xy 434.673406 -31.01682) (xy 434.72764 -31.009024) (xy 434.755036 -31.008574) (xy 434.782045 -31.008987)
			(xy 434.835525 -31.016598) (xy 434.887396 -31.031678) (xy 434.936622 -31.053924) (xy 434.982216 -31.082892)
			(xy 435.023269 -31.118002) (xy 435.058957 -31.158553) (xy 435.088569 -31.203732) (xy 435.111511 -31.252637)
			(xy 435.127324 -31.304289) (xy 435.131972 -31.3309) (xy 435.133496 -31.341568) (xy 435.144926 -31.359348)
			(xy 435.22519 -31.412688) (xy 435.245764 -31.416498) (xy 435.256432 -31.413958) (xy 435.283071 -31.407893)
			(xy 435.337319 -31.401401) (xy 435.364636 -31.401004) (xy 435.386809 -31.401227) (xy 435.430955 -31.405429)
			(xy 435.452774 -31.409386) (xy 435.463188 -31.411418) (xy 435.483 -31.407354) (xy 435.559962 -31.354014)
			(xy 435.570884 -31.336996) (xy 435.572662 -31.326582) (xy 435.577507 -31.300233) (xy 435.593731 -31.249173)
			(xy 435.616938 -31.200885) (xy 435.646673 -31.156319) (xy 435.68235 -31.11635) (xy 435.723268 -31.081766)
			(xy 435.768622 -31.053247) (xy 435.817519 -31.031353) (xy 435.868999 -31.016515) (xy 435.922048 -31.009024)
			(xy 435.948836 -31.008574) (xy 435.976084 -31.009099) (xy 436.030025 -31.016859) (xy 436.082313 -31.032216)
			(xy 436.131884 -31.054859) (xy 436.177727 -31.084324) (xy 436.218911 -31.120014) (xy 436.254597 -31.161202)
			(xy 436.284059 -31.207048) (xy 436.306696 -31.25662) (xy 436.322049 -31.30891) (xy 436.329804 -31.362852)
			(xy 436.329804 -31.417348) (xy 436.322049 -31.47129) (xy 436.306696 -31.52358) (xy 436.284059 -31.573152)
			(xy 436.254597 -31.618998) (xy 436.218911 -31.660186) (xy 436.177727 -31.695876) (xy 436.131884 -31.725341)
			(xy 436.082313 -31.747984) (xy 436.030025 -31.763341) (xy 435.976084 -31.771101) (xy 435.948836 -31.77159)
			(xy 435.937314 -31.771497) (xy 435.914311 -31.770097) (xy 435.902862 -31.768796) (xy 435.891948 -31.768058)
			(xy 435.871151 -31.774768) (xy 435.86273 -31.78175) (xy 435.838854 -31.80334) (xy 435.831025 -31.811213)
			(xy 435.822325 -31.831611) (xy 435.82209 -31.84271) (xy 435.822344 -31.858712) (xy 435.822344 -32.722312)
			(xy 435.82209 -32.737552) (xy 435.822275 -32.748664) (xy 435.830971 -32.769088) (xy 435.838854 -32.776922)
			(xy 435.86273 -32.798512) (xy 435.871142 -32.805506) (xy 435.891946 -32.812211) (xy 435.902862 -32.811466)
			(xy 435.91431 -32.810152) (xy 435.937313 -32.808756) (xy 435.948836 -32.808672) (xy 435.976084 -32.809201)
			(xy 436.030025 -32.816961) (xy 436.082313 -32.832318) (xy 436.131883 -32.85496) (xy 436.177726 -32.884426)
			(xy 436.21891 -32.920116) (xy 436.254596 -32.961303) (xy 436.284057 -33.007149) (xy 436.306694 -33.056721)
			(xy 436.322047 -33.10901) (xy 436.329802 -33.162952) (xy 436.329802 -33.217448) (xy 436.322047 -33.27139)
			(xy 436.306694 -33.323679) (xy 436.284057 -33.373251) (xy 436.254596 -33.419097) (xy 436.21891 -33.460284)
			(xy 436.177726 -33.495974) (xy 436.131883 -33.52544) (xy 436.082313 -33.548082) (xy 436.030025 -33.563439)
			(xy 435.976084 -33.571199) (xy 435.948836 -33.571688) (xy 435.922069 -33.571284) (xy 435.869059 -33.563818)
			(xy 435.817614 -33.549012) (xy 435.768744 -33.527159) (xy 435.72341 -33.498687) (xy 435.682503 -33.464156)
			(xy 435.646826 -33.424244) (xy 435.61708 -33.379736) (xy 435.593849 -33.331506) (xy 435.577591 -33.280501)
			(xy 435.572662 -33.254188) (xy 435.570884 -33.243774) (xy 435.560216 -33.226756) (xy 435.483 -33.17367)
			(xy 435.463188 -33.169606) (xy 435.453028 -33.171638) (xy 435.431149 -33.175623) (xy 435.386874 -33.179819)
			(xy 435.364636 -33.18002) (xy 435.337254 -33.179654) (xy 435.282878 -33.173153) (xy 435.256178 -33.167066)
			(xy 435.245764 -33.164526) (xy 435.22519 -33.168082) (xy 435.144926 -33.221676) (xy 435.133496 -33.239202)
			(xy 435.131718 -33.24987) (xy 435.127033 -33.276438) (xy 435.111183 -33.328004) (xy 435.088224 -33.376822)
			(xy 435.058615 -33.421918) (xy 435.022946 -33.462391) (xy 434.98193 -33.497434) (xy 434.936386 -33.526347)
			(xy 434.887221 -33.548554) (xy 434.835418 -33.563612) (xy 434.78201 -33.571219) (xy 434.755036 -33.571688)
			(xy 434.727666 -33.571204) (xy 434.673488 -33.563391) (xy 434.620985 -33.547906) (xy 434.571238 -33.525068)
			(xy 434.52527 -33.495348) (xy 434.504338 -33.477708) (xy 434.497226 -33.471612) (xy 434.480208 -33.465262)
			(xy 434.394864 -33.465262) (xy 434.377846 -33.471612) (xy 434.370734 -33.477708) (xy 434.349801 -33.495346)
			(xy 434.303828 -33.525058) (xy 434.254081 -33.547894) (xy 434.201581 -33.563385) (xy 434.147405 -33.571214)
			(xy 434.120036 -33.571688) (xy 434.102924 -33.571496) (xy 434.068837 -33.568444) (xy 434.051964 -33.565592)
			(xy 434.040699 -33.564169) (xy 434.018813 -33.570114) (xy 434.0098 -33.577022) (xy 433.985416 -33.598104)
			(xy 433.977045 -33.606045) (xy 433.967912 -33.627206) (xy 433.96789 -33.638744) (xy 433.968144 -33.65881)
			(xy 433.968144 -34.52241) (xy 433.96789 -34.541714) (xy 433.968077 -34.553222) (xy 433.977168 -34.574329)
			(xy 433.985416 -34.582354) (xy 434.0098 -34.603436) (xy 434.018798 -34.610373) (xy 434.040695 -34.616311)
			(xy 434.051964 -34.614866) (xy 434.068836 -34.611999) (xy 434.102924 -34.608945) (xy 434.120036 -34.60877)
			(xy 434.147284 -34.609303) (xy 434.201225 -34.617063) (xy 434.253512 -34.63242) (xy 434.303082 -34.655062)
			(xy 434.348925 -34.684528) (xy 434.390108 -34.720217) (xy 434.425794 -34.761404) (xy 434.455255 -34.80725)
			(xy 434.477892 -34.856822) (xy 434.493245 -34.909111) (xy 434.501 -34.963052) (xy 434.501 -34.990024)
			(xy 435.566818 -34.990024) (xy 435.570889 -34.934402) (xy 435.583015 -34.879965) (xy 435.602938 -34.827874)
			(xy 435.630234 -34.779239) (xy 435.66432 -34.735096) (xy 435.704469 -34.696387) (xy 435.749827 -34.663936)
			(xy 435.799427 -34.638435) (xy 435.852211 -34.620428) (xy 435.907054 -34.610298) (xy 435.962788 -34.608261)
			(xy 436.018225 -34.614361) (xy 436.072182 -34.628467) (xy 436.123511 -34.650279) (xy 436.171117 -34.679333)
			(xy 436.213985 -34.715008) (xy 436.251202 -34.756545) (xy 436.281975 -34.803058) (xy 436.305647 -34.853555)
			(xy 436.321715 -34.906962) (xy 436.329835 -34.962138) (xy 436.330344 -34.990024) (xy 436.329835 -35.01791)
			(xy 436.321715 -35.073086) (xy 436.305647 -35.126493) (xy 436.281975 -35.17699) (xy 436.251202 -35.223503)
			(xy 436.213985 -35.26504) (xy 436.171117 -35.300715) (xy 436.123511 -35.329769) (xy 436.072182 -35.351581)
			(xy 436.018225 -35.365687) (xy 435.962788 -35.371787) (xy 435.907054 -35.36975) (xy 435.852211 -35.35962)
			(xy 435.799427 -35.341613) (xy 435.749827 -35.316112) (xy 435.704469 -35.283661) (xy 435.66432 -35.244952)
			(xy 435.630234 -35.200809) (xy 435.602938 -35.152174) (xy 435.583015 -35.100083) (xy 435.570889 -35.045646)
			(xy 435.566818 -34.990024) (xy 434.501 -34.990024) (xy 434.501 -35.017548) (xy 434.493245 -35.071489)
			(xy 434.477892 -35.123778) (xy 434.455255 -35.17335) (xy 434.425794 -35.219196) (xy 434.390108 -35.260383)
			(xy 434.348925 -35.296072) (xy 434.303082 -35.325538) (xy 434.253512 -35.34818) (xy 434.201225 -35.363537)
			(xy 434.147284 -35.371297) (xy 434.120036 -35.371786) (xy 434.093058 -35.371339) (xy 434.03964 -35.363751)
			(xy 433.987825 -35.348705) (xy 433.93865 -35.326504) (xy 433.893096 -35.29759) (xy 433.852075 -35.262543)
			(xy 433.816405 -35.222061) (xy 433.7868 -35.176953) (xy 433.763851 -35.128122) (xy 433.748017 -35.076543)
			(xy 433.743354 -35.049968) (xy 433.741576 -35.0393) (xy 433.730146 -35.021774) (xy 433.649882 -34.96818)
			(xy 433.629308 -34.964624) (xy 433.618894 -34.967164) (xy 433.592198 -34.973295) (xy 433.537824 -34.979923)
			(xy 433.510436 -34.980372) (xy 433.483048 -34.979924) (xy 433.428672 -34.973306) (xy 433.401978 -34.967164)
			(xy 433.391564 -34.964624) (xy 433.37099 -34.96818) (xy 433.290726 -35.021774) (xy 433.279296 -35.0393)
			(xy 433.277518 -35.049968) (xy 433.272908 -35.07655) (xy 433.257044 -35.128116) (xy 433.234074 -35.176933)
			(xy 433.204454 -35.222027) (xy 433.168777 -35.262498) (xy 433.127754 -35.297538) (xy 433.082202 -35.32645)
			(xy 433.033032 -35.348655) (xy 432.981224 -35.36371) (xy 432.927812 -35.371317) (xy 432.900836 -35.371786)
			(xy 432.87358 -35.37137) (xy 432.819622 -35.363616) (xy 432.767317 -35.348262) (xy 432.717729 -35.325621)
			(xy 432.671869 -35.296152) (xy 432.630669 -35.260456) (xy 432.59497 -35.21926) (xy 432.565497 -35.173403)
			(xy 432.54285 -35.123817) (xy 432.527491 -35.071513) (xy 432.519733 -35.017556) (xy 430.874342 -35.017556)
			(xy 430.886722 -35.031373) (xy 430.917495 -35.077886) (xy 430.941167 -35.128383) (xy 430.957235 -35.18179)
			(xy 430.965355 -35.236966) (xy 430.965864 -35.264852) (xy 430.965355 -35.292738) (xy 430.957235 -35.347914)
			(xy 430.941167 -35.401321) (xy 430.917495 -35.451818) (xy 430.886722 -35.498331) (xy 430.849505 -35.539868)
			(xy 430.806637 -35.575543) (xy 430.759031 -35.604597) (xy 430.707702 -35.626409) (xy 430.653745 -35.640515)
			(xy 430.598308 -35.646615) (xy 430.542574 -35.644578) (xy 430.487731 -35.634448) (xy 430.434947 -35.616441)
			(xy 430.385347 -35.59094) (xy 430.339989 -35.558489) (xy 430.29984 -35.51978) (xy 430.265754 -35.475637)
			(xy 430.238458 -35.427002) (xy 430.218535 -35.374911) (xy 430.206409 -35.320474) (xy 430.202338 -35.264852)
			(xy 427.700948 -35.264852) (xy 427.700948 -37.087048) (xy 431.500788 -37.087048) (xy 431.501278 -37.060445)
			(xy 431.508653 -37.007754) (xy 431.523281 -36.9566) (xy 431.544877 -36.907975) (xy 431.573022 -36.862824)
			(xy 431.607169 -36.822024) (xy 431.646657 -36.786366) (xy 431.668428 -36.771072) (xy 431.67836 -36.76355)
			(xy 431.690082 -36.7416) (xy 431.69078 -36.729162) (xy 431.69078 -36.644834) (xy 431.690131 -36.63238)
			(xy 431.678407 -36.610403) (xy 431.668428 -36.602924) (xy 431.646657 -36.58763) (xy 431.607179 -36.551963)
			(xy 431.573036 -36.511159) (xy 431.544891 -36.466009) (xy 431.523288 -36.417388) (xy 431.508648 -36.366238)
			(xy 431.501252 -36.31355) (xy 431.500788 -36.286948) (xy 431.5013 -36.259697) (xy 431.50905 -36.205748)
			(xy 431.5244 -36.153451) (xy 431.547037 -36.103871) (xy 431.576499 -36.058018) (xy 431.612188 -36.016825)
			(xy 431.653376 -35.98113) (xy 431.699225 -35.951662) (xy 431.748802 -35.929018) (xy 431.801097 -35.913661)
			(xy 431.855045 -35.905904) (xy 431.882296 -35.90544) (xy 431.886868 -35.90544) (xy 431.89652 -35.905694)
			(xy 431.913284 -35.899344) (xy 431.978816 -35.843464) (xy 431.987452 -35.827462) (xy 431.988722 -35.818064)
			(xy 431.993031 -35.791127) (xy 432.008344 -35.738768) (xy 432.030958 -35.689124) (xy 432.060413 -35.643207)
			(xy 432.096108 -35.601954) (xy 432.137315 -35.566206) (xy 432.183194 -35.536693) (xy 432.232808 -35.514015)
			(xy 432.285148 -35.498635) (xy 432.339144 -35.490868) (xy 432.36642 -35.490404) (xy 432.393671 -35.490867)
			(xy 432.447618 -35.498626) (xy 432.499912 -35.513984) (xy 432.549489 -35.536627) (xy 432.595338 -35.566094)
			(xy 432.636527 -35.601787) (xy 432.672218 -35.642978) (xy 432.701683 -35.688829) (xy 432.724323 -35.738406)
			(xy 432.739678 -35.790701) (xy 432.747434 -35.844649) (xy 432.747434 -35.899151) (xy 432.739678 -35.953099)
			(xy 432.724323 -36.005394) (xy 432.701683 -36.054971) (xy 432.672218 -36.100822) (xy 432.636527 -36.142013)
			(xy 432.595338 -36.177706) (xy 432.549489 -36.207173) (xy 432.499912 -36.229816) (xy 432.447618 -36.245174)
			(xy 432.393671 -36.252933) (xy 432.36642 -36.25342) (xy 432.361848 -36.25342) (xy 432.352196 -36.253166)
			(xy 432.335432 -36.259516) (xy 432.2699 -36.315396) (xy 432.261264 -36.331398) (xy 432.259994 -36.340796)
			(xy 432.255779 -36.366996) (xy 432.241096 -36.417989) (xy 432.219486 -36.466455) (xy 432.191365 -36.511456)
			(xy 432.187935 -36.515548) (xy 433.314092 -36.515548) (xy 433.318163 -36.459926) (xy 433.330289 -36.405489)
			(xy 433.350212 -36.353398) (xy 433.377508 -36.304763) (xy 433.411594 -36.26062) (xy 433.451743 -36.221911)
			(xy 433.497101 -36.18946) (xy 433.546701 -36.163959) (xy 433.599485 -36.145952) (xy 433.654328 -36.135822)
			(xy 433.710062 -36.133785) (xy 433.765499 -36.139885) (xy 433.819456 -36.153991) (xy 433.870785 -36.175803)
			(xy 433.918391 -36.204857) (xy 433.961259 -36.240532) (xy 433.998476 -36.282069) (xy 434.029249 -36.328582)
			(xy 434.052921 -36.379079) (xy 434.068989 -36.432486) (xy 434.077109 -36.487662) (xy 434.077618 -36.515548)
			(xy 434.077109 -36.543434) (xy 434.068989 -36.59861) (xy 434.052921 -36.652017) (xy 434.029249 -36.702514)
			(xy 433.998476 -36.749027) (xy 433.961259 -36.790564) (xy 433.918391 -36.826239) (xy 433.870785 -36.855293)
			(xy 433.819456 -36.877105) (xy 433.765499 -36.891211) (xy 433.710062 -36.897311) (xy 433.654328 -36.895274)
			(xy 433.599485 -36.885144) (xy 433.546701 -36.867137) (xy 433.497101 -36.841636) (xy 433.451743 -36.809185)
			(xy 433.411594 -36.770476) (xy 433.377508 -36.726333) (xy 433.350212 -36.677698) (xy 433.330289 -36.625607)
			(xy 433.318163 -36.57117) (xy 433.314092 -36.515548) (xy 432.187935 -36.515548) (xy 432.157277 -36.552124)
			(xy 432.11788 -36.587673) (xy 432.096164 -36.602924) (xy 432.086233 -36.610446) (xy 432.074511 -36.632397)
			(xy 432.073812 -36.644834) (xy 432.073812 -36.729162) (xy 432.074467 -36.741615) (xy 432.086187 -36.763592)
			(xy 432.096164 -36.771072) (xy 432.117931 -36.786371) (xy 432.15741 -36.822037) (xy 432.191553 -36.86284)
			(xy 432.219699 -36.907989) (xy 432.241302 -36.95661) (xy 432.255943 -37.007759) (xy 432.263339 -37.060446)
			(xy 432.263804 -37.087048) (xy 432.263199 -37.118807) (xy 432.252713 -37.181453) (xy 432.231972 -37.241489)
			(xy 432.217322 -37.269674) (xy 432.211988 -37.27958) (xy 432.210464 -37.301678) (xy 432.246278 -37.394896)
			(xy 432.26228 -37.41039) (xy 432.272948 -37.4142) (xy 432.29747 -37.423296) (xy 432.344001 -37.447173)
			(xy 432.386834 -37.477184) (xy 432.425165 -37.512765) (xy 432.458274 -37.55325) (xy 432.485542 -37.59788)
			(xy 432.506456 -37.645816) (xy 432.520625 -37.69616) (xy 432.527781 -37.747968) (xy 432.528218 -37.774118)
			(xy 432.527732 -37.801369) (xy 432.519976 -37.855317) (xy 432.504621 -37.907612) (xy 432.481979 -37.957189)
			(xy 432.452513 -38.003039) (xy 432.416822 -38.04423) (xy 432.375631 -38.079921) (xy 432.329781 -38.109387)
			(xy 432.280204 -38.132029) (xy 432.227909 -38.147384) (xy 432.173961 -38.15514) (xy 432.119459 -38.15514)
			(xy 432.065511 -38.147384) (xy 432.013216 -38.132029) (xy 431.963639 -38.109387) (xy 431.917789 -38.079921)
			(xy 431.876598 -38.04423) (xy 431.840907 -38.003039) (xy 431.811441 -37.957189) (xy 431.788799 -37.907612)
			(xy 431.773444 -37.855317) (xy 431.765688 -37.801369) (xy 431.765202 -37.774118) (xy 431.765793 -37.742358)
			(xy 431.776285 -37.679712) (xy 431.797031 -37.619676) (xy 431.811684 -37.591492) (xy 431.817018 -37.581586)
			(xy 431.818542 -37.559488) (xy 431.782728 -37.46627) (xy 431.766726 -37.450776) (xy 431.756058 -37.446966)
			(xy 431.731526 -37.437896) (xy 431.684993 -37.414017) (xy 431.642159 -37.384003) (xy 431.603828 -37.348419)
			(xy 431.570719 -37.30793) (xy 431.543453 -37.263297) (xy 431.522541 -37.215358) (xy 431.508375 -37.16501)
			(xy 431.501222 -37.113199) (xy 431.500788 -37.087048) (xy 427.700948 -37.087048) (xy 427.700948 -38.315138)
			(xy 432.717954 -38.315138) (xy 432.722025 -38.259516) (xy 432.734151 -38.205079) (xy 432.754074 -38.152988)
			(xy 432.78137 -38.104353) (xy 432.815456 -38.06021) (xy 432.855605 -38.021501) (xy 432.900963 -37.98905)
			(xy 432.950563 -37.963549) (xy 433.003347 -37.945542) (xy 433.05819 -37.935412) (xy 433.113924 -37.933375)
			(xy 433.169361 -37.939475) (xy 433.223318 -37.953581) (xy 433.274647 -37.975393) (xy 433.322253 -38.004447)
			(xy 433.365121 -38.040122) (xy 433.402338 -38.081659) (xy 433.433111 -38.128172) (xy 433.456783 -38.178669)
			(xy 433.472851 -38.232076) (xy 433.480971 -38.287252) (xy 433.48148 -38.315138) (xy 433.480971 -38.343024)
			(xy 433.472851 -38.3982) (xy 433.456783 -38.451607) (xy 433.433111 -38.502104) (xy 433.402338 -38.548617)
			(xy 433.365121 -38.590154) (xy 433.322253 -38.625829) (xy 433.274647 -38.654883) (xy 433.223318 -38.676695)
			(xy 433.169361 -38.690801) (xy 433.113924 -38.696901) (xy 433.05819 -38.694864) (xy 433.003347 -38.684734)
			(xy 432.950563 -38.666727) (xy 432.900963 -38.641226) (xy 432.855605 -38.608775) (xy 432.815456 -38.570066)
			(xy 432.78137 -38.525923) (xy 432.754074 -38.477288) (xy 432.734151 -38.425197) (xy 432.722025 -38.37076)
			(xy 432.717954 -38.315138) (xy 427.700948 -38.315138) (xy 427.700948 -42.4307) (xy 427.701239 -42.438368)
			(xy 427.705884 -42.452986) (xy 427.710092 -42.459402) (xy 427.710092 -42.459656) (xy 427.71494 -42.466073)
			(xy 427.727746 -42.475784) (xy 427.735238 -42.478706) (xy 427.735746 -42.47896) (xy 427.760729 -42.487766)
			(xy 427.808182 -42.511308) (xy 427.851921 -42.541188) (xy 427.891107 -42.576832) (xy 427.924984 -42.617554)
			(xy 427.952903 -42.662571) (xy 427.974325 -42.711018) (xy 427.988839 -42.761962) (xy 427.996165 -42.814424)
			(xy 427.996604 -42.84091) (xy 427.996063 -42.87028) (xy 427.987063 -42.928328) (xy 427.969276 -42.984311)
			(xy 427.943122 -43.036908) (xy 427.909219 -43.084878) (xy 427.889162 -43.10634) (xy 427.8884 -43.107102)
			(xy 427.887892 -43.10761) (xy 427.866821 -43.129145) (xy 427.819124 -43.165949) (xy 427.766229 -43.194787)
			(xy 427.738032 -43.2054) (xy 427.735238 -43.206416) (xy 427.729142 -43.209464) (xy 427.720903 -43.214046)
			(xy 427.708204 -43.227957) (xy 427.701383 -43.245513) (xy 427.700948 -43.25493) (xy 427.700948 -43.4467)
			(xy 427.701239 -43.454368) (xy 427.705884 -43.468986) (xy 427.710092 -43.475402) (xy 427.710092 -43.475656)
			(xy 427.71494 -43.482073) (xy 427.727746 -43.491784) (xy 427.735238 -43.494706) (xy 427.735746 -43.49496)
			(xy 427.760729 -43.503766) (xy 427.808182 -43.527308) (xy 427.851921 -43.557188) (xy 427.891107 -43.592832)
			(xy 427.924984 -43.633554) (xy 427.952903 -43.678571) (xy 427.974325 -43.727018) (xy 427.988839 -43.777962)
			(xy 427.996165 -43.830424) (xy 427.996604 -43.85691) (xy 427.996063 -43.88628) (xy 427.987063 -43.944328)
			(xy 427.969276 -44.000311) (xy 427.943122 -44.052908) (xy 427.909219 -44.100878) (xy 427.889162 -44.12234)
			(xy 427.8884 -44.123102) (xy 427.887892 -44.12361) (xy 427.866821 -44.145145) (xy 427.819124 -44.181949)
			(xy 427.766229 -44.210787) (xy 427.738032 -44.2214) (xy 427.735238 -44.222416) (xy 427.729142 -44.225464)
			(xy 427.720903 -44.230046) (xy 427.708204 -44.243957) (xy 427.701383 -44.261513) (xy 427.700948 -44.27093)
			(xy 427.700948 -44.4627) (xy 427.701239 -44.470368) (xy 427.705884 -44.484986) (xy 427.710092 -44.491402)
			(xy 427.710092 -44.491656) (xy 427.71494 -44.498073) (xy 427.727746 -44.507784) (xy 427.735238 -44.510706)
			(xy 427.735746 -44.51096) (xy 427.760729 -44.519766) (xy 427.808182 -44.543308) (xy 427.851921 -44.573188)
			(xy 427.891107 -44.608832) (xy 427.924984 -44.649554) (xy 427.952903 -44.694571) (xy 427.974325 -44.743018)
			(xy 427.988839 -44.793962) (xy 427.996165 -44.846424) (xy 427.996604 -44.87291) (xy 427.996063 -44.90228)
			(xy 427.987063 -44.960328) (xy 427.969276 -45.016311) (xy 427.943122 -45.068908) (xy 427.909219 -45.116878)
			(xy 427.889162 -45.13834) (xy 427.8884 -45.139102) (xy 427.887892 -45.13961) (xy 427.866821 -45.161145)
			(xy 427.819124 -45.197949) (xy 427.766229 -45.226787) (xy 427.738032 -45.2374) (xy 427.735238 -45.238416)
			(xy 427.729142 -45.241464) (xy 427.720903 -45.246046) (xy 427.708204 -45.259957) (xy 427.701383 -45.277513)
			(xy 427.700948 -45.28693) (xy 427.700948 -45.4787) (xy 427.701239 -45.486368) (xy 427.705884 -45.500986)
			(xy 427.710092 -45.507402) (xy 427.710092 -45.507656) (xy 427.71494 -45.514073) (xy 427.727746 -45.523784)
			(xy 427.735238 -45.526706) (xy 427.735746 -45.52696) (xy 427.760729 -45.535766) (xy 427.808182 -45.559308)
			(xy 427.851921 -45.589188) (xy 427.891107 -45.624832) (xy 427.924984 -45.665554) (xy 427.952903 -45.710571)
			(xy 427.974325 -45.759018) (xy 427.988839 -45.809962) (xy 427.996165 -45.862424) (xy 427.996604 -45.88891)
			(xy 427.996063 -45.91828) (xy 427.987063 -45.976328) (xy 427.969276 -46.032311) (xy 427.943122 -46.084908)
			(xy 427.909219 -46.132878) (xy 427.889162 -46.15434) (xy 427.8884 -46.155102) (xy 427.887892 -46.15561)
			(xy 427.866821 -46.177145) (xy 427.819124 -46.213949) (xy 427.766229 -46.242787) (xy 427.738032 -46.2534)
			(xy 427.735238 -46.254416) (xy 427.729142 -46.257464) (xy 427.720903 -46.262046) (xy 427.708204 -46.275957)
			(xy 427.701383 -46.293513) (xy 427.700948 -46.30293) (xy 427.700948 -47.040546) (xy 427.72203 -47.067724)
			(xy 427.739048 -47.072296) (xy 427.766004 -47.07973) (xy 427.817544 -47.10141) (xy 427.865364 -47.130389)
			(xy 427.908436 -47.166044) (xy 427.945835 -47.20761) (xy 427.97676 -47.254195) (xy 428.000545 -47.304799)
			(xy 428.016681 -47.358335) (xy 428.02482 -47.413654) (xy 428.025306 -47.441612) (xy 428.025227 -47.45435)
			(xy 428.023573 -47.479771) (xy 428.022004 -47.492412) (xy 428.02175 -47.494952) (xy 428.01697 -47.524514)
			(xy 427.999411 -47.581761) (xy 427.973126 -47.635564) (xy 427.93876 -47.684601) (xy 427.918372 -47.706534)
			(xy 427.917864 -47.707042) (xy 427.916086 -47.709074) (xy 427.89781 -47.727724) (xy 427.857046 -47.760357)
			(xy 427.81221 -47.787122) (xy 427.764142 -47.807518) (xy 427.739048 -47.814738) (xy 427.73854 -47.814992)
			(xy 427.73727 -47.8155) (xy 427.726975 -47.819074) (xy 427.710525 -47.833333) (xy 427.701466 -47.85313)
			(xy 427.700948 -47.864014) (xy 427.700948 -48.5267) (xy 427.701239 -48.534368) (xy 427.705884 -48.548986)
			(xy 427.710092 -48.555402) (xy 427.710092 -48.555656) (xy 427.71494 -48.562073) (xy 427.727746 -48.571784)
			(xy 427.735238 -48.574706) (xy 427.735746 -48.57496) (xy 427.760729 -48.583766) (xy 427.808182 -48.607308)
			(xy 427.851921 -48.637188) (xy 427.891107 -48.672832) (xy 427.924984 -48.713554) (xy 427.952903 -48.758571)
			(xy 427.974325 -48.807018) (xy 427.988839 -48.857962) (xy 427.996165 -48.910424) (xy 427.996604 -48.93691)
			(xy 427.996063 -48.96628) (xy 427.987063 -49.024328) (xy 427.969276 -49.080311) (xy 427.943122 -49.132908)
			(xy 427.909219 -49.180878) (xy 427.889162 -49.20234) (xy 427.8884 -49.203102) (xy 427.887892 -49.20361)
			(xy 427.866821 -49.225145) (xy 427.819124 -49.261949) (xy 427.766229 -49.290787) (xy 427.738032 -49.3014)
			(xy 427.735238 -49.302416) (xy 427.729142 -49.305464) (xy 427.720903 -49.310046) (xy 427.708204 -49.323957)
			(xy 427.701383 -49.341513) (xy 427.700948 -49.35093) (xy 427.700948 -49.53381) (xy 427.701208 -49.541454)
			(xy 427.705736 -49.556056) (xy 427.709838 -49.562512) (xy 427.72838 -49.589944) (xy 427.740318 -49.599088)
			(xy 427.747232 -49.601949) (xy 428.590982 -49.601949) (xy 428.590982 -49.547451) (xy 428.598737 -49.493507)
			(xy 428.61409 -49.441215) (xy 428.636729 -49.391641) (xy 428.666191 -49.345793) (xy 428.701878 -49.304604)
			(xy 428.743064 -49.268913) (xy 428.788909 -49.239446) (xy 428.838482 -49.216803) (xy 428.890771 -49.201445)
			(xy 428.944715 -49.193684) (xy 428.971964 -49.193196) (xy 428.999333 -49.193684) (xy 429.053512 -49.201497)
			(xy 429.106014 -49.216981) (xy 429.155762 -49.239818) (xy 429.201729 -49.269537) (xy 429.222662 -49.287176)
			(xy 429.229774 -49.293272) (xy 429.246792 -49.299622) (xy 429.332136 -49.299622) (xy 429.349154 -49.293272)
			(xy 429.356266 -49.287176) (xy 429.377199 -49.269535) (xy 429.423167 -49.239811) (xy 429.472913 -49.216965)
			(xy 429.525415 -49.201469) (xy 429.579593 -49.19364) (xy 429.634335 -49.19364) (xy 429.688513 -49.201469)
			(xy 429.741015 -49.216965) (xy 429.790761 -49.239811) (xy 429.836729 -49.269535) (xy 429.857662 -49.287176)
			(xy 429.864774 -49.293272) (xy 429.881792 -49.299622) (xy 429.967136 -49.299622) (xy 429.984154 -49.293272)
			(xy 429.991266 -49.287176) (xy 430.012197 -49.269536) (xy 430.05817 -49.239825) (xy 430.107918 -49.21699)
			(xy 430.160419 -49.201499) (xy 430.214595 -49.19367) (xy 430.241964 -49.193196) (xy 430.268281 -49.193628)
			(xy 430.320416 -49.200853) (xy 430.371064 -49.21517) (xy 430.419266 -49.236308) (xy 430.464107 -49.263867)
			(xy 430.504738 -49.297324) (xy 430.522888 -49.316386) (xy 430.530414 -49.323782) (xy 430.549691 -49.33231)
			(xy 430.560226 -49.332896) (xy 430.634902 -49.332896) (xy 430.645454 -49.332382) (xy 430.664749 -49.323836)
			(xy 430.67224 -49.316386) (xy 430.690352 -49.297285) (xy 430.730978 -49.263809) (xy 430.775823 -49.236242)
			(xy 430.824035 -49.215107) (xy 430.874696 -49.200807) (xy 430.926843 -49.193614) (xy 430.953164 -49.193196)
			(xy 430.980419 -49.193649) (xy 431.034374 -49.201402) (xy 431.086677 -49.216755) (xy 431.136262 -49.239396)
			(xy 431.18212 -49.268863) (xy 431.223318 -49.304557) (xy 431.259016 -49.345751) (xy 431.288487 -49.391606)
			(xy 431.311133 -49.441189) (xy 431.326491 -49.493491) (xy 431.334249 -49.547445) (xy 431.334249 -49.601955)
			(xy 431.326491 -49.655909) (xy 431.311133 -49.708211) (xy 431.288487 -49.757794) (xy 431.259016 -49.803649)
			(xy 431.223318 -49.844843) (xy 431.18212 -49.880537) (xy 431.136262 -49.910004) (xy 431.086677 -49.932645)
			(xy 431.034374 -49.947998) (xy 430.980419 -49.955751) (xy 430.953164 -49.956212) (xy 430.926848 -49.955759)
			(xy 430.874714 -49.948538) (xy 430.824066 -49.934225) (xy 430.775864 -49.91309) (xy 430.731022 -49.885535)
			(xy 430.69039 -49.852082) (xy 430.67224 -49.833022) (xy 430.664703 -49.825639) (xy 430.645435 -49.817103)
			(xy 430.634902 -49.816512) (xy 430.560226 -49.816512) (xy 430.549676 -49.817038) (xy 430.53038 -49.825575)
			(xy 430.522888 -49.833022) (xy 430.504744 -49.852092) (xy 430.464127 -49.885574) (xy 430.419289 -49.913148)
			(xy 430.371083 -49.934288) (xy 430.320427 -49.948594) (xy 430.268283 -49.955792) (xy 430.241964 -49.956212)
			(xy 430.214593 -49.955764) (xy 430.160413 -49.947941) (xy 430.10791 -49.932448) (xy 430.058164 -49.909602)
			(xy 430.012197 -49.879875) (xy 429.991266 -49.862232) (xy 429.984154 -49.856136) (xy 429.967136 -49.849786)
			(xy 429.881792 -49.849786) (xy 429.864774 -49.856136) (xy 429.857662 -49.862232) (xy 429.836729 -49.879873)
			(xy 429.790761 -49.909597) (xy 429.741015 -49.932443) (xy 429.688513 -49.947939) (xy 429.634335 -49.955768)
			(xy 429.579593 -49.955768) (xy 429.525415 -49.947939) (xy 429.472913 -49.932443) (xy 429.423167 -49.909597)
			(xy 429.377199 -49.879873) (xy 429.356266 -49.862232) (xy 429.349154 -49.856136) (xy 429.332136 -49.849786)
			(xy 429.246792 -49.849786) (xy 429.229774 -49.856136) (xy 429.222662 -49.862232) (xy 429.201721 -49.87986)
			(xy 429.15575 -49.909573) (xy 429.106005 -49.93241) (xy 429.053506 -49.947904) (xy 428.999333 -49.955736)
			(xy 428.971964 -49.956212) (xy 428.944715 -49.955716) (xy 428.890771 -49.947955) (xy 428.838482 -49.932597)
			(xy 428.788909 -49.909954) (xy 428.743064 -49.880487) (xy 428.701878 -49.844796) (xy 428.666191 -49.803607)
			(xy 428.636729 -49.757759) (xy 428.61409 -49.708185) (xy 428.598737 -49.655893) (xy 428.590982 -49.601949)
			(xy 427.747232 -49.601949) (xy 427.747684 -49.602136) (xy 427.77298 -49.612402) (xy 427.820584 -49.639122)
			(xy 427.863894 -49.672355) (xy 427.902023 -49.711423) (xy 427.934194 -49.755527) (xy 427.95975 -49.803767)
			(xy 427.978167 -49.855157) (xy 427.989071 -49.908648) (xy 427.992238 -49.963147) (xy 427.987603 -50.017541)
			(xy 427.975262 -50.070718) (xy 427.955467 -50.121593) (xy 427.928621 -50.169127) (xy 427.895273 -50.212349)
			(xy 427.856105 -50.250375) (xy 427.811916 -50.282429) (xy 427.763608 -50.307856) (xy 427.738032 -50.3174)
			(xy 427.735238 -50.318416) (xy 427.729142 -50.321464) (xy 427.720903 -50.326046) (xy 427.708204 -50.339957)
			(xy 427.701383 -50.357513) (xy 427.700948 -50.36693) (xy 427.700948 -50.62347) (xy 427.720506 -50.65014)
			(xy 427.736762 -50.65522) (xy 427.762304 -50.663668) (xy 427.810904 -50.68674) (xy 427.855779 -50.716412)
			(xy 427.896041 -50.752094) (xy 427.930891 -50.793078) (xy 427.959636 -50.838553) (xy 427.981708 -50.887615)
			(xy 427.996667 -50.939291) (xy 428.004218 -50.992557) (xy 428.004732 -51.019456) (xy 428.004178 -51.048682)
			(xy 427.995271 -51.106451) (xy 427.97766 -51.162186) (xy 427.951755 -51.214584) (xy 427.918163 -51.262419)
			(xy 427.898306 -51.28387) (xy 427.897544 -51.284632) (xy 427.897036 -51.28514) (xy 427.874579 -51.308175)
			(xy 427.823385 -51.347126) (xy 427.76639 -51.37695) (xy 427.736 -51.387502) (xy 427.72838 -51.390042)
			(xy 427.715426 -51.399186) (xy 427.710854 -51.40579) (xy 427.706295 -51.41243) (xy 427.701237 -51.427713)
			(xy 427.700948 -51.435762) (xy 427.700948 -51.63947) (xy 427.720506 -51.66614) (xy 427.736762 -51.67122)
			(xy 427.762304 -51.679668) (xy 427.782069 -51.689051) (xy 428.555377 -51.689051) (xy 428.555377 -51.634549)
			(xy 428.563134 -51.5806) (xy 428.578489 -51.528305) (xy 428.601131 -51.478728) (xy 428.630597 -51.432877)
			(xy 428.666289 -51.391687) (xy 428.70748 -51.355995) (xy 428.753331 -51.326529) (xy 428.802909 -51.303888)
			(xy 428.855204 -51.288533) (xy 428.909153 -51.280777) (xy 428.936404 -51.280314) (xy 428.963774 -51.280774)
			(xy 429.017954 -51.288593) (xy 429.070457 -51.304083) (xy 429.120204 -51.326926) (xy 429.166171 -51.356652)
			(xy 429.187102 -51.374294) (xy 429.194214 -51.38039) (xy 429.211232 -51.38674) (xy 429.296576 -51.38674)
			(xy 429.313594 -51.38039) (xy 429.320706 -51.374294) (xy 429.341624 -51.356638) (xy 429.387601 -51.326929)
			(xy 429.437352 -51.304096) (xy 429.489856 -51.288609) (xy 429.544034 -51.280786) (xy 429.571404 -51.280314)
			(xy 429.589747 -51.280542) (xy 429.62626 -51.284108) (xy 429.644302 -51.287426) (xy 429.655224 -51.289458)
			(xy 429.675798 -51.284632) (xy 429.753776 -51.225704) (xy 429.76419 -51.206908) (xy 429.764952 -51.195986)
			(xy 429.767841 -51.167701) (xy 429.780879 -51.112364) (xy 429.801976 -51.05957) (xy 429.830666 -51.010487)
			(xy 429.866316 -50.966199) (xy 429.886872 -50.946558) (xy 429.89429 -50.93905) (xy 429.902806 -50.91976)
			(xy 429.903382 -50.90922) (xy 429.903382 -50.834544) (xy 429.902848 -50.823995) (xy 429.894317 -50.804699)
			(xy 429.886872 -50.797206) (xy 429.867809 -50.779054) (xy 429.834327 -50.738439) (xy 429.806753 -50.693603)
			(xy 429.785611 -50.645398) (xy 429.771303 -50.594743) (xy 429.764103 -50.542601) (xy 429.763682 -50.516282)
			(xy 429.764168 -50.489031) (xy 429.771924 -50.435083) (xy 429.787279 -50.382788) (xy 429.809921 -50.333211)
			(xy 429.839387 -50.287361) (xy 429.875078 -50.24617) (xy 429.916269 -50.210479) (xy 429.962119 -50.181013)
			(xy 430.011696 -50.158371) (xy 430.063991 -50.143016) (xy 430.117939 -50.13526) (xy 430.172441 -50.13526)
			(xy 430.226389 -50.143016) (xy 430.278684 -50.158371) (xy 430.328261 -50.181013) (xy 430.374111 -50.210479)
			(xy 430.415302 -50.24617) (xy 430.450993 -50.287361) (xy 430.480459 -50.333211) (xy 430.503101 -50.382788)
			(xy 430.518456 -50.435083) (xy 430.526212 -50.489031) (xy 430.526698 -50.516282) (xy 430.52628 -50.542599)
			(xy 430.519053 -50.594735) (xy 430.504733 -50.645384) (xy 430.483592 -50.693585) (xy 430.45603 -50.738427)
			(xy 430.422571 -50.779057) (xy 430.403508 -50.797206) (xy 430.396103 -50.804725) (xy 430.38758 -50.824007)
			(xy 430.386998 -50.834544) (xy 430.386998 -50.90922) (xy 430.387558 -50.919766) (xy 430.396072 -50.939062)
			(xy 430.403508 -50.946558) (xy 430.422569 -50.964712) (xy 430.456048 -51.005328) (xy 430.483621 -51.050165)
			(xy 430.504762 -51.098368) (xy 430.519071 -51.149023) (xy 430.526274 -51.201164) (xy 430.526698 -51.227482)
			(xy 430.526228 -51.254735) (xy 430.518473 -51.308686) (xy 430.503119 -51.360984) (xy 430.480478 -51.410565)
			(xy 430.451011 -51.456419) (xy 430.415318 -51.497612) (xy 430.374125 -51.533306) (xy 430.328272 -51.562774)
			(xy 430.278692 -51.585416) (xy 430.226394 -51.600771) (xy 430.172443 -51.608527) (xy 430.14519 -51.60899)
			(xy 430.126847 -51.608763) (xy 430.090334 -51.605196) (xy 430.072292 -51.601878) (xy 430.06137 -51.599846)
			(xy 430.040796 -51.604672) (xy 429.962818 -51.6636) (xy 429.952404 -51.682396) (xy 429.951642 -51.693318)
			(xy 429.94876 -51.721578) (xy 429.935727 -51.776864) (xy 429.914641 -51.829608) (xy 429.885968 -51.878642)
			(xy 429.850343 -51.922883) (xy 429.808552 -51.961354) (xy 429.761519 -51.993204) (xy 429.710284 -52.017728)
			(xy 429.655979 -52.034386) (xy 429.599805 -52.042808) (xy 429.571404 -52.04333) (xy 429.544033 -52.042879)
			(xy 429.489853 -52.03506) (xy 429.437349 -52.019568) (xy 429.387602 -51.996723) (xy 429.341636 -51.966994)
			(xy 429.320706 -51.94935) (xy 429.313594 -51.943254) (xy 429.296576 -51.936904) (xy 429.211232 -51.936904)
			(xy 429.194214 -51.943254) (xy 429.187102 -51.94935) (xy 429.166174 -51.966994) (xy 429.120201 -51.996707)
			(xy 429.070452 -52.019543) (xy 429.01795 -52.035032) (xy 428.963774 -52.042858) (xy 428.936404 -52.04333)
			(xy 428.909153 -52.042823) (xy 428.855204 -52.035067) (xy 428.802909 -52.019712) (xy 428.753331 -51.997071)
			(xy 428.70748 -51.967605) (xy 428.666289 -51.931913) (xy 428.630597 -51.890723) (xy 428.601131 -51.844872)
			(xy 428.578489 -51.795295) (xy 428.563134 -51.743) (xy 428.555377 -51.689051) (xy 427.782069 -51.689051)
			(xy 427.810904 -51.70274) (xy 427.855779 -51.732412) (xy 427.896041 -51.768094) (xy 427.930891 -51.809078)
			(xy 427.959636 -51.854553) (xy 427.981708 -51.903615) (xy 427.996667 -51.955291) (xy 428.004218 -52.008557)
			(xy 428.004732 -52.035456) (xy 428.004178 -52.064682) (xy 427.995271 -52.122451) (xy 427.97766 -52.178186)
			(xy 427.951755 -52.230584) (xy 427.918163 -52.278419) (xy 427.898306 -52.29987) (xy 427.897544 -52.300632)
			(xy 427.897036 -52.30114) (xy 427.874579 -52.324175) (xy 427.823385 -52.363126) (xy 427.76639 -52.39295)
			(xy 427.736 -52.403502) (xy 427.72838 -52.406042) (xy 427.715426 -52.415186) (xy 427.710854 -52.42179)
			(xy 427.706295 -52.42843) (xy 427.701237 -52.443713) (xy 427.700948 -52.451762) (xy 427.700948 -52.564153)
			(xy 430.12713 -52.564153) (xy 430.12713 -52.509647) (xy 430.134886 -52.455697) (xy 430.150241 -52.403399)
			(xy 430.172882 -52.353818) (xy 430.202348 -52.307964) (xy 430.238039 -52.26677) (xy 430.279229 -52.231074)
			(xy 430.32508 -52.201603) (xy 430.374658 -52.178956) (xy 430.426954 -52.163595) (xy 430.480903 -52.155833)
			(xy 430.508156 -52.155344) (xy 430.535526 -52.155825) (xy 430.589705 -52.163638) (xy 430.642208 -52.179123)
			(xy 430.691955 -52.201961) (xy 430.737922 -52.231684) (xy 430.758854 -52.249324) (xy 430.765966 -52.25542)
			(xy 430.782984 -52.26177) (xy 430.868328 -52.26177) (xy 430.885346 -52.25542) (xy 430.892458 -52.249324)
			(xy 430.913398 -52.231695) (xy 430.959368 -52.201981) (xy 431.009114 -52.179142) (xy 431.061613 -52.163649)
			(xy 431.115787 -52.155819) (xy 431.143156 -52.155344) (xy 431.170407 -52.1559) (xy 431.224356 -52.163651)
			(xy 431.276653 -52.179001) (xy 431.326232 -52.201639) (xy 431.372085 -52.231102) (xy 431.413278 -52.266791)
			(xy 431.448972 -52.307979) (xy 431.47844 -52.353829) (xy 431.501083 -52.403406) (xy 431.51644 -52.455701)
			(xy 431.524197 -52.509649) (xy 431.524197 -52.564151) (xy 431.51644 -52.618099) (xy 431.501083 -52.670394)
			(xy 431.47844 -52.719971) (xy 431.448972 -52.765821) (xy 431.413278 -52.807009) (xy 431.372085 -52.842698)
			(xy 431.326232 -52.872161) (xy 431.276653 -52.894799) (xy 431.224356 -52.910149) (xy 431.170407 -52.9179)
			(xy 431.143156 -52.91836) (xy 431.115786 -52.917871) (xy 431.061608 -52.91006) (xy 431.009105 -52.894577)
			(xy 430.959357 -52.87174) (xy 430.91339 -52.84202) (xy 430.892458 -52.82438) (xy 430.885346 -52.818284)
			(xy 430.868328 -52.811934) (xy 430.782984 -52.811934) (xy 430.765966 -52.818284) (xy 430.758854 -52.82438)
			(xy 430.73791 -52.842004) (xy 430.691941 -52.871719) (xy 430.642196 -52.894558) (xy 430.589698 -52.910053)
			(xy 430.535524 -52.917884) (xy 430.508156 -52.91836) (xy 430.480903 -52.917967) (xy 430.426954 -52.910205)
			(xy 430.374658 -52.894844) (xy 430.32508 -52.872197) (xy 430.279229 -52.842726) (xy 430.238039 -52.80703)
			(xy 430.202348 -52.765836) (xy 430.172882 -52.719982) (xy 430.150241 -52.670401) (xy 430.134886 -52.618103)
			(xy 430.12713 -52.564153) (xy 427.700948 -52.564153) (xy 427.700948 -52.65547) (xy 427.720506 -52.68214)
			(xy 427.736762 -52.68722) (xy 427.762304 -52.695668) (xy 427.810904 -52.71874) (xy 427.855779 -52.748412)
			(xy 427.896041 -52.784094) (xy 427.930891 -52.825078) (xy 427.959636 -52.870553) (xy 427.981708 -52.919615)
			(xy 427.996667 -52.971291) (xy 428.004218 -53.024557) (xy 428.004732 -53.051456) (xy 428.004178 -53.080682)
			(xy 427.995271 -53.138451) (xy 427.97766 -53.194186) (xy 427.951755 -53.246584) (xy 427.918163 -53.294419)
			(xy 427.898306 -53.31587) (xy 427.897544 -53.316632) (xy 427.897036 -53.31714) (xy 427.874579 -53.340175)
			(xy 427.823385 -53.379126) (xy 427.76639 -53.40895) (xy 427.736 -53.419502) (xy 427.72838 -53.422042)
			(xy 427.715426 -53.431186) (xy 427.710854 -53.43779) (xy 427.706295 -53.44443) (xy 427.701237 -53.459713)
			(xy 427.700948 -53.467762) (xy 427.700948 -53.67147) (xy 427.720506 -53.69814) (xy 427.736762 -53.70322)
			(xy 427.762304 -53.711668) (xy 427.810904 -53.73474) (xy 427.855779 -53.764412) (xy 427.896041 -53.800094)
			(xy 427.930891 -53.841078) (xy 427.959636 -53.886553) (xy 427.981708 -53.935615) (xy 427.996667 -53.987291)
			(xy 428.004218 -54.040557) (xy 428.004732 -54.067456) (xy 428.004178 -54.096682) (xy 427.995271 -54.154451)
			(xy 427.97766 -54.210186) (xy 427.963461 -54.238906) (xy 434.685946 -54.238906) (xy 434.690017 -54.183284)
			(xy 434.702143 -54.128847) (xy 434.722066 -54.076756) (xy 434.749362 -54.028121) (xy 434.783448 -53.983978)
			(xy 434.823597 -53.945269) (xy 434.868955 -53.912818) (xy 434.918555 -53.887317) (xy 434.971339 -53.86931)
			(xy 435.026182 -53.85918) (xy 435.081916 -53.857143) (xy 435.137353 -53.863243) (xy 435.19131 -53.877349)
			(xy 435.242639 -53.899161) (xy 435.290245 -53.928215) (xy 435.333113 -53.96389) (xy 435.37033 -54.005427)
			(xy 435.401103 -54.05194) (xy 435.424775 -54.102437) (xy 435.440843 -54.155844) (xy 435.448963 -54.21102)
			(xy 435.449472 -54.238906) (xy 435.448963 -54.266792) (xy 435.440843 -54.321968) (xy 435.424775 -54.375375)
			(xy 435.401103 -54.425872) (xy 435.37033 -54.472385) (xy 435.333113 -54.513922) (xy 435.290245 -54.549597)
			(xy 435.242639 -54.578651) (xy 435.19131 -54.600463) (xy 435.137353 -54.614569) (xy 435.081916 -54.620669)
			(xy 435.026182 -54.618632) (xy 434.971339 -54.608502) (xy 434.918555 -54.590495) (xy 434.868955 -54.564994)
			(xy 434.823597 -54.532543) (xy 434.783448 -54.493834) (xy 434.749362 -54.449691) (xy 434.722066 -54.401056)
			(xy 434.702143 -54.348965) (xy 434.690017 -54.294528) (xy 434.685946 -54.238906) (xy 427.963461 -54.238906)
			(xy 427.951755 -54.262584) (xy 427.918163 -54.310419) (xy 427.898306 -54.33187) (xy 427.897544 -54.332632)
			(xy 427.897036 -54.33314) (xy 427.874579 -54.356175) (xy 427.823385 -54.395126) (xy 427.76639 -54.42495)
			(xy 427.736 -54.435502) (xy 427.72838 -54.438042) (xy 427.715426 -54.447186) (xy 427.710854 -54.45379)
			(xy 427.706295 -54.46043) (xy 427.701237 -54.475713) (xy 427.700948 -54.483762) (xy 427.700948 -54.68747)
			(xy 427.720506 -54.71414) (xy 427.736762 -54.71922) (xy 427.762304 -54.727668) (xy 427.810904 -54.75074)
			(xy 427.855779 -54.780412) (xy 427.896041 -54.816094) (xy 427.930891 -54.857078) (xy 427.959636 -54.902553)
			(xy 427.981708 -54.951615) (xy 427.992545 -54.989051) (xy 430.201068 -54.989051) (xy 430.201068 -54.934549)
			(xy 430.208824 -54.880603) (xy 430.224178 -54.828309) (xy 430.246817 -54.778733) (xy 430.276281 -54.732882)
			(xy 430.311971 -54.691692) (xy 430.353158 -54.655999) (xy 430.399006 -54.626532) (xy 430.448581 -54.603888)
			(xy 430.500874 -54.58853) (xy 430.554819 -54.58077) (xy 430.58207 -54.580282) (xy 430.610161 -54.580801)
			(xy 430.665737 -54.589023) (xy 430.719505 -54.60531) (xy 430.770303 -54.629309) (xy 430.81703 -54.6605)
			(xy 430.858675 -54.698209) (xy 430.894339 -54.741619) (xy 430.909222 -54.765448) (xy 430.914556 -54.774592)
			(xy 430.931574 -54.786784) (xy 431.024792 -54.80685) (xy 431.045366 -54.802786) (xy 431.054002 -54.79669)
			(xy 431.078063 -54.780686) (xy 431.129996 -54.755344) (xy 431.185154 -54.73812) (xy 431.242279 -54.729406)
			(xy 431.271172 -54.728872) (xy 431.298423 -54.729381) (xy 431.352371 -54.737134) (xy 431.404667 -54.752485)
			(xy 431.454246 -54.775123) (xy 431.500098 -54.804586) (xy 431.541291 -54.840275) (xy 431.576985 -54.881463)
			(xy 431.606454 -54.927312) (xy 431.629098 -54.976888) (xy 431.644456 -55.029182) (xy 431.652215 -55.083129)
			(xy 431.65268 -55.11038) (xy 431.652207 -55.13775) (xy 431.644392 -55.191929) (xy 431.628904 -55.244432)
			(xy 431.606064 -55.294179) (xy 431.576341 -55.340146) (xy 431.5587 -55.361078) (xy 431.552604 -55.36819)
			(xy 431.546254 -55.385208) (xy 431.546254 -55.470552) (xy 431.552604 -55.48757) (xy 431.5587 -55.494682)
			(xy 431.57632 -55.515631) (xy 431.606044 -55.561597) (xy 431.628888 -55.61134) (xy 431.644385 -55.66384)
			(xy 431.652215 -55.718016) (xy 431.652217 -55.772754) (xy 431.644392 -55.826931) (xy 431.628899 -55.879431)
			(xy 431.606058 -55.929177) (xy 431.576338 -55.975145) (xy 431.5587 -55.996078) (xy 431.552604 -56.00319)
			(xy 431.546254 -56.020208) (xy 431.546254 -56.105552) (xy 431.552604 -56.12257) (xy 431.5587 -56.129682)
			(xy 431.576344 -56.15061) (xy 431.606055 -56.196584) (xy 431.62889 -56.246332) (xy 431.64438 -56.298834)
			(xy 431.652207 -56.353011) (xy 431.65268 -56.38038) (xy 431.652194 -56.407631) (xy 431.644438 -56.461579)
			(xy 431.629083 -56.513874) (xy 431.606441 -56.563451) (xy 431.576975 -56.609301) (xy 431.541284 -56.650492)
			(xy 431.500093 -56.686183) (xy 431.454243 -56.715649) (xy 431.404666 -56.738291) (xy 431.352371 -56.753646)
			(xy 431.298423 -56.761402) (xy 431.243921 -56.761402) (xy 431.189973 -56.753646) (xy 431.137678 -56.738291)
			(xy 431.088101 -56.715649) (xy 431.042251 -56.686183) (xy 431.00106 -56.650492) (xy 430.965369 -56.609301)
			(xy 430.935903 -56.563451) (xy 430.913261 -56.513874) (xy 430.897906 -56.461579) (xy 430.89015 -56.407631)
			(xy 430.889664 -56.38038) (xy 430.890103 -56.353009) (xy 430.897925 -56.298828) (xy 430.913419 -56.246324)
			(xy 430.936268 -56.196577) (xy 430.965999 -56.150612) (xy 430.983644 -56.129682) (xy 430.98974 -56.12257)
			(xy 430.99609 -56.105552) (xy 430.99609 -56.020208) (xy 430.98974 -56.00319) (xy 430.983644 -55.996078)
			(xy 430.965983 -55.975161) (xy 430.936258 -55.929191) (xy 430.913412 -55.879442) (xy 430.897917 -55.826938)
			(xy 430.89009 -55.772757) (xy 430.890092 -55.718013) (xy 430.897923 -55.663833) (xy 430.913423 -55.611329)
			(xy 430.936272 -55.561582) (xy 430.966001 -55.515614) (xy 430.983644 -55.494682) (xy 430.98974 -55.48757)
			(xy 430.99609 -55.470552) (xy 430.99609 -55.385208) (xy 430.98974 -55.36819) (xy 430.983644 -55.361078)
			(xy 430.972694 -55.348281) (xy 430.952853 -55.321062) (xy 430.94402 -55.306722) (xy 430.938686 -55.297578)
			(xy 430.921668 -55.285386) (xy 430.82845 -55.26532) (xy 430.807876 -55.269384) (xy 430.79924 -55.27548)
			(xy 430.775165 -55.291463) (xy 430.723238 -55.31681) (xy 430.668083 -55.334041) (xy 430.610962 -55.342761)
			(xy 430.58207 -55.343298) (xy 430.554819 -55.34283) (xy 430.500874 -55.33507) (xy 430.448581 -55.319712)
			(xy 430.399006 -55.297068) (xy 430.353158 -55.267601) (xy 430.311971 -55.231908) (xy 430.276281 -55.190718)
			(xy 430.246817 -55.144867) (xy 430.224178 -55.095291) (xy 430.208824 -55.042997) (xy 430.201068 -54.989051)
			(xy 427.992545 -54.989051) (xy 427.996667 -55.003291) (xy 428.004218 -55.056557) (xy 428.004732 -55.083456)
			(xy 428.004178 -55.112682) (xy 427.995271 -55.170451) (xy 427.97766 -55.226186) (xy 427.951755 -55.278584)
			(xy 427.918163 -55.326419) (xy 427.898306 -55.34787) (xy 427.897544 -55.348632) (xy 427.897036 -55.34914)
			(xy 427.874579 -55.372175) (xy 427.823385 -55.411126) (xy 427.8048 -55.420851) (xy 428.524668 -55.420851)
			(xy 428.524668 -55.366349) (xy 428.532424 -55.312403) (xy 428.547778 -55.260109) (xy 428.570417 -55.210533)
			(xy 428.599881 -55.164682) (xy 428.635571 -55.123492) (xy 428.676758 -55.087799) (xy 428.722606 -55.058332)
			(xy 428.772181 -55.035688) (xy 428.824474 -55.02033) (xy 428.878419 -55.01257) (xy 428.90567 -55.012082)
			(xy 428.931987 -55.012514) (xy 428.984121 -55.01974) (xy 429.03477 -55.034057) (xy 429.082971 -55.055195)
			(xy 429.127813 -55.082754) (xy 429.168444 -55.116211) (xy 429.186594 -55.135272) (xy 429.19412 -55.142669)
			(xy 429.213396 -55.151197) (xy 429.223932 -55.151782) (xy 429.298608 -55.151782) (xy 429.30916 -55.151276)
			(xy 429.328456 -55.142725) (xy 429.335946 -55.135272) (xy 429.354072 -55.116184) (xy 429.394693 -55.082704)
			(xy 429.439535 -55.055133) (xy 429.487744 -55.033995) (xy 429.538404 -55.019694) (xy 429.59055 -55.0125)
			(xy 429.61687 -55.012082) (xy 429.644124 -55.012563) (xy 429.698076 -55.020317) (xy 429.750376 -55.03567)
			(xy 429.799959 -55.05831) (xy 429.845815 -55.087776) (xy 429.88701 -55.123469) (xy 429.922706 -55.164661)
			(xy 429.952176 -55.210515) (xy 429.97482 -55.260095) (xy 429.990177 -55.312394) (xy 429.997935 -55.366347)
			(xy 429.997935 -55.420854) (xy 429.990177 -55.474806) (xy 429.97482 -55.527105) (xy 429.952176 -55.576685)
			(xy 429.922706 -55.622539) (xy 429.88701 -55.663731) (xy 429.845815 -55.699424) (xy 429.799959 -55.72889)
			(xy 429.750376 -55.75153) (xy 429.698076 -55.766883) (xy 429.644124 -55.774637) (xy 429.61687 -55.775098)
			(xy 429.590554 -55.774645) (xy 429.53842 -55.767425) (xy 429.487772 -55.753112) (xy 429.43957 -55.731978)
			(xy 429.394728 -55.704422) (xy 429.354096 -55.670968) (xy 429.335946 -55.651908) (xy 429.328445 -55.644482)
			(xy 429.309149 -55.635971) (xy 429.298608 -55.635398) (xy 429.223932 -55.635398) (xy 429.213383 -55.635932)
			(xy 429.194087 -55.644464) (xy 429.186594 -55.651908) (xy 429.168464 -55.670992) (xy 429.127842 -55.704469)
			(xy 429.083001 -55.732039) (xy 429.034792 -55.753177) (xy 428.984134 -55.76748) (xy 428.93199 -55.774678)
			(xy 428.90567 -55.775098) (xy 428.878419 -55.77463) (xy 428.824474 -55.76687) (xy 428.772181 -55.751512)
			(xy 428.722606 -55.728868) (xy 428.676758 -55.699401) (xy 428.635571 -55.663708) (xy 428.599881 -55.622518)
			(xy 428.570417 -55.576667) (xy 428.547778 -55.527091) (xy 428.532424 -55.474797) (xy 428.524668 -55.420851)
			(xy 427.8048 -55.420851) (xy 427.76639 -55.44095) (xy 427.736 -55.451502) (xy 427.72838 -55.454042)
			(xy 427.715426 -55.463186) (xy 427.710854 -55.46979) (xy 427.706295 -55.47643) (xy 427.701237 -55.491713)
			(xy 427.700948 -55.499762) (xy 427.700948 -55.95747) (xy 427.720506 -55.98414) (xy 427.736762 -55.98922)
			(xy 427.762304 -55.997668) (xy 427.810904 -56.02074) (xy 427.855779 -56.050412) (xy 427.896041 -56.086094)
			(xy 427.930891 -56.127078) (xy 427.959636 -56.172553) (xy 427.981708 -56.221615) (xy 427.996667 -56.273291)
			(xy 428.004218 -56.326557) (xy 428.004732 -56.353456) (xy 428.004178 -56.382682) (xy 427.995271 -56.440451)
			(xy 427.97766 -56.496186) (xy 427.951755 -56.548584) (xy 427.918163 -56.596419) (xy 427.898306 -56.61787)
			(xy 427.897544 -56.618632) (xy 427.897036 -56.61914) (xy 427.874579 -56.642175) (xy 427.823385 -56.681126)
			(xy 427.76639 -56.71095) (xy 427.736 -56.721502) (xy 427.72838 -56.724042) (xy 427.715426 -56.733186)
			(xy 427.710854 -56.73979) (xy 427.706295 -56.74643) (xy 427.701237 -56.761713) (xy 427.700948 -56.769762)
			(xy 427.700948 -57.48528) (xy 430.905918 -57.48528) (xy 430.909989 -57.429658) (xy 430.922115 -57.375221)
			(xy 430.942038 -57.32313) (xy 430.969334 -57.274495) (xy 431.00342 -57.230352) (xy 431.043569 -57.191643)
			(xy 431.088927 -57.159192) (xy 431.138527 -57.133691) (xy 431.191311 -57.115684) (xy 431.246154 -57.105554)
			(xy 431.301888 -57.103517) (xy 431.357325 -57.109617) (xy 431.411282 -57.123723) (xy 431.462611 -57.145535)
			(xy 431.510217 -57.174589) (xy 431.553085 -57.210264) (xy 431.590302 -57.251801) (xy 431.621075 -57.298314)
			(xy 431.644747 -57.348811) (xy 431.660815 -57.402218) (xy 431.668935 -57.457394) (xy 431.669444 -57.48528)
			(xy 431.668935 -57.513166) (xy 431.660815 -57.568342) (xy 431.644747 -57.621749) (xy 431.621075 -57.672246)
			(xy 431.590302 -57.718759) (xy 431.553085 -57.760296) (xy 431.510217 -57.795971) (xy 431.462611 -57.825025)
			(xy 431.411282 -57.846837) (xy 431.357325 -57.860943) (xy 431.301888 -57.867043) (xy 431.246154 -57.865006)
			(xy 431.191311 -57.854876) (xy 431.138527 -57.836869) (xy 431.088927 -57.811368) (xy 431.043569 -57.778917)
			(xy 431.00342 -57.740208) (xy 430.969334 -57.696065) (xy 430.942038 -57.64743) (xy 430.922115 -57.595339)
			(xy 430.909989 -57.540902) (xy 430.905918 -57.48528) (xy 427.700948 -57.48528) (xy 427.700948 -58.076084)
			(xy 431.658012 -58.076084) (xy 431.662083 -58.020462) (xy 431.674209 -57.966025) (xy 431.694132 -57.913934)
			(xy 431.721428 -57.865299) (xy 431.755514 -57.821156) (xy 431.795663 -57.782447) (xy 431.841021 -57.749996)
			(xy 431.890621 -57.724495) (xy 431.943405 -57.706488) (xy 431.998248 -57.696358) (xy 432.053982 -57.694321)
			(xy 432.109419 -57.700421) (xy 432.163376 -57.714527) (xy 432.214705 -57.736339) (xy 432.262311 -57.765393)
			(xy 432.305179 -57.801068) (xy 432.342396 -57.842605) (xy 432.373169 -57.889118) (xy 432.396841 -57.939615)
			(xy 432.412909 -57.993022) (xy 432.421029 -58.048198) (xy 432.421538 -58.076084) (xy 432.42107 -58.101738)
			(xy 433.942996 -58.101738) (xy 433.947067 -58.046116) (xy 433.959193 -57.991679) (xy 433.979116 -57.939588)
			(xy 434.006412 -57.890953) (xy 434.040498 -57.84681) (xy 434.080647 -57.808101) (xy 434.126005 -57.77565)
			(xy 434.175605 -57.750149) (xy 434.228389 -57.732142) (xy 434.283232 -57.722012) (xy 434.338966 -57.719975)
			(xy 434.394403 -57.726075) (xy 434.44836 -57.740181) (xy 434.499689 -57.761993) (xy 434.547295 -57.791047)
			(xy 434.590163 -57.826722) (xy 434.62738 -57.868259) (xy 434.658153 -57.914772) (xy 434.681825 -57.965269)
			(xy 434.697893 -58.018676) (xy 434.706013 -58.073852) (xy 434.706522 -58.101738) (xy 434.706013 -58.129624)
			(xy 434.697893 -58.1848) (xy 434.681825 -58.238207) (xy 434.658153 -58.288704) (xy 434.62738 -58.335217)
			(xy 434.590163 -58.376754) (xy 434.547295 -58.412429) (xy 434.499689 -58.441483) (xy 434.48031 -58.449718)
			(xy 435.108856 -58.449718) (xy 435.112927 -58.394096) (xy 435.125053 -58.339659) (xy 435.144976 -58.287568)
			(xy 435.172272 -58.238933) (xy 435.206358 -58.19479) (xy 435.246507 -58.156081) (xy 435.291865 -58.12363)
			(xy 435.341465 -58.098129) (xy 435.394249 -58.080122) (xy 435.449092 -58.069992) (xy 435.504826 -58.067955)
			(xy 435.560263 -58.074055) (xy 435.61422 -58.088161) (xy 435.665549 -58.109973) (xy 435.713155 -58.139027)
			(xy 435.756023 -58.174702) (xy 435.79324 -58.216239) (xy 435.824013 -58.262752) (xy 435.847685 -58.313249)
			(xy 435.863753 -58.366656) (xy 435.871873 -58.421832) (xy 435.872382 -58.449718) (xy 435.871873 -58.477604)
			(xy 435.863753 -58.53278) (xy 435.847685 -58.586187) (xy 435.824013 -58.636684) (xy 435.79324 -58.683197)
			(xy 435.756023 -58.724734) (xy 435.713155 -58.760409) (xy 435.665549 -58.789463) (xy 435.61422 -58.811275)
			(xy 435.560263 -58.825381) (xy 435.504826 -58.831481) (xy 435.449092 -58.829444) (xy 435.394249 -58.819314)
			(xy 435.341465 -58.801307) (xy 435.291865 -58.775806) (xy 435.246507 -58.743355) (xy 435.206358 -58.704646)
			(xy 435.172272 -58.660503) (xy 435.144976 -58.611868) (xy 435.125053 -58.559777) (xy 435.112927 -58.50534)
			(xy 435.108856 -58.449718) (xy 434.48031 -58.449718) (xy 434.44836 -58.463295) (xy 434.394403 -58.477401)
			(xy 434.338966 -58.483501) (xy 434.283232 -58.481464) (xy 434.228389 -58.471334) (xy 434.175605 -58.453327)
			(xy 434.126005 -58.427826) (xy 434.080647 -58.395375) (xy 434.040498 -58.356666) (xy 434.006412 -58.312523)
			(xy 433.979116 -58.263888) (xy 433.959193 -58.211797) (xy 433.947067 -58.15736) (xy 433.942996 -58.101738)
			(xy 432.42107 -58.101738) (xy 432.421029 -58.10397) (xy 432.412909 -58.159146) (xy 432.396841 -58.212553)
			(xy 432.373169 -58.26305) (xy 432.342396 -58.309563) (xy 432.305179 -58.3511) (xy 432.262311 -58.386775)
			(xy 432.214705 -58.415829) (xy 432.163376 -58.437641) (xy 432.109419 -58.451747) (xy 432.053982 -58.457847)
			(xy 431.998248 -58.45581) (xy 431.943405 -58.44568) (xy 431.890621 -58.427673) (xy 431.841021 -58.402172)
			(xy 431.795663 -58.369721) (xy 431.755514 -58.331012) (xy 431.721428 -58.286869) (xy 431.694132 -58.238234)
			(xy 431.674209 -58.186143) (xy 431.662083 -58.131706) (xy 431.658012 -58.076084) (xy 427.700948 -58.076084)
			(xy 427.700948 -58.561224) (xy 432.862226 -58.561224) (xy 432.866297 -58.505602) (xy 432.878423 -58.451165)
			(xy 432.898346 -58.399074) (xy 432.925642 -58.350439) (xy 432.959728 -58.306296) (xy 432.999877 -58.267587)
			(xy 433.045235 -58.235136) (xy 433.094835 -58.209635) (xy 433.147619 -58.191628) (xy 433.202462 -58.181498)
			(xy 433.258196 -58.179461) (xy 433.313633 -58.185561) (xy 433.36759 -58.199667) (xy 433.418919 -58.221479)
			(xy 433.466525 -58.250533) (xy 433.509393 -58.286208) (xy 433.54661 -58.327745) (xy 433.577383 -58.374258)
			(xy 433.601055 -58.424755) (xy 433.617123 -58.478162) (xy 433.625243 -58.533338) (xy 433.625752 -58.561224)
			(xy 433.625243 -58.58911) (xy 433.617123 -58.644286) (xy 433.601055 -58.697693) (xy 433.577383 -58.74819)
			(xy 433.54661 -58.794703) (xy 433.509393 -58.83624) (xy 433.466525 -58.871915) (xy 433.418919 -58.900969)
			(xy 433.36759 -58.922781) (xy 433.313633 -58.936887) (xy 433.258196 -58.942987) (xy 433.202462 -58.94095)
			(xy 433.147619 -58.93082) (xy 433.094835 -58.912813) (xy 433.045235 -58.887312) (xy 432.999877 -58.854861)
			(xy 432.959728 -58.816152) (xy 432.925642 -58.772009) (xy 432.898346 -58.723374) (xy 432.878423 -58.671283)
			(xy 432.866297 -58.616846) (xy 432.862226 -58.561224) (xy 427.700948 -58.561224) (xy 427.700948 -59.974734)
			(xy 431.386996 -59.974734) (xy 431.387429 -59.947907) (xy 431.39495 -59.894783) (xy 431.409833 -59.843234)
			(xy 431.431786 -59.794277) (xy 431.460377 -59.748875) (xy 431.495042 -59.707923) (xy 431.535098 -59.672227)
			(xy 431.557176 -59.65698) (xy 431.568746 -59.648765) (xy 431.587158 -59.627187) (xy 431.598917 -59.601373)
			(xy 431.603114 -59.573319) (xy 431.599423 -59.545195) (xy 431.588132 -59.519173) (xy 431.570112 -59.497267)
			(xy 431.5587 -59.488832) (xy 431.537248 -59.473472) (xy 431.498335 -59.437847) (xy 431.464701 -59.3972)
			(xy 431.436989 -59.352305) (xy 431.415728 -59.304021) (xy 431.401323 -59.253267) (xy 431.394048 -59.201013)
			(xy 431.3936 -59.174634) (xy 431.394086 -59.147383) (xy 431.401842 -59.093435) (xy 431.417197 -59.04114)
			(xy 431.439839 -58.991563) (xy 431.469305 -58.945713) (xy 431.504996 -58.904522) (xy 431.546187 -58.868831)
			(xy 431.592037 -58.839365) (xy 431.641614 -58.816723) (xy 431.693909 -58.801368) (xy 431.747857 -58.793612)
			(xy 431.802359 -58.793612) (xy 431.856307 -58.801368) (xy 431.908602 -58.816723) (xy 431.958179 -58.839365)
			(xy 432.004029 -58.868831) (xy 432.04522 -58.904522) (xy 432.080911 -58.945713) (xy 432.110377 -58.991563)
			(xy 432.133019 -59.04114) (xy 432.148374 -59.093435) (xy 432.15613 -59.147383) (xy 432.156616 -59.174634)
			(xy 432.156153 -59.20146) (xy 432.148637 -59.254583) (xy 432.133759 -59.30613) (xy 432.11181 -59.355087)
			(xy 432.083224 -59.400489) (xy 432.048564 -59.441442) (xy 432.008512 -59.47714) (xy 431.986436 -59.492388)
			(xy 431.974904 -59.500648) (xy 431.956509 -59.522221) (xy 431.944759 -59.548024) (xy 431.940563 -59.576063)
			(xy 431.944244 -59.604174) (xy 431.955517 -59.630188) (xy 431.973513 -59.652096) (xy 431.984912 -59.660536)
			(xy 432.006398 -59.675849) (xy 432.04531 -59.711483) (xy 432.078941 -59.752139) (xy 432.106648 -59.797041)
			(xy 432.127904 -59.845332) (xy 432.142302 -59.896093) (xy 432.149568 -59.948353) (xy 432.150012 -59.974734)
			(xy 432.149526 -60.001985) (xy 432.14177 -60.055933) (xy 432.126415 -60.108228) (xy 432.103773 -60.157805)
			(xy 432.074307 -60.203655) (xy 432.038616 -60.244846) (xy 431.997425 -60.280537) (xy 431.951575 -60.310003)
			(xy 431.901998 -60.332645) (xy 431.849703 -60.348) (xy 431.795755 -60.355756) (xy 431.741253 -60.355756)
			(xy 431.687305 -60.348) (xy 431.63501 -60.332645) (xy 431.585433 -60.310003) (xy 431.539583 -60.280537)
			(xy 431.498392 -60.244846) (xy 431.462701 -60.203655) (xy 431.433235 -60.157805) (xy 431.410593 -60.108228)
			(xy 431.395238 -60.055933) (xy 431.387482 -60.001985) (xy 431.386996 -59.974734) (xy 427.700948 -59.974734)
			(xy 427.700948 -60.601606) (xy 430.633122 -60.601606) (xy 430.637193 -60.545984) (xy 430.649319 -60.491547)
			(xy 430.669242 -60.439456) (xy 430.696538 -60.390821) (xy 430.730624 -60.346678) (xy 430.770773 -60.307969)
			(xy 430.816131 -60.275518) (xy 430.865731 -60.250017) (xy 430.918515 -60.23201) (xy 430.973358 -60.22188)
			(xy 431.029092 -60.219843) (xy 431.084529 -60.225943) (xy 431.138486 -60.240049) (xy 431.189815 -60.261861)
			(xy 431.237421 -60.290915) (xy 431.280289 -60.32659) (xy 431.317506 -60.368127) (xy 431.348279 -60.41464)
			(xy 431.371951 -60.465137) (xy 431.388019 -60.518544) (xy 431.396139 -60.57372) (xy 431.396648 -60.601606)
			(xy 431.396184 -60.627006) (xy 433.02123 -60.627006) (xy 433.025301 -60.571384) (xy 433.037427 -60.516947)
			(xy 433.05735 -60.464856) (xy 433.084646 -60.416221) (xy 433.118732 -60.372078) (xy 433.158881 -60.333369)
			(xy 433.204239 -60.300918) (xy 433.253839 -60.275417) (xy 433.306623 -60.25741) (xy 433.361466 -60.24728)
			(xy 433.4172 -60.245243) (xy 433.472637 -60.251343) (xy 433.526594 -60.265449) (xy 433.577923 -60.287261)
			(xy 433.625529 -60.316315) (xy 433.668397 -60.35199) (xy 433.705614 -60.393527) (xy 433.736387 -60.44004)
			(xy 433.760059 -60.490537) (xy 433.776127 -60.543944) (xy 433.784247 -60.59912) (xy 433.784756 -60.627006)
			(xy 433.78464 -60.633356) (xy 435.11292 -60.633356) (xy 435.116991 -60.577734) (xy 435.129117 -60.523297)
			(xy 435.14904 -60.471206) (xy 435.176336 -60.422571) (xy 435.210422 -60.378428) (xy 435.250571 -60.339719)
			(xy 435.295929 -60.307268) (xy 435.345529 -60.281767) (xy 435.398313 -60.26376) (xy 435.453156 -60.25363)
			(xy 435.50889 -60.251593) (xy 435.564327 -60.257693) (xy 435.618284 -60.271799) (xy 435.669613 -60.293611)
			(xy 435.717219 -60.322665) (xy 435.760087 -60.35834) (xy 435.797304 -60.399877) (xy 435.828077 -60.44639)
			(xy 435.851749 -60.496887) (xy 435.867817 -60.550294) (xy 435.875937 -60.60547) (xy 435.876446 -60.633356)
			(xy 435.875937 -60.661242) (xy 435.867817 -60.716418) (xy 435.851749 -60.769825) (xy 435.828077 -60.820322)
			(xy 435.797304 -60.866835) (xy 435.760087 -60.908372) (xy 435.717219 -60.944047) (xy 435.669613 -60.973101)
			(xy 435.618284 -60.994913) (xy 435.564327 -61.009019) (xy 435.50889 -61.015119) (xy 435.453156 -61.013082)
			(xy 435.398313 -61.002952) (xy 435.345529 -60.984945) (xy 435.295929 -60.959444) (xy 435.250571 -60.926993)
			(xy 435.210422 -60.888284) (xy 435.176336 -60.844141) (xy 435.14904 -60.795506) (xy 435.129117 -60.743415)
			(xy 435.116991 -60.688978) (xy 435.11292 -60.633356) (xy 433.78464 -60.633356) (xy 433.784247 -60.654892)
			(xy 433.776127 -60.710068) (xy 433.760059 -60.763475) (xy 433.736387 -60.813972) (xy 433.705614 -60.860485)
			(xy 433.668397 -60.902022) (xy 433.625529 -60.937697) (xy 433.577923 -60.966751) (xy 433.526594 -60.988563)
			(xy 433.472637 -61.002669) (xy 433.4172 -61.008769) (xy 433.361466 -61.006732) (xy 433.306623 -60.996602)
			(xy 433.253839 -60.978595) (xy 433.204239 -60.953094) (xy 433.158881 -60.920643) (xy 433.118732 -60.881934)
			(xy 433.084646 -60.837791) (xy 433.05735 -60.789156) (xy 433.037427 -60.737065) (xy 433.025301 -60.682628)
			(xy 433.02123 -60.627006) (xy 431.396184 -60.627006) (xy 431.396139 -60.629492) (xy 431.388019 -60.684668)
			(xy 431.371951 -60.738075) (xy 431.348279 -60.788572) (xy 431.317506 -60.835085) (xy 431.280289 -60.876622)
			(xy 431.237421 -60.912297) (xy 431.189815 -60.941351) (xy 431.138486 -60.963163) (xy 431.084529 -60.977269)
			(xy 431.029092 -60.983369) (xy 430.973358 -60.981332) (xy 430.918515 -60.971202) (xy 430.865731 -60.953195)
			(xy 430.816131 -60.927694) (xy 430.770773 -60.895243) (xy 430.730624 -60.856534) (xy 430.696538 -60.812391)
			(xy 430.669242 -60.763756) (xy 430.649319 -60.711665) (xy 430.637193 -60.657228) (xy 430.633122 -60.601606)
			(xy 427.700948 -60.601606) (xy 427.700948 -61.333126) (xy 427.701377 -61.343193) (xy 427.709104 -61.361786)
			(xy 427.715934 -61.369194) (xy 427.914816 -61.568076) (xy 427.934882 -61.575696) (xy 427.945804 -61.575188)
			(xy 427.961806 -61.57468) (xy 430.485042 -61.57468) (xy 430.51984 -61.576712) (xy 430.522888 -61.576966)
			(xy 431.325782 -61.576966)
		)
		(stroke
			(width 0)
			(type solid)
		)
		(fill yes)
		(layer "In9.Cu")
		(net "P3V3_SSD15")
	)
	(gr_poly
		(pts
			(xy 315.228732 -61.576712) (xy 315.263276 -61.57468) (xy 316.397132 -61.57468) (xy 316.406276 -61.573918)
			(xy 316.410594 -61.573156) (xy 316.417906 -61.571558) (xy 316.431208 -61.564717) (xy 316.436756 -61.559694)
			(xy 316.484762 -61.51372) (xy 316.491395 -61.506753) (xy 316.499369 -61.489262) (xy 316.500256 -61.479684)
			(xy 316.500256 -61.478668) (xy 316.501762 -61.451595) (xy 316.51147 -61.39825) (xy 316.528627 -61.346816)
			(xy 316.552888 -61.298325) (xy 316.583764 -61.253754) (xy 316.601856 -61.233558) (xy 316.602364 -61.23305)
			(xy 316.603126 -61.232288) (xy 316.60465 -61.23051) (xy 316.605158 -61.230002) (xy 316.606428 -61.228478)
			(xy 316.624557 -61.209564) (xy 316.665099 -61.176379) (xy 316.709797 -61.149049) (xy 316.757812 -61.128087)
			(xy 316.808242 -61.113887) (xy 316.86014 -61.106715) (xy 316.886336 -61.106304) (xy 316.913346 -61.106775)
			(xy 316.966825 -61.114398) (xy 317.018694 -61.129487) (xy 317.067917 -61.151741) (xy 317.113509 -61.180713)
			(xy 317.15456 -61.215826) (xy 317.190249 -61.256377) (xy 317.219862 -61.301557) (xy 317.242808 -61.35046)
			(xy 317.258628 -61.402112) (xy 317.267005 -61.455477) (xy 317.267844 -61.482478) (xy 317.268098 -61.492892)
			(xy 317.275972 -61.51118) (xy 317.320168 -61.553852) (xy 317.32601 -61.55944) (xy 317.33161 -61.564534)
			(xy 317.345038 -61.571505) (xy 317.352426 -61.573156) (xy 317.361316 -61.57468) (xy 318.343026 -61.57468)
			(xy 318.352 -61.57473) (xy 318.369918 -61.575748) (xy 318.37884 -61.576712) (xy 319.242948 -61.576712)
			(xy 319.25187 -61.575745) (xy 319.269788 -61.574729) (xy 319.278762 -61.57468) (xy 320.95313 -61.57468)
			(xy 320.959424 -61.574488) (xy 320.971626 -61.571397) (xy 320.97726 -61.568584) (xy 320.983864 -61.565028)
			(xy 321.61226 -60.936632) (xy 321.615308 -60.93333) (xy 321.625722 -60.922916) (xy 321.628394 -60.917444)
			(xy 321.631346 -60.905634) (xy 321.631564 -60.899548) (xy 321.631564 -38.90645) (xy 321.630802 -38.897306)
			(xy 321.628008 -38.882574) (xy 321.619626 -38.867842) (xy 321.613022 -38.862) (xy 321.580362 -38.832691)
			(xy 321.520052 -38.768936) (xy 321.465946 -38.699838) (xy 321.418516 -38.625999) (xy 321.378173 -38.548061)
			(xy 321.34527 -38.466702) (xy 321.320093 -38.38263) (xy 321.30286 -38.296578) (xy 321.293722 -38.209295)
			(xy 321.292758 -38.12154) (xy 321.299977 -38.034077) (xy 321.315316 -37.947667) (xy 321.338642 -37.863063)
			(xy 321.36975 -37.781001) (xy 321.408372 -37.702195) (xy 321.454169 -37.627332) (xy 321.506744 -37.557063)
			(xy 321.535806 -37.524182) (xy 321.540378 -37.519102) (xy 321.540632 -37.518594) (xy 321.5523 -37.505892)
			(xy 321.576434 -37.481246) (xy 321.588892 -37.469318) (xy 321.602354 -37.457126) (xy 321.602608 -37.456872)
			(xy 321.606926 -37.452808) (xy 321.61099 -37.448998) (xy 321.617086 -37.440616) (xy 321.627246 -37.417248)
			(xy 321.62925 -37.412408) (xy 321.631429 -37.402164) (xy 321.631564 -37.396928) (xy 321.631564 -31.777432)
			(xy 321.62877 -31.769304) (xy 321.618613 -31.738539) (xy 321.607634 -31.674695) (xy 321.606926 -31.642304)
			(xy 321.607636 -31.609914) (xy 321.618621 -31.546071) (xy 321.62877 -31.515304) (xy 321.631564 -31.507176)
			(xy 321.631564 -31.238444) (xy 321.631678 -31.233489) (xy 321.633588 -31.223763) (xy 321.635374 -31.21914)
			(xy 321.640454 -31.207202) (xy 321.642254 -31.202516) (xy 321.644174 -31.192663) (xy 321.644264 -31.187644)
			(xy 321.644264 -29.841952) (xy 321.644003 -29.834013) (xy 321.639223 -29.818875) (xy 321.634866 -29.812234)
			(xy 321.618012 -29.787796) (xy 321.591269 -29.734799) (xy 321.573054 -29.678301) (xy 321.563804 -29.619664)
			(xy 321.563238 -29.589984) (xy 321.563821 -29.560304) (xy 321.573054 -29.501665) (xy 321.591264 -29.445165)
			(xy 321.618011 -29.392171) (xy 321.634866 -29.367734) (xy 321.639227 -29.361093) (xy 321.644026 -29.345957)
			(xy 321.644264 -29.338016) (xy 321.644264 -28.112974) (xy 321.644384 -28.108426) (xy 321.646039 -28.09948)
			(xy 321.647566 -28.095194) (xy 321.649332 -28.090052) (xy 321.650867 -28.07929) (xy 321.650614 -28.073858)
			(xy 321.648328 -28.044394) (xy 321.647592 -28.037202) (xy 321.642554 -28.023657) (xy 321.638422 -28.017724)
			(xy 321.620733 -27.99288) (xy 321.592643 -27.93875) (xy 321.573513 -27.880843) (xy 321.56383 -27.820632)
			(xy 321.563238 -27.79014) (xy 321.563699 -27.762886) (xy 321.571451 -27.708934) (xy 321.586804 -27.656634)
			(xy 321.609445 -27.607051) (xy 321.638913 -27.561197) (xy 321.674607 -27.520003) (xy 321.715801 -27.484309)
			(xy 321.761657 -27.454842) (xy 321.811239 -27.432202) (xy 321.86354 -27.41685) (xy 321.917492 -27.409098)
			(xy 321.944746 -27.408632) (xy 321.970293 -27.409044) (xy 322.020929 -27.415865) (xy 322.070203 -27.429378)
			(xy 322.117234 -27.449343) (xy 322.161182 -27.475403) (xy 322.181474 -27.490928) (xy 322.196968 -27.50312)
			(xy 322.235068 -27.501088) (xy 322.388484 -27.347672) (xy 322.395884 -27.340831) (xy 322.414483 -27.333116)
			(xy 322.424552 -27.332686) (xy 322.570602 -27.332686) (xy 322.575936 -27.33167) (xy 322.576698 -27.33167)
			(xy 322.580254 -27.330908) (xy 322.581016 -27.330908) (xy 322.584572 -27.3304) (xy 322.58508 -27.3304)
			(xy 322.602606 -27.328368) (xy 322.627244 -27.327352) (xy 326.672702 -27.327352) (xy 326.68266 -27.326866)
			(xy 326.701059 -27.319245) (xy 326.715142 -27.305163) (xy 326.722765 -27.286764) (xy 326.723248 -27.276806)
			(xy 326.723248 -26.479246) (xy 326.72342 -26.463316) (xy 326.725708 -26.431537) (xy 326.72782 -26.415746)
			(xy 326.72782 -26.415238) (xy 326.728836 -26.409396) (xy 326.728836 -26.408888) (xy 326.731376 -26.39441)
			(xy 326.732646 -26.387044) (xy 326.731122 -26.372566) (xy 326.728328 -26.365708) (xy 326.725339 -26.358993)
			(xy 326.716175 -26.34751) (xy 326.710294 -26.343102) (xy 326.702674 -26.337768) (xy 326.676512 -26.31948)
			(xy 326.653814 -26.333028) (xy 326.605471 -26.354408) (xy 326.554634 -26.368893) (xy 326.502282 -26.376202)
			(xy 326.475852 -26.37663) (xy 326.448602 -26.376141) (xy 326.394659 -26.368379) (xy 326.342368 -26.35302)
			(xy 326.292796 -26.330376) (xy 326.24695 -26.300909) (xy 326.205764 -26.265218) (xy 326.170075 -26.224029)
			(xy 326.140611 -26.178181) (xy 326.117971 -26.128607) (xy 326.102615 -26.076316) (xy 326.094857 -26.022372)
			(xy 326.094344 -25.995122) (xy 326.094884 -25.965825) (xy 326.103849 -25.90792) (xy 326.121557 -25.852066)
			(xy 326.147591 -25.799572) (xy 326.18134 -25.751674) (xy 326.201278 -25.7302) (xy 326.20204 -25.729438)
			(xy 326.202548 -25.72893) (xy 326.220652 -25.710289) (xy 326.261033 -25.677586) (xy 326.305479 -25.650665)
			(xy 326.353167 -25.630025) (xy 326.403215 -25.616048) (xy 326.454697 -25.608993) (xy 326.480678 -25.608534)
			(xy 326.509625 -25.609076) (xy 326.566853 -25.617834) (xy 326.622101 -25.635137) (xy 326.674101 -25.660587)
			(xy 326.72166 -25.693601) (xy 326.763685 -25.733421) (xy 326.799213 -25.779133) (xy 326.827427 -25.829687)
			(xy 326.828311 -25.832054) (xy 328.387708 -25.832054) (xy 328.391779 -25.776432) (xy 328.403905 -25.721995)
			(xy 328.423828 -25.669904) (xy 328.451124 -25.621269) (xy 328.48521 -25.577126) (xy 328.525359 -25.538417)
			(xy 328.570717 -25.505966) (xy 328.620317 -25.480465) (xy 328.673101 -25.462458) (xy 328.727944 -25.452328)
			(xy 328.783678 -25.450291) (xy 328.839115 -25.456391) (xy 328.893072 -25.470497) (xy 328.944401 -25.492309)
			(xy 328.992007 -25.521363) (xy 329.034875 -25.557038) (xy 329.036409 -25.55875) (xy 332.842108 -25.55875)
			(xy 332.842594 -25.531499) (xy 332.85035 -25.477551) (xy 332.865705 -25.425256) (xy 332.888347 -25.375679)
			(xy 332.917813 -25.329829) (xy 332.953504 -25.288638) (xy 332.994695 -25.252947) (xy 333.040545 -25.223481)
			(xy 333.090122 -25.200839) (xy 333.142417 -25.185484) (xy 333.196365 -25.177728) (xy 333.250867 -25.177728)
			(xy 333.304815 -25.185484) (xy 333.35711 -25.200839) (xy 333.406687 -25.223481) (xy 333.452537 -25.252947)
			(xy 333.493728 -25.288638) (xy 333.529419 -25.329829) (xy 333.558885 -25.375679) (xy 333.581527 -25.425256)
			(xy 333.596882 -25.477551) (xy 333.604638 -25.531499) (xy 333.605124 -25.55875) (xy 333.60457 -25.589013)
			(xy 333.595018 -25.648779) (xy 333.576144 -25.706287) (xy 333.548424 -25.760091) (xy 333.530956 -25.78481)
			(xy 333.522684 -25.79696) (xy 333.512737 -25.824602) (xy 333.51107 -25.853932) (xy 333.517822 -25.882523)
			(xy 333.532435 -25.908009) (xy 333.553697 -25.92828) (xy 333.579851 -25.94166) (xy 333.594202 -25.94483)
			(xy 333.620095 -25.950173) (xy 333.670218 -25.966989) (xy 333.717537 -25.990568) (xy 333.761146 -26.020457)
			(xy 333.800208 -26.056083) (xy 333.833974 -26.096764) (xy 333.861797 -26.141718) (xy 333.883144 -26.190085)
			(xy 333.897606 -26.240938) (xy 333.904904 -26.2933) (xy 333.905352 -26.319734) (xy 335.041746 -26.319734)
			(xy 335.045817 -26.264112) (xy 335.057943 -26.209675) (xy 335.077866 -26.157584) (xy 335.105162 -26.108949)
			(xy 335.139248 -26.064806) (xy 335.179397 -26.026097) (xy 335.224755 -25.993646) (xy 335.274355 -25.968145)
			(xy 335.327139 -25.950138) (xy 335.381982 -25.940008) (xy 335.437716 -25.937971) (xy 335.493153 -25.944071)
			(xy 335.54711 -25.958177) (xy 335.598439 -25.979989) (xy 335.646045 -26.009043) (xy 335.688913 -26.044718)
			(xy 335.72613 -26.086255) (xy 335.756903 -26.132768) (xy 335.780575 -26.183265) (xy 335.796643 -26.236672)
			(xy 335.804763 -26.291848) (xy 335.805272 -26.319734) (xy 335.804763 -26.34762) (xy 335.796643 -26.402796)
			(xy 335.780575 -26.456203) (xy 335.756903 -26.5067) (xy 335.72613 -26.553213) (xy 335.688913 -26.59475)
			(xy 335.646045 -26.630425) (xy 335.598439 -26.659479) (xy 335.54711 -26.681291) (xy 335.493153 -26.695397)
			(xy 335.437716 -26.701497) (xy 335.381982 -26.69946) (xy 335.327139 -26.68933) (xy 335.274355 -26.671323)
			(xy 335.224755 -26.645822) (xy 335.179397 -26.613371) (xy 335.139248 -26.574662) (xy 335.105162 -26.530519)
			(xy 335.077866 -26.481884) (xy 335.057943 -26.429793) (xy 335.045817 -26.375356) (xy 335.041746 -26.319734)
			(xy 333.905352 -26.319734) (xy 333.904866 -26.346985) (xy 333.89711 -26.400933) (xy 333.881755 -26.453228)
			(xy 333.859113 -26.502805) (xy 333.829647 -26.548655) (xy 333.793956 -26.589846) (xy 333.752765 -26.625537)
			(xy 333.706915 -26.655003) (xy 333.657338 -26.677645) (xy 333.605043 -26.693) (xy 333.551095 -26.700756)
			(xy 333.496593 -26.700756) (xy 333.442645 -26.693) (xy 333.39035 -26.677645) (xy 333.340773 -26.655003)
			(xy 333.294923 -26.625537) (xy 333.253732 -26.589846) (xy 333.218041 -26.548655) (xy 333.188575 -26.502805)
			(xy 333.165933 -26.453228) (xy 333.150578 -26.400933) (xy 333.142822 -26.346985) (xy 333.142336 -26.319734)
			(xy 333.142889 -26.289471) (xy 333.152443 -26.229705) (xy 333.171317 -26.172198) (xy 333.199036 -26.118393)
			(xy 333.216504 -26.093674) (xy 333.22482 -26.08155) (xy 333.234772 -26.053899) (xy 333.236437 -26.024559)
			(xy 333.22968 -25.995959) (xy 333.215058 -25.970468) (xy 333.193782 -25.950195) (xy 333.167615 -25.93682)
			(xy 333.153258 -25.933654) (xy 333.127355 -25.928356) (xy 333.077231 -25.911533) (xy 333.029912 -25.887949)
			(xy 332.986303 -25.858054) (xy 332.947242 -25.822423) (xy 332.913477 -25.781737) (xy 332.885655 -25.736778)
			(xy 332.86431 -25.688407) (xy 332.849851 -25.637551) (xy 332.842555 -25.585186) (xy 332.842108 -25.55875)
			(xy 329.036409 -25.55875) (xy 329.072092 -25.598575) (xy 329.102865 -25.645088) (xy 329.126537 -25.695585)
			(xy 329.142605 -25.748992) (xy 329.150725 -25.804168) (xy 329.151234 -25.832054) (xy 329.150725 -25.85994)
			(xy 329.142605 -25.915116) (xy 329.126537 -25.968523) (xy 329.102865 -26.01902) (xy 329.072092 -26.065533)
			(xy 329.034875 -26.10707) (xy 328.992007 -26.142745) (xy 328.944401 -26.171799) (xy 328.893072 -26.193611)
			(xy 328.839115 -26.207717) (xy 328.783678 -26.213817) (xy 328.727944 -26.21178) (xy 328.673101 -26.20165)
			(xy 328.620317 -26.183643) (xy 328.570717 -26.158142) (xy 328.525359 -26.125691) (xy 328.48521 -26.086982)
			(xy 328.451124 -26.042839) (xy 328.423828 -25.994204) (xy 328.403905 -25.942113) (xy 328.391779 -25.887676)
			(xy 328.387708 -25.832054) (xy 326.828311 -25.832054) (xy 326.84768 -25.883923) (xy 326.859507 -25.940596)
			(xy 326.861678 -25.969468) (xy 326.861678 -25.969976) (xy 326.86311 -25.982104) (xy 326.875581 -26.003059)
			(xy 326.885554 -26.010108) (xy 326.92086 -26.031952) (xy 326.96658 -26.0604) (xy 326.991218 -26.062432)
			(xy 327.002648 -26.057606) (xy 327.030644 -26.046256) (xy 327.088879 -26.030187) (xy 327.148722 -26.021924)
			(xy 327.178924 -26.021284) (xy 327.18121 -26.021284) (xy 327.211194 -26.021754) (xy 327.270649 -26.029583)
			(xy 327.328574 -26.045106) (xy 327.383976 -26.068057) (xy 327.435909 -26.098044) (xy 327.483483 -26.134553)
			(xy 327.525884 -26.176959) (xy 327.562387 -26.224538) (xy 327.592368 -26.276474) (xy 327.615312 -26.331879)
			(xy 327.623081 -26.360882) (xy 330.305408 -26.360882) (xy 330.309479 -26.30526) (xy 330.321605 -26.250823)
			(xy 330.341528 -26.198732) (xy 330.368824 -26.150097) (xy 330.40291 -26.105954) (xy 330.443059 -26.067245)
			(xy 330.488417 -26.034794) (xy 330.538017 -26.009293) (xy 330.590801 -25.991286) (xy 330.645644 -25.981156)
			(xy 330.701378 -25.979119) (xy 330.756815 -25.985219) (xy 330.810772 -25.999325) (xy 330.862101 -26.021137)
			(xy 330.909707 -26.050191) (xy 330.952575 -26.085866) (xy 330.989792 -26.127403) (xy 331.020565 -26.173916)
			(xy 331.044237 -26.224413) (xy 331.060305 -26.27782) (xy 331.068425 -26.332996) (xy 331.068934 -26.360882)
			(xy 331.068425 -26.388768) (xy 331.060305 -26.443944) (xy 331.044237 -26.497351) (xy 331.020565 -26.547848)
			(xy 330.989792 -26.594361) (xy 330.952575 -26.635898) (xy 330.909707 -26.671573) (xy 330.862101 -26.700627)
			(xy 330.810772 -26.722439) (xy 330.756815 -26.736545) (xy 330.701378 -26.742645) (xy 330.645644 -26.740608)
			(xy 330.590801 -26.730478) (xy 330.538017 -26.712471) (xy 330.488417 -26.68697) (xy 330.443059 -26.654519)
			(xy 330.40291 -26.61581) (xy 330.368824 -26.571667) (xy 330.341528 -26.523032) (xy 330.321605 -26.470941)
			(xy 330.309479 -26.416504) (xy 330.305408 -26.360882) (xy 327.623081 -26.360882) (xy 327.630828 -26.389806)
			(xy 327.63865 -26.449262) (xy 327.639172 -26.479246) (xy 327.639172 -27.276806) (xy 327.63956 -27.286787)
			(xy 327.647164 -27.30524) (xy 327.66128 -27.319349) (xy 327.679737 -27.326945) (xy 327.689718 -27.327352)
			(xy 336.895694 -27.327352) (xy 336.905566 -27.32688) (xy 336.92385 -27.319423) (xy 336.931254 -27.312874)
			(xy 336.931508 -27.31262) (xy 337.290664 -26.953464) (xy 337.297509 -26.946065) (xy 337.305236 -26.927467)
			(xy 337.30565 -26.917396) (xy 337.30565 -19.893534) (xy 337.305566 -19.888858) (xy 337.303903 -19.879657)
			(xy 337.302348 -19.875246) (xy 337.264067 -19.773391) (xy 337.194945 -19.56704) (xy 337.134421 -19.358006)
			(xy 337.082601 -19.146646) (xy 337.06054 -19.040094) (xy 337.040307 -18.937356) (xy 337.007037 -18.730597)
			(xy 336.982027 -18.522676) (xy 336.965318 -18.313925) (xy 336.956935 -18.104674) (xy 336.9564 -17.999964)
			(xy 336.956942 -17.895255) (xy 336.965331 -17.686004) (xy 336.982041 -17.477253) (xy 337.007047 -17.269332)
			(xy 337.040309 -17.062572) (xy 337.06054 -16.959834) (xy 337.082604 -16.853283) (xy 337.134429 -16.641924)
			(xy 337.194952 -16.43289) (xy 337.264069 -16.226538) (xy 337.302348 -16.124682) (xy 337.303908 -16.120273)
			(xy 337.305568 -16.11107) (xy 337.30565 -16.106394) (xy 337.30565 -8.639556) (xy 337.280758 -8.611108)
			(xy 337.261708 -8.608314) (xy 337.234601 -8.604191) (xy 337.181868 -8.58918) (xy 337.131828 -8.566771)
			(xy 337.085513 -8.537426) (xy 337.043879 -8.50175) (xy 337.007784 -8.460479) (xy 336.977972 -8.414463)
			(xy 336.955058 -8.364652) (xy 336.939515 -8.312073) (xy 336.931663 -8.257809) (xy 336.931664 -8.202981)
			(xy 336.939517 -8.148717) (xy 336.955062 -8.096139) (xy 336.977977 -8.046328) (xy 337.00779 -8.000313)
			(xy 337.043886 -7.959043) (xy 337.085521 -7.923368) (xy 337.131836 -7.894024) (xy 337.181877 -7.871616)
			(xy 337.234611 -7.856607) (xy 337.261708 -7.85241) (xy 337.280758 -7.849616) (xy 337.30565 -7.821168)
			(xy 337.30565 -7.352538) (xy 337.305111 -7.341937) (xy 337.29658 -7.322527) (xy 337.280978 -7.30817)
			(xy 337.271106 -7.304278) (xy 337.270852 -7.304278) (xy 337.245954 -7.295408) (xy 337.198679 -7.271772)
			(xy 337.155115 -7.241843) (xy 337.116095 -7.206193) (xy 337.082363 -7.165502) (xy 337.054565 -7.120549)
			(xy 337.033231 -7.072192) (xy 337.018769 -7.021355) (xy 337.011456 -6.969009) (xy 337.01101 -6.942582)
			(xy 337.011461 -6.916141) (xy 337.018766 -6.863767) (xy 337.033232 -6.812903) (xy 337.054583 -6.764524)
			(xy 337.082409 -6.719556) (xy 337.116179 -6.678862) (xy 337.155243 -6.64322) (xy 337.198855 -6.613313)
			(xy 337.246179 -6.589715) (xy 337.271106 -6.580886) (xy 337.2866 -6.575552) (xy 337.30565 -6.549136)
			(xy 337.30565 -5.070348) (xy 337.305216 -5.060283) (xy 337.297483 -5.041697) (xy 337.290664 -5.03428)
			(xy 336.862928 -4.606544) (xy 336.855528 -4.599704) (xy 336.836929 -4.591989) (xy 336.82686 -4.591558)
			(xy 329.604116 -4.591558) (xy 329.594054 -4.591998) (xy 329.575477 -4.59974) (xy 329.568048 -4.606544)
			(xy 329.449684 -4.724908) (xy 329.443003 -4.732319) (xy 329.435426 -4.750755) (xy 329.434952 -4.760722)
			(xy 329.434952 -6.68655) (xy 330.361798 -6.68655) (xy 330.362257 -6.657661) (xy 330.370954 -6.600542)
			(xy 330.388173 -6.54539) (xy 330.413518 -6.493469) (xy 330.446408 -6.445967) (xy 330.486092 -6.403974)
			(xy 330.531658 -6.36845) (xy 330.582064 -6.340211) (xy 330.636154 -6.319902) (xy 330.664312 -6.313424)
			(xy 330.678746 -6.309934) (xy 330.704811 -6.295722) (xy 330.725688 -6.274615) (xy 330.739614 -6.248397)
			(xy 330.745413 -6.219281) (xy 330.742594 -6.189728) (xy 330.731396 -6.162233) (xy 330.722478 -6.150356)
			(xy 330.706688 -6.129942) (xy 330.680116 -6.085701) (xy 330.65976 -6.038278) (xy 330.645993 -5.988541)
			(xy 330.639066 -5.9374) (xy 330.638658 -5.911596) (xy 330.639144 -5.884345) (xy 330.6469 -5.830397)
			(xy 330.662255 -5.778102) (xy 330.684897 -5.728525) (xy 330.714363 -5.682675) (xy 330.750054 -5.641484)
			(xy 330.791245 -5.605793) (xy 330.837095 -5.576327) (xy 330.886672 -5.553685) (xy 330.938967 -5.53833)
			(xy 330.992915 -5.530574) (xy 331.047417 -5.530574) (xy 331.101365 -5.53833) (xy 331.15366 -5.553685)
			(xy 331.203237 -5.576327) (xy 331.249087 -5.605793) (xy 331.290278 -5.641484) (xy 331.325969 -5.682675)
			(xy 331.355435 -5.728525) (xy 331.377331 -5.776468) (xy 335.944462 -5.776468) (xy 335.948533 -5.720846)
			(xy 335.960659 -5.666409) (xy 335.980582 -5.614318) (xy 336.007878 -5.565683) (xy 336.041964 -5.52154)
			(xy 336.082113 -5.482831) (xy 336.127471 -5.45038) (xy 336.177071 -5.424879) (xy 336.229855 -5.406872)
			(xy 336.284698 -5.396742) (xy 336.340432 -5.394705) (xy 336.395869 -5.400805) (xy 336.449826 -5.414911)
			(xy 336.501155 -5.436723) (xy 336.548761 -5.465777) (xy 336.591629 -5.501452) (xy 336.628846 -5.542989)
			(xy 336.659619 -5.589502) (xy 336.683291 -5.639999) (xy 336.699359 -5.693406) (xy 336.707479 -5.748582)
			(xy 336.707988 -5.776468) (xy 336.707479 -5.804354) (xy 336.699359 -5.85953) (xy 336.683291 -5.912937)
			(xy 336.659619 -5.963434) (xy 336.628846 -6.009947) (xy 336.591629 -6.051484) (xy 336.548761 -6.087159)
			(xy 336.501155 -6.116213) (xy 336.449826 -6.138025) (xy 336.395869 -6.152131) (xy 336.340432 -6.158231)
			(xy 336.284698 -6.156194) (xy 336.229855 -6.146064) (xy 336.177071 -6.128057) (xy 336.127471 -6.102556)
			(xy 336.082113 -6.070105) (xy 336.041964 -6.031396) (xy 336.007878 -5.987253) (xy 335.980582 -5.938618)
			(xy 335.960659 -5.886527) (xy 335.948533 -5.83209) (xy 335.944462 -5.776468) (xy 331.377331 -5.776468)
			(xy 331.378077 -5.778102) (xy 331.393432 -5.830397) (xy 331.401188 -5.884345) (xy 331.401674 -5.911596)
			(xy 331.401109 -5.940481) (xy 331.392422 -5.997592) (xy 331.375215 -6.052738) (xy 331.349882 -6.104656)
			(xy 331.317005 -6.152156) (xy 331.277335 -6.19415) (xy 331.231783 -6.229677) (xy 331.18139 -6.257922)
			(xy 331.127312 -6.278239) (xy 331.09916 -6.284722) (xy 331.084756 -6.288325) (xy 331.058694 -6.302512)
			(xy 331.037815 -6.323597) (xy 331.023884 -6.349796) (xy 331.018079 -6.378896) (xy 331.02089 -6.408436)
			(xy 331.03208 -6.435918) (xy 331.040994 -6.44779) (xy 331.056815 -6.46818) (xy 331.08338 -6.512429)
			(xy 331.103729 -6.559858) (xy 331.117489 -6.6096) (xy 331.124409 -6.660744) (xy 331.124814 -6.68655)
			(xy 331.124328 -6.713801) (xy 331.116572 -6.767749) (xy 331.101217 -6.820044) (xy 331.078575 -6.869621)
			(xy 331.049109 -6.915471) (xy 331.013418 -6.956662) (xy 330.972227 -6.992353) (xy 330.926377 -7.021819)
			(xy 330.8768 -7.044461) (xy 330.824505 -7.059816) (xy 330.770557 -7.067572) (xy 330.716055 -7.067572)
			(xy 330.662107 -7.059816) (xy 330.609812 -7.044461) (xy 330.560235 -7.021819) (xy 330.514385 -6.992353)
			(xy 330.473194 -6.956662) (xy 330.437503 -6.915471) (xy 330.408037 -6.869621) (xy 330.385395 -6.820044)
			(xy 330.37004 -6.767749) (xy 330.362284 -6.713801) (xy 330.361798 -6.68655) (xy 329.434952 -6.68655)
			(xy 329.434952 -7.304786) (xy 329.43555 -7.316119) (xy 329.445305 -7.336574) (xy 329.453748 -7.344156)
			(xy 329.523852 -7.400798) (xy 329.546204 -7.406132) (xy 329.55738 -7.403846) (xy 329.576709 -7.399982)
			(xy 329.615903 -7.395783) (xy 329.635612 -7.395464) (xy 329.63993 -7.395464) (xy 329.667065 -7.396122)
			(xy 329.720743 -7.40417) (xy 329.772739 -7.419744) (xy 329.822002 -7.44253) (xy 329.86754 -7.472067)
			(xy 329.908431 -7.50776) (xy 329.943852 -7.548887) (xy 329.973087 -7.594619) (xy 329.995545 -7.644033)
			(xy 330.010775 -7.696131) (xy 330.018467 -7.749861) (xy 330.018467 -7.804139) (xy 330.010775 -7.857869)
			(xy 329.995546 -7.909967) (xy 329.992498 -7.916672) (xy 330.525372 -7.916672) (xy 330.529443 -7.86105)
			(xy 330.541569 -7.806613) (xy 330.561492 -7.754522) (xy 330.588788 -7.705887) (xy 330.622874 -7.661744)
			(xy 330.663023 -7.623035) (xy 330.708381 -7.590584) (xy 330.757981 -7.565083) (xy 330.810765 -7.547076)
			(xy 330.865608 -7.536946) (xy 330.921342 -7.534909) (xy 330.976779 -7.541009) (xy 331.030736 -7.555115)
			(xy 331.082065 -7.576927) (xy 331.129671 -7.605981) (xy 331.172539 -7.641656) (xy 331.209756 -7.683193)
			(xy 331.240529 -7.729706) (xy 331.264201 -7.780203) (xy 331.280269 -7.83361) (xy 331.288389 -7.888786)
			(xy 331.288898 -7.916672) (xy 331.288389 -7.944558) (xy 331.280269 -7.999734) (xy 331.264201 -8.053141)
			(xy 331.240529 -8.103638) (xy 331.209756 -8.150151) (xy 331.172539 -8.191688) (xy 331.129671 -8.227363)
			(xy 331.082065 -8.256417) (xy 331.030736 -8.278229) (xy 330.976779 -8.292335) (xy 330.921342 -8.298435)
			(xy 330.865608 -8.296398) (xy 330.810765 -8.286268) (xy 330.757981 -8.268261) (xy 330.708381 -8.24276)
			(xy 330.663023 -8.210309) (xy 330.622874 -8.1716) (xy 330.588788 -8.127457) (xy 330.561492 -8.078822)
			(xy 330.541569 -8.026731) (xy 330.529443 -7.972294) (xy 330.525372 -7.916672) (xy 329.992498 -7.916672)
			(xy 329.973087 -7.95938) (xy 329.943852 -8.005113) (xy 329.908432 -8.04624) (xy 329.86754 -8.081933)
			(xy 329.822003 -8.11147) (xy 329.772739 -8.134256) (xy 329.720744 -8.14983) (xy 329.667066 -8.157878)
			(xy 329.63993 -8.15848) (xy 329.637136 -8.15848) (xy 329.617567 -8.158258) (xy 329.578628 -8.154316)
			(xy 329.559412 -8.150606) (xy 329.557126 -8.150098) (xy 329.552046 -8.14959) (xy 329.542029 -8.148898)
			(xy 329.522771 -8.154528) (xy 329.514708 -8.160512) (xy 329.453748 -8.209788) (xy 329.445343 -8.217402)
			(xy 329.435571 -8.237836) (xy 329.434952 -8.249158) (xy 329.434952 -11.543792) (xy 333.59928 -11.543792)
			(xy 333.603351 -11.48817) (xy 333.615477 -11.433733) (xy 333.6354 -11.381642) (xy 333.662696 -11.333007)
			(xy 333.696782 -11.288864) (xy 333.736931 -11.250155) (xy 333.782289 -11.217704) (xy 333.831889 -11.192203)
			(xy 333.884673 -11.174196) (xy 333.939516 -11.164066) (xy 333.99525 -11.162029) (xy 334.050687 -11.168129)
			(xy 334.104644 -11.182235) (xy 334.155973 -11.204047) (xy 334.203579 -11.233101) (xy 334.246447 -11.268776)
			(xy 334.283664 -11.310313) (xy 334.314437 -11.356826) (xy 334.338109 -11.407323) (xy 334.354177 -11.46073)
			(xy 334.362297 -11.515906) (xy 334.362806 -11.543792) (xy 334.608168 -11.543792) (xy 334.612239 -11.48817)
			(xy 334.624365 -11.433733) (xy 334.644288 -11.381642) (xy 334.671584 -11.333007) (xy 334.70567 -11.288864)
			(xy 334.745819 -11.250155) (xy 334.791177 -11.217704) (xy 334.840777 -11.192203) (xy 334.893561 -11.174196)
			(xy 334.948404 -11.164066) (xy 335.004138 -11.162029) (xy 335.059575 -11.168129) (xy 335.113532 -11.182235)
			(xy 335.164861 -11.204047) (xy 335.212467 -11.233101) (xy 335.255335 -11.268776) (xy 335.292552 -11.310313)
			(xy 335.323325 -11.356826) (xy 335.346997 -11.407323) (xy 335.363065 -11.46073) (xy 335.371185 -11.515906)
			(xy 335.371694 -11.543792) (xy 335.371185 -11.571678) (xy 335.363065 -11.626854) (xy 335.346997 -11.680261)
			(xy 335.323325 -11.730758) (xy 335.292552 -11.777271) (xy 335.255335 -11.818808) (xy 335.212467 -11.854483)
			(xy 335.164861 -11.883537) (xy 335.113532 -11.905349) (xy 335.059575 -11.919455) (xy 335.004138 -11.925555)
			(xy 334.948404 -11.923518) (xy 334.893561 -11.913388) (xy 334.840777 -11.895381) (xy 334.791177 -11.86988)
			(xy 334.745819 -11.837429) (xy 334.70567 -11.79872) (xy 334.671584 -11.754577) (xy 334.644288 -11.705942)
			(xy 334.624365 -11.653851) (xy 334.612239 -11.599414) (xy 334.608168 -11.543792) (xy 334.362806 -11.543792)
			(xy 334.362297 -11.571678) (xy 334.354177 -11.626854) (xy 334.338109 -11.680261) (xy 334.314437 -11.730758)
			(xy 334.283664 -11.777271) (xy 334.246447 -11.818808) (xy 334.203579 -11.854483) (xy 334.155973 -11.883537)
			(xy 334.104644 -11.905349) (xy 334.050687 -11.919455) (xy 333.99525 -11.925555) (xy 333.939516 -11.923518)
			(xy 333.884673 -11.913388) (xy 333.831889 -11.895381) (xy 333.782289 -11.86988) (xy 333.736931 -11.837429)
			(xy 333.696782 -11.79872) (xy 333.662696 -11.754577) (xy 333.6354 -11.705942) (xy 333.615477 -11.653851)
			(xy 333.603351 -11.599414) (xy 333.59928 -11.543792) (xy 329.434952 -11.543792) (xy 329.434952 -11.85037)
			(xy 329.434435 -11.918856) (xy 329.426174 -12.055579) (xy 329.409687 -12.191555) (xy 329.385033 -12.32629)
			(xy 329.369166 -12.392914) (xy 329.367642 -12.398756) (xy 329.367642 -13.47724) (xy 329.367289 -13.485929)
			(xy 329.361433 -13.502289) (xy 329.356212 -13.509244) (xy 329.350624 -13.515848) (xy 329.347576 -13.523976)
			(xy 329.346133 -13.528277) (xy 329.344608 -13.53722) (xy 329.344528 -13.541756) (xy 329.344528 -13.54201)
			(xy 329.344987 -13.551887) (xy 329.352431 -13.570185) (xy 329.359006 -13.57757) (xy 329.35926 -13.577824)
			(xy 329.359514 -13.578078) (xy 329.364333 -13.582638) (xy 329.375778 -13.589341) (xy 329.38212 -13.591286)
			(xy 329.445919 -13.609239) (xy 329.571373 -13.652026) (xy 329.693929 -13.702516) (xy 329.813116 -13.760515)
			(xy 329.928474 -13.825799) (xy 330.039557 -13.898116) (xy 330.145939 -13.977188) (xy 330.247207 -14.062711)
			(xy 330.342973 -14.154353) (xy 330.432867 -14.251762) (xy 330.516542 -14.354562) (xy 330.593675 -14.462357)
			(xy 330.66397 -14.574732) (xy 330.727155 -14.691252) (xy 330.782987 -14.811469) (xy 330.83125 -14.93492)
			(xy 330.871758 -15.061128) (xy 330.904356 -15.189606) (xy 330.928917 -15.319861) (xy 330.945347 -15.451388)
			(xy 330.953582 -15.583681) (xy 330.954126 -15.649956) (xy 330.95362 -15.715692) (xy 330.945527 -15.846913)
			(xy 330.92937 -15.977388) (xy 330.905213 -16.106621) (xy 330.873145 -16.234121) (xy 330.833289 -16.359405)
			(xy 330.785796 -16.481999) (xy 330.730847 -16.601436) (xy 330.668648 -16.717263) (xy 330.599438 -16.829042)
			(xy 330.523477 -16.936349) (xy 330.441055 -17.038775) (xy 330.352483 -17.135934) (xy 330.258098 -17.227455)
			(xy 330.158259 -17.312993) (xy 330.053342 -17.392222) (xy 329.943748 -17.464842) (xy 329.82989 -17.530577)
			(xy 329.712202 -17.589179) (xy 329.59113 -17.640425) (xy 329.467132 -17.68412) (xy 329.34068 -17.720099)
			(xy 329.212252 -17.748225) (xy 329.082337 -17.768391) (xy 328.951427 -17.780522) (xy 328.820018 -17.784571)
			(xy 328.688609 -17.780522) (xy 328.557699 -17.768391) (xy 328.427784 -17.748225) (xy 328.299356 -17.720099)
			(xy 328.172904 -17.68412) (xy 328.048906 -17.640425) (xy 327.927834 -17.589179) (xy 327.810146 -17.530577)
			(xy 327.696288 -17.464842) (xy 327.586694 -17.392222) (xy 327.481777 -17.312993) (xy 327.381938 -17.227455)
			(xy 327.287553 -17.135934) (xy 327.198981 -17.038775) (xy 327.116559 -16.936349) (xy 327.040598 -16.829042)
			(xy 326.971388 -16.717263) (xy 326.909189 -16.601436) (xy 326.85424 -16.481999) (xy 326.806747 -16.359405)
			(xy 326.766891 -16.234121) (xy 326.734823 -16.106621) (xy 326.710666 -15.977388) (xy 326.694509 -15.846913)
			(xy 326.686416 -15.715692) (xy 326.68591 -15.649956) (xy 326.68591 -15.649194) (xy 326.686371 -15.58701)
			(xy 326.693643 -15.462855) (xy 326.708133 -15.339334) (xy 326.729792 -15.216867) (xy 326.758547 -15.095869)
			(xy 326.794299 -14.976751) (xy 326.815196 -14.918182) (xy 326.818244 -14.909546) (xy 326.818244 -14.900402)
			(xy 326.83831 -14.850618) (xy 326.843136 -14.83868) (xy 326.840596 -14.813788) (xy 326.809862 -14.768068)
			(xy 326.78624 -14.733016) (xy 326.778706 -14.723008) (xy 326.756589 -14.71131) (xy 326.744076 -14.710664)
			(xy 324.929246 -14.710664) (xy 324.919905 -14.711139) (xy 324.902489 -14.717919) (xy 324.888633 -14.73046)
			(xy 324.884034 -14.738604) (xy 324.840092 -14.825218) (xy 324.842378 -14.853666) (xy 324.85076 -14.86535)
			(xy 324.877133 -14.902353) (xy 324.923441 -14.980541) (xy 324.961996 -15.062829) (xy 324.992439 -15.14845)
			(xy 325.014486 -15.236608) (xy 325.027932 -15.32648) (xy 325.030846 -15.371826) (xy 325.031608 -15.389352)
			(xy 325.032426 -15.423761) (xy 325.029629 -15.492537) (xy 325.02602 -15.526766) (xy 325.022532 -15.555337)
			(xy 325.012495 -15.61202) (xy 325.005954 -15.64005) (xy 324.997318 -15.673324) (xy 324.997318 -15.673578)
			(xy 324.996048 -15.677642) (xy 324.981418 -15.726548) (xy 324.942974 -15.821117) (xy 324.91934 -15.866364)
			(xy 324.913244 -15.877794) (xy 324.913244 -15.903194) (xy 324.961504 -15.992602) (xy 324.98284 -16.006572)
			(xy 324.995794 -16.007588) (xy 325.039183 -16.011728) (xy 325.12503 -16.026845) (xy 325.209166 -16.049635)
			(xy 325.290905 -16.079915) (xy 325.369583 -16.117438) (xy 325.44456 -16.161898) (xy 325.515225 -16.212933)
			(xy 325.581004 -16.270128) (xy 325.641361 -16.333019) (xy 325.695805 -16.401092) (xy 325.743894 -16.473795)
			(xy 325.785235 -16.550536) (xy 325.819492 -16.630689) (xy 325.846388 -16.713604) (xy 325.865702 -16.798605)
			(xy 325.877278 -16.885) (xy 325.881021 -16.972087) (xy 325.876902 -17.059158) (xy 325.864953 -17.145502)
			(xy 325.845271 -17.230419) (xy 325.818018 -17.313217) (xy 325.783414 -17.393221) (xy 325.741742 -17.469782)
			(xy 325.69334 -17.542277) (xy 325.638602 -17.610115) (xy 325.608696 -17.641824) (xy 325.608442 -17.642078)
			(xy 325.577155 -17.674112) (xy 325.509583 -17.732877) (xy 325.436861 -17.785133) (xy 325.359613 -17.830433)
			(xy 325.278503 -17.868385) (xy 325.194227 -17.898666) (xy 325.10751 -17.921014) (xy 325.019096 -17.935238)
			(xy 324.929746 -17.941215) (xy 324.840226 -17.938894) (xy 324.751305 -17.928295) (xy 324.663747 -17.909509)
			(xy 324.578304 -17.882698) (xy 324.536816 -17.865852) (xy 324.495752 -17.848111) (xy 324.416785 -17.806074)
			(xy 324.342045 -17.756913) (xy 324.272174 -17.701049) (xy 324.20777 -17.63896) (xy 324.149386 -17.57118)
			(xy 324.097522 -17.49829) (xy 324.052624 -17.420914) (xy 324.015076 -17.339716) (xy 323.985201 -17.255394)
			(xy 323.963254 -17.168669) (xy 323.949425 -17.080286) (xy 323.94383 -16.991002) (xy 323.946519 -16.901584)
			(xy 323.957469 -16.812798) (xy 323.976585 -16.725405) (xy 324.003704 -16.640156) (xy 324.038592 -16.557781)
			(xy 324.059296 -16.518128) (xy 324.05955 -16.517366) (xy 324.061074 -16.514318) (xy 324.062598 -16.510762)
			(xy 324.066945 -16.499101) (xy 324.064962 -16.474322) (xy 324.058788 -16.463518) (xy 324.058026 -16.462502)
			(xy 324.014846 -16.390112) (xy 324.01005 -16.382731) (xy 323.996499 -16.371516) (xy 323.979953 -16.365547)
			(xy 323.971158 -16.36522) (xy 322.232782 -16.36522) (xy 322.189344 -16.364733) (xy 322.10284 -16.356715)
			(xy 322.017444 -16.34075) (xy 321.933885 -16.316973) (xy 321.852877 -16.285588) (xy 321.77511 -16.246863)
			(xy 321.701248 -16.201127) (xy 321.631922 -16.148771) (xy 321.567722 -16.090242) (xy 321.509196 -16.026038)
			(xy 321.456844 -15.956709) (xy 321.411112 -15.882844) (xy 321.37239 -15.805075) (xy 321.34101 -15.724065)
			(xy 321.317238 -15.640506) (xy 321.301278 -15.555109) (xy 321.293265 -15.468604) (xy 321.292728 -15.425166)
			(xy 321.292728 -15.424658) (xy 321.293225 -15.382462) (xy 321.300838 -15.298414) (xy 321.315955 -15.215387)
			(xy 321.338452 -15.134049) (xy 321.36815 -15.055055) (xy 321.404809 -14.979041) (xy 321.448134 -14.906619)
			(xy 321.47256 -14.872208) (xy 321.480942 -14.860524) (xy 321.483228 -14.831822) (xy 321.471036 -14.8082)
			(xy 321.435984 -14.738858) (xy 321.432259 -14.732252) (xy 321.421673 -14.721401) (xy 321.415156 -14.717522)
			(xy 321.414648 -14.717014) (xy 321.408865 -14.71403) (xy 321.396261 -14.71081) (xy 321.389756 -14.710664)
			(xy 312.06948 -14.710664) (xy 312.059413 -14.711092) (xy 312.04082 -14.718819) (xy 312.033412 -14.72565)
			(xy 311.839102 -14.91996) (xy 311.832237 -14.927518) (xy 311.824622 -14.946444) (xy 311.824963 -14.966842)
			(xy 311.828688 -14.976348) (xy 311.828688 -14.976602) (xy 311.866788 -15.062708) (xy 311.870241 -15.069799)
			(xy 311.880717 -15.081575) (xy 311.887362 -15.085822) (xy 311.894474 -15.09014) (xy 311.908698 -15.093696)
			(xy 311.916064 -15.093188) (xy 311.917588 -15.093188) (xy 311.936638 -15.09268) (xy 311.963888 -15.093168)
			(xy 312.017834 -15.10093) (xy 312.070125 -15.116288) (xy 312.119699 -15.138932) (xy 312.165547 -15.168401)
			(xy 312.206734 -15.204093) (xy 312.242422 -15.245284) (xy 312.271886 -15.291134) (xy 312.294525 -15.34071)
			(xy 312.309879 -15.393004) (xy 312.317634 -15.44695) (xy 312.317634 -15.50145) (xy 312.309879 -15.555396)
			(xy 312.294525 -15.60769) (xy 312.271886 -15.657266) (xy 312.242422 -15.703116) (xy 312.206734 -15.744307)
			(xy 312.165547 -15.779999) (xy 312.119699 -15.809468) (xy 312.070125 -15.832112) (xy 312.017834 -15.84747)
			(xy 311.963888 -15.855232) (xy 311.936638 -15.855696) (xy 311.906647 -15.855144) (xy 311.847404 -15.845757)
			(xy 311.790368 -15.827194) (xy 311.76341 -15.81404) (xy 311.751472 -15.807944) (xy 311.72531 -15.80896)
			(xy 311.639966 -15.861284) (xy 311.632806 -15.866117) (xy 311.621972 -15.87956) (xy 311.616207 -15.895833)
			(xy 311.615836 -15.904464) (xy 311.615836 -20.72513) (xy 315.380636 -20.72513) (xy 315.384606 -20.594996)
			(xy 315.396502 -20.465346) (xy 315.416281 -20.336663) (xy 315.443867 -20.209424) (xy 315.47916 -20.084105)
			(xy 315.522026 -19.961169) (xy 315.572308 -19.841076) (xy 315.629817 -19.724272) (xy 315.694341 -19.61119)
			(xy 315.765638 -19.502253) (xy 315.843443 -19.397865) (xy 315.927468 -19.298414) (xy 316.0174 -19.204271)
			(xy 316.112904 -19.115786) (xy 316.213624 -19.033287) (xy 316.319186 -18.957082) (xy 316.429198 -18.887455)
			(xy 316.54325 -18.824664) (xy 316.660918 -18.768942) (xy 316.781764 -18.720498) (xy 316.905339 -18.679511)
			(xy 317.031182 -18.646134) (xy 317.158827 -18.620491) (xy 317.287797 -18.602677) (xy 317.417613 -18.592759)
			(xy 317.547792 -18.590774) (xy 317.677851 -18.596728) (xy 317.807304 -18.610601) (xy 317.935671 -18.632339)
			(xy 318.062474 -18.661863) (xy 318.187241 -18.699062) (xy 318.309508 -18.743798) (xy 318.428821 -18.795906)
			(xy 318.544734 -18.855189) (xy 318.656819 -18.92143) (xy 318.764656 -18.99438) (xy 318.867845 -19.073768)
			(xy 318.966003 -19.1593) (xy 319.058764 -19.250657) (xy 319.145783 -19.347499) (xy 319.226736 -19.449466)
			(xy 319.301322 -19.556178) (xy 319.369263 -19.667239) (xy 319.430308 -19.782235) (xy 319.484229 -19.900739)
			(xy 319.530824 -20.02231) (xy 319.569922 -20.146495) (xy 319.601376 -20.272833) (xy 319.62507 -20.400854)
			(xy 319.640914 -20.53008) (xy 319.648852 -20.660033) (xy 319.649348 -20.72513) (xy 319.648852 -20.790227)
			(xy 319.640914 -20.92018) (xy 319.62507 -21.049406) (xy 319.601376 -21.177427) (xy 319.569922 -21.303765)
			(xy 319.530824 -21.42795) (xy 319.484229 -21.549521) (xy 319.430308 -21.668025) (xy 319.392984 -21.738336)
			(xy 321.616578 -21.738336) (xy 321.617069 -21.709596) (xy 321.6257 -21.652767) (xy 321.642758 -21.597876)
			(xy 321.667857 -21.546165) (xy 321.700428 -21.498804) (xy 321.719702 -21.477478) (xy 321.726306 -21.470366)
			(xy 321.733418 -21.45284) (xy 321.733418 -21.363432) (xy 321.726306 -21.345906) (xy 321.719702 -21.338794)
			(xy 321.700468 -21.317436) (xy 321.667903 -21.270078) (xy 321.642811 -21.218371) (xy 321.62576 -21.163486)
			(xy 321.617134 -21.106663) (xy 321.61713 -21.049189) (xy 321.625748 -20.992366) (xy 321.642792 -20.937478)
			(xy 321.667877 -20.885767) (xy 321.700435 -20.838405) (xy 321.719702 -20.817078) (xy 321.726306 -20.809966)
			(xy 321.733418 -20.79244) (xy 321.733418 -20.703032) (xy 321.726306 -20.685506) (xy 321.719702 -20.678394)
			(xy 321.700468 -20.657036) (xy 321.667903 -20.609678) (xy 321.642811 -20.557971) (xy 321.62576 -20.503086)
			(xy 321.617134 -20.446263) (xy 321.61713 -20.388789) (xy 321.625748 -20.331966) (xy 321.642792 -20.277078)
			(xy 321.667877 -20.225367) (xy 321.700435 -20.178005) (xy 321.719702 -20.156678) (xy 321.726306 -20.149566)
			(xy 321.733418 -20.13204) (xy 321.733418 -20.042632) (xy 321.726306 -20.025106) (xy 321.719702 -20.017994)
			(xy 321.700468 -19.996636) (xy 321.667903 -19.949278) (xy 321.642811 -19.897571) (xy 321.62576 -19.842686)
			(xy 321.617134 -19.785863) (xy 321.61713 -19.728389) (xy 321.625748 -19.671566) (xy 321.642792 -19.616678)
			(xy 321.667877 -19.564967) (xy 321.700435 -19.517605) (xy 321.719702 -19.496278) (xy 321.726306 -19.489166)
			(xy 321.733418 -19.47164) (xy 321.733418 -19.382232) (xy 321.726306 -19.364706) (xy 321.719702 -19.357594)
			(xy 321.700459 -19.336242) (xy 321.667887 -19.288888) (xy 321.642788 -19.237183) (xy 321.625731 -19.182297)
			(xy 321.617102 -19.125474) (xy 321.616578 -19.096736) (xy 321.617064 -19.069485) (xy 321.62482 -19.015537)
			(xy 321.640175 -18.963242) (xy 321.662817 -18.913665) (xy 321.692283 -18.867815) (xy 321.727974 -18.826624)
			(xy 321.769165 -18.790933) (xy 321.815015 -18.761467) (xy 321.864592 -18.738825) (xy 321.916887 -18.72347)
			(xy 321.970835 -18.715714) (xy 322.025337 -18.715714) (xy 322.079285 -18.72347) (xy 322.13158 -18.738825)
			(xy 322.181157 -18.761467) (xy 322.227007 -18.790933) (xy 322.268198 -18.826624) (xy 322.303889 -18.867815)
			(xy 322.333355 -18.913665) (xy 322.355997 -18.963242) (xy 322.371352 -19.015537) (xy 322.379108 -19.069485)
			(xy 322.379594 -19.096736) (xy 322.379094 -19.125476) (xy 322.370466 -19.182304) (xy 322.35341 -19.237195)
			(xy 322.328313 -19.288907) (xy 322.295743 -19.336268) (xy 322.27647 -19.357594) (xy 322.269866 -19.364706)
			(xy 322.262754 -19.382232) (xy 322.262754 -19.47164) (xy 322.269866 -19.489166) (xy 322.27647 -19.496278)
			(xy 322.295777 -19.517574) (xy 322.328341 -19.564941) (xy 322.353431 -19.616658) (xy 322.370479 -19.671554)
			(xy 322.379098 -19.728385) (xy 322.379094 -19.785867) (xy 322.370467 -19.842698) (xy 322.353412 -19.897591)
			(xy 322.328315 -19.949304) (xy 322.295744 -19.996667) (xy 322.27647 -20.017994) (xy 322.269866 -20.025106)
			(xy 322.262754 -20.042632) (xy 322.262754 -20.13204) (xy 322.269866 -20.149566) (xy 322.27647 -20.156678)
			(xy 322.295777 -20.177974) (xy 322.328341 -20.225341) (xy 322.353431 -20.277058) (xy 322.370479 -20.331954)
			(xy 322.379098 -20.388785) (xy 322.379094 -20.446267) (xy 322.370467 -20.503098) (xy 322.353412 -20.557991)
			(xy 322.328315 -20.609704) (xy 322.295744 -20.657067) (xy 322.27647 -20.678394) (xy 322.269866 -20.685506)
			(xy 322.262754 -20.703032) (xy 322.262754 -20.79244) (xy 322.269866 -20.809966) (xy 322.27647 -20.817078)
			(xy 322.295777 -20.838374) (xy 322.328341 -20.885741) (xy 322.353431 -20.937458) (xy 322.370479 -20.992354)
			(xy 322.379098 -21.049185) (xy 322.379094 -21.106667) (xy 322.370467 -21.163498) (xy 322.353412 -21.218391)
			(xy 322.328315 -21.270104) (xy 322.295744 -21.317467) (xy 322.27647 -21.338794) (xy 322.269866 -21.345906)
			(xy 322.262754 -21.363432) (xy 322.262754 -21.45284) (xy 322.269866 -21.470366) (xy 322.27647 -21.477478)
			(xy 322.295759 -21.498789) (xy 322.328323 -21.546156) (xy 322.353411 -21.597871) (xy 322.370458 -21.652766)
			(xy 322.379076 -21.709596) (xy 322.379388 -21.726906) (xy 326.273668 -21.726906) (xy 326.274204 -21.698168)
			(xy 326.282825 -21.641341) (xy 326.299873 -21.586451) (xy 326.324961 -21.534739) (xy 326.357523 -21.487376)
			(xy 326.376792 -21.466048) (xy 326.383396 -21.458936) (xy 326.390508 -21.44141) (xy 326.390508 -21.352002)
			(xy 326.383396 -21.334476) (xy 326.376792 -21.327364) (xy 326.357529 -21.306031) (xy 326.324966 -21.258669)
			(xy 326.299876 -21.206958) (xy 326.282827 -21.152068) (xy 326.274205 -21.095243) (xy 326.274204 -21.037766)
			(xy 326.282825 -20.98094) (xy 326.299873 -20.92605) (xy 326.324961 -20.874339) (xy 326.357523 -20.826975)
			(xy 326.376792 -20.805648) (xy 326.383396 -20.798536) (xy 326.390508 -20.78101) (xy 326.390508 -20.691602)
			(xy 326.383396 -20.674076) (xy 326.376792 -20.666964) (xy 326.357529 -20.645631) (xy 326.324966 -20.598269)
			(xy 326.299876 -20.546558) (xy 326.282827 -20.491668) (xy 326.274205 -20.434843) (xy 326.274204 -20.377366)
			(xy 326.282825 -20.32054) (xy 326.299873 -20.26565) (xy 326.324961 -20.213939) (xy 326.357523 -20.166575)
			(xy 326.376792 -20.145248) (xy 326.383396 -20.138136) (xy 326.390508 -20.12061) (xy 326.390508 -20.031202)
			(xy 326.383396 -20.013676) (xy 326.376792 -20.006564) (xy 326.357529 -19.985231) (xy 326.324966 -19.937869)
			(xy 326.299876 -19.886158) (xy 326.282827 -19.831268) (xy 326.274205 -19.774443) (xy 326.274204 -19.716966)
			(xy 326.282825 -19.66014) (xy 326.299873 -19.60525) (xy 326.324961 -19.553539) (xy 326.357523 -19.506175)
			(xy 326.376792 -19.484848) (xy 326.383396 -19.477736) (xy 326.390508 -19.46021) (xy 326.390508 -19.370802)
			(xy 326.383396 -19.353276) (xy 326.376792 -19.346164) (xy 326.357533 -19.324826) (xy 326.324964 -19.277468)
			(xy 326.299868 -19.225759) (xy 326.282815 -19.170871) (xy 326.27419 -19.114044) (xy 326.273668 -19.085306)
			(xy 326.274154 -19.058055) (xy 326.28191 -19.004107) (xy 326.297265 -18.951812) (xy 326.319907 -18.902235)
			(xy 326.349373 -18.856385) (xy 326.385064 -18.815194) (xy 326.426255 -18.779503) (xy 326.472105 -18.750037)
			(xy 326.521682 -18.727395) (xy 326.573977 -18.71204) (xy 326.627925 -18.704284) (xy 326.682427 -18.704284)
			(xy 326.736375 -18.71204) (xy 326.78867 -18.727395) (xy 326.838247 -18.750037) (xy 326.884097 -18.779503)
			(xy 326.925288 -18.815194) (xy 326.960979 -18.856385) (xy 326.990445 -18.902235) (xy 327.013087 -18.951812)
			(xy 327.028442 -19.004107) (xy 327.036198 -19.058055) (xy 327.036684 -19.085306) (xy 327.036141 -19.114044)
			(xy 327.02752 -19.170869) (xy 327.010473 -19.225759) (xy 326.985386 -19.277471) (xy 326.952827 -19.324835)
			(xy 326.939526 -19.33956) (xy 331.7781 -19.33956) (xy 331.782171 -19.283938) (xy 331.794297 -19.229501)
			(xy 331.81422 -19.17741) (xy 331.841516 -19.128775) (xy 331.875602 -19.084632) (xy 331.915751 -19.045923)
			(xy 331.961109 -19.013472) (xy 332.010709 -18.987971) (xy 332.063493 -18.969964) (xy 332.118336 -18.959834)
			(xy 332.17407 -18.957797) (xy 332.229507 -18.963897) (xy 332.283464 -18.978003) (xy 332.334793 -18.999815)
			(xy 332.382399 -19.028869) (xy 332.425267 -19.064544) (xy 332.462484 -19.106081) (xy 332.493257 -19.152594)
			(xy 332.516929 -19.203091) (xy 332.532997 -19.256498) (xy 332.541117 -19.311674) (xy 332.541626 -19.33956)
			(xy 332.541117 -19.367446) (xy 332.532997 -19.422622) (xy 332.516929 -19.476029) (xy 332.493257 -19.526526)
			(xy 332.462484 -19.573039) (xy 332.425267 -19.614576) (xy 332.382399 -19.650251) (xy 332.334793 -19.679305)
			(xy 332.283464 -19.701117) (xy 332.229507 -19.715223) (xy 332.17407 -19.721323) (xy 332.118336 -19.719286)
			(xy 332.063493 -19.709156) (xy 332.010709 -19.691149) (xy 331.961109 -19.665648) (xy 331.915751 -19.633197)
			(xy 331.875602 -19.594488) (xy 331.841516 -19.550345) (xy 331.81422 -19.50171) (xy 331.794297 -19.449619)
			(xy 331.782171 -19.395182) (xy 331.7781 -19.33956) (xy 326.939526 -19.33956) (xy 326.93356 -19.346164)
			(xy 326.926956 -19.353276) (xy 326.919844 -19.370802) (xy 326.919844 -19.46021) (xy 326.926956 -19.477736)
			(xy 326.93356 -19.484848) (xy 326.952837 -19.506169) (xy 326.985404 -19.553532) (xy 327.010496 -19.605245)
			(xy 327.027547 -19.660137) (xy 327.036169 -19.716965) (xy 327.036168 -19.774444) (xy 327.027545 -19.831272)
			(xy 327.010493 -19.886163) (xy 326.985399 -19.937875) (xy 326.952832 -19.985238) (xy 326.93356 -20.006564)
			(xy 326.926956 -20.013676) (xy 326.919844 -20.031202) (xy 326.919844 -20.12061) (xy 326.926956 -20.138136)
			(xy 326.93356 -20.145248) (xy 326.952837 -20.166569) (xy 326.985404 -20.213932) (xy 327.010496 -20.265645)
			(xy 327.027547 -20.320537) (xy 327.032861 -20.35556) (xy 331.7781 -20.35556) (xy 331.782171 -20.299938)
			(xy 331.794297 -20.245501) (xy 331.81422 -20.19341) (xy 331.841516 -20.144775) (xy 331.875602 -20.100632)
			(xy 331.915751 -20.061923) (xy 331.961109 -20.029472) (xy 332.010709 -20.003971) (xy 332.063493 -19.985964)
			(xy 332.118336 -19.975834) (xy 332.17407 -19.973797) (xy 332.229507 -19.979897) (xy 332.283464 -19.994003)
			(xy 332.334793 -20.015815) (xy 332.382399 -20.044869) (xy 332.425267 -20.080544) (xy 332.462484 -20.122081)
			(xy 332.493257 -20.168594) (xy 332.516929 -20.219091) (xy 332.532997 -20.272498) (xy 332.541117 -20.327674)
			(xy 332.541626 -20.35556) (xy 332.541117 -20.383446) (xy 332.532997 -20.438622) (xy 332.516929 -20.492029)
			(xy 332.493257 -20.542526) (xy 332.462484 -20.589039) (xy 332.425267 -20.630576) (xy 332.382399 -20.666251)
			(xy 332.334793 -20.695305) (xy 332.283464 -20.717117) (xy 332.229507 -20.731223) (xy 332.17407 -20.737323)
			(xy 332.118336 -20.735286) (xy 332.063493 -20.725156) (xy 332.010709 -20.707149) (xy 331.961109 -20.681648)
			(xy 331.915751 -20.649197) (xy 331.875602 -20.610488) (xy 331.841516 -20.566345) (xy 331.81422 -20.51771)
			(xy 331.794297 -20.465619) (xy 331.782171 -20.411182) (xy 331.7781 -20.35556) (xy 327.032861 -20.35556)
			(xy 327.036169 -20.377365) (xy 327.036168 -20.434844) (xy 327.027545 -20.491672) (xy 327.010493 -20.546563)
			(xy 326.985399 -20.598275) (xy 326.952832 -20.645638) (xy 326.93356 -20.666964) (xy 326.926956 -20.674076)
			(xy 326.919844 -20.691602) (xy 326.919844 -20.78101) (xy 326.926956 -20.798536) (xy 326.93356 -20.805648)
			(xy 326.952837 -20.826969) (xy 326.985404 -20.874332) (xy 327.010496 -20.926045) (xy 327.027547 -20.980937)
			(xy 327.036169 -21.037765) (xy 327.036168 -21.095244) (xy 327.027545 -21.152072) (xy 327.010493 -21.206963)
			(xy 326.985399 -21.258675) (xy 326.952832 -21.306038) (xy 326.93356 -21.327364) (xy 326.926956 -21.334476)
			(xy 326.919844 -21.352002) (xy 326.919844 -21.37156) (xy 331.7781 -21.37156) (xy 331.782171 -21.315938)
			(xy 331.794297 -21.261501) (xy 331.81422 -21.20941) (xy 331.841516 -21.160775) (xy 331.875602 -21.116632)
			(xy 331.915751 -21.077923) (xy 331.961109 -21.045472) (xy 332.010709 -21.019971) (xy 332.063493 -21.001964)
			(xy 332.118336 -20.991834) (xy 332.17407 -20.989797) (xy 332.229507 -20.995897) (xy 332.283464 -21.010003)
			(xy 332.334793 -21.031815) (xy 332.382399 -21.060869) (xy 332.425267 -21.096544) (xy 332.462484 -21.138081)
			(xy 332.493257 -21.184594) (xy 332.516929 -21.235091) (xy 332.532997 -21.288498) (xy 332.541117 -21.343674)
			(xy 332.541626 -21.37156) (xy 332.541117 -21.399446) (xy 332.532997 -21.454622) (xy 332.516929 -21.508029)
			(xy 332.493257 -21.558526) (xy 332.462484 -21.605039) (xy 332.425267 -21.646576) (xy 332.382399 -21.682251)
			(xy 332.334793 -21.711305) (xy 332.283464 -21.733117) (xy 332.229507 -21.747223) (xy 332.17407 -21.753323)
			(xy 332.118336 -21.751286) (xy 332.063493 -21.741156) (xy 332.010709 -21.723149) (xy 331.961109 -21.697648)
			(xy 331.915751 -21.665197) (xy 331.875602 -21.626488) (xy 331.841516 -21.582345) (xy 331.81422 -21.53371)
			(xy 331.794297 -21.481619) (xy 331.782171 -21.427182) (xy 331.7781 -21.37156) (xy 326.919844 -21.37156)
			(xy 326.919844 -21.44141) (xy 326.926956 -21.458936) (xy 326.93356 -21.466048) (xy 326.952833 -21.487373)
			(xy 326.985399 -21.534735) (xy 327.010491 -21.586448) (xy 327.027541 -21.641339) (xy 327.036163 -21.698167)
			(xy 327.036684 -21.726906) (xy 327.036198 -21.754157) (xy 327.028442 -21.808105) (xy 327.013087 -21.8604)
			(xy 326.990445 -21.909977) (xy 326.960979 -21.955827) (xy 326.925288 -21.997018) (xy 326.884097 -22.032709)
			(xy 326.838247 -22.062175) (xy 326.78867 -22.084817) (xy 326.736375 -22.100172) (xy 326.682427 -22.107928)
			(xy 326.627925 -22.107928) (xy 326.573977 -22.100172) (xy 326.521682 -22.084817) (xy 326.472105 -22.062175)
			(xy 326.426255 -22.032709) (xy 326.385064 -21.997018) (xy 326.349373 -21.955827) (xy 326.319907 -21.909977)
			(xy 326.297265 -21.8604) (xy 326.28191 -21.808105) (xy 326.274154 -21.754157) (xy 326.273668 -21.726906)
			(xy 322.379388 -21.726906) (xy 322.379594 -21.738336) (xy 322.379108 -21.765587) (xy 322.371352 -21.819535)
			(xy 322.355997 -21.87183) (xy 322.333355 -21.921407) (xy 322.303889 -21.967257) (xy 322.268198 -22.008448)
			(xy 322.227007 -22.044139) (xy 322.181157 -22.073605) (xy 322.13158 -22.096247) (xy 322.079285 -22.111602)
			(xy 322.025337 -22.119358) (xy 321.970835 -22.119358) (xy 321.916887 -22.111602) (xy 321.864592 -22.096247)
			(xy 321.815015 -22.073605) (xy 321.769165 -22.044139) (xy 321.727974 -22.008448) (xy 321.692283 -21.967257)
			(xy 321.662817 -21.921407) (xy 321.640175 -21.87183) (xy 321.62482 -21.819535) (xy 321.617064 -21.765587)
			(xy 321.616578 -21.738336) (xy 319.392984 -21.738336) (xy 319.369263 -21.783021) (xy 319.301322 -21.894082)
			(xy 319.226736 -22.000794) (xy 319.145783 -22.102761) (xy 319.058764 -22.199603) (xy 318.966003 -22.29096)
			(xy 318.867845 -22.376492) (xy 318.764656 -22.45588) (xy 318.656819 -22.52883) (xy 318.544734 -22.595071)
			(xy 318.428821 -22.654354) (xy 318.309508 -22.706462) (xy 318.187241 -22.751198) (xy 318.062474 -22.788397)
			(xy 317.935671 -22.817921) (xy 317.807304 -22.839659) (xy 317.677851 -22.853532) (xy 317.547792 -22.859486)
			(xy 317.417613 -22.857501) (xy 317.287797 -22.847583) (xy 317.158827 -22.829769) (xy 317.031182 -22.804126)
			(xy 316.905339 -22.770749) (xy 316.781764 -22.729762) (xy 316.660918 -22.681318) (xy 316.54325 -22.625596)
			(xy 316.429198 -22.562805) (xy 316.319186 -22.493178) (xy 316.213624 -22.416973) (xy 316.112904 -22.334474)
			(xy 316.0174 -22.245989) (xy 315.927468 -22.151846) (xy 315.843443 -22.052395) (xy 315.765638 -21.948007)
			(xy 315.694341 -21.83907) (xy 315.629817 -21.725988) (xy 315.572308 -21.609184) (xy 315.522026 -21.489091)
			(xy 315.47916 -21.366155) (xy 315.443867 -21.240836) (xy 315.416281 -21.113597) (xy 315.396502 -20.984914)
			(xy 315.384606 -20.855264) (xy 315.380636 -20.72513) (xy 311.615836 -20.72513) (xy 311.615836 -21.487892)
			(xy 311.616008 -21.494044) (xy 311.618967 -21.505988) (xy 311.621678 -21.511514) (xy 311.634886 -21.53666)
			(xy 311.642252 -21.545296) (xy 311.646824 -21.548598) (xy 311.668654 -21.565281) (xy 311.707748 -21.603883)
			(xy 311.740901 -21.647693) (xy 311.767426 -21.695807) (xy 311.786775 -21.747227) (xy 311.798547 -21.800892)
			(xy 311.801876 -21.847048) (xy 312.272678 -21.847048) (xy 312.276749 -21.791426) (xy 312.288875 -21.736989)
			(xy 312.308798 -21.684898) (xy 312.336094 -21.636263) (xy 312.37018 -21.59212) (xy 312.410329 -21.553411)
			(xy 312.455687 -21.52096) (xy 312.505287 -21.495459) (xy 312.558071 -21.477452) (xy 312.612914 -21.467322)
			(xy 312.668648 -21.465285) (xy 312.724085 -21.471385) (xy 312.778042 -21.485491) (xy 312.829371 -21.507303)
			(xy 312.876977 -21.536357) (xy 312.919845 -21.572032) (xy 312.957062 -21.613569) (xy 312.987835 -21.660082)
			(xy 313.011507 -21.710579) (xy 313.027575 -21.763986) (xy 313.035695 -21.819162) (xy 313.036204 -21.847048)
			(xy 313.035695 -21.874934) (xy 313.027575 -21.93011) (xy 313.011507 -21.983517) (xy 312.987835 -22.034014)
			(xy 312.957062 -22.080527) (xy 312.919845 -22.122064) (xy 312.876977 -22.157739) (xy 312.829371 -22.186793)
			(xy 312.778042 -22.208605) (xy 312.724085 -22.222711) (xy 312.668648 -22.228811) (xy 312.612914 -22.226774)
			(xy 312.558071 -22.216644) (xy 312.505287 -22.198637) (xy 312.455687 -22.173136) (xy 312.410329 -22.140685)
			(xy 312.37018 -22.101976) (xy 312.336094 -22.057833) (xy 312.308798 -22.009198) (xy 312.288875 -21.957107)
			(xy 312.276749 -21.90267) (xy 312.272678 -21.847048) (xy 311.801876 -21.847048) (xy 311.802499 -21.85569)
			(xy 311.79855 -21.910489) (xy 311.78678 -21.964154) (xy 311.767434 -22.015576) (xy 311.740911 -22.063691)
			(xy 311.707761 -22.107503) (xy 311.668668 -22.146107) (xy 311.646824 -22.16277) (xy 311.642252 -22.166072)
			(xy 311.634886 -22.174708) (xy 311.621678 -22.199854) (xy 311.61898 -22.205385) (xy 311.616021 -22.217325)
			(xy 311.615836 -22.223476) (xy 311.615836 -23.0251) (xy 321.56222 -23.0251) (xy 321.566291 -22.969478)
			(xy 321.578417 -22.915041) (xy 321.59834 -22.86295) (xy 321.625636 -22.814315) (xy 321.659722 -22.770172)
			(xy 321.699871 -22.731463) (xy 321.745229 -22.699012) (xy 321.794829 -22.673511) (xy 321.847613 -22.655504)
			(xy 321.902456 -22.645374) (xy 321.95819 -22.643337) (xy 322.013627 -22.649437) (xy 322.067584 -22.663543)
			(xy 322.118913 -22.685355) (xy 322.166519 -22.714409) (xy 322.209387 -22.750084) (xy 322.246604 -22.791621)
			(xy 322.277377 -22.838134) (xy 322.301049 -22.888631) (xy 322.317117 -22.942038) (xy 322.325237 -22.997214)
			(xy 322.325746 -23.0251) (xy 322.325237 -23.052986) (xy 322.317117 -23.108162) (xy 322.301049 -23.161569)
			(xy 322.277377 -23.212066) (xy 322.246604 -23.258579) (xy 322.209387 -23.300116) (xy 322.166519 -23.335791)
			(xy 322.118913 -23.364845) (xy 322.067584 -23.386657) (xy 322.013627 -23.400763) (xy 321.95819 -23.406863)
			(xy 321.902456 -23.404826) (xy 321.847613 -23.394696) (xy 321.794829 -23.376689) (xy 321.745229 -23.351188)
			(xy 321.699871 -23.318737) (xy 321.659722 -23.280028) (xy 321.625636 -23.235885) (xy 321.59834 -23.18725)
			(xy 321.578417 -23.135159) (xy 321.566291 -23.080722) (xy 321.56222 -23.0251) (xy 311.615836 -23.0251)
			(xy 311.615836 -23.504144) (xy 311.623456 -23.522178) (xy 311.630568 -23.529544) (xy 311.658508 -23.557738)
			(xy 311.675272 -23.565358) (xy 311.684924 -23.56612) (xy 311.71368 -23.568365) (xy 311.770083 -23.580427)
			(xy 311.824027 -23.60084) (xy 311.874285 -23.62914) (xy 311.91971 -23.664682) (xy 311.959269 -23.706656)
			(xy 311.992059 -23.754107) (xy 312.017334 -23.805951) (xy 312.034518 -23.86101) (xy 312.043219 -23.918027)
			(xy 312.043826 -23.946866) (xy 312.04408 -23.946866) (xy 312.043642 -23.970996) (xy 312.272678 -23.970996)
			(xy 312.276749 -23.915374) (xy 312.288875 -23.860937) (xy 312.308798 -23.808846) (xy 312.336094 -23.760211)
			(xy 312.37018 -23.716068) (xy 312.410329 -23.677359) (xy 312.455687 -23.644908) (xy 312.505287 -23.619407)
			(xy 312.558071 -23.6014) (xy 312.612914 -23.59127) (xy 312.668648 -23.589233) (xy 312.724085 -23.595333)
			(xy 312.778042 -23.609439) (xy 312.781318 -23.610831) (xy 322.265823 -23.610831) (xy 322.265825 -23.556336)
			(xy 322.273583 -23.502397) (xy 322.288938 -23.45011) (xy 322.311577 -23.400541) (xy 322.34104 -23.354698)
			(xy 322.376728 -23.313515) (xy 322.417913 -23.277829) (xy 322.463757 -23.248368) (xy 322.513328 -23.225731)
			(xy 322.565615 -23.210379) (xy 322.619555 -23.202624) (xy 322.646802 -23.202138) (xy 322.670831 -23.202515)
			(xy 322.718509 -23.208553) (xy 322.76505 -23.220534) (xy 322.787518 -23.229062) (xy 322.800678 -23.233824)
			(xy 322.828502 -23.236729) (xy 322.856071 -23.231979) (xy 322.881319 -23.21993) (xy 322.902354 -23.201486)
			(xy 322.917598 -23.178029) (xy 322.925909 -23.151316) (xy 322.926664 -23.123351) (xy 322.923662 -23.109682)
			(xy 322.918211 -23.086699) (xy 322.91235 -23.039828) (xy 322.911978 -23.01621) (xy 322.912444 -22.988956)
			(xy 322.9202 -22.935003) (xy 322.935556 -22.882702) (xy 322.958198 -22.83312) (xy 322.987666 -22.787264)
			(xy 323.023361 -22.746069) (xy 323.064555 -22.710374) (xy 323.110409 -22.680904) (xy 323.159991 -22.65826)
			(xy 323.212291 -22.642903) (xy 323.266244 -22.635145) (xy 323.320752 -22.635145) (xy 323.374705 -22.642902)
			(xy 323.427005 -22.658258) (xy 323.476587 -22.680902) (xy 323.522442 -22.710371) (xy 323.563636 -22.746066)
			(xy 323.599331 -22.787261) (xy 323.6288 -22.833116) (xy 323.651443 -22.882699) (xy 323.666799 -22.934999)
			(xy 323.674556 -22.988952) (xy 323.674555 -23.04346) (xy 323.666796 -23.097413) (xy 323.651439 -23.149713)
			(xy 323.628794 -23.199294) (xy 323.599324 -23.245149) (xy 323.563628 -23.286342) (xy 323.522433 -23.322036)
			(xy 323.476577 -23.351504) (xy 323.426994 -23.374146) (xy 323.374693 -23.389501) (xy 323.32074 -23.397256)
			(xy 323.293486 -23.397718) (xy 323.269457 -23.397341) (xy 323.221779 -23.391302) (xy 323.175238 -23.379322)
			(xy 323.15277 -23.370794) (xy 323.1396 -23.36607) (xy 323.111784 -23.363171) (xy 323.084224 -23.367922)
			(xy 323.058984 -23.379966) (xy 323.037955 -23.398403) (xy 323.022711 -23.42185) (xy 323.014395 -23.448552)
			(xy 323.01363 -23.476508) (xy 323.016626 -23.490174) (xy 323.022086 -23.513155) (xy 323.027942 -23.560028)
			(xy 323.02831 -23.583646) (xy 323.028185 -23.589996) (xy 326.284334 -23.589996) (xy 326.288405 -23.534374)
			(xy 326.300531 -23.479937) (xy 326.320454 -23.427846) (xy 326.34775 -23.379211) (xy 326.381836 -23.335068)
			(xy 326.421985 -23.296359) (xy 326.467343 -23.263908) (xy 326.516943 -23.238407) (xy 326.569727 -23.2204)
			(xy 326.62457 -23.21027) (xy 326.680304 -23.208233) (xy 326.735741 -23.214333) (xy 326.789698 -23.228439)
			(xy 326.841027 -23.250251) (xy 326.888633 -23.279305) (xy 326.931501 -23.31498) (xy 326.968718 -23.356517)
			(xy 326.999491 -23.40303) (xy 327.023163 -23.453527) (xy 327.039231 -23.506934) (xy 327.047351 -23.56211)
			(xy 327.04786 -23.589996) (xy 327.047351 -23.617882) (xy 327.039231 -23.673058) (xy 327.023163 -23.726465)
			(xy 326.999491 -23.776962) (xy 326.968718 -23.823475) (xy 326.931501 -23.865012) (xy 326.913109 -23.880318)
			(xy 327.440542 -23.880318) (xy 327.444613 -23.824696) (xy 327.456739 -23.770259) (xy 327.476662 -23.718168)
			(xy 327.503958 -23.669533) (xy 327.538044 -23.62539) (xy 327.578193 -23.586681) (xy 327.623551 -23.55423)
			(xy 327.673151 -23.528729) (xy 327.725935 -23.510722) (xy 327.780778 -23.500592) (xy 327.836512 -23.498555)
			(xy 327.891949 -23.504655) (xy 327.945906 -23.518761) (xy 327.997235 -23.540573) (xy 328.044841 -23.569627)
			(xy 328.087709 -23.605302) (xy 328.124926 -23.646839) (xy 328.155699 -23.693352) (xy 328.179371 -23.743849)
			(xy 328.195439 -23.797256) (xy 328.203559 -23.852432) (xy 328.204068 -23.880318) (xy 328.456542 -23.880318)
			(xy 328.460613 -23.824696) (xy 328.472739 -23.770259) (xy 328.492662 -23.718168) (xy 328.519958 -23.669533)
			(xy 328.554044 -23.62539) (xy 328.594193 -23.586681) (xy 328.639551 -23.55423) (xy 328.689151 -23.528729)
			(xy 328.741935 -23.510722) (xy 328.796778 -23.500592) (xy 328.852512 -23.498555) (xy 328.907949 -23.504655)
			(xy 328.961906 -23.518761) (xy 329.013235 -23.540573) (xy 329.060841 -23.569627) (xy 329.103709 -23.605302)
			(xy 329.140926 -23.646839) (xy 329.171699 -23.693352) (xy 329.195371 -23.743849) (xy 329.211439 -23.797256)
			(xy 329.219559 -23.852432) (xy 329.220068 -23.880318) (xy 329.472542 -23.880318) (xy 329.476613 -23.824696)
			(xy 329.488739 -23.770259) (xy 329.508662 -23.718168) (xy 329.535958 -23.669533) (xy 329.570044 -23.62539)
			(xy 329.610193 -23.586681) (xy 329.655551 -23.55423) (xy 329.705151 -23.528729) (xy 329.757935 -23.510722)
			(xy 329.812778 -23.500592) (xy 329.868512 -23.498555) (xy 329.923949 -23.504655) (xy 329.977906 -23.518761)
			(xy 330.029235 -23.540573) (xy 330.076841 -23.569627) (xy 330.119709 -23.605302) (xy 330.156926 -23.646839)
			(xy 330.187699 -23.693352) (xy 330.211371 -23.743849) (xy 330.227439 -23.797256) (xy 330.235559 -23.852432)
			(xy 330.236068 -23.880318) (xy 330.490828 -23.880318) (xy 330.494899 -23.824696) (xy 330.507025 -23.770259)
			(xy 330.526948 -23.718168) (xy 330.554244 -23.669533) (xy 330.58833 -23.62539) (xy 330.628479 -23.586681)
			(xy 330.673837 -23.55423) (xy 330.723437 -23.528729) (xy 330.776221 -23.510722) (xy 330.831064 -23.500592)
			(xy 330.886798 -23.498555) (xy 330.942235 -23.504655) (xy 330.996192 -23.518761) (xy 331.047521 -23.540573)
			(xy 331.095127 -23.569627) (xy 331.137995 -23.605302) (xy 331.175212 -23.646839) (xy 331.205985 -23.693352)
			(xy 331.229657 -23.743849) (xy 331.245725 -23.797256) (xy 331.253845 -23.852432) (xy 331.254354 -23.880318)
			(xy 331.253845 -23.908204) (xy 331.245725 -23.96338) (xy 331.229657 -24.016787) (xy 331.205985 -24.067284)
			(xy 331.175212 -24.113797) (xy 331.137995 -24.155334) (xy 331.095127 -24.191009) (xy 331.047521 -24.220063)
			(xy 330.996192 -24.241875) (xy 330.942235 -24.255981) (xy 330.886798 -24.262081) (xy 330.831064 -24.260044)
			(xy 330.776221 -24.249914) (xy 330.723437 -24.231907) (xy 330.673837 -24.206406) (xy 330.628479 -24.173955)
			(xy 330.58833 -24.135246) (xy 330.554244 -24.091103) (xy 330.526948 -24.042468) (xy 330.507025 -23.990377)
			(xy 330.494899 -23.93594) (xy 330.490828 -23.880318) (xy 330.236068 -23.880318) (xy 330.235559 -23.908204)
			(xy 330.227439 -23.96338) (xy 330.211371 -24.016787) (xy 330.187699 -24.067284) (xy 330.156926 -24.113797)
			(xy 330.119709 -24.155334) (xy 330.076841 -24.191009) (xy 330.029235 -24.220063) (xy 329.977906 -24.241875)
			(xy 329.923949 -24.255981) (xy 329.868512 -24.262081) (xy 329.812778 -24.260044) (xy 329.757935 -24.249914)
			(xy 329.705151 -24.231907) (xy 329.655551 -24.206406) (xy 329.610193 -24.173955) (xy 329.570044 -24.135246)
			(xy 329.535958 -24.091103) (xy 329.508662 -24.042468) (xy 329.488739 -23.990377) (xy 329.476613 -23.93594)
			(xy 329.472542 -23.880318) (xy 329.220068 -23.880318) (xy 329.219559 -23.908204) (xy 329.211439 -23.96338)
			(xy 329.195371 -24.016787) (xy 329.171699 -24.067284) (xy 329.140926 -24.113797) (xy 329.103709 -24.155334)
			(xy 329.060841 -24.191009) (xy 329.013235 -24.220063) (xy 328.961906 -24.241875) (xy 328.907949 -24.255981)
			(xy 328.852512 -24.262081) (xy 328.796778 -24.260044) (xy 328.741935 -24.249914) (xy 328.689151 -24.231907)
			(xy 328.639551 -24.206406) (xy 328.594193 -24.173955) (xy 328.554044 -24.135246) (xy 328.519958 -24.091103)
			(xy 328.492662 -24.042468) (xy 328.472739 -23.990377) (xy 328.460613 -23.93594) (xy 328.456542 -23.880318)
			(xy 328.204068 -23.880318) (xy 328.203559 -23.908204) (xy 328.195439 -23.96338) (xy 328.179371 -24.016787)
			(xy 328.155699 -24.067284) (xy 328.124926 -24.113797) (xy 328.087709 -24.155334) (xy 328.044841 -24.191009)
			(xy 327.997235 -24.220063) (xy 327.945906 -24.241875) (xy 327.891949 -24.255981) (xy 327.836512 -24.262081)
			(xy 327.780778 -24.260044) (xy 327.725935 -24.249914) (xy 327.673151 -24.231907) (xy 327.623551 -24.206406)
			(xy 327.578193 -24.173955) (xy 327.538044 -24.135246) (xy 327.503958 -24.091103) (xy 327.476662 -24.042468)
			(xy 327.456739 -23.990377) (xy 327.444613 -23.93594) (xy 327.440542 -23.880318) (xy 326.913109 -23.880318)
			(xy 326.888633 -23.900687) (xy 326.841027 -23.929741) (xy 326.789698 -23.951553) (xy 326.735741 -23.965659)
			(xy 326.680304 -23.971759) (xy 326.62457 -23.969722) (xy 326.569727 -23.959592) (xy 326.516943 -23.941585)
			(xy 326.467343 -23.916084) (xy 326.421985 -23.883633) (xy 326.381836 -23.844924) (xy 326.34775 -23.800781)
			(xy 326.320454 -23.752146) (xy 326.300531 -23.700055) (xy 326.288405 -23.645618) (xy 326.284334 -23.589996)
			(xy 323.028185 -23.589996) (xy 323.027773 -23.610893) (xy 323.020011 -23.664832) (xy 323.004652 -23.717118)
			(xy 322.982009 -23.766685) (xy 322.952542 -23.812526) (xy 322.916851 -23.853706) (xy 322.875664 -23.889388)
			(xy 322.829817 -23.918846) (xy 322.780245 -23.941479) (xy 322.727956 -23.956827) (xy 322.674016 -23.964578)
			(xy 322.619521 -23.964574) (xy 322.565582 -23.956814) (xy 322.513296 -23.941457) (xy 322.463728 -23.918816)
			(xy 322.417886 -23.889351) (xy 322.376704 -23.853662) (xy 322.34102 -23.812475) (xy 322.311561 -23.76663)
			(xy 322.288926 -23.717059) (xy 322.273576 -23.664771) (xy 322.265823 -23.610831) (xy 312.781318 -23.610831)
			(xy 312.829371 -23.631251) (xy 312.876977 -23.660305) (xy 312.919845 -23.69598) (xy 312.957062 -23.737517)
			(xy 312.987835 -23.78403) (xy 313.011507 -23.834527) (xy 313.027575 -23.887934) (xy 313.035695 -23.94311)
			(xy 313.036204 -23.970996) (xy 313.035695 -23.998882) (xy 313.027575 -24.054058) (xy 313.011507 -24.107465)
			(xy 312.987835 -24.157962) (xy 312.987682 -24.158194) (xy 317.65062 -24.158194) (xy 317.654691 -24.102572)
			(xy 317.666817 -24.048135) (xy 317.68674 -23.996044) (xy 317.714036 -23.947409) (xy 317.748122 -23.903266)
			(xy 317.788271 -23.864557) (xy 317.833629 -23.832106) (xy 317.883229 -23.806605) (xy 317.936013 -23.788598)
			(xy 317.990856 -23.778468) (xy 318.04659 -23.776431) (xy 318.102027 -23.782531) (xy 318.155984 -23.796637)
			(xy 318.207313 -23.818449) (xy 318.254919 -23.847503) (xy 318.297787 -23.883178) (xy 318.335004 -23.924715)
			(xy 318.365777 -23.971228) (xy 318.389449 -24.021725) (xy 318.405517 -24.075132) (xy 318.413637 -24.130308)
			(xy 318.414146 -24.158194) (xy 318.413637 -24.18608) (xy 318.413068 -24.189944) (xy 321.49872 -24.189944)
			(xy 321.502791 -24.134322) (xy 321.514917 -24.079885) (xy 321.53484 -24.027794) (xy 321.562136 -23.979159)
			(xy 321.596222 -23.935016) (xy 321.636371 -23.896307) (xy 321.681729 -23.863856) (xy 321.731329 -23.838355)
			(xy 321.784113 -23.820348) (xy 321.838956 -23.810218) (xy 321.89469 -23.808181) (xy 321.950127 -23.814281)
			(xy 322.004084 -23.828387) (xy 322.055413 -23.850199) (xy 322.103019 -23.879253) (xy 322.145887 -23.914928)
			(xy 322.183104 -23.956465) (xy 322.213877 -24.002978) (xy 322.237549 -24.053475) (xy 322.253617 -24.106882)
			(xy 322.261737 -24.162058) (xy 322.262246 -24.189944) (xy 324.021702 -24.189944) (xy 324.025773 -24.134322)
			(xy 324.037899 -24.079885) (xy 324.057822 -24.027794) (xy 324.085118 -23.979159) (xy 324.119204 -23.935016)
			(xy 324.159353 -23.896307) (xy 324.204711 -23.863856) (xy 324.254311 -23.838355) (xy 324.307095 -23.820348)
			(xy 324.361938 -23.810218) (xy 324.417672 -23.808181) (xy 324.473109 -23.814281) (xy 324.527066 -23.828387)
			(xy 324.578395 -23.850199) (xy 324.626001 -23.879253) (xy 324.668869 -23.914928) (xy 324.706086 -23.956465)
			(xy 324.736859 -24.002978) (xy 324.760531 -24.053475) (xy 324.776599 -24.106882) (xy 324.784719 -24.162058)
			(xy 324.785228 -24.189944) (xy 324.784719 -24.21783) (xy 324.776599 -24.273006) (xy 324.760531 -24.326413)
			(xy 324.736859 -24.37691) (xy 324.706086 -24.423423) (xy 324.668869 -24.46496) (xy 324.626001 -24.500635)
			(xy 324.578395 -24.529689) (xy 324.527066 -24.551501) (xy 324.473109 -24.565607) (xy 324.417672 -24.571707)
			(xy 324.361938 -24.56967) (xy 324.307095 -24.55954) (xy 324.254311 -24.541533) (xy 324.204711 -24.516032)
			(xy 324.159353 -24.483581) (xy 324.119204 -24.444872) (xy 324.085118 -24.400729) (xy 324.057822 -24.352094)
			(xy 324.037899 -24.300003) (xy 324.025773 -24.245566) (xy 324.021702 -24.189944) (xy 322.262246 -24.189944)
			(xy 322.261737 -24.21783) (xy 322.253617 -24.273006) (xy 322.237549 -24.326413) (xy 322.213877 -24.37691)
			(xy 322.183104 -24.423423) (xy 322.145887 -24.46496) (xy 322.103019 -24.500635) (xy 322.055413 -24.529689)
			(xy 322.004084 -24.551501) (xy 321.950127 -24.565607) (xy 321.89469 -24.571707) (xy 321.838956 -24.56967)
			(xy 321.784113 -24.55954) (xy 321.731329 -24.541533) (xy 321.681729 -24.516032) (xy 321.636371 -24.483581)
			(xy 321.596222 -24.444872) (xy 321.562136 -24.400729) (xy 321.53484 -24.352094) (xy 321.514917 -24.300003)
			(xy 321.502791 -24.245566) (xy 321.49872 -24.189944) (xy 318.413068 -24.189944) (xy 318.405517 -24.241256)
			(xy 318.389449 -24.294663) (xy 318.365777 -24.34516) (xy 318.335004 -24.391673) (xy 318.297787 -24.43321)
			(xy 318.254919 -24.468885) (xy 318.207313 -24.497939) (xy 318.155984 -24.519751) (xy 318.102027 -24.533857)
			(xy 318.04659 -24.539957) (xy 317.990856 -24.53792) (xy 317.936013 -24.52779) (xy 317.883229 -24.509783)
			(xy 317.833629 -24.484282) (xy 317.788271 -24.451831) (xy 317.748122 -24.413122) (xy 317.714036 -24.368979)
			(xy 317.68674 -24.320344) (xy 317.666817 -24.268253) (xy 317.654691 -24.213816) (xy 317.65062 -24.158194)
			(xy 312.987682 -24.158194) (xy 312.957062 -24.204475) (xy 312.919845 -24.246012) (xy 312.876977 -24.281687)
			(xy 312.829371 -24.310741) (xy 312.778042 -24.332553) (xy 312.724085 -24.346659) (xy 312.668648 -24.352759)
			(xy 312.612914 -24.350722) (xy 312.558071 -24.340592) (xy 312.505287 -24.322585) (xy 312.455687 -24.297084)
			(xy 312.410329 -24.264633) (xy 312.37018 -24.225924) (xy 312.336094 -24.181781) (xy 312.308798 -24.133146)
			(xy 312.288875 -24.081055) (xy 312.276749 -24.026618) (xy 312.272678 -23.970996) (xy 312.043642 -23.970996)
			(xy 312.043566 -23.975194) (xy 312.035194 -24.031229) (xy 312.018628 -24.085409) (xy 311.994233 -24.136545)
			(xy 311.962545 -24.183511) (xy 311.924261 -24.225275) (xy 311.880223 -24.26092) (xy 311.831398 -24.289662)
			(xy 311.77886 -24.310867) (xy 311.723763 -24.324072) (xy 311.695592 -24.327104) (xy 311.684416 -24.327866)
			(xy 311.675018 -24.332692) (xy 311.671129 -24.334797) (xy 311.664098 -24.340158) (xy 311.661048 -24.34336)
			(xy 311.614312 -24.393906) (xy 311.608122 -24.401163) (xy 311.601194 -24.418918) (xy 311.60085 -24.42845)
			(xy 311.60085 -24.807418) (xy 318.820036 -24.807418) (xy 318.824107 -24.751796) (xy 318.836233 -24.697359)
			(xy 318.856156 -24.645268) (xy 318.883452 -24.596633) (xy 318.917538 -24.55249) (xy 318.957687 -24.513781)
			(xy 319.003045 -24.48133) (xy 319.052645 -24.455829) (xy 319.105429 -24.437822) (xy 319.160272 -24.427692)
			(xy 319.216006 -24.425655) (xy 319.271443 -24.431755) (xy 319.3254 -24.445861) (xy 319.376729 -24.467673)
			(xy 319.424335 -24.496727) (xy 319.467203 -24.532402) (xy 319.50442 -24.573939) (xy 319.535193 -24.620452)
			(xy 319.558865 -24.670949) (xy 319.574933 -24.724356) (xy 319.57998 -24.75865) (xy 331.068424 -24.75865)
			(xy 331.072495 -24.703028) (xy 331.084621 -24.648591) (xy 331.104544 -24.5965) (xy 331.13184 -24.547865)
			(xy 331.165926 -24.503722) (xy 331.206075 -24.465013) (xy 331.251433 -24.432562) (xy 331.301033 -24.407061)
			(xy 331.353817 -24.389054) (xy 331.40866 -24.378924) (xy 331.464394 -24.376887) (xy 331.519831 -24.382987)
			(xy 331.573788 -24.397093) (xy 331.625117 -24.418905) (xy 331.672723 -24.447959) (xy 331.715591 -24.483634)
			(xy 331.752808 -24.525171) (xy 331.783581 -24.571684) (xy 331.807253 -24.622181) (xy 331.823321 -24.675588)
			(xy 331.831441 -24.730764) (xy 331.83195 -24.75865) (xy 331.831441 -24.786536) (xy 331.823321 -24.841712)
			(xy 331.807253 -24.895119) (xy 331.783581 -24.945616) (xy 331.752808 -24.992129) (xy 331.715591 -25.033666)
			(xy 331.672723 -25.069341) (xy 331.625117 -25.098395) (xy 331.573788 -25.120207) (xy 331.519831 -25.134313)
			(xy 331.464394 -25.140413) (xy 331.40866 -25.138376) (xy 331.353817 -25.128246) (xy 331.301033 -25.110239)
			(xy 331.251433 -25.084738) (xy 331.206075 -25.052287) (xy 331.165926 -25.013578) (xy 331.13184 -24.969435)
			(xy 331.104544 -24.9208) (xy 331.084621 -24.868709) (xy 331.072495 -24.814272) (xy 331.068424 -24.75865)
			(xy 319.57998 -24.75865) (xy 319.583053 -24.779532) (xy 319.583562 -24.807418) (xy 319.583053 -24.835304)
			(xy 319.574933 -24.89048) (xy 319.558865 -24.943887) (xy 319.535193 -24.994384) (xy 319.50442 -25.040897)
			(xy 319.467203 -25.082434) (xy 319.424335 -25.118109) (xy 319.376729 -25.147163) (xy 319.3254 -25.168975)
			(xy 319.271443 -25.183081) (xy 319.216006 -25.189181) (xy 319.160272 -25.187144) (xy 319.105429 -25.177014)
			(xy 319.052645 -25.159007) (xy 319.003045 -25.133506) (xy 318.957687 -25.101055) (xy 318.917538 -25.062346)
			(xy 318.883452 -25.018203) (xy 318.856156 -24.969568) (xy 318.836233 -24.917477) (xy 318.824107 -24.86304)
			(xy 318.820036 -24.807418) (xy 311.60085 -24.807418) (xy 311.60085 -25.390094) (xy 324.009512 -25.390094)
			(xy 324.009998 -25.362843) (xy 324.017754 -25.308895) (xy 324.033109 -25.2566) (xy 324.055751 -25.207023)
			(xy 324.085217 -25.161173) (xy 324.120908 -25.119982) (xy 324.162099 -25.084291) (xy 324.207949 -25.054825)
			(xy 324.257526 -25.032183) (xy 324.309821 -25.016828) (xy 324.363769 -25.009072) (xy 324.418271 -25.009072)
			(xy 324.472219 -25.016828) (xy 324.524514 -25.032183) (xy 324.574091 -25.054825) (xy 324.619941 -25.084291)
			(xy 324.661132 -25.119982) (xy 324.696823 -25.161173) (xy 324.726289 -25.207023) (xy 324.748931 -25.2566)
			(xy 324.764286 -25.308895) (xy 324.772042 -25.362843) (xy 324.772528 -25.390094) (xy 324.771965 -25.419114)
			(xy 324.763175 -25.476485) (xy 324.745795 -25.531863) (xy 324.720229 -25.583969) (xy 324.687064 -25.631601)
			(xy 324.647067 -25.67366) (xy 324.624446 -25.691846) (xy 324.613907 -25.70062) (xy 324.597474 -25.722556)
			(xy 324.587474 -25.748075) (xy 324.584629 -25.775336) (xy 324.589144 -25.80237) (xy 324.600693 -25.827227)
			(xy 324.618443 -25.848111) (xy 324.629526 -25.856184) (xy 324.651171 -25.871498) (xy 324.690426 -25.907138)
			(xy 324.724367 -25.94787) (xy 324.752341 -25.992911) (xy 324.773806 -26.041392) (xy 324.788351 -26.092378)
			(xy 324.795694 -26.144888) (xy 324.79615 -26.171398) (xy 324.795664 -26.198649) (xy 324.787908 -26.252597)
			(xy 324.772553 -26.304892) (xy 324.749911 -26.354469) (xy 324.720445 -26.400319) (xy 324.684754 -26.44151)
			(xy 324.643563 -26.477201) (xy 324.597713 -26.506667) (xy 324.548136 -26.529309) (xy 324.495841 -26.544664)
			(xy 324.441893 -26.55242) (xy 324.387391 -26.55242) (xy 324.333443 -26.544664) (xy 324.281148 -26.529309)
			(xy 324.231571 -26.506667) (xy 324.185721 -26.477201) (xy 324.14453 -26.44151) (xy 324.108839 -26.400319)
			(xy 324.079373 -26.354469) (xy 324.056731 -26.304892) (xy 324.041376 -26.252597) (xy 324.03362 -26.198649)
			(xy 324.033134 -26.171398) (xy 324.033706 -26.142378) (xy 324.042496 -26.085008) (xy 324.059875 -26.029632)
			(xy 324.08544 -25.977526) (xy 324.118602 -25.929894) (xy 324.158596 -25.887834) (xy 324.181216 -25.869646)
			(xy 324.191768 -25.860885) (xy 324.208207 -25.838947) (xy 324.218211 -25.813425) (xy 324.221056 -25.786159)
			(xy 324.216538 -25.759121) (xy 324.204982 -25.734262) (xy 324.187224 -25.713378) (xy 324.176136 -25.705308)
			(xy 324.154502 -25.68998) (xy 324.115243 -25.654345) (xy 324.081299 -25.613616) (xy 324.053323 -25.568577)
			(xy 324.031856 -25.520098) (xy 324.01731 -25.469113) (xy 324.009967 -25.416604) (xy 324.009512 -25.390094)
			(xy 311.60085 -25.390094) (xy 311.60085 -25.971246) (xy 312.159648 -25.971246) (xy 312.163719 -25.915624)
			(xy 312.175845 -25.861187) (xy 312.195768 -25.809096) (xy 312.223064 -25.760461) (xy 312.25715 -25.716318)
			(xy 312.297299 -25.677609) (xy 312.342657 -25.645158) (xy 312.392257 -25.619657) (xy 312.445041 -25.60165)
			(xy 312.499884 -25.59152) (xy 312.555618 -25.589483) (xy 312.611055 -25.595583) (xy 312.665012 -25.609689)
			(xy 312.716341 -25.631501) (xy 312.763947 -25.660555) (xy 312.806815 -25.69623) (xy 312.844032 -25.737767)
			(xy 312.874805 -25.78428) (xy 312.898477 -25.834777) (xy 312.914545 -25.888184) (xy 312.922665 -25.94336)
			(xy 312.923174 -25.971246) (xy 313.175648 -25.971246) (xy 313.179719 -25.915624) (xy 313.191845 -25.861187)
			(xy 313.211768 -25.809096) (xy 313.239064 -25.760461) (xy 313.27315 -25.716318) (xy 313.313299 -25.677609)
			(xy 313.358657 -25.645158) (xy 313.408257 -25.619657) (xy 313.461041 -25.60165) (xy 313.515884 -25.59152)
			(xy 313.571618 -25.589483) (xy 313.627055 -25.595583) (xy 313.681012 -25.609689) (xy 313.732341 -25.631501)
			(xy 313.779947 -25.660555) (xy 313.822815 -25.69623) (xy 313.860032 -25.737767) (xy 313.890805 -25.78428)
			(xy 313.914477 -25.834777) (xy 313.930545 -25.888184) (xy 313.938665 -25.94336) (xy 313.939174 -25.971246)
			(xy 314.191648 -25.971246) (xy 314.195719 -25.915624) (xy 314.207845 -25.861187) (xy 314.227768 -25.809096)
			(xy 314.255064 -25.760461) (xy 314.28915 -25.716318) (xy 314.329299 -25.677609) (xy 314.374657 -25.645158)
			(xy 314.424257 -25.619657) (xy 314.477041 -25.60165) (xy 314.531884 -25.59152) (xy 314.587618 -25.589483)
			(xy 314.643055 -25.595583) (xy 314.697012 -25.609689) (xy 314.748341 -25.631501) (xy 314.795947 -25.660555)
			(xy 314.838815 -25.69623) (xy 314.876032 -25.737767) (xy 314.906805 -25.78428) (xy 314.930477 -25.834777)
			(xy 314.946545 -25.888184) (xy 314.954665 -25.94336) (xy 314.955174 -25.971246) (xy 314.954665 -25.999132)
			(xy 314.949573 -26.03373) (xy 315.467744 -26.03373) (xy 315.471815 -25.978108) (xy 315.483941 -25.923671)
			(xy 315.503864 -25.87158) (xy 315.53116 -25.822945) (xy 315.565246 -25.778802) (xy 315.605395 -25.740093)
			(xy 315.650753 -25.707642) (xy 315.700353 -25.682141) (xy 315.753137 -25.664134) (xy 315.80798 -25.654004)
			(xy 315.863714 -25.651967) (xy 315.919151 -25.658067) (xy 315.973108 -25.672173) (xy 316.024437 -25.693985)
			(xy 316.072043 -25.723039) (xy 316.114911 -25.758714) (xy 316.152128 -25.800251) (xy 316.182901 -25.846764)
			(xy 316.206573 -25.897261) (xy 316.222641 -25.950668) (xy 316.230761 -26.005844) (xy 316.23127 -26.03373)
			(xy 316.230761 -26.061616) (xy 316.222641 -26.116792) (xy 316.206573 -26.170199) (xy 316.182901 -26.220696)
			(xy 316.152667 -26.266394) (xy 318.72047 -26.266394) (xy 318.720972 -26.239144) (xy 318.728729 -26.185198)
			(xy 318.744084 -26.132905) (xy 318.766724 -26.083329) (xy 318.796189 -26.037479) (xy 318.831878 -25.99629)
			(xy 318.873067 -25.960598) (xy 318.918915 -25.931132) (xy 318.968489 -25.908489) (xy 319.020782 -25.893132)
			(xy 319.074728 -25.885373) (xy 319.101978 -25.884886) (xy 319.131303 -25.885425) (xy 319.18926 -25.894405)
			(xy 319.245159 -25.912155) (xy 319.29768 -25.938257) (xy 319.321942 -25.954736) (xy 319.332356 -25.961848)
			(xy 319.35674 -25.96515) (xy 319.459102 -25.927304) (xy 319.475866 -25.908762) (xy 319.478914 -25.89657)
			(xy 319.486278 -25.86949) (xy 319.507836 -25.817679) (xy 319.536754 -25.769587) (xy 319.572408 -25.726251)
			(xy 319.614027 -25.688608) (xy 319.660713 -25.657471) (xy 319.711459 -25.633511) (xy 319.765167 -25.617247)
			(xy 319.820679 -25.609029) (xy 319.848738 -25.608534) (xy 319.87599 -25.608938) (xy 319.92994 -25.6167)
			(xy 319.982236 -25.63206) (xy 320.031814 -25.654706) (xy 320.077665 -25.684177) (xy 320.118855 -25.719872)
			(xy 320.154546 -25.761066) (xy 320.184012 -25.80692) (xy 320.206653 -25.8565) (xy 320.222008 -25.908797)
			(xy 320.229764 -25.962747) (xy 320.229764 -25.990042) (xy 321.49872 -25.990042) (xy 321.502791 -25.93442)
			(xy 321.514917 -25.879983) (xy 321.53484 -25.827892) (xy 321.562136 -25.779257) (xy 321.596222 -25.735114)
			(xy 321.636371 -25.696405) (xy 321.681729 -25.663954) (xy 321.731329 -25.638453) (xy 321.784113 -25.620446)
			(xy 321.838956 -25.610316) (xy 321.89469 -25.608279) (xy 321.950127 -25.614379) (xy 322.004084 -25.628485)
			(xy 322.055413 -25.650297) (xy 322.103019 -25.679351) (xy 322.145887 -25.715026) (xy 322.183104 -25.756563)
			(xy 322.213877 -25.803076) (xy 322.237549 -25.853573) (xy 322.253617 -25.90698) (xy 322.261737 -25.962156)
			(xy 322.262246 -25.990042) (xy 322.261737 -26.017928) (xy 322.253617 -26.073104) (xy 322.237549 -26.126511)
			(xy 322.213877 -26.177008) (xy 322.183104 -26.223521) (xy 322.145887 -26.265058) (xy 322.103019 -26.300733)
			(xy 322.055413 -26.329787) (xy 322.004084 -26.351599) (xy 321.950127 -26.365705) (xy 321.89469 -26.371805)
			(xy 321.838956 -26.369768) (xy 321.784113 -26.359638) (xy 321.731329 -26.341631) (xy 321.681729 -26.31613)
			(xy 321.636371 -26.283679) (xy 321.596222 -26.24497) (xy 321.562136 -26.200827) (xy 321.53484 -26.152192)
			(xy 321.514917 -26.100101) (xy 321.502791 -26.045664) (xy 321.49872 -25.990042) (xy 320.229764 -25.990042)
			(xy 320.229764 -26.017253) (xy 320.222008 -26.071203) (xy 320.206653 -26.1235) (xy 320.184012 -26.17308)
			(xy 320.154546 -26.218934) (xy 320.118855 -26.260128) (xy 320.077665 -26.295823) (xy 320.031814 -26.325294)
			(xy 319.982236 -26.34794) (xy 319.92994 -26.3633) (xy 319.87599 -26.371062) (xy 319.848738 -26.37155)
			(xy 319.819414 -26.370996) (xy 319.761457 -26.36202) (xy 319.705558 -26.344274) (xy 319.653037 -26.318177)
			(xy 319.628774 -26.3017) (xy 319.61836 -26.294588) (xy 319.593976 -26.291286) (xy 319.491614 -26.329132)
			(xy 319.47485 -26.347674) (xy 319.471802 -26.359866) (xy 319.465037 -26.384903) (xy 319.445618 -26.432994)
			(xy 319.419858 -26.478008) (xy 319.388232 -26.519113) (xy 319.351324 -26.555551) (xy 319.330832 -26.571448)
			(xy 319.320672 -26.579322) (xy 319.310004 -26.601928) (xy 319.315592 -26.711656) (xy 319.328546 -26.733246)
			(xy 319.339468 -26.73985) (xy 319.363197 -26.754766) (xy 319.406434 -26.790429) (xy 319.443987 -26.832034)
			(xy 319.475049 -26.878686) (xy 319.49895 -26.929381) (xy 319.515176 -26.983027) (xy 319.523377 -27.038471)
			(xy 319.523872 -27.066494) (xy 319.523386 -27.093745) (xy 319.51563 -27.147693) (xy 319.500275 -27.199988)
			(xy 319.477633 -27.249565) (xy 319.448167 -27.295415) (xy 319.412476 -27.336606) (xy 319.371285 -27.372297)
			(xy 319.325435 -27.401763) (xy 319.275858 -27.424405) (xy 319.223563 -27.43976) (xy 319.169615 -27.447516)
			(xy 319.115113 -27.447516) (xy 319.061165 -27.43976) (xy 319.00887 -27.424405) (xy 318.959293 -27.401763)
			(xy 318.913443 -27.372297) (xy 318.872252 -27.336606) (xy 318.836561 -27.295415) (xy 318.807095 -27.249565)
			(xy 318.784453 -27.199988) (xy 318.769098 -27.147693) (xy 318.761342 -27.093745) (xy 318.760856 -27.066494)
			(xy 318.761417 -27.037007) (xy 318.770512 -26.978738) (xy 318.78847 -26.922563) (xy 318.814861 -26.869823)
			(xy 318.849058 -26.821775) (xy 318.890244 -26.779564) (xy 318.91351 -26.76144) (xy 318.92367 -26.753566)
			(xy 318.934338 -26.73096) (xy 318.92875 -26.621232) (xy 318.915796 -26.599642) (xy 318.904874 -26.593038)
			(xy 318.881126 -26.578151) (xy 318.837892 -26.542481) (xy 318.800342 -26.50087) (xy 318.769284 -26.454213)
			(xy 318.745386 -26.403514) (xy 318.729163 -26.349864) (xy 318.720964 -26.294418) (xy 318.72047 -26.266394)
			(xy 316.152667 -26.266394) (xy 316.152128 -26.267209) (xy 316.114911 -26.308746) (xy 316.072043 -26.344421)
			(xy 316.024437 -26.373475) (xy 315.973108 -26.395287) (xy 315.919151 -26.409393) (xy 315.863714 -26.415493)
			(xy 315.80798 -26.413456) (xy 315.753137 -26.403326) (xy 315.700353 -26.385319) (xy 315.650753 -26.359818)
			(xy 315.605395 -26.327367) (xy 315.565246 -26.288658) (xy 315.53116 -26.244515) (xy 315.503864 -26.19588)
			(xy 315.483941 -26.143789) (xy 315.471815 -26.089352) (xy 315.467744 -26.03373) (xy 314.949573 -26.03373)
			(xy 314.946545 -26.054308) (xy 314.930477 -26.107715) (xy 314.906805 -26.158212) (xy 314.876032 -26.204725)
			(xy 314.838815 -26.246262) (xy 314.795947 -26.281937) (xy 314.748341 -26.310991) (xy 314.697012 -26.332803)
			(xy 314.643055 -26.346909) (xy 314.587618 -26.353009) (xy 314.531884 -26.350972) (xy 314.477041 -26.340842)
			(xy 314.424257 -26.322835) (xy 314.374657 -26.297334) (xy 314.329299 -26.264883) (xy 314.28915 -26.226174)
			(xy 314.255064 -26.182031) (xy 314.227768 -26.133396) (xy 314.207845 -26.081305) (xy 314.195719 -26.026868)
			(xy 314.191648 -25.971246) (xy 313.939174 -25.971246) (xy 313.938665 -25.999132) (xy 313.930545 -26.054308)
			(xy 313.914477 -26.107715) (xy 313.890805 -26.158212) (xy 313.860032 -26.204725) (xy 313.822815 -26.246262)
			(xy 313.779947 -26.281937) (xy 313.732341 -26.310991) (xy 313.681012 -26.332803) (xy 313.627055 -26.346909)
			(xy 313.571618 -26.353009) (xy 313.515884 -26.350972) (xy 313.461041 -26.340842) (xy 313.408257 -26.322835)
			(xy 313.358657 -26.297334) (xy 313.313299 -26.264883) (xy 313.27315 -26.226174) (xy 313.239064 -26.182031)
			(xy 313.211768 -26.133396) (xy 313.191845 -26.081305) (xy 313.179719 -26.026868) (xy 313.175648 -25.971246)
			(xy 312.923174 -25.971246) (xy 312.922665 -25.999132) (xy 312.914545 -26.054308) (xy 312.898477 -26.107715)
			(xy 312.874805 -26.158212) (xy 312.844032 -26.204725) (xy 312.806815 -26.246262) (xy 312.763947 -26.281937)
			(xy 312.716341 -26.310991) (xy 312.665012 -26.332803) (xy 312.611055 -26.346909) (xy 312.555618 -26.353009)
			(xy 312.499884 -26.350972) (xy 312.445041 -26.340842) (xy 312.392257 -26.322835) (xy 312.342657 -26.297334)
			(xy 312.297299 -26.264883) (xy 312.25715 -26.226174) (xy 312.223064 -26.182031) (xy 312.195768 -26.133396)
			(xy 312.175845 -26.081305) (xy 312.163719 -26.026868) (xy 312.159648 -25.971246) (xy 311.60085 -25.971246)
			(xy 311.60085 -27.654758) (xy 311.601208 -27.664324) (xy 311.608137 -27.682152) (xy 311.62112 -27.696198)
			(xy 311.629552 -27.700732) (xy 311.629806 -27.700732) (xy 311.656612 -27.714208) (xy 311.706024 -27.748233)
			(xy 311.715203 -27.756951) (xy 314.958966 -27.756951) (xy 314.958966 -27.702449) (xy 314.966722 -27.648501)
			(xy 314.982077 -27.596205) (xy 315.004718 -27.546628) (xy 315.034183 -27.500777) (xy 315.069874 -27.459586)
			(xy 315.111064 -27.423893) (xy 315.156914 -27.394425) (xy 315.20649 -27.371783) (xy 315.258785 -27.356426)
			(xy 315.312733 -27.348667) (xy 315.339984 -27.34818) (xy 315.354069 -27.348275) (xy 315.382165 -27.350313)
			(xy 315.396118 -27.352244) (xy 315.409834 -27.354276) (xy 315.435742 -27.343862) (xy 315.5061 -27.249882)
			(xy 315.509148 -27.221942) (xy 315.503306 -27.209242) (xy 315.492267 -27.184111) (xy 315.476662 -27.131489)
			(xy 315.468754 -27.077173) (xy 315.468254 -27.04973) (xy 315.46874 -27.022479) (xy 315.476496 -26.968531)
			(xy 315.491851 -26.916236) (xy 315.514493 -26.866659) (xy 315.543959 -26.820809) (xy 315.57965 -26.779618)
			(xy 315.620841 -26.743927) (xy 315.666691 -26.714461) (xy 315.716268 -26.691819) (xy 315.768563 -26.676464)
			(xy 315.822511 -26.668708) (xy 315.877013 -26.668708) (xy 315.930961 -26.676464) (xy 315.983256 -26.691819)
			(xy 316.032833 -26.714461) (xy 316.078683 -26.743927) (xy 316.119874 -26.779618) (xy 316.155565 -26.820809)
			(xy 316.185031 -26.866659) (xy 316.207673 -26.916236) (xy 316.223028 -26.968531) (xy 316.230784 -27.022479)
			(xy 316.23127 -27.04973) (xy 316.230653 -27.081146) (xy 316.22039 -27.143133) (xy 316.200113 -27.202603)
			(xy 316.185804 -27.230578) (xy 316.18047 -27.24023) (xy 316.178946 -27.262074) (xy 316.213236 -27.354022)
			(xy 316.228476 -27.369516) (xy 316.238636 -27.37358) (xy 316.265288 -27.384326) (xy 316.315254 -27.41271)
			(xy 316.360396 -27.44827) (xy 316.39969 -27.490201) (xy 316.432246 -27.537555) (xy 316.457328 -27.589258)
			(xy 316.474367 -27.644139) (xy 316.482977 -27.700955) (xy 316.483492 -27.729688) (xy 316.483033 -27.756941)
			(xy 316.475278 -27.810893) (xy 316.459922 -27.863192) (xy 316.43728 -27.912773) (xy 316.407812 -27.958627)
			(xy 316.372118 -27.99982) (xy 316.330924 -28.035514) (xy 316.28507 -28.064982) (xy 316.235488 -28.087624)
			(xy 316.183189 -28.102979) (xy 316.129237 -28.110734) (xy 316.101984 -28.111196) (xy 316.073069 -28.110619)
			(xy 316.015901 -28.101902) (xy 315.960703 -28.084656) (xy 315.908741 -28.059276) (xy 315.861205 -28.026342)
			(xy 315.819186 -27.986611) (xy 315.800994 -27.96413) (xy 315.793442 -27.955358) (xy 315.772675 -27.945183)
			(xy 315.761116 -27.944572) (xy 315.680852 -27.944572) (xy 315.669284 -27.945147) (xy 315.648511 -27.955336)
			(xy 315.640974 -27.96413) (xy 315.622805 -27.986632) (xy 315.58078 -28.026365) (xy 315.53324 -28.059301)
			(xy 315.481275 -28.084686) (xy 315.426074 -28.101938) (xy 315.368901 -28.110663) (xy 315.339984 -28.111196)
			(xy 315.312733 -28.110733) (xy 315.258785 -28.102974) (xy 315.20649 -28.087617) (xy 315.156914 -28.064975)
			(xy 315.111064 -28.035507) (xy 315.069874 -27.999814) (xy 315.034183 -27.958623) (xy 315.004718 -27.912772)
			(xy 314.982077 -27.863195) (xy 314.966722 -27.810899) (xy 314.958966 -27.756951) (xy 311.715203 -27.756951)
			(xy 311.749525 -27.789547) (xy 311.768236 -27.813) (xy 311.770522 -27.816048) (xy 311.773062 -27.818588)
			(xy 311.77611 -27.821636) (xy 311.782072 -27.82714) (xy 311.796578 -27.834391) (xy 311.804558 -27.83586)
			(xy 311.815734 -27.837638) (xy 311.883552 -27.847544) (xy 311.90311 -27.842464) (xy 311.911238 -27.836114)
			(xy 311.931287 -27.821286) (xy 311.974502 -27.796405) (xy 312.02059 -27.777364) (xy 312.068765 -27.764489)
			(xy 312.118207 -27.757999) (xy 312.14314 -27.757628) (xy 312.171192 -27.75812) (xy 312.226692 -27.766326)
			(xy 312.280392 -27.782571) (xy 312.331134 -27.806504) (xy 312.377825 -27.83761) (xy 312.419458 -27.875217)
			(xy 312.455136 -27.918515) (xy 312.470038 -27.942286) (xy 312.473594 -27.947874) (xy 312.48223 -27.956764)
			(xy 312.508138 -27.97175) (xy 312.518298 -27.976322) (xy 312.527696 -27.978608) (xy 312.533792 -27.978862)
			(xy 312.587386 -27.978862) (xy 312.593821 -27.97865) (xy 312.606283 -27.975429) (xy 312.612024 -27.972512)
			(xy 312.637678 -27.958288) (xy 312.646822 -27.949398) (xy 312.650378 -27.94381) (xy 312.66145 -27.926395)
			(xy 312.68678 -27.893814) (xy 312.700924 -27.878786) (xy 312.701432 -27.878278) (xy 312.70194 -27.87777)
			(xy 312.720041 -27.859169) (xy 312.760401 -27.826537) (xy 312.804811 -27.799676) (xy 312.852452 -27.779082)
			(xy 312.902444 -27.765133) (xy 312.953865 -27.758088) (xy 312.979816 -27.757628) (xy 313.007067 -27.758092)
			(xy 313.061014 -27.765851) (xy 313.113308 -27.781209) (xy 313.162884 -27.803853) (xy 313.208733 -27.833322)
			(xy 313.24992 -27.869016) (xy 313.285609 -27.910209) (xy 313.315072 -27.956062) (xy 313.337709 -28.00564)
			(xy 313.35306 -28.057936) (xy 313.360811 -28.111885) (xy 313.361324 -28.139136) (xy 313.867798 -28.139136)
			(xy 313.871869 -28.083514) (xy 313.883995 -28.029077) (xy 313.903918 -27.976986) (xy 313.931214 -27.928351)
			(xy 313.9653 -27.884208) (xy 314.005449 -27.845499) (xy 314.050807 -27.813048) (xy 314.100407 -27.787547)
			(xy 314.153191 -27.76954) (xy 314.208034 -27.75941) (xy 314.263768 -27.757373) (xy 314.319205 -27.763473)
			(xy 314.373162 -27.777579) (xy 314.424491 -27.799391) (xy 314.472097 -27.828445) (xy 314.514965 -27.86412)
			(xy 314.552182 -27.905657) (xy 314.582955 -27.95217) (xy 314.606627 -28.002667) (xy 314.622695 -28.056074)
			(xy 314.630815 -28.11125) (xy 314.631324 -28.139136) (xy 314.630815 -28.167022) (xy 314.622695 -28.222198)
			(xy 314.606627 -28.275605) (xy 314.582955 -28.326102) (xy 314.552182 -28.372615) (xy 314.514965 -28.414152)
			(xy 314.472097 -28.449827) (xy 314.424491 -28.478881) (xy 314.373162 -28.500693) (xy 314.319205 -28.514799)
			(xy 314.263768 -28.520899) (xy 314.208034 -28.518862) (xy 314.153191 -28.508732) (xy 314.100407 -28.490725)
			(xy 314.050807 -28.465224) (xy 314.005449 -28.432773) (xy 313.9653 -28.394064) (xy 313.931214 -28.349921)
			(xy 313.903918 -28.301286) (xy 313.883995 -28.249195) (xy 313.871869 -28.194758) (xy 313.867798 -28.139136)
			(xy 313.361324 -28.139136) (xy 313.360787 -28.168434) (xy 313.351827 -28.226341) (xy 313.334123 -28.282199)
			(xy 313.308091 -28.334696) (xy 313.274342 -28.382597) (xy 313.25439 -28.404058) (xy 313.253628 -28.40482)
			(xy 313.25185 -28.406598) (xy 313.233778 -28.425062) (xy 313.193517 -28.45744) (xy 313.149253 -28.484084)
			(xy 313.101795 -28.504506) (xy 313.052014 -28.518331) (xy 313.000823 -28.525308) (xy 312.97499 -28.525724)
			(xy 312.946435 -28.52519) (xy 312.889964 -28.516681) (xy 312.83539 -28.499852) (xy 312.783932 -28.475082)
			(xy 312.73674 -28.442921) (xy 312.694865 -28.404089) (xy 312.659242 -28.359451) (xy 312.644536 -28.33497)
			(xy 312.639754 -28.327482) (xy 312.626148 -28.316079) (xy 312.60947 -28.309996) (xy 312.600594 -28.30957)
			(xy 312.514488 -28.30957) (xy 312.5057 -28.309942) (xy 312.489164 -28.315899) (xy 312.475623 -28.327104)
			(xy 312.4708 -28.334462) (xy 312.459949 -28.352117) (xy 312.435006 -28.385214) (xy 312.421016 -28.400502)
			(xy 312.420254 -28.401264) (xy 312.419238 -28.402534) (xy 312.418476 -28.403296) (xy 312.418222 -28.40355)
			(xy 312.400091 -28.42246) (xy 312.359547 -28.455637) (xy 312.314848 -28.482959) (xy 312.266833 -28.503914)
			(xy 312.216404 -28.518106) (xy 312.164508 -28.525271) (xy 312.138314 -28.525724) (xy 312.109156 -28.525173)
			(xy 312.051517 -28.516302) (xy 311.9959 -28.498766) (xy 311.943598 -28.472972) (xy 311.895829 -28.439521)
			(xy 311.853705 -28.399191) (xy 311.835546 -28.376372) (xy 311.83326 -28.373324) (xy 311.83072 -28.370784)
			(xy 311.827672 -28.367736) (xy 311.821708 -28.362237) (xy 311.807201 -28.354995) (xy 311.799224 -28.353512)
			(xy 311.72912 -28.343098) (xy 311.719118 -28.342011) (xy 311.699607 -28.346858) (xy 311.691274 -28.352496)
			(xy 311.679336 -28.361132) (xy 311.67451 -28.364434) (xy 311.666382 -28.373324) (xy 311.652158 -28.398978)
			(xy 311.649199 -28.404702) (xy 311.645982 -28.417175) (xy 311.645808 -28.423616) (xy 311.645808 -28.428696)
			(xy 311.645993 -28.435136) (xy 311.649199 -28.447611) (xy 311.652158 -28.453334) (xy 311.656476 -28.460954)
			(xy 311.659665 -28.466301) (xy 311.66814 -28.475416) (xy 311.67324 -28.478988) (xy 311.673748 -28.479242)
			(xy 311.674002 -28.479242) (xy 311.69697 -28.494341) (xy 311.738726 -28.530084) (xy 311.774929 -28.571443)
			(xy 311.804831 -28.617562) (xy 311.827817 -28.66749) (xy 311.84341 -28.720196) (xy 311.85129 -28.774594)
			(xy 311.851802 -28.802076) (xy 311.851286 -28.830781) (xy 311.84269 -28.887543) (xy 311.825688 -28.942376)
			(xy 311.800664 -28.994045) (xy 311.768182 -29.041382) (xy 311.748932 -29.06268) (xy 311.748424 -29.063188)
			(xy 311.747662 -29.064204) (xy 311.746392 -29.065474) (xy 311.745884 -29.065982) (xy 311.729199 -29.083502)
			(xy 311.692151 -29.114619) (xy 311.651471 -29.14081) (xy 311.629806 -29.15158) (xy 311.616344 -29.15793)
			(xy 311.60085 -29.182568) (xy 311.60085 -29.222446) (xy 311.601291 -29.232119) (xy 311.608462 -29.250091)
			(xy 311.621744 -29.264162) (xy 311.630314 -29.268674) (xy 311.654757 -29.28048) (xy 311.700319 -29.309985)
			(xy 311.741235 -29.345654) (xy 311.776678 -29.386766) (xy 311.805931 -29.432491) (xy 311.828401 -29.481902)
			(xy 311.843635 -29.534002) (xy 311.851324 -29.587735) (xy 311.851802 -29.614876) (xy 311.851272 -29.644139)
			(xy 311.84234 -29.70198) (xy 311.824681 -29.757778) (xy 311.798709 -29.810226) (xy 311.765035 -29.858094)
			(xy 311.745122 -29.879544) (xy 311.744614 -29.880052) (xy 311.744106 -29.88056) (xy 311.733763 -29.891404)
			(xy 311.71164 -29.91162) (xy 311.69991 -29.920946) (xy 311.691073 -29.928533) (xy 311.680875 -29.949444)
			(xy 311.680352 -29.961078) (xy 311.680352 -30.02026) (xy 311.680533 -30.026063) (xy 311.683219 -30.037357)
			(xy 311.685686 -30.042612) (xy 311.697624 -30.066996) (xy 311.704482 -30.075632) (xy 311.7088 -30.078934)
			(xy 311.730706 -30.097165) (xy 311.769385 -30.13902) (xy 311.801408 -30.186163) (xy 311.826063 -30.237544)
			(xy 311.842802 -30.29202) (xy 311.851253 -30.348381) (xy 311.851802 -30.376876) (xy 311.851286 -30.405581)
			(xy 311.84269 -30.462343) (xy 311.825688 -30.517176) (xy 311.800664 -30.568845) (xy 311.768182 -30.616182)
			(xy 311.748932 -30.63748) (xy 311.748424 -30.637988) (xy 311.747662 -30.639004) (xy 311.746392 -30.640274)
			(xy 311.745884 -30.640782) (xy 311.729199 -30.658302) (xy 311.692151 -30.689419) (xy 311.651471 -30.71561)
			(xy 311.629806 -30.72638) (xy 311.616344 -30.73273) (xy 311.60085 -30.757368) (xy 311.60085 -31.159958)
			(xy 311.62498 -31.188406) (xy 311.643268 -31.191454) (xy 311.670409 -31.196468) (xy 311.722976 -31.213283)
			(xy 311.772573 -31.237497) (xy 311.818162 -31.268605) (xy 311.858794 -31.305957) (xy 311.893619 -31.348774)
			(xy 311.921912 -31.396162) (xy 311.943081 -31.447133) (xy 311.956686 -31.500621) (xy 311.962441 -31.555512)
			(xy 311.960227 -31.610659) (xy 311.95009 -31.664912) (xy 311.932241 -31.717138) (xy 311.93115 -31.719266)
			(xy 312.485276 -31.719266) (xy 312.489347 -31.663644) (xy 312.501473 -31.609207) (xy 312.521396 -31.557116)
			(xy 312.548692 -31.508481) (xy 312.582778 -31.464338) (xy 312.622927 -31.425629) (xy 312.668285 -31.393178)
			(xy 312.717885 -31.367677) (xy 312.770669 -31.34967) (xy 312.825512 -31.33954) (xy 312.881246 -31.337503)
			(xy 312.936683 -31.343603) (xy 312.99064 -31.357709) (xy 313.041969 -31.379521) (xy 313.089575 -31.408575)
			(xy 313.132443 -31.44425) (xy 313.16966 -31.485787) (xy 313.200433 -31.5323) (xy 313.224105 -31.582797)
			(xy 313.240173 -31.636204) (xy 313.244323 -31.664402) (xy 313.760864 -31.664402) (xy 313.764935 -31.60878)
			(xy 313.777061 -31.554343) (xy 313.796984 -31.502252) (xy 313.82428 -31.453617) (xy 313.858366 -31.409474)
			(xy 313.898515 -31.370765) (xy 313.943873 -31.338314) (xy 313.993473 -31.312813) (xy 314.046257 -31.294806)
			(xy 314.1011 -31.284676) (xy 314.156834 -31.282639) (xy 314.212271 -31.288739) (xy 314.266228 -31.302845)
			(xy 314.317557 -31.324657) (xy 314.365163 -31.353711) (xy 314.408031 -31.389386) (xy 314.445248 -31.430923)
			(xy 314.476021 -31.477436) (xy 314.499693 -31.527933) (xy 314.515761 -31.58134) (xy 314.523881 -31.636516)
			(xy 314.52439 -31.664402) (xy 314.523881 -31.692288) (xy 314.515761 -31.747464) (xy 314.506821 -31.777178)
			(xy 315.026038 -31.777178) (xy 315.030109 -31.721556) (xy 315.042235 -31.667119) (xy 315.062158 -31.615028)
			(xy 315.089454 -31.566393) (xy 315.12354 -31.52225) (xy 315.163689 -31.483541) (xy 315.209047 -31.45109)
			(xy 315.258647 -31.425589) (xy 315.311431 -31.407582) (xy 315.366274 -31.397452) (xy 315.422008 -31.395415)
			(xy 315.477445 -31.401515) (xy 315.531402 -31.415621) (xy 315.582731 -31.437433) (xy 315.630337 -31.466487)
			(xy 315.673205 -31.502162) (xy 315.710422 -31.543699) (xy 315.741195 -31.590212) (xy 315.764867 -31.640709)
			(xy 315.780935 -31.694116) (xy 315.789055 -31.749292) (xy 315.789564 -31.777178) (xy 315.789055 -31.805064)
			(xy 315.780935 -31.86024) (xy 315.764867 -31.913647) (xy 315.741195 -31.964144) (xy 315.710422 -32.010657)
			(xy 315.673205 -32.052194) (xy 315.630337 -32.087869) (xy 315.582731 -32.116923) (xy 315.531402 -32.138735)
			(xy 315.477445 -32.152841) (xy 315.422008 -32.158941) (xy 315.366274 -32.156904) (xy 315.311431 -32.146774)
			(xy 315.258647 -32.128767) (xy 315.209047 -32.103266) (xy 315.163689 -32.070815) (xy 315.12354 -32.032106)
			(xy 315.089454 -31.987963) (xy 315.062158 -31.939328) (xy 315.042235 -31.887237) (xy 315.030109 -31.8328)
			(xy 315.026038 -31.777178) (xy 314.506821 -31.777178) (xy 314.499693 -31.800871) (xy 314.476021 -31.851368)
			(xy 314.445248 -31.897881) (xy 314.408031 -31.939418) (xy 314.365163 -31.975093) (xy 314.317557 -32.004147)
			(xy 314.266228 -32.025959) (xy 314.212271 -32.040065) (xy 314.156834 -32.046165) (xy 314.1011 -32.044128)
			(xy 314.046257 -32.033998) (xy 313.993473 -32.015991) (xy 313.943873 -31.99049) (xy 313.898515 -31.958039)
			(xy 313.858366 -31.91933) (xy 313.82428 -31.875187) (xy 313.796984 -31.826552) (xy 313.777061 -31.774461)
			(xy 313.764935 -31.720024) (xy 313.760864 -31.664402) (xy 313.244323 -31.664402) (xy 313.248293 -31.69138)
			(xy 313.248802 -31.719266) (xy 313.248293 -31.747152) (xy 313.240173 -31.802328) (xy 313.224105 -31.855735)
			(xy 313.200433 -31.906232) (xy 313.16966 -31.952745) (xy 313.132443 -31.994282) (xy 313.089575 -32.029957)
			(xy 313.041969 -32.059011) (xy 312.99064 -32.080823) (xy 312.936683 -32.094929) (xy 312.881246 -32.101029)
			(xy 312.825512 -32.098992) (xy 312.770669 -32.088862) (xy 312.717885 -32.070855) (xy 312.668285 -32.045354)
			(xy 312.622927 -32.012903) (xy 312.582778 -31.974194) (xy 312.548692 -31.930051) (xy 312.521396 -31.881416)
			(xy 312.501473 -31.829325) (xy 312.489347 -31.774888) (xy 312.485276 -31.719266) (xy 311.93115 -31.719266)
			(xy 311.907054 -31.766247) (xy 311.875054 -31.811214) (xy 311.856374 -31.831534) (xy 311.855866 -31.832042)
			(xy 311.855358 -31.832804) (xy 311.833941 -31.854966) (xy 311.785265 -31.892764) (xy 311.731147 -31.922249)
			(xy 311.672995 -31.942655) (xy 311.64276 -31.948628) (xy 311.624472 -31.95193) (xy 311.60085 -31.97987)
			(xy 311.60085 -33.512506) (xy 311.601332 -33.522401) (xy 311.608842 -33.540712) (xy 311.622708 -33.554834)
			(xy 311.631584 -33.559242) (xy 311.731406 -33.602168) (xy 311.761124 -33.596834) (xy 311.7723 -33.586166)
			(xy 311.786197 -33.573341) (xy 311.816098 -33.550187) (xy 311.83199 -33.539938) (xy 311.83453 -33.53816)
			(xy 311.834784 -33.537906) (xy 311.841388 -33.532762) (xy 311.851119 -33.519154) (xy 311.853834 -33.511236)
			(xy 311.875678 -33.437322) (xy 311.874154 -33.41878) (xy 311.87009 -33.410144) (xy 311.858677 -33.384673)
			(xy 311.842599 -33.331224) (xy 311.834504 -33.276) (xy 311.834022 -33.248092) (xy 311.834508 -33.220841)
			(xy 311.842264 -33.166893) (xy 311.857619 -33.114598) (xy 311.880261 -33.065021) (xy 311.909727 -33.019171)
			(xy 311.945418 -32.97798) (xy 311.986609 -32.942289) (xy 312.032459 -32.912823) (xy 312.082036 -32.890181)
			(xy 312.134331 -32.874826) (xy 312.188279 -32.86707) (xy 312.242781 -32.86707) (xy 312.296729 -32.874826)
			(xy 312.349024 -32.890181) (xy 312.398601 -32.912823) (xy 312.444451 -32.942289) (xy 312.485642 -32.97798)
			(xy 312.521333 -33.019171) (xy 312.550799 -33.065021) (xy 312.573441 -33.114598) (xy 312.588796 -33.166893)
			(xy 312.596552 -33.220841) (xy 312.597038 -33.248092) (xy 312.596556 -33.275628) (xy 312.588641 -33.330129)
			(xy 312.572975 -33.382926) (xy 312.549882 -33.432922) (xy 312.519843 -33.479081) (xy 312.483481 -33.520442)
			(xy 312.441551 -33.556147) (xy 312.418476 -33.57118) (xy 312.410602 -33.57626) (xy 312.399172 -33.590992)
			(xy 312.375042 -33.673288) (xy 312.375804 -33.68294) (xy 312.376566 -33.692592) (xy 312.38063 -33.70072)
			(xy 312.384186 -33.708848) (xy 312.38444 -33.70961) (xy 312.398156 -33.744662) (xy 312.40095 -33.753298)
			(xy 312.41238 -33.767522) (xy 312.485532 -33.81121) (xy 312.49366 -33.812734) (xy 312.516221 -33.8075)
			(xy 312.562196 -33.801892) (xy 312.585354 -33.801558) (xy 312.61261 -33.802018) (xy 312.666568 -33.809769)
			(xy 312.718873 -33.825121) (xy 312.768461 -33.84776) (xy 312.783919 -33.857692) (xy 313.689998 -33.857692)
			(xy 313.694069 -33.80207) (xy 313.706195 -33.747633) (xy 313.726118 -33.695542) (xy 313.753414 -33.646907)
			(xy 313.7875 -33.602764) (xy 313.827649 -33.564055) (xy 313.873007 -33.531604) (xy 313.922607 -33.506103)
			(xy 313.975391 -33.488096) (xy 314.030234 -33.477966) (xy 314.085968 -33.475929) (xy 314.141405 -33.482029)
			(xy 314.195362 -33.496135) (xy 314.246691 -33.517947) (xy 314.294297 -33.547001) (xy 314.337165 -33.582676)
			(xy 314.374382 -33.624213) (xy 314.405155 -33.670726) (xy 314.428827 -33.721223) (xy 314.444895 -33.77463)
			(xy 314.453015 -33.829806) (xy 314.453524 -33.857692) (xy 314.453015 -33.885578) (xy 314.444895 -33.940754)
			(xy 314.428827 -33.994161) (xy 314.405155 -34.044658) (xy 314.374382 -34.091171) (xy 314.337165 -34.132708)
			(xy 314.294297 -34.168383) (xy 314.246691 -34.197437) (xy 314.195362 -34.219249) (xy 314.141405 -34.233355)
			(xy 314.085968 -34.239455) (xy 314.030234 -34.237418) (xy 313.975391 -34.227288) (xy 313.922607 -34.209281)
			(xy 313.873007 -34.18378) (xy 313.827649 -34.151329) (xy 313.7875 -34.11262) (xy 313.753414 -34.068477)
			(xy 313.726118 -34.019842) (xy 313.706195 -33.967751) (xy 313.694069 -33.913314) (xy 313.689998 -33.857692)
			(xy 312.783919 -33.857692) (xy 312.814323 -33.877227) (xy 312.855524 -33.91292) (xy 312.891225 -33.954113)
			(xy 312.920701 -33.999968) (xy 312.943351 -34.049552) (xy 312.958714 -34.101854) (xy 312.966477 -34.15581)
			(xy 312.966862 -34.183066) (xy 312.966323 -34.212364) (xy 312.95736 -34.270269) (xy 312.939654 -34.326125)
			(xy 312.913621 -34.37862) (xy 312.879873 -34.42652) (xy 312.859928 -34.447988) (xy 312.859166 -34.44875)
			(xy 312.857388 -34.450528) (xy 312.839317 -34.468992) (xy 312.799056 -34.501369) (xy 312.754791 -34.528011)
			(xy 312.707333 -34.548429) (xy 312.657552 -34.562249) (xy 312.60636 -34.569218) (xy 312.580528 -34.569654)
			(xy 312.553921 -34.569194) (xy 312.501224 -34.561804) (xy 312.450065 -34.547162) (xy 312.401436 -34.525554)
			(xy 312.356282 -34.497398) (xy 312.315478 -34.463241) (xy 312.279817 -34.423746) (xy 312.249989 -34.379678)
			(xy 312.226575 -34.331893) (xy 312.217816 -34.306764) (xy 312.217562 -34.306256) (xy 312.214394 -34.297739)
			(xy 312.203066 -34.283548) (xy 312.195464 -34.27857) (xy 312.130186 -34.239708) (xy 312.112406 -34.236406)
			(xy 312.103262 -34.238184) (xy 312.086452 -34.241028) (xy 312.052492 -34.244082) (xy 312.035444 -34.24428)
			(xy 312.03519 -34.24428) (xy 312.006178 -34.24374) (xy 311.948823 -34.234962) (xy 311.893454 -34.217612)
			(xy 311.841347 -34.192087) (xy 311.793699 -34.158974) (xy 311.7723 -34.139378) (xy 311.761124 -34.128964)
			(xy 311.731406 -34.12363) (xy 311.631584 -34.166302) (xy 311.622655 -34.170632) (xy 311.608755 -34.184767)
			(xy 311.60127 -34.203125) (xy 311.60085 -34.213038) (xy 311.60085 -35.264852) (xy 314.10224 -35.264852)
			(xy 314.106311 -35.20923) (xy 314.118437 -35.154793) (xy 314.13836 -35.102702) (xy 314.165656 -35.054067)
			(xy 314.199742 -35.009924) (xy 314.239891 -34.971215) (xy 314.285249 -34.938764) (xy 314.334849 -34.913263)
			(xy 314.387633 -34.895256) (xy 314.442476 -34.885126) (xy 314.49821 -34.883089) (xy 314.553647 -34.889189)
			(xy 314.607604 -34.903295) (xy 314.658933 -34.925107) (xy 314.706539 -34.954161) (xy 314.749407 -34.989836)
			(xy 314.774244 -35.017556) (xy 316.419633 -35.017556) (xy 316.419633 -34.963044) (xy 316.427391 -34.909086)
			(xy 316.44275 -34.856782) (xy 316.465397 -34.807197) (xy 316.49487 -34.761339) (xy 316.53057 -34.720143)
			(xy 316.57177 -34.684447) (xy 316.61763 -34.654979) (xy 316.667218 -34.632337) (xy 316.719524 -34.616983)
			(xy 316.773482 -34.60923) (xy 316.800738 -34.60877) (xy 316.81785 -34.608964) (xy 316.851937 -34.612014)
			(xy 316.86881 -34.614866) (xy 316.880076 -34.616259) (xy 316.901958 -34.610332) (xy 316.910974 -34.603436)
			(xy 316.935358 -34.582354) (xy 316.943746 -34.574428) (xy 316.95287 -34.553255) (xy 316.952884 -34.541714)
			(xy 316.952376 -34.52241) (xy 316.952376 -33.65881) (xy 316.952884 -33.638744) (xy 316.95273 -33.627233)
			(xy 316.943617 -33.606125) (xy 316.935358 -33.598104) (xy 316.910974 -33.577022) (xy 316.901989 -33.570067)
			(xy 316.880081 -33.564142) (xy 316.86881 -33.565592) (xy 316.851939 -33.568462) (xy 316.817851 -33.571515)
			(xy 316.800738 -33.571688) (xy 316.773482 -33.571268) (xy 316.719524 -33.563515) (xy 316.667219 -33.548161)
			(xy 316.617631 -33.52552) (xy 316.571771 -33.496051) (xy 316.530571 -33.460355) (xy 316.494872 -33.41916)
			(xy 316.465399 -33.373302) (xy 316.442752 -33.323717) (xy 316.427393 -33.271413) (xy 316.419635 -33.217456)
			(xy 316.419635 -33.162944) (xy 316.427393 -33.108987) (xy 316.442752 -33.056683) (xy 316.465399 -33.007098)
			(xy 316.494872 -32.96124) (xy 316.530571 -32.920045) (xy 316.571771 -32.884349) (xy 316.617631 -32.85488)
			(xy 316.667219 -32.832239) (xy 316.719524 -32.816885) (xy 316.773482 -32.809132) (xy 316.800738 -32.808672)
			(xy 316.827747 -32.809085) (xy 316.881227 -32.816696) (xy 316.933098 -32.831776) (xy 316.982323 -32.854022)
			(xy 317.027918 -32.88299) (xy 317.06897 -32.918101) (xy 317.104659 -32.958651) (xy 317.13427 -33.00383)
			(xy 317.157212 -33.052735) (xy 317.173026 -33.104387) (xy 317.177674 -33.130998) (xy 317.179198 -33.141666)
			(xy 317.190628 -33.159446) (xy 317.270892 -33.212786) (xy 317.291466 -33.216596) (xy 317.302134 -33.214056)
			(xy 317.328767 -33.207931) (xy 317.383014 -33.201307) (xy 317.410338 -33.200848) (xy 317.437662 -33.201303)
			(xy 317.491911 -33.207924) (xy 317.518542 -33.214056) (xy 317.52921 -33.216596) (xy 317.549784 -33.212786)
			(xy 317.630048 -33.159446) (xy 317.641478 -33.141666) (xy 317.643002 -33.130998) (xy 317.647666 -33.104395)
			(xy 317.663497 -33.052758) (xy 317.68645 -33.003868) (xy 317.716067 -32.958703) (xy 317.751756 -32.918165)
			(xy 317.792803 -32.883064) (xy 317.83839 -32.854101) (xy 317.887605 -32.831854) (xy 317.939465 -32.816768)
			(xy 317.992933 -32.809144) (xy 318.019938 -32.808672) (xy 318.047308 -32.809157) (xy 318.101487 -32.816967)
			(xy 318.15399 -32.832451) (xy 318.203738 -32.855289) (xy 318.249705 -32.885011) (xy 318.270636 -32.902652)
			(xy 318.277748 -32.908748) (xy 318.294766 -32.915098) (xy 318.38011 -32.915098) (xy 318.397128 -32.908748)
			(xy 318.40424 -32.902652) (xy 318.425191 -32.885036) (xy 318.471157 -32.855319) (xy 318.5209 -32.832477)
			(xy 318.573397 -32.816981) (xy 318.62757 -32.809148) (xy 318.654938 -32.808672) (xy 318.67205 -32.808866)
			(xy 318.706137 -32.811916) (xy 318.72301 -32.814768) (xy 318.734276 -32.816161) (xy 318.756158 -32.810234)
			(xy 318.765174 -32.803338) (xy 318.789558 -32.782256) (xy 318.797945 -32.774329) (xy 318.80707 -32.753157)
			(xy 318.807084 -32.741616) (xy 318.806576 -32.722312) (xy 318.806576 -31.858712) (xy 318.807084 -31.838646)
			(xy 318.806929 -31.827135) (xy 318.797817 -31.806027) (xy 318.789558 -31.798006) (xy 318.765174 -31.776924)
			(xy 318.756188 -31.769969) (xy 318.734281 -31.764044) (xy 318.72301 -31.765494) (xy 318.706139 -31.768364)
			(xy 318.672051 -31.771417) (xy 318.654938 -31.77159) (xy 318.627568 -31.771104) (xy 318.57339 -31.763291)
			(xy 318.520887 -31.747807) (xy 318.47114 -31.72497) (xy 318.425172 -31.695249) (xy 318.40424 -31.67761)
			(xy 318.397128 -31.671514) (xy 318.380364 -31.665164) (xy 318.294766 -31.665164) (xy 318.277748 -31.671514)
			(xy 318.27089 -31.677864) (xy 318.249922 -31.6955) (xy 318.203911 -31.725244) (xy 318.154115 -31.748095)
			(xy 318.101562 -31.763583) (xy 318.047332 -31.771389) (xy 318.019938 -31.771844) (xy 317.992959 -31.771431)
			(xy 317.939537 -31.763841) (xy 317.88772 -31.748794) (xy 317.838543 -31.72659) (xy 317.792988 -31.697673)
			(xy 317.751965 -31.662621) (xy 317.716296 -31.622135) (xy 317.686693 -31.577023) (xy 317.663747 -31.528187)
			(xy 317.647917 -31.476603) (xy 317.643256 -31.450026) (xy 317.641478 -31.439358) (xy 317.630048 -31.421832)
			(xy 317.549784 -31.368238) (xy 317.52921 -31.364682) (xy 317.518796 -31.367222) (xy 317.492094 -31.373293)
			(xy 317.437719 -31.379789) (xy 317.410338 -31.380176) (xy 317.382956 -31.379809) (xy 317.32858 -31.373309)
			(xy 317.30188 -31.367222) (xy 317.291466 -31.364682) (xy 317.270892 -31.368238) (xy 317.190628 -31.421832)
			(xy 317.179198 -31.439358) (xy 317.17742 -31.450026) (xy 317.172776 -31.476602) (xy 317.156918 -31.528168)
			(xy 317.133953 -31.576985) (xy 317.104338 -31.622079) (xy 317.068665 -31.662551) (xy 317.027645 -31.697593)
			(xy 316.982097 -31.726505) (xy 316.932929 -31.748711) (xy 316.881123 -31.763768) (xy 316.827713 -31.771375)
			(xy 316.800738 -31.771844) (xy 316.773486 -31.771311) (xy 316.719536 -31.763559) (xy 316.667239 -31.748208)
			(xy 316.617658 -31.72557) (xy 316.571805 -31.696106) (xy 316.530611 -31.660416) (xy 316.494917 -31.619226)
			(xy 316.465448 -31.573375) (xy 316.442805 -31.523797) (xy 316.427449 -31.471501) (xy 316.419691 -31.417552)
			(xy 316.419691 -31.363048) (xy 316.427449 -31.309099) (xy 316.442805 -31.256803) (xy 316.465448 -31.207225)
			(xy 316.494917 -31.161374) (xy 316.530611 -31.120184) (xy 316.571805 -31.084494) (xy 316.617658 -31.05503)
			(xy 316.667239 -31.032392) (xy 316.719536 -31.01704) (xy 316.773486 -31.009289) (xy 316.800738 -31.008828)
			(xy 316.81785 -31.009023) (xy 316.851937 -31.012073) (xy 316.86881 -31.014924) (xy 316.880076 -31.016327)
			(xy 316.90196 -31.010395) (xy 316.910974 -31.003494) (xy 316.935358 -30.982412) (xy 316.943717 -30.974461)
			(xy 316.952857 -30.953307) (xy 316.952884 -30.941772) (xy 316.952376 -30.922468) (xy 316.952376 -30.058868)
			(xy 316.952884 -30.038802) (xy 316.952696 -30.027294) (xy 316.943607 -30.006186) (xy 316.935358 -29.998162)
			(xy 316.910974 -29.97708) (xy 316.901991 -29.970121) (xy 316.880082 -29.9642) (xy 316.86881 -29.96565)
			(xy 316.851939 -29.968521) (xy 316.817851 -29.971573) (xy 316.800738 -29.971746) (xy 316.773486 -29.971209)
			(xy 316.719536 -29.963458) (xy 316.667239 -29.948106) (xy 316.617659 -29.925468) (xy 316.571806 -29.896004)
			(xy 316.530613 -29.860314) (xy 316.494919 -29.819125) (xy 316.46545 -29.773274) (xy 316.442807 -29.723696)
			(xy 316.427451 -29.671401) (xy 316.419693 -29.617452) (xy 316.419693 -29.562948) (xy 316.427451 -29.508999)
			(xy 316.442807 -29.456704) (xy 316.46545 -29.407126) (xy 316.494919 -29.361275) (xy 316.530613 -29.320086)
			(xy 316.571806 -29.284396) (xy 316.617659 -29.254932) (xy 316.667239 -29.232294) (xy 316.719536 -29.216942)
			(xy 316.773486 -29.209191) (xy 316.800738 -29.20873) (xy 316.827746 -29.209178) (xy 316.881222 -29.216789)
			(xy 316.933091 -29.231866) (xy 316.982314 -29.25411) (xy 317.027907 -29.283074) (xy 317.068959 -29.31818)
			(xy 317.104648 -29.358726) (xy 317.134261 -29.4039) (xy 317.157206 -29.4528) (xy 317.173024 -29.504448)
			(xy 317.177674 -29.531056) (xy 317.179198 -29.541724) (xy 317.190628 -29.559504) (xy 317.270892 -29.612844)
			(xy 317.291466 -29.616654) (xy 317.302134 -29.614114) (xy 317.328772 -29.608048) (xy 317.38302 -29.601557)
			(xy 317.410338 -29.60116) (xy 317.437656 -29.601552) (xy 317.491904 -29.608043) (xy 317.518542 -29.614114)
			(xy 317.52921 -29.616654) (xy 317.549784 -29.612844) (xy 317.630048 -29.559504) (xy 317.641478 -29.541724)
			(xy 317.643002 -29.531056) (xy 317.64771 -29.504461) (xy 317.663534 -29.452824) (xy 317.68648 -29.403934)
			(xy 317.716091 -29.358768) (xy 317.751774 -29.318229) (xy 317.792817 -29.283126) (xy 317.8384 -29.254161)
			(xy 317.887611 -29.231913) (xy 317.939468 -29.216826) (xy 317.992935 -29.209202) (xy 318.019938 -29.20873)
			(xy 318.047307 -29.209225) (xy 318.101485 -29.217035) (xy 318.153988 -29.232517) (xy 318.203736 -29.255352)
			(xy 318.249704 -29.285071) (xy 318.270636 -29.30271) (xy 318.277748 -29.308806) (xy 318.294766 -29.315156)
			(xy 318.38011 -29.315156) (xy 318.397128 -29.308806) (xy 318.40424 -29.30271) (xy 318.425185 -29.285087)
			(xy 318.471154 -29.255373) (xy 318.520898 -29.232533) (xy 318.573396 -29.217038) (xy 318.62757 -29.209206)
			(xy 318.654938 -29.20873) (xy 318.67205 -29.208925) (xy 318.706137 -29.211975) (xy 318.72301 -29.214826)
			(xy 318.734276 -29.216229) (xy 318.75616 -29.210297) (xy 318.765174 -29.203396) (xy 318.789558 -29.182314)
			(xy 318.797916 -29.174362) (xy 318.807057 -29.153209) (xy 318.807084 -29.141674) (xy 318.806576 -29.12237)
			(xy 318.806576 -28.25877) (xy 318.807084 -28.238704) (xy 318.806895 -28.227196) (xy 318.797807 -28.206089)
			(xy 318.789558 -28.198064) (xy 318.765174 -28.176982) (xy 318.756191 -28.170023) (xy 318.734282 -28.164102)
			(xy 318.72301 -28.165552) (xy 318.706139 -28.168423) (xy 318.672051 -28.171475) (xy 318.654938 -28.171648)
			(xy 318.627686 -28.171107) (xy 318.573737 -28.163356) (xy 318.52144 -28.148004) (xy 318.47186 -28.125366)
			(xy 318.426007 -28.095903) (xy 318.384814 -28.060213) (xy 318.34912 -28.019023) (xy 318.319652 -27.973173)
			(xy 318.297009 -27.923596) (xy 318.281652 -27.8713) (xy 318.273895 -27.817352) (xy 318.273895 -27.762848)
			(xy 318.281652 -27.7089) (xy 318.297009 -27.656604) (xy 318.319652 -27.607027) (xy 318.34912 -27.561177)
			(xy 318.384814 -27.519987) (xy 318.426007 -27.484297) (xy 318.47186 -27.454833) (xy 318.52144 -27.432196)
			(xy 318.573737 -27.416844) (xy 318.627686 -27.409093) (xy 318.654938 -27.408632) (xy 318.681946 -27.409078)
			(xy 318.735423 -27.416689) (xy 318.787291 -27.431767) (xy 318.836514 -27.45401) (xy 318.882107 -27.482975)
			(xy 318.923159 -27.518081) (xy 318.958848 -27.558627) (xy 318.988461 -27.603802) (xy 319.011406 -27.652702)
			(xy 319.027224 -27.704349) (xy 319.031874 -27.730958) (xy 319.033398 -27.741626) (xy 319.044828 -27.759406)
			(xy 319.125092 -27.812746) (xy 319.145666 -27.816556) (xy 319.156334 -27.814016) (xy 319.182967 -27.80789)
			(xy 319.237214 -27.801267) (xy 319.264538 -27.800808) (xy 319.286716 -27.801104) (xy 319.330862 -27.805429)
			(xy 319.352676 -27.809444) (xy 319.36309 -27.811476) (xy 319.382902 -27.807412) (xy 319.459864 -27.754072)
			(xy 319.470786 -27.737054) (xy 319.472564 -27.72664) (xy 319.477451 -27.700299) (xy 319.493668 -27.64924)
			(xy 319.516868 -27.600951) (xy 319.546597 -27.556383) (xy 319.582269 -27.516414) (xy 319.623183 -27.481828)
			(xy 319.668533 -27.453307) (xy 319.717427 -27.431412) (xy 319.768905 -27.416573) (xy 319.821951 -27.409083)
			(xy 319.848738 -27.408632) (xy 319.87599 -27.40904) (xy 319.92994 -27.416802) (xy 319.982235 -27.432162)
			(xy 320.031813 -27.454808) (xy 320.077663 -27.484278) (xy 320.118853 -27.519974) (xy 320.154545 -27.561167)
			(xy 320.18401 -27.607021) (xy 320.206651 -27.6566) (xy 320.222006 -27.708898) (xy 320.229762 -27.762848)
			(xy 320.229762 -27.817352) (xy 320.222006 -27.871302) (xy 320.206651 -27.9236) (xy 320.18401 -27.97318)
			(xy 320.154545 -28.019033) (xy 320.118853 -28.060226) (xy 320.077663 -28.095922) (xy 320.031813 -28.125392)
			(xy 319.982235 -28.148038) (xy 319.92994 -28.163398) (xy 319.87599 -28.17116) (xy 319.848738 -28.171648)
			(xy 319.837216 -28.171557) (xy 319.814213 -28.170157) (xy 319.802764 -28.168854) (xy 319.79185 -28.168127)
			(xy 319.771054 -28.174831) (xy 319.762632 -28.181808) (xy 319.738756 -28.203398) (xy 319.730901 -28.211249)
			(xy 319.722215 -28.231664) (xy 319.721992 -28.242768) (xy 319.7225 -28.25877) (xy 319.7225 -29.12237)
			(xy 319.722246 -29.137356) (xy 319.722378 -29.148441) (xy 319.730942 -29.168862) (xy 319.738756 -29.176726)
			(xy 319.762632 -29.198316) (xy 319.771043 -29.205312) (xy 319.791848 -29.212015) (xy 319.802764 -29.21127)
			(xy 319.814212 -29.209955) (xy 319.837215 -29.208559) (xy 319.848738 -29.208476) (xy 319.875986 -29.208997)
			(xy 319.929928 -29.216757) (xy 319.982216 -29.232115) (xy 320.031786 -29.254757) (xy 320.077629 -29.284224)
			(xy 320.118813 -29.319914) (xy 320.154499 -29.361101) (xy 320.183961 -29.406948) (xy 320.206598 -29.45652)
			(xy 320.221951 -29.50881) (xy 320.229706 -29.562752) (xy 320.229706 -29.617248) (xy 320.221951 -29.67119)
			(xy 320.206598 -29.72348) (xy 320.183961 -29.773052) (xy 320.154499 -29.818899) (xy 320.118813 -29.860086)
			(xy 320.077629 -29.895776) (xy 320.031786 -29.925243) (xy 319.982216 -29.947885) (xy 319.929928 -29.963243)
			(xy 319.875986 -29.971003) (xy 319.848738 -29.971492) (xy 319.821992 -29.970987) (xy 319.769025 -29.963499)
			(xy 319.717623 -29.948692) (xy 319.66879 -29.926855) (xy 319.623483 -29.898416) (xy 319.582588 -29.863932)
			(xy 319.546906 -29.824079) (xy 319.517136 -29.779635) (xy 319.493861 -29.731471) (xy 319.477535 -29.68053)
			(xy 319.472564 -29.654246) (xy 319.470786 -29.643832) (xy 319.460118 -29.626814) (xy 319.382902 -29.573728)
			(xy 319.36309 -29.569664) (xy 319.35293 -29.571696) (xy 319.331057 -29.575748) (xy 319.286781 -29.580071)
			(xy 319.264538 -29.580332) (xy 319.23715 -29.579885) (xy 319.182774 -29.573266) (xy 319.15608 -29.567124)
			(xy 319.145666 -29.564584) (xy 319.125092 -29.56814) (xy 319.044828 -29.621734) (xy 319.033398 -29.63926)
			(xy 319.03162 -29.649928) (xy 319.026978 -29.676504) (xy 319.011119 -29.72807) (xy 318.988154 -29.776887)
			(xy 318.958539 -29.821982) (xy 318.922865 -29.862453) (xy 318.881845 -29.897495) (xy 318.836297 -29.926407)
			(xy 318.787129 -29.948613) (xy 318.735323 -29.96367) (xy 318.681913 -29.971277) (xy 318.654938 -29.971746)
			(xy 318.627568 -29.971271) (xy 318.573389 -29.963457) (xy 318.520885 -29.947971) (xy 318.471138 -29.925131)
			(xy 318.425171 -29.895407) (xy 318.40424 -29.877766) (xy 318.397128 -29.87167) (xy 318.38011 -29.86532)
			(xy 318.294766 -29.86532) (xy 318.277748 -29.87167) (xy 318.270636 -29.877766) (xy 318.249697 -29.895396)
			(xy 318.203727 -29.925111) (xy 318.153981 -29.947949) (xy 318.101482 -29.963442) (xy 318.047307 -29.971271)
			(xy 318.019938 -29.971746) (xy 318.002826 -29.971555) (xy 317.968739 -29.968502) (xy 317.951866 -29.96565)
			(xy 317.940601 -29.964238) (xy 317.918716 -29.970177) (xy 317.909702 -29.97708) (xy 317.885318 -29.998162)
			(xy 317.876919 -30.006078) (xy 317.867802 -30.027259) (xy 317.867792 -30.038802) (xy 317.8683 -30.058868)
			(xy 317.8683 -30.922468) (xy 317.867792 -30.941772) (xy 317.867944 -30.953283) (xy 317.877059 -30.97439)
			(xy 317.885318 -30.982412) (xy 317.909702 -31.003494) (xy 317.918695 -31.010437) (xy 317.940596 -31.016369)
			(xy 317.951866 -31.014924) (xy 317.968737 -31.012056) (xy 318.002826 -31.009002) (xy 318.019938 -31.008828)
			(xy 318.047307 -31.009324) (xy 318.101485 -31.017133) (xy 318.153988 -31.032615) (xy 318.203736 -31.05545)
			(xy 318.249704 -31.085169) (xy 318.270636 -31.102808) (xy 318.277748 -31.108904) (xy 318.294512 -31.115254)
			(xy 318.38011 -31.115254) (xy 318.397128 -31.108904) (xy 318.403986 -31.102554) (xy 318.424928 -31.084885)
			(xy 318.470946 -31.055145) (xy 318.520748 -31.0323) (xy 318.573307 -31.01682) (xy 318.627542 -31.009024)
			(xy 318.654938 -31.008574) (xy 318.681947 -31.008985) (xy 318.735427 -31.016597) (xy 318.787299 -31.031677)
			(xy 318.836524 -31.053923) (xy 318.882119 -31.082891) (xy 318.923171 -31.118002) (xy 318.958859 -31.158552)
			(xy 318.988471 -31.203732) (xy 319.011413 -31.252637) (xy 319.027226 -31.304289) (xy 319.031874 -31.3309)
			(xy 319.033398 -31.341568) (xy 319.044828 -31.359348) (xy 319.125092 -31.412688) (xy 319.145666 -31.416498)
			(xy 319.156334 -31.413958) (xy 319.182973 -31.407893) (xy 319.237221 -31.401401) (xy 319.264538 -31.401004)
			(xy 319.286711 -31.401227) (xy 319.330857 -31.405429) (xy 319.352676 -31.409386) (xy 319.36309 -31.411418)
			(xy 319.382902 -31.407354) (xy 319.459864 -31.354014) (xy 319.470786 -31.336996) (xy 319.472564 -31.326582)
			(xy 319.477407 -31.300233) (xy 319.493631 -31.249173) (xy 319.516839 -31.200885) (xy 319.546574 -31.156318)
			(xy 319.582251 -31.11635) (xy 319.623169 -31.081766) (xy 319.668523 -31.053246) (xy 319.717421 -31.031352)
			(xy 319.768901 -31.016514) (xy 319.82195 -31.009024) (xy 319.848738 -31.008574) (xy 319.875986 -31.009099)
			(xy 319.929927 -31.016859) (xy 319.982215 -31.032217) (xy 320.031785 -31.054859) (xy 320.077628 -31.084325)
			(xy 320.118812 -31.120015) (xy 320.154498 -31.161202) (xy 320.183959 -31.207049) (xy 320.206596 -31.256621)
			(xy 320.221949 -31.30891) (xy 320.229704 -31.362852) (xy 320.229704 -31.417348) (xy 320.221949 -31.47129)
			(xy 320.206596 -31.523579) (xy 320.183959 -31.573151) (xy 320.154498 -31.618998) (xy 320.118812 -31.660185)
			(xy 320.077628 -31.695875) (xy 320.031785 -31.725341) (xy 319.982215 -31.747983) (xy 319.929927 -31.763341)
			(xy 319.875986 -31.771101) (xy 319.848738 -31.77159) (xy 319.837216 -31.771496) (xy 319.814213 -31.770097)
			(xy 319.802764 -31.768796) (xy 319.79185 -31.768059) (xy 319.771053 -31.774768) (xy 319.762632 -31.78175)
			(xy 319.738756 -31.80334) (xy 319.730928 -31.811213) (xy 319.722227 -31.831611) (xy 319.721992 -31.84271)
			(xy 319.7225 -31.858712) (xy 319.7225 -32.722312) (xy 319.721992 -32.737552) (xy 319.722176 -32.748664)
			(xy 319.730873 -32.769088) (xy 319.738756 -32.776922) (xy 319.762632 -32.798512) (xy 319.771044 -32.805507)
			(xy 319.791848 -32.812211) (xy 319.802764 -32.811466) (xy 319.814212 -32.810151) (xy 319.837215 -32.808755)
			(xy 319.848738 -32.808672) (xy 319.875986 -32.809201) (xy 319.929927 -32.816961) (xy 319.982214 -32.832319)
			(xy 320.031784 -32.854961) (xy 320.077627 -32.884427) (xy 320.118811 -32.920116) (xy 320.154496 -32.961303)
			(xy 320.183957 -33.007149) (xy 320.206594 -33.056722) (xy 320.221947 -33.10901) (xy 320.229702 -33.162952)
			(xy 320.229702 -33.217448) (xy 320.221947 -33.27139) (xy 320.206594 -33.323678) (xy 320.183957 -33.373251)
			(xy 320.154496 -33.419097) (xy 320.118811 -33.460284) (xy 320.077627 -33.495973) (xy 320.031784 -33.525439)
			(xy 319.982214 -33.548081) (xy 319.929927 -33.563439) (xy 319.875986 -33.571199) (xy 319.848738 -33.571688)
			(xy 319.821971 -33.571282) (xy 319.768961 -33.563816) (xy 319.717516 -33.549011) (xy 319.668646 -33.527158)
			(xy 319.623312 -33.498686) (xy 319.582405 -33.464155) (xy 319.546728 -33.424244) (xy 319.516982 -33.379736)
			(xy 319.493751 -33.331505) (xy 319.477493 -33.280501) (xy 319.472564 -33.254188) (xy 319.470786 -33.243774)
			(xy 319.460118 -33.226756) (xy 319.382902 -33.17367) (xy 319.36309 -33.169606) (xy 319.35293 -33.171638)
			(xy 319.331051 -33.175623) (xy 319.286776 -33.179819) (xy 319.264538 -33.18002) (xy 319.237156 -33.179654)
			(xy 319.18278 -33.173153) (xy 319.15608 -33.167066) (xy 319.145666 -33.164526) (xy 319.125092 -33.168082)
			(xy 319.044828 -33.221676) (xy 319.033398 -33.239202) (xy 319.03162 -33.24987) (xy 319.026933 -33.276438)
			(xy 319.011083 -33.328004) (xy 318.988124 -33.376821) (xy 318.958515 -33.421917) (xy 318.922847 -33.46239)
			(xy 318.881831 -33.497433) (xy 318.836287 -33.526347) (xy 318.787123 -33.548554) (xy 318.73532 -33.563611)
			(xy 318.681911 -33.571218) (xy 318.654938 -33.571688) (xy 318.627568 -33.571203) (xy 318.57339 -33.56339)
			(xy 318.520887 -33.547905) (xy 318.47114 -33.525068) (xy 318.425172 -33.495347) (xy 318.40424 -33.477708)
			(xy 318.397128 -33.471612) (xy 318.38011 -33.465262) (xy 318.294766 -33.465262) (xy 318.277748 -33.471612)
			(xy 318.270636 -33.477708) (xy 318.249702 -33.495345) (xy 318.20373 -33.525057) (xy 318.153983 -33.547893)
			(xy 318.101482 -33.563385) (xy 318.047307 -33.571214) (xy 318.019938 -33.571688) (xy 318.002826 -33.571496)
			(xy 317.968739 -33.568444) (xy 317.951866 -33.565592) (xy 317.940601 -33.56417) (xy 317.918715 -33.570114)
			(xy 317.909702 -33.577022) (xy 317.885318 -33.598104) (xy 317.876947 -33.606045) (xy 317.867814 -33.627206)
			(xy 317.867792 -33.638744) (xy 317.8683 -33.65881) (xy 317.8683 -34.52241) (xy 317.867792 -34.541714)
			(xy 317.867978 -34.553222) (xy 317.877069 -34.574329) (xy 317.885318 -34.582354) (xy 317.909702 -34.603436)
			(xy 317.918699 -34.610374) (xy 317.940597 -34.616311) (xy 317.951866 -34.614866) (xy 317.968737 -34.611999)
			(xy 318.002826 -34.608944) (xy 318.019938 -34.60877) (xy 318.047189 -34.609242) (xy 318.101136 -34.617004)
			(xy 318.15343 -34.632362) (xy 318.203006 -34.655006) (xy 318.248855 -34.684475) (xy 318.290044 -34.720167)
			(xy 318.325735 -34.761358) (xy 318.355201 -34.807208) (xy 318.377843 -34.856785) (xy 318.3932 -34.909079)
			(xy 318.400959 -34.963027) (xy 318.401441 -34.990024) (xy 319.46672 -34.990024) (xy 319.470791 -34.934402)
			(xy 319.482917 -34.879965) (xy 319.50284 -34.827874) (xy 319.530136 -34.779239) (xy 319.564222 -34.735096)
			(xy 319.604371 -34.696387) (xy 319.649729 -34.663936) (xy 319.699329 -34.638435) (xy 319.752113 -34.620428)
			(xy 319.806956 -34.610298) (xy 319.86269 -34.608261) (xy 319.918127 -34.614361) (xy 319.972084 -34.628467)
			(xy 320.023413 -34.650279) (xy 320.071019 -34.679333) (xy 320.113887 -34.715008) (xy 320.151104 -34.756545)
			(xy 320.181877 -34.803058) (xy 320.205549 -34.853555) (xy 320.221617 -34.906962) (xy 320.229737 -34.962138)
			(xy 320.230246 -34.990024) (xy 320.229737 -35.01791) (xy 320.221617 -35.073086) (xy 320.205549 -35.126493)
			(xy 320.181877 -35.17699) (xy 320.151104 -35.223503) (xy 320.113887 -35.26504) (xy 320.071019 -35.300715)
			(xy 320.023413 -35.329769) (xy 319.972084 -35.351581) (xy 319.918127 -35.365687) (xy 319.86269 -35.371787)
			(xy 319.806956 -35.36975) (xy 319.752113 -35.35962) (xy 319.699329 -35.341613) (xy 319.649729 -35.316112)
			(xy 319.604371 -35.283661) (xy 319.564222 -35.244952) (xy 319.530136 -35.200809) (xy 319.50284 -35.152174)
			(xy 319.482917 -35.100083) (xy 319.470791 -35.045646) (xy 319.46672 -34.990024) (xy 318.401441 -34.990024)
			(xy 318.401446 -34.990278) (xy 318.401011 -35.017051) (xy 318.3935 -35.070069) (xy 318.378651 -35.121515)
			(xy 318.356754 -35.17038) (xy 318.328241 -35.215705) (xy 318.293672 -35.256597) (xy 318.253725 -35.292255)
			(xy 318.209185 -35.321978) (xy 318.160927 -35.345182) (xy 318.109899 -35.361411) (xy 318.057103 -35.370347)
			(xy 318.030352 -35.371532) (xy 318.017906 -35.37204) (xy 317.996824 -35.38347) (xy 317.936372 -35.471862)
			(xy 317.933324 -35.495484) (xy 317.937388 -35.507168) (xy 317.947705 -35.538161) (xy 317.958818 -35.602526)
			(xy 317.959486 -35.635184) (xy 317.959 -35.662435) (xy 317.951244 -35.716383) (xy 317.935889 -35.768678)
			(xy 317.913247 -35.818255) (xy 317.883781 -35.864105) (xy 317.84809 -35.905296) (xy 317.806899 -35.940987)
			(xy 317.761049 -35.970453) (xy 317.711472 -35.993095) (xy 317.659177 -36.00845) (xy 317.605229 -36.016206)
			(xy 317.550727 -36.016206) (xy 317.496779 -36.00845) (xy 317.444484 -35.993095) (xy 317.394907 -35.970453)
			(xy 317.349057 -35.940987) (xy 317.307866 -35.905296) (xy 317.272175 -35.864105) (xy 317.242709 -35.818255)
			(xy 317.220067 -35.768678) (xy 317.204712 -35.716383) (xy 317.196956 -35.662435) (xy 317.19647 -35.635184)
			(xy 317.196951 -35.608414) (xy 317.204465 -35.555402) (xy 317.219315 -35.503961) (xy 317.24121 -35.455101)
			(xy 317.269719 -35.409781) (xy 317.304283 -35.368891) (xy 317.344224 -35.333233) (xy 317.388756 -35.303509)
			(xy 317.437007 -35.280301) (xy 317.488027 -35.264065) (xy 317.540816 -35.25512) (xy 317.567564 -35.25393)
			(xy 317.58001 -35.253422) (xy 317.601092 -35.241992) (xy 317.661544 -35.1536) (xy 317.664592 -35.129978)
			(xy 317.660528 -35.118294) (xy 317.654825 -35.101592) (xy 317.646176 -35.067373) (xy 317.643256 -35.049968)
			(xy 317.641478 -35.0393) (xy 317.630048 -35.021774) (xy 317.549784 -34.96818) (xy 317.52921 -34.964624)
			(xy 317.518796 -34.967164) (xy 317.4921 -34.973295) (xy 317.437725 -34.979923) (xy 317.410338 -34.980372)
			(xy 317.38295 -34.979924) (xy 317.328574 -34.973306) (xy 317.30188 -34.967164) (xy 317.291466 -34.964624)
			(xy 317.270892 -34.96818) (xy 317.190628 -35.021774) (xy 317.179198 -35.0393) (xy 317.17742 -35.049968)
			(xy 317.172808 -35.076549) (xy 317.156945 -35.128116) (xy 317.133974 -35.176933) (xy 317.104355 -35.222026)
			(xy 317.068678 -35.262497) (xy 317.027655 -35.297538) (xy 316.982104 -35.326449) (xy 316.932934 -35.348654)
			(xy 316.881126 -35.36371) (xy 316.827714 -35.371317) (xy 316.800738 -35.371786) (xy 316.773482 -35.37137)
			(xy 316.719524 -35.363617) (xy 316.667218 -35.348263) (xy 316.61763 -35.325621) (xy 316.57177 -35.296153)
			(xy 316.53057 -35.260457) (xy 316.49487 -35.219261) (xy 316.465397 -35.173403) (xy 316.44275 -35.123818)
			(xy 316.427391 -35.071514) (xy 316.419633 -35.017556) (xy 314.774244 -35.017556) (xy 314.786624 -35.031373)
			(xy 314.817397 -35.077886) (xy 314.841069 -35.128383) (xy 314.857137 -35.18179) (xy 314.865257 -35.236966)
			(xy 314.865766 -35.264852) (xy 314.865257 -35.292738) (xy 314.857137 -35.347914) (xy 314.841069 -35.401321)
			(xy 314.817397 -35.451818) (xy 314.786624 -35.498331) (xy 314.749407 -35.539868) (xy 314.706539 -35.575543)
			(xy 314.658933 -35.604597) (xy 314.607604 -35.626409) (xy 314.553647 -35.640515) (xy 314.49821 -35.646615)
			(xy 314.442476 -35.644578) (xy 314.387633 -35.634448) (xy 314.334849 -35.616441) (xy 314.285249 -35.59094)
			(xy 314.239891 -35.558489) (xy 314.199742 -35.51978) (xy 314.165656 -35.475637) (xy 314.13836 -35.427002)
			(xy 314.118437 -35.374911) (xy 314.106311 -35.320474) (xy 314.10224 -35.264852) (xy 311.60085 -35.264852)
			(xy 311.60085 -37.087048) (xy 315.40069 -37.087048) (xy 315.40118 -37.060445) (xy 315.408555 -37.007754)
			(xy 315.423182 -36.9566) (xy 315.444778 -36.907975) (xy 315.472923 -36.862824) (xy 315.507071 -36.822024)
			(xy 315.546559 -36.786366) (xy 315.56833 -36.771072) (xy 315.578262 -36.763551) (xy 315.589984 -36.7416)
			(xy 315.590682 -36.729162) (xy 315.590682 -36.644834) (xy 315.590032 -36.632381) (xy 315.578309 -36.610403)
			(xy 315.56833 -36.602924) (xy 315.54656 -36.587629) (xy 315.507081 -36.551962) (xy 315.472938 -36.511159)
			(xy 315.444793 -36.466009) (xy 315.42319 -36.417388) (xy 315.40855 -36.366238) (xy 315.401154 -36.31355)
			(xy 315.40069 -36.286948) (xy 315.4012 -36.259696) (xy 315.40895 -36.205747) (xy 315.4243 -36.15345)
			(xy 315.446937 -36.103871) (xy 315.4764 -36.058017) (xy 315.512089 -36.016824) (xy 315.553277 -35.98113)
			(xy 315.599127 -35.951661) (xy 315.648703 -35.929018) (xy 315.700998 -35.913661) (xy 315.754946 -35.905904)
			(xy 315.782198 -35.90544) (xy 315.78677 -35.90544) (xy 315.796422 -35.905694) (xy 315.813186 -35.899344)
			(xy 315.878718 -35.843464) (xy 315.887354 -35.827462) (xy 315.888624 -35.818064) (xy 315.892931 -35.791126)
			(xy 315.908244 -35.738767) (xy 315.930858 -35.689123) (xy 315.960313 -35.643206) (xy 315.996009 -35.601953)
			(xy 316.037216 -35.566206) (xy 316.083095 -35.536692) (xy 316.13271 -35.514014) (xy 316.185049 -35.498635)
			(xy 316.239046 -35.490867) (xy 316.266322 -35.490404) (xy 316.293573 -35.490867) (xy 316.34752 -35.498627)
			(xy 316.399814 -35.513984) (xy 316.44939 -35.536627) (xy 316.495239 -35.566095) (xy 316.536428 -35.601788)
			(xy 316.572118 -35.642979) (xy 316.601583 -35.688829) (xy 316.624224 -35.738407) (xy 316.639578 -35.790701)
			(xy 316.647334 -35.844649) (xy 316.647334 -35.899151) (xy 316.639578 -35.953099) (xy 316.624224 -36.005393)
			(xy 316.601583 -36.054971) (xy 316.572118 -36.100821) (xy 316.536428 -36.142012) (xy 316.495239 -36.177705)
			(xy 316.44939 -36.207173) (xy 316.399814 -36.229816) (xy 316.34752 -36.245173) (xy 316.293573 -36.252933)
			(xy 316.266322 -36.25342) (xy 316.26175 -36.25342) (xy 316.252098 -36.253166) (xy 316.235334 -36.259516)
			(xy 316.169802 -36.315396) (xy 316.161166 -36.331398) (xy 316.159896 -36.340796) (xy 316.15568 -36.366996)
			(xy 316.140998 -36.417989) (xy 316.119388 -36.466454) (xy 316.091267 -36.511456) (xy 316.087837 -36.515548)
			(xy 317.213994 -36.515548) (xy 317.218065 -36.459926) (xy 317.230191 -36.405489) (xy 317.250114 -36.353398)
			(xy 317.27741 -36.304763) (xy 317.311496 -36.26062) (xy 317.351645 -36.221911) (xy 317.397003 -36.18946)
			(xy 317.446603 -36.163959) (xy 317.499387 -36.145952) (xy 317.55423 -36.135822) (xy 317.609964 -36.133785)
			(xy 317.665401 -36.139885) (xy 317.719358 -36.153991) (xy 317.770687 -36.175803) (xy 317.818293 -36.204857)
			(xy 317.861161 -36.240532) (xy 317.898378 -36.282069) (xy 317.929151 -36.328582) (xy 317.952823 -36.379079)
			(xy 317.968891 -36.432486) (xy 317.977011 -36.487662) (xy 317.97752 -36.515548) (xy 317.977011 -36.543434)
			(xy 317.968891 -36.59861) (xy 317.952823 -36.652017) (xy 317.929151 -36.702514) (xy 317.898378 -36.749027)
			(xy 317.861161 -36.790564) (xy 317.818293 -36.826239) (xy 317.770687 -36.855293) (xy 317.719358 -36.877105)
			(xy 317.665401 -36.891211) (xy 317.609964 -36.897311) (xy 317.55423 -36.895274) (xy 317.499387 -36.885144)
			(xy 317.446603 -36.867137) (xy 317.397003 -36.841636) (xy 317.351645 -36.809185) (xy 317.311496 -36.770476)
			(xy 317.27741 -36.726333) (xy 317.250114 -36.677698) (xy 317.230191 -36.625607) (xy 317.218065 -36.57117)
			(xy 317.213994 -36.515548) (xy 316.087837 -36.515548) (xy 316.057179 -36.552124) (xy 316.017782 -36.587673)
			(xy 315.996066 -36.602924) (xy 315.986135 -36.610447) (xy 315.974413 -36.632397) (xy 315.973714 -36.644834)
			(xy 315.973714 -36.729162) (xy 315.974368 -36.741615) (xy 315.986088 -36.763592) (xy 315.996066 -36.771072)
			(xy 316.017833 -36.786371) (xy 316.057312 -36.822037) (xy 316.091456 -36.86284) (xy 316.119601 -36.907989)
			(xy 316.141204 -36.956609) (xy 316.155845 -37.007759) (xy 316.163241 -37.060446) (xy 316.163706 -37.087048)
			(xy 316.163101 -37.118807) (xy 316.152614 -37.181453) (xy 316.131874 -37.241489) (xy 316.117224 -37.269674)
			(xy 316.11189 -37.27958) (xy 316.110366 -37.301678) (xy 316.14618 -37.394896) (xy 316.162182 -37.41039)
			(xy 316.17285 -37.4142) (xy 316.197372 -37.423295) (xy 316.243904 -37.447172) (xy 316.286736 -37.477183)
			(xy 316.325067 -37.512765) (xy 316.358176 -37.55325) (xy 316.385444 -37.597879) (xy 316.406358 -37.645816)
			(xy 316.420527 -37.69616) (xy 316.427683 -37.747968) (xy 316.42812 -37.774118) (xy 316.427634 -37.801369)
			(xy 316.419878 -37.855317) (xy 316.404523 -37.907612) (xy 316.381881 -37.957189) (xy 316.352415 -38.003039)
			(xy 316.316724 -38.04423) (xy 316.275533 -38.079921) (xy 316.229683 -38.109387) (xy 316.180106 -38.132029)
			(xy 316.127811 -38.147384) (xy 316.073863 -38.15514) (xy 316.019361 -38.15514) (xy 315.965413 -38.147384)
			(xy 315.913118 -38.132029) (xy 315.863541 -38.109387) (xy 315.817691 -38.079921) (xy 315.7765 -38.04423)
			(xy 315.740809 -38.003039) (xy 315.711343 -37.957189) (xy 315.688701 -37.907612) (xy 315.673346 -37.855317)
			(xy 315.66559 -37.801369) (xy 315.665104 -37.774118) (xy 315.665695 -37.742358) (xy 315.676187 -37.679712)
			(xy 315.696933 -37.619676) (xy 315.711586 -37.591492) (xy 315.71692 -37.581586) (xy 315.718444 -37.559488)
			(xy 315.68263 -37.46627) (xy 315.666628 -37.450776) (xy 315.65596 -37.446966) (xy 315.631407 -37.437952)
			(xy 315.584876 -37.414061) (xy 315.542045 -37.384038) (xy 315.503718 -37.348445) (xy 315.470612 -37.307949)
			(xy 315.443349 -37.263311) (xy 315.422439 -37.215366) (xy 315.408276 -37.165015) (xy 315.401124 -37.113201)
			(xy 315.40069 -37.087048) (xy 311.60085 -37.087048) (xy 311.60085 -38.315138) (xy 316.617856 -38.315138)
			(xy 316.621927 -38.259516) (xy 316.634053 -38.205079) (xy 316.653976 -38.152988) (xy 316.681272 -38.104353)
			(xy 316.715358 -38.06021) (xy 316.755507 -38.021501) (xy 316.800865 -37.98905) (xy 316.850465 -37.963549)
			(xy 316.903249 -37.945542) (xy 316.958092 -37.935412) (xy 317.013826 -37.933375) (xy 317.069263 -37.939475)
			(xy 317.12322 -37.953581) (xy 317.174549 -37.975393) (xy 317.222155 -38.004447) (xy 317.265023 -38.040122)
			(xy 317.30224 -38.081659) (xy 317.333013 -38.128172) (xy 317.356685 -38.178669) (xy 317.372753 -38.232076)
			(xy 317.380873 -38.287252) (xy 317.381382 -38.315138) (xy 317.380873 -38.343024) (xy 317.372753 -38.3982)
			(xy 317.356685 -38.451607) (xy 317.333013 -38.502104) (xy 317.30224 -38.548617) (xy 317.265023 -38.590154)
			(xy 317.222155 -38.625829) (xy 317.174549 -38.654883) (xy 317.12322 -38.676695) (xy 317.069263 -38.690801)
			(xy 317.013826 -38.696901) (xy 316.958092 -38.694864) (xy 316.903249 -38.684734) (xy 316.850465 -38.666727)
			(xy 316.800865 -38.641226) (xy 316.755507 -38.608775) (xy 316.715358 -38.570066) (xy 316.681272 -38.525923)
			(xy 316.653976 -38.477288) (xy 316.634053 -38.425197) (xy 316.621927 -38.37076) (xy 316.617856 -38.315138)
			(xy 311.60085 -38.315138) (xy 311.60085 -42.4307) (xy 311.601141 -42.438368) (xy 311.605786 -42.452985)
			(xy 311.609994 -42.459402) (xy 311.609994 -42.459656) (xy 311.614816 -42.466097) (xy 311.627632 -42.475814)
			(xy 311.63514 -42.478706) (xy 311.635648 -42.47896) (xy 311.660631 -42.487766) (xy 311.708084 -42.511308)
			(xy 311.751823 -42.541188) (xy 311.791008 -42.576832) (xy 311.824885 -42.617554) (xy 311.852803 -42.662571)
			(xy 311.874225 -42.711018) (xy 311.888739 -42.761962) (xy 311.896066 -42.814424) (xy 311.896506 -42.84091)
			(xy 311.895965 -42.87028) (xy 311.886963 -42.928325) (xy 311.869172 -42.984306) (xy 311.843013 -43.036899)
			(xy 311.809104 -43.084863) (xy 311.789064 -43.10634) (xy 311.788302 -43.107102) (xy 311.787794 -43.10761)
			(xy 311.766723 -43.129145) (xy 311.719027 -43.165949) (xy 311.666131 -43.194788) (xy 311.637934 -43.2054)
			(xy 311.63514 -43.206416) (xy 311.629044 -43.209464) (xy 311.620804 -43.214045) (xy 311.608106 -43.227956)
			(xy 311.601284 -43.245513) (xy 311.60085 -43.25493) (xy 311.60085 -43.4467) (xy 311.601141 -43.454368)
			(xy 311.605786 -43.468985) (xy 311.609994 -43.475402) (xy 311.609994 -43.475656) (xy 311.614816 -43.482097)
			(xy 311.627632 -43.491814) (xy 311.63514 -43.494706) (xy 311.635648 -43.49496) (xy 311.660631 -43.503766)
			(xy 311.708084 -43.527308) (xy 311.751823 -43.557188) (xy 311.791008 -43.592832) (xy 311.824885 -43.633554)
			(xy 311.852803 -43.678571) (xy 311.874225 -43.727018) (xy 311.888739 -43.777962) (xy 311.896066 -43.830424)
			(xy 311.896506 -43.85691) (xy 311.895965 -43.88628) (xy 311.886963 -43.944325) (xy 311.869172 -44.000306)
			(xy 311.843013 -44.052899) (xy 311.809104 -44.100863) (xy 311.789064 -44.12234) (xy 311.788302 -44.123102)
			(xy 311.787794 -44.12361) (xy 311.766723 -44.145145) (xy 311.719027 -44.181949) (xy 311.666131 -44.210788)
			(xy 311.637934 -44.2214) (xy 311.63514 -44.222416) (xy 311.629044 -44.225464) (xy 311.620804 -44.230045)
			(xy 311.608106 -44.243956) (xy 311.601284 -44.261513) (xy 311.60085 -44.27093) (xy 311.60085 -44.4627)
			(xy 311.601141 -44.470368) (xy 311.605786 -44.484985) (xy 311.609994 -44.491402) (xy 311.609994 -44.491656)
			(xy 311.614816 -44.498097) (xy 311.627632 -44.507814) (xy 311.63514 -44.510706) (xy 311.635648 -44.51096)
			(xy 311.660631 -44.519766) (xy 311.708084 -44.543308) (xy 311.751823 -44.573188) (xy 311.791008 -44.608832)
			(xy 311.824885 -44.649554) (xy 311.852803 -44.694571) (xy 311.874225 -44.743018) (xy 311.888739 -44.793962)
			(xy 311.896066 -44.846424) (xy 311.896506 -44.87291) (xy 311.895965 -44.90228) (xy 311.886963 -44.960325)
			(xy 311.869172 -45.016306) (xy 311.843013 -45.068899) (xy 311.809104 -45.116863) (xy 311.789064 -45.13834)
			(xy 311.788302 -45.139102) (xy 311.787794 -45.13961) (xy 311.766723 -45.161145) (xy 311.719027 -45.197949)
			(xy 311.666131 -45.226788) (xy 311.637934 -45.2374) (xy 311.63514 -45.238416) (xy 311.629044 -45.241464)
			(xy 311.620804 -45.246045) (xy 311.608106 -45.259956) (xy 311.601284 -45.277513) (xy 311.60085 -45.28693)
			(xy 311.60085 -45.4787) (xy 311.601141 -45.486368) (xy 311.605786 -45.500985) (xy 311.609994 -45.507402)
			(xy 311.609994 -45.507656) (xy 311.614816 -45.514097) (xy 311.627632 -45.523814) (xy 311.63514 -45.526706)
			(xy 311.635648 -45.52696) (xy 311.660631 -45.535766) (xy 311.708084 -45.559308) (xy 311.751823 -45.589188)
			(xy 311.791008 -45.624832) (xy 311.824885 -45.665554) (xy 311.852803 -45.710571) (xy 311.874225 -45.759018)
			(xy 311.888739 -45.809962) (xy 311.896066 -45.862424) (xy 311.896506 -45.88891) (xy 311.895965 -45.91828)
			(xy 311.886963 -45.976325) (xy 311.869172 -46.032306) (xy 311.843013 -46.084899) (xy 311.809104 -46.132863)
			(xy 311.789064 -46.15434) (xy 311.788302 -46.155102) (xy 311.787794 -46.15561) (xy 311.766723 -46.177145)
			(xy 311.719027 -46.213949) (xy 311.666131 -46.242788) (xy 311.637934 -46.2534) (xy 311.63514 -46.254416)
			(xy 311.629044 -46.257464) (xy 311.620804 -46.262045) (xy 311.608106 -46.275956) (xy 311.601284 -46.293513)
			(xy 311.60085 -46.30293) (xy 311.60085 -47.040546) (xy 311.621932 -47.067724) (xy 311.63895 -47.072296)
			(xy 311.665905 -47.07973) (xy 311.717446 -47.10141) (xy 311.765265 -47.130389) (xy 311.808337 -47.166044)
			(xy 311.845736 -47.20761) (xy 311.87666 -47.254195) (xy 311.900446 -47.304799) (xy 311.916581 -47.358335)
			(xy 311.924721 -47.413654) (xy 311.925208 -47.441612) (xy 311.925129 -47.45435) (xy 311.923475 -47.479771)
			(xy 311.921906 -47.492412) (xy 311.921652 -47.494952) (xy 311.916872 -47.524514) (xy 311.899313 -47.581761)
			(xy 311.873028 -47.635564) (xy 311.838662 -47.684601) (xy 311.818274 -47.706534) (xy 311.817766 -47.707042)
			(xy 311.815988 -47.709074) (xy 311.797712 -47.727724) (xy 311.756948 -47.760357) (xy 311.712113 -47.787122)
			(xy 311.664044 -47.807519) (xy 311.63895 -47.814738) (xy 311.638442 -47.814992) (xy 311.637172 -47.8155)
			(xy 311.626877 -47.819073) (xy 311.610426 -47.833333) (xy 311.601367 -47.853129) (xy 311.60085 -47.864014)
			(xy 311.60085 -48.5267) (xy 311.601141 -48.534368) (xy 311.605786 -48.548985) (xy 311.609994 -48.555402)
			(xy 311.609994 -48.555656) (xy 311.614816 -48.562097) (xy 311.627632 -48.571814) (xy 311.63514 -48.574706)
			(xy 311.635648 -48.57496) (xy 311.660631 -48.583766) (xy 311.708084 -48.607308) (xy 311.751823 -48.637188)
			(xy 311.791008 -48.672832) (xy 311.824885 -48.713554) (xy 311.852803 -48.758571) (xy 311.874225 -48.807018)
			(xy 311.888739 -48.857962) (xy 311.896066 -48.910424) (xy 311.896506 -48.93691) (xy 311.895965 -48.96628)
			(xy 311.886963 -49.024325) (xy 311.869172 -49.080306) (xy 311.843013 -49.132899) (xy 311.809104 -49.180863)
			(xy 311.789064 -49.20234) (xy 311.788302 -49.203102) (xy 311.787794 -49.20361) (xy 311.766723 -49.225145)
			(xy 311.719027 -49.261949) (xy 311.666131 -49.290788) (xy 311.637934 -49.3014) (xy 311.63514 -49.302416)
			(xy 311.629044 -49.305464) (xy 311.620804 -49.310045) (xy 311.608106 -49.323956) (xy 311.601284 -49.341513)
			(xy 311.60085 -49.35093) (xy 311.60085 -49.53381) (xy 311.60111 -49.541454) (xy 311.605638 -49.556056)
			(xy 311.60974 -49.562512) (xy 311.628282 -49.589944) (xy 311.64022 -49.599088) (xy 311.647134 -49.601949)
			(xy 312.490882 -49.601949) (xy 312.490882 -49.547451) (xy 312.498637 -49.493506) (xy 312.51399 -49.441215)
			(xy 312.536629 -49.39164) (xy 312.566092 -49.345792) (xy 312.601779 -49.304603) (xy 312.642965 -49.268912)
			(xy 312.688811 -49.239445) (xy 312.738383 -49.216802) (xy 312.790673 -49.201444) (xy 312.844617 -49.193684)
			(xy 312.871866 -49.193196) (xy 312.899235 -49.193683) (xy 312.953414 -49.201496) (xy 313.005916 -49.21698)
			(xy 313.055664 -49.239817) (xy 313.101632 -49.269537) (xy 313.122564 -49.287176) (xy 313.129676 -49.293272)
			(xy 313.146694 -49.299622) (xy 313.232038 -49.299622) (xy 313.249056 -49.293272) (xy 313.256168 -49.287176)
			(xy 313.277101 -49.269535) (xy 313.323069 -49.239811) (xy 313.372815 -49.216965) (xy 313.425317 -49.201469)
			(xy 313.479495 -49.19364) (xy 313.534237 -49.19364) (xy 313.588415 -49.201469) (xy 313.640917 -49.216965)
			(xy 313.690663 -49.239811) (xy 313.736631 -49.269535) (xy 313.757564 -49.287176) (xy 313.764676 -49.293272)
			(xy 313.781694 -49.299622) (xy 313.867038 -49.299622) (xy 313.884056 -49.293272) (xy 313.891168 -49.287176)
			(xy 313.912098 -49.269535) (xy 313.958072 -49.239824) (xy 314.00782 -49.216989) (xy 314.060321 -49.201498)
			(xy 314.114497 -49.19367) (xy 314.141866 -49.193196) (xy 314.168183 -49.193627) (xy 314.220318 -49.200851)
			(xy 314.270966 -49.215169) (xy 314.319168 -49.236308) (xy 314.36401 -49.263867) (xy 314.40464 -49.297324)
			(xy 314.42279 -49.316386) (xy 314.430315 -49.323783) (xy 314.449592 -49.332311) (xy 314.460128 -49.332896)
			(xy 314.534804 -49.332896) (xy 314.545356 -49.332384) (xy 314.564651 -49.323837) (xy 314.572142 -49.316386)
			(xy 314.590253 -49.297284) (xy 314.630879 -49.263808) (xy 314.675725 -49.236241) (xy 314.723937 -49.215107)
			(xy 314.774598 -49.200807) (xy 314.826745 -49.193614) (xy 314.853066 -49.193196) (xy 314.880321 -49.193649)
			(xy 314.934276 -49.201402) (xy 314.986578 -49.216755) (xy 315.036163 -49.239396) (xy 315.082021 -49.268864)
			(xy 315.123218 -49.304558) (xy 315.158916 -49.345752) (xy 315.188387 -49.391607) (xy 315.211033 -49.44119)
			(xy 315.226391 -49.493491) (xy 315.234149 -49.547445) (xy 315.234149 -49.601955) (xy 315.226391 -49.655909)
			(xy 315.211033 -49.70821) (xy 315.188387 -49.757793) (xy 315.158916 -49.803648) (xy 315.123218 -49.844842)
			(xy 315.082021 -49.880536) (xy 315.036163 -49.910004) (xy 314.986578 -49.932645) (xy 314.934276 -49.947998)
			(xy 314.880321 -49.955751) (xy 314.853066 -49.956212) (xy 314.82675 -49.955758) (xy 314.774616 -49.948537)
			(xy 314.723968 -49.934224) (xy 314.675766 -49.91309) (xy 314.630924 -49.885535) (xy 314.590292 -49.852082)
			(xy 314.572142 -49.833022) (xy 314.564604 -49.82564) (xy 314.545336 -49.817104) (xy 314.534804 -49.816512)
			(xy 314.460128 -49.816512) (xy 314.449578 -49.817039) (xy 314.430282 -49.825575) (xy 314.42279 -49.833022)
			(xy 314.404645 -49.852091) (xy 314.364028 -49.885573) (xy 314.319191 -49.913147) (xy 314.270985 -49.934288)
			(xy 314.220328 -49.948594) (xy 314.168185 -49.955792) (xy 314.141866 -49.956212) (xy 314.114495 -49.955763)
			(xy 314.060316 -49.947941) (xy 314.007812 -49.932447) (xy 313.958066 -49.909602) (xy 313.912099 -49.879874)
			(xy 313.891168 -49.862232) (xy 313.884056 -49.856136) (xy 313.867038 -49.849786) (xy 313.781694 -49.849786)
			(xy 313.764676 -49.856136) (xy 313.757564 -49.862232) (xy 313.736631 -49.879873) (xy 313.690663 -49.909597)
			(xy 313.640917 -49.932443) (xy 313.588415 -49.947939) (xy 313.534237 -49.955768) (xy 313.479495 -49.955768)
			(xy 313.425317 -49.947939) (xy 313.372815 -49.932443) (xy 313.323069 -49.909597) (xy 313.277101 -49.879873)
			(xy 313.256168 -49.862232) (xy 313.249056 -49.856136) (xy 313.232038 -49.849786) (xy 313.146694 -49.849786)
			(xy 313.129676 -49.856136) (xy 313.122564 -49.862232) (xy 313.101623 -49.87986) (xy 313.055652 -49.909572)
			(xy 313.005907 -49.93241) (xy 312.953408 -49.947904) (xy 312.899234 -49.955736) (xy 312.871866 -49.956212)
			(xy 312.844617 -49.955716) (xy 312.790673 -49.947956) (xy 312.738383 -49.932598) (xy 312.688811 -49.909955)
			(xy 312.642965 -49.880488) (xy 312.601779 -49.844797) (xy 312.566092 -49.803608) (xy 312.536629 -49.75776)
			(xy 312.51399 -49.708185) (xy 312.498637 -49.655894) (xy 312.490882 -49.601949) (xy 311.647134 -49.601949)
			(xy 311.647586 -49.602136) (xy 311.672882 -49.612402) (xy 311.720486 -49.639122) (xy 311.763795 -49.672355)
			(xy 311.801925 -49.711423) (xy 311.834095 -49.755527) (xy 311.859651 -49.803767) (xy 311.878068 -49.855157)
			(xy 311.888971 -49.908648) (xy 311.892138 -49.963147) (xy 311.887504 -50.01754) (xy 311.875163 -50.070718)
			(xy 311.855368 -50.121593) (xy 311.828522 -50.169127) (xy 311.795174 -50.212348) (xy 311.756006 -50.250374)
			(xy 311.711817 -50.282429) (xy 311.66351 -50.307856) (xy 311.637934 -50.3174) (xy 311.63514 -50.318416)
			(xy 311.629044 -50.321464) (xy 311.620804 -50.326045) (xy 311.608106 -50.339956) (xy 311.601284 -50.357513)
			(xy 311.60085 -50.36693) (xy 311.60085 -50.62347) (xy 311.620408 -50.65014) (xy 311.636664 -50.65522)
			(xy 311.662206 -50.663668) (xy 311.710805 -50.68674) (xy 311.755681 -50.716412) (xy 311.795943 -50.752094)
			(xy 311.830792 -50.793079) (xy 311.859537 -50.838553) (xy 311.881609 -50.887615) (xy 311.896568 -50.939291)
			(xy 311.904119 -50.992557) (xy 311.904634 -51.019456) (xy 311.90408 -51.048682) (xy 311.895173 -51.106451)
			(xy 311.877562 -51.162186) (xy 311.851657 -51.214584) (xy 311.818065 -51.262419) (xy 311.798208 -51.28387)
			(xy 311.797446 -51.284632) (xy 311.796938 -51.28514) (xy 311.774481 -51.308175) (xy 311.723287 -51.347126)
			(xy 311.666293 -51.376951) (xy 311.635902 -51.387502) (xy 311.628282 -51.390042) (xy 311.615328 -51.399186)
			(xy 311.610756 -51.40579) (xy 311.606196 -51.41243) (xy 311.601139 -51.427713) (xy 311.60085 -51.435762)
			(xy 311.60085 -51.63947) (xy 311.620408 -51.66614) (xy 311.636664 -51.67122) (xy 311.662206 -51.679668)
			(xy 311.681973 -51.689052) (xy 312.455277 -51.689052) (xy 312.455277 -51.634548) (xy 312.463034 -51.5806)
			(xy 312.478389 -51.528305) (xy 312.501031 -51.478727) (xy 312.530498 -51.432876) (xy 312.56619 -51.391686)
			(xy 312.607381 -51.355994) (xy 312.653232 -51.326528) (xy 312.70281 -51.303887) (xy 312.755106 -51.288533)
			(xy 312.809054 -51.280777) (xy 312.836306 -51.280314) (xy 312.863677 -51.280773) (xy 312.917856 -51.288592)
			(xy 312.970359 -51.304083) (xy 313.020106 -51.326926) (xy 313.066073 -51.356652) (xy 313.087004 -51.374294)
			(xy 313.094116 -51.38039) (xy 313.111134 -51.38674) (xy 313.196478 -51.38674) (xy 313.213496 -51.38039)
			(xy 313.220608 -51.374294) (xy 313.241525 -51.356637) (xy 313.287502 -51.326928) (xy 313.337254 -51.304096)
			(xy 313.389757 -51.288609) (xy 313.443936 -51.280785) (xy 313.471306 -51.280314) (xy 313.489649 -51.280542)
			(xy 313.526162 -51.284108) (xy 313.544204 -51.287426) (xy 313.555126 -51.289458) (xy 313.5757 -51.284632)
			(xy 313.653678 -51.225704) (xy 313.664092 -51.206908) (xy 313.664854 -51.195986) (xy 313.667742 -51.167701)
			(xy 313.68078 -51.112363) (xy 313.701878 -51.05957) (xy 313.730568 -51.010487) (xy 313.766218 -50.966199)
			(xy 313.786774 -50.946558) (xy 313.794192 -50.939051) (xy 313.802708 -50.91976) (xy 313.803284 -50.90922)
			(xy 313.803284 -50.834544) (xy 313.80275 -50.823995) (xy 313.794219 -50.804699) (xy 313.786774 -50.797206)
			(xy 313.767712 -50.779054) (xy 313.734229 -50.738439) (xy 313.706655 -50.693603) (xy 313.685513 -50.645398)
			(xy 313.671205 -50.594743) (xy 313.664005 -50.542601) (xy 313.663584 -50.516282) (xy 313.66407 -50.489031)
			(xy 313.671826 -50.435083) (xy 313.687181 -50.382788) (xy 313.709823 -50.333211) (xy 313.739289 -50.287361)
			(xy 313.77498 -50.24617) (xy 313.816171 -50.210479) (xy 313.862021 -50.181013) (xy 313.911598 -50.158371)
			(xy 313.963893 -50.143016) (xy 314.017841 -50.13526) (xy 314.072343 -50.13526) (xy 314.126291 -50.143016)
			(xy 314.178586 -50.158371) (xy 314.228163 -50.181013) (xy 314.274013 -50.210479) (xy 314.315204 -50.24617)
			(xy 314.350895 -50.287361) (xy 314.380361 -50.333211) (xy 314.403003 -50.382788) (xy 314.418358 -50.435083)
			(xy 314.426114 -50.489031) (xy 314.4266 -50.516282) (xy 314.426181 -50.542599) (xy 314.418954 -50.594735)
			(xy 314.404634 -50.645384) (xy 314.383494 -50.693585) (xy 314.355932 -50.738426) (xy 314.322473 -50.779057)
			(xy 314.30341 -50.797206) (xy 314.296005 -50.804725) (xy 314.287482 -50.824007) (xy 314.2869 -50.834544)
			(xy 314.2869 -50.90922) (xy 314.287459 -50.919766) (xy 314.295973 -50.939062) (xy 314.30341 -50.946558)
			(xy 314.322471 -50.964711) (xy 314.35595 -51.005328) (xy 314.383523 -51.050165) (xy 314.404665 -51.098368)
			(xy 314.418973 -51.149022) (xy 314.426176 -51.201164) (xy 314.4266 -51.227482) (xy 314.426128 -51.254735)
			(xy 314.418373 -51.308686) (xy 314.403019 -51.360984) (xy 314.380378 -51.410565) (xy 314.350911 -51.456418)
			(xy 314.315218 -51.497611) (xy 314.274026 -51.533305) (xy 314.228173 -51.562773) (xy 314.178593 -51.585416)
			(xy 314.126296 -51.600771) (xy 314.072345 -51.608527) (xy 314.045092 -51.60899) (xy 314.026749 -51.608762)
			(xy 313.990236 -51.605196) (xy 313.972194 -51.601878) (xy 313.961272 -51.599846) (xy 313.940698 -51.604672)
			(xy 313.86272 -51.6636) (xy 313.852306 -51.682396) (xy 313.851544 -51.693318) (xy 313.84866 -51.721577)
			(xy 313.835627 -51.776864) (xy 313.814541 -51.829607) (xy 313.785869 -51.878641) (xy 313.750244 -51.922883)
			(xy 313.708453 -51.961353) (xy 313.66142 -51.993203) (xy 313.610186 -52.017728) (xy 313.555881 -52.034385)
			(xy 313.499707 -52.042807) (xy 313.471306 -52.04333) (xy 313.443935 -52.042877) (xy 313.389755 -52.035059)
			(xy 313.337251 -52.019568) (xy 313.287504 -51.996723) (xy 313.241539 -51.966994) (xy 313.220608 -51.94935)
			(xy 313.213496 -51.943254) (xy 313.196478 -51.936904) (xy 313.111134 -51.936904) (xy 313.094116 -51.943254)
			(xy 313.087004 -51.94935) (xy 313.066075 -51.966993) (xy 313.020102 -51.996706) (xy 312.970354 -52.019542)
			(xy 312.917852 -52.035032) (xy 312.863676 -52.042858) (xy 312.836306 -52.04333) (xy 312.809054 -52.042823)
			(xy 312.755106 -52.035067) (xy 312.70281 -52.019713) (xy 312.653232 -51.997072) (xy 312.607381 -51.967606)
			(xy 312.56619 -51.931914) (xy 312.530498 -51.890724) (xy 312.501031 -51.844873) (xy 312.478389 -51.795295)
			(xy 312.463034 -51.743) (xy 312.455277 -51.689052) (xy 311.681973 -51.689052) (xy 311.710805 -51.70274)
			(xy 311.755681 -51.732412) (xy 311.795943 -51.768094) (xy 311.830792 -51.809079) (xy 311.859537 -51.854553)
			(xy 311.881609 -51.903615) (xy 311.896568 -51.955291) (xy 311.904119 -52.008557) (xy 311.904634 -52.035456)
			(xy 311.90408 -52.064682) (xy 311.895173 -52.122451) (xy 311.877562 -52.178186) (xy 311.851657 -52.230584)
			(xy 311.818065 -52.278419) (xy 311.798208 -52.29987) (xy 311.797446 -52.300632) (xy 311.796938 -52.30114)
			(xy 311.774481 -52.324175) (xy 311.723287 -52.363126) (xy 311.666293 -52.392951) (xy 311.635902 -52.403502)
			(xy 311.628282 -52.406042) (xy 311.615328 -52.415186) (xy 311.610756 -52.42179) (xy 311.606196 -52.42843)
			(xy 311.601139 -52.443713) (xy 311.60085 -52.451762) (xy 311.60085 -52.564153) (xy 314.02703 -52.564153)
			(xy 314.02703 -52.509647) (xy 314.034786 -52.455696) (xy 314.050141 -52.403398) (xy 314.072782 -52.353818)
			(xy 314.102248 -52.307964) (xy 314.13794 -52.266769) (xy 314.17913 -52.231073) (xy 314.224981 -52.201602)
			(xy 314.274559 -52.178956) (xy 314.326855 -52.163595) (xy 314.380805 -52.155833) (xy 314.408058 -52.155344)
			(xy 314.435428 -52.155824) (xy 314.489607 -52.163637) (xy 314.54211 -52.179122) (xy 314.591857 -52.201961)
			(xy 314.637824 -52.231683) (xy 314.658756 -52.249324) (xy 314.665868 -52.25542) (xy 314.682886 -52.26177)
			(xy 314.76823 -52.26177) (xy 314.785248 -52.25542) (xy 314.79236 -52.249324) (xy 314.813299 -52.231694)
			(xy 314.85927 -52.20198) (xy 314.909015 -52.179142) (xy 314.961515 -52.163649) (xy 315.015689 -52.155819)
			(xy 315.043058 -52.155344) (xy 315.070309 -52.1559) (xy 315.124258 -52.163651) (xy 315.176554 -52.179002)
			(xy 315.226134 -52.201639) (xy 315.271986 -52.231102) (xy 315.313179 -52.266792) (xy 315.348872 -52.30798)
			(xy 315.378341 -52.35383) (xy 315.400983 -52.403406) (xy 315.41634 -52.455701) (xy 315.424097 -52.509649)
			(xy 315.424097 -52.564151) (xy 315.41634 -52.618099) (xy 315.400983 -52.670394) (xy 315.378341 -52.71997)
			(xy 315.348872 -52.76582) (xy 315.313179 -52.807008) (xy 315.271986 -52.842698) (xy 315.226134 -52.872161)
			(xy 315.176554 -52.894798) (xy 315.124258 -52.910149) (xy 315.070309 -52.9179) (xy 315.043058 -52.91836)
			(xy 315.015689 -52.91787) (xy 314.96151 -52.910059) (xy 314.909007 -52.894576) (xy 314.85926 -52.87174)
			(xy 314.813292 -52.842019) (xy 314.79236 -52.82438) (xy 314.785248 -52.818284) (xy 314.76823 -52.811934)
			(xy 314.682886 -52.811934) (xy 314.665868 -52.818284) (xy 314.658756 -52.82438) (xy 314.637811 -52.842003)
			(xy 314.591842 -52.871718) (xy 314.542098 -52.894557) (xy 314.4896 -52.910052) (xy 314.435426 -52.917884)
			(xy 314.408058 -52.91836) (xy 314.380805 -52.917967) (xy 314.326855 -52.910205) (xy 314.274559 -52.894844)
			(xy 314.224981 -52.872198) (xy 314.17913 -52.842727) (xy 314.13794 -52.807031) (xy 314.102248 -52.765836)
			(xy 314.072782 -52.719982) (xy 314.050141 -52.670402) (xy 314.034786 -52.618104) (xy 314.02703 -52.564153)
			(xy 311.60085 -52.564153) (xy 311.60085 -52.65547) (xy 311.620408 -52.68214) (xy 311.636664 -52.68722)
			(xy 311.662206 -52.695668) (xy 311.710805 -52.71874) (xy 311.755681 -52.748412) (xy 311.795943 -52.784094)
			(xy 311.830792 -52.825079) (xy 311.859537 -52.870553) (xy 311.881609 -52.919615) (xy 311.896568 -52.971291)
			(xy 311.904119 -53.024557) (xy 311.904634 -53.051456) (xy 311.90408 -53.080682) (xy 311.895173 -53.138451)
			(xy 311.877562 -53.194186) (xy 311.851657 -53.246584) (xy 311.818065 -53.294419) (xy 311.798208 -53.31587)
			(xy 311.797446 -53.316632) (xy 311.796938 -53.31714) (xy 311.774481 -53.340175) (xy 311.723287 -53.379126)
			(xy 311.666293 -53.408951) (xy 311.635902 -53.419502) (xy 311.628282 -53.422042) (xy 311.615328 -53.431186)
			(xy 311.610756 -53.43779) (xy 311.606196 -53.44443) (xy 311.601139 -53.459713) (xy 311.60085 -53.467762)
			(xy 311.60085 -53.67147) (xy 311.620408 -53.69814) (xy 311.636664 -53.70322) (xy 311.662206 -53.711668)
			(xy 311.710805 -53.73474) (xy 311.755681 -53.764412) (xy 311.795943 -53.800094) (xy 311.830792 -53.841079)
			(xy 311.859537 -53.886553) (xy 311.881609 -53.935615) (xy 311.896568 -53.987291) (xy 311.904119 -54.040557)
			(xy 311.904634 -54.067456) (xy 311.90408 -54.096682) (xy 311.895173 -54.154451) (xy 311.877562 -54.210186)
			(xy 311.863363 -54.238906) (xy 318.585848 -54.238906) (xy 318.589919 -54.183284) (xy 318.602045 -54.128847)
			(xy 318.621968 -54.076756) (xy 318.649264 -54.028121) (xy 318.68335 -53.983978) (xy 318.723499 -53.945269)
			(xy 318.768857 -53.912818) (xy 318.818457 -53.887317) (xy 318.871241 -53.86931) (xy 318.926084 -53.85918)
			(xy 318.981818 -53.857143) (xy 319.037255 -53.863243) (xy 319.091212 -53.877349) (xy 319.142541 -53.899161)
			(xy 319.190147 -53.928215) (xy 319.233015 -53.96389) (xy 319.270232 -54.005427) (xy 319.301005 -54.05194)
			(xy 319.324677 -54.102437) (xy 319.340745 -54.155844) (xy 319.348865 -54.21102) (xy 319.349374 -54.238906)
			(xy 319.348865 -54.266792) (xy 319.340745 -54.321968) (xy 319.324677 -54.375375) (xy 319.301005 -54.425872)
			(xy 319.270232 -54.472385) (xy 319.233015 -54.513922) (xy 319.190147 -54.549597) (xy 319.142541 -54.578651)
			(xy 319.091212 -54.600463) (xy 319.037255 -54.614569) (xy 318.981818 -54.620669) (xy 318.926084 -54.618632)
			(xy 318.871241 -54.608502) (xy 318.818457 -54.590495) (xy 318.768857 -54.564994) (xy 318.723499 -54.532543)
			(xy 318.68335 -54.493834) (xy 318.649264 -54.449691) (xy 318.621968 -54.401056) (xy 318.602045 -54.348965)
			(xy 318.589919 -54.294528) (xy 318.585848 -54.238906) (xy 311.863363 -54.238906) (xy 311.851657 -54.262584)
			(xy 311.818065 -54.310419) (xy 311.798208 -54.33187) (xy 311.797446 -54.332632) (xy 311.796938 -54.33314)
			(xy 311.774481 -54.356175) (xy 311.723287 -54.395126) (xy 311.666293 -54.424951) (xy 311.635902 -54.435502)
			(xy 311.628282 -54.438042) (xy 311.615328 -54.447186) (xy 311.610756 -54.45379) (xy 311.606196 -54.46043)
			(xy 311.601139 -54.475713) (xy 311.60085 -54.483762) (xy 311.60085 -54.68747) (xy 311.620408 -54.71414)
			(xy 311.636664 -54.71922) (xy 311.662206 -54.727668) (xy 311.710805 -54.75074) (xy 311.755681 -54.780412)
			(xy 311.795943 -54.816094) (xy 311.830792 -54.857079) (xy 311.859537 -54.902553) (xy 311.881609 -54.951615)
			(xy 311.892446 -54.989051) (xy 314.100968 -54.989051) (xy 314.100968 -54.934549) (xy 314.108724 -54.880603)
			(xy 314.124078 -54.828309) (xy 314.146718 -54.778732) (xy 314.176182 -54.732882) (xy 314.211871 -54.691691)
			(xy 314.253059 -54.655999) (xy 314.298907 -54.626531) (xy 314.348482 -54.603888) (xy 314.400775 -54.58853)
			(xy 314.454721 -54.58077) (xy 314.481972 -54.580282) (xy 314.510063 -54.580799) (xy 314.565639 -54.589022)
			(xy 314.619407 -54.605309) (xy 314.670205 -54.629308) (xy 314.716932 -54.6605) (xy 314.758578 -54.698209)
			(xy 314.794241 -54.741619) (xy 314.809124 -54.765448) (xy 314.814458 -54.774592) (xy 314.831476 -54.786784)
			(xy 314.924694 -54.80685) (xy 314.945268 -54.802786) (xy 314.953904 -54.79669) (xy 314.977965 -54.780685)
			(xy 315.029897 -54.755344) (xy 315.085056 -54.738119) (xy 315.142181 -54.729406) (xy 315.171074 -54.728872)
			(xy 315.198325 -54.729379) (xy 315.252274 -54.737132) (xy 315.304569 -54.752484) (xy 315.354148 -54.775122)
			(xy 315.4 -54.804586) (xy 315.441193 -54.840275) (xy 315.476887 -54.881463) (xy 315.506356 -54.927311)
			(xy 315.529 -54.976887) (xy 315.544358 -55.029181) (xy 315.552117 -55.083129) (xy 315.552582 -55.11038)
			(xy 315.552109 -55.13775) (xy 315.544293 -55.191929) (xy 315.528806 -55.244432) (xy 315.505966 -55.294179)
			(xy 315.476243 -55.340146) (xy 315.458602 -55.361078) (xy 315.452506 -55.36819) (xy 315.446156 -55.385208)
			(xy 315.446156 -55.470552) (xy 315.452506 -55.48757) (xy 315.458602 -55.494682) (xy 315.476222 -55.515631)
			(xy 315.505945 -55.561597) (xy 315.52879 -55.611341) (xy 315.544287 -55.66384) (xy 315.552116 -55.718016)
			(xy 315.552119 -55.772754) (xy 315.544293 -55.826931) (xy 315.528801 -55.879431) (xy 315.50596 -55.929177)
			(xy 315.47624 -55.975145) (xy 315.458602 -55.996078) (xy 315.452506 -56.00319) (xy 315.446156 -56.020208)
			(xy 315.446156 -56.105552) (xy 315.452506 -56.12257) (xy 315.458602 -56.129682) (xy 315.476246 -56.15061)
			(xy 315.505957 -56.196584) (xy 315.528792 -56.246332) (xy 315.544282 -56.298834) (xy 315.552109 -56.353011)
			(xy 315.552582 -56.38038) (xy 315.552096 -56.407631) (xy 315.54434 -56.461579) (xy 315.528985 -56.513874)
			(xy 315.506343 -56.563451) (xy 315.476877 -56.609301) (xy 315.441186 -56.650492) (xy 315.399995 -56.686183)
			(xy 315.354145 -56.715649) (xy 315.304568 -56.738291) (xy 315.252273 -56.753646) (xy 315.198325 -56.761402)
			(xy 315.143823 -56.761402) (xy 315.089875 -56.753646) (xy 315.03758 -56.738291) (xy 314.988003 -56.715649)
			(xy 314.942153 -56.686183) (xy 314.900962 -56.650492) (xy 314.865271 -56.609301) (xy 314.835805 -56.563451)
			(xy 314.813163 -56.513874) (xy 314.797808 -56.461579) (xy 314.790052 -56.407631) (xy 314.789566 -56.38038)
			(xy 314.790004 -56.353009) (xy 314.797826 -56.298828) (xy 314.813321 -56.246324) (xy 314.836169 -56.196577)
			(xy 314.865901 -56.150612) (xy 314.883546 -56.129682) (xy 314.889642 -56.12257) (xy 314.895992 -56.105552)
			(xy 314.895992 -56.020208) (xy 314.889642 -56.00319) (xy 314.883546 -55.996078) (xy 314.865885 -55.975162)
			(xy 314.836159 -55.929191) (xy 314.813314 -55.879443) (xy 314.797819 -55.826938) (xy 314.789991 -55.772757)
			(xy 314.789994 -55.718013) (xy 314.797825 -55.663833) (xy 314.813325 -55.611329) (xy 314.836174 -55.561582)
			(xy 314.865903 -55.515614) (xy 314.883546 -55.494682) (xy 314.889642 -55.48757) (xy 314.895992 -55.470552)
			(xy 314.895992 -55.385208) (xy 314.889642 -55.36819) (xy 314.883546 -55.361078) (xy 314.872591 -55.348285)
			(xy 314.852753 -55.321064) (xy 314.843922 -55.306722) (xy 314.838588 -55.297578) (xy 314.82157 -55.285386)
			(xy 314.728352 -55.26532) (xy 314.707778 -55.269384) (xy 314.699142 -55.27548) (xy 314.675067 -55.291462)
			(xy 314.62314 -55.316809) (xy 314.567985 -55.33404) (xy 314.510864 -55.342761) (xy 314.481972 -55.343298)
			(xy 314.454721 -55.34283) (xy 314.400775 -55.33507) (xy 314.348482 -55.319712) (xy 314.298907 -55.297069)
			(xy 314.253059 -55.267601) (xy 314.211871 -55.231909) (xy 314.176182 -55.190718) (xy 314.146718 -55.144868)
			(xy 314.124078 -55.095291) (xy 314.108724 -55.042997) (xy 314.100968 -54.989051) (xy 311.892446 -54.989051)
			(xy 311.896568 -55.003291) (xy 311.904119 -55.056557) (xy 311.904634 -55.083456) (xy 311.90408 -55.112682)
			(xy 311.895173 -55.170451) (xy 311.877562 -55.226186) (xy 311.851657 -55.278584) (xy 311.818065 -55.326419)
			(xy 311.798208 -55.34787) (xy 311.797446 -55.348632) (xy 311.796938 -55.34914) (xy 311.774481 -55.372175)
			(xy 311.723287 -55.411126) (xy 311.704703 -55.420851) (xy 312.424568 -55.420851) (xy 312.424568 -55.366349)
			(xy 312.432324 -55.312403) (xy 312.447678 -55.260109) (xy 312.470318 -55.210532) (xy 312.499782 -55.164682)
			(xy 312.535471 -55.123491) (xy 312.576659 -55.087799) (xy 312.622507 -55.058331) (xy 312.672082 -55.035688)
			(xy 312.724375 -55.02033) (xy 312.778321 -55.01257) (xy 312.805572 -55.012082) (xy 312.831889 -55.012513)
			(xy 312.884023 -55.019738) (xy 312.934672 -55.034056) (xy 312.982874 -55.055195) (xy 313.027715 -55.082754)
			(xy 313.068346 -55.11621) (xy 313.086496 -55.135272) (xy 313.094021 -55.14267) (xy 313.113298 -55.151197)
			(xy 313.123834 -55.151782) (xy 313.19851 -55.151782) (xy 313.209063 -55.151277) (xy 313.228358 -55.142725)
			(xy 313.235848 -55.135272) (xy 313.253973 -55.116183) (xy 313.294594 -55.082703) (xy 313.339436 -55.055132)
			(xy 313.387646 -55.033995) (xy 313.438306 -55.019693) (xy 313.490452 -55.0125) (xy 313.516772 -55.012082)
			(xy 313.544025 -55.012563) (xy 313.597978 -55.020317) (xy 313.650278 -55.03567) (xy 313.69986 -55.05831)
			(xy 313.745716 -55.087777) (xy 313.786911 -55.12347) (xy 313.822606 -55.164662) (xy 313.852076 -55.210515)
			(xy 313.87472 -55.260096) (xy 313.890077 -55.312395) (xy 313.897835 -55.366347) (xy 313.897835 -55.420853)
			(xy 313.890077 -55.474805) (xy 313.87472 -55.527104) (xy 313.852076 -55.576685) (xy 313.822606 -55.622538)
			(xy 313.786911 -55.66373) (xy 313.745716 -55.699423) (xy 313.69986 -55.72889) (xy 313.650278 -55.75153)
			(xy 313.597978 -55.766883) (xy 313.544025 -55.774637) (xy 313.516772 -55.775098) (xy 313.490456 -55.774644)
			(xy 313.438322 -55.767424) (xy 313.387674 -55.753111) (xy 313.339472 -55.731977) (xy 313.29463 -55.704422)
			(xy 313.253998 -55.670968) (xy 313.235848 -55.651908) (xy 313.228347 -55.644483) (xy 313.209051 -55.635972)
			(xy 313.19851 -55.635398) (xy 313.123834 -55.635398) (xy 313.113285 -55.635933) (xy 313.09399 -55.644464)
			(xy 313.086496 -55.651908) (xy 313.068365 -55.670991) (xy 313.027743 -55.704468) (xy 312.982902 -55.732038)
			(xy 312.934694 -55.753176) (xy 312.884036 -55.76748) (xy 312.831892 -55.774678) (xy 312.805572 -55.775098)
			(xy 312.778321 -55.77463) (xy 312.724375 -55.76687) (xy 312.672082 -55.751512) (xy 312.622507 -55.728869)
			(xy 312.576659 -55.699401) (xy 312.535471 -55.663709) (xy 312.499782 -55.622518) (xy 312.470318 -55.576668)
			(xy 312.447678 -55.527091) (xy 312.432324 -55.474797) (xy 312.424568 -55.420851) (xy 311.704703 -55.420851)
			(xy 311.666293 -55.440951) (xy 311.635902 -55.451502) (xy 311.628282 -55.454042) (xy 311.615328 -55.463186)
			(xy 311.610756 -55.46979) (xy 311.606196 -55.47643) (xy 311.601139 -55.491713) (xy 311.60085 -55.499762)
			(xy 311.60085 -55.95747) (xy 311.620408 -55.98414) (xy 311.636664 -55.98922) (xy 311.662206 -55.997668)
			(xy 311.710805 -56.02074) (xy 311.755681 -56.050412) (xy 311.795943 -56.086094) (xy 311.830792 -56.127079)
			(xy 311.859537 -56.172553) (xy 311.881609 -56.221615) (xy 311.896568 -56.273291) (xy 311.904119 -56.326557)
			(xy 311.904634 -56.353456) (xy 311.90408 -56.382682) (xy 311.895173 -56.440451) (xy 311.877562 -56.496186)
			(xy 311.851657 -56.548584) (xy 311.818065 -56.596419) (xy 311.798208 -56.61787) (xy 311.797446 -56.618632)
			(xy 311.796938 -56.61914) (xy 311.774481 -56.642175) (xy 311.723287 -56.681126) (xy 311.666293 -56.710951)
			(xy 311.635902 -56.721502) (xy 311.628282 -56.724042) (xy 311.615328 -56.733186) (xy 311.610756 -56.73979)
			(xy 311.606196 -56.74643) (xy 311.601139 -56.761713) (xy 311.60085 -56.769762) (xy 311.60085 -57.48528)
			(xy 314.80582 -57.48528) (xy 314.809891 -57.429658) (xy 314.822017 -57.375221) (xy 314.84194 -57.32313)
			(xy 314.869236 -57.274495) (xy 314.903322 -57.230352) (xy 314.943471 -57.191643) (xy 314.988829 -57.159192)
			(xy 315.038429 -57.133691) (xy 315.091213 -57.115684) (xy 315.146056 -57.105554) (xy 315.20179 -57.103517)
			(xy 315.257227 -57.109617) (xy 315.311184 -57.123723) (xy 315.362513 -57.145535) (xy 315.410119 -57.174589)
			(xy 315.452987 -57.210264) (xy 315.490204 -57.251801) (xy 315.520977 -57.298314) (xy 315.544649 -57.348811)
			(xy 315.560717 -57.402218) (xy 315.568837 -57.457394) (xy 315.569346 -57.48528) (xy 315.568837 -57.513166)
			(xy 315.560717 -57.568342) (xy 315.544649 -57.621749) (xy 315.520977 -57.672246) (xy 315.490204 -57.718759)
			(xy 315.452987 -57.760296) (xy 315.410119 -57.795971) (xy 315.362513 -57.825025) (xy 315.311184 -57.846837)
			(xy 315.257227 -57.860943) (xy 315.20179 -57.867043) (xy 315.146056 -57.865006) (xy 315.091213 -57.854876)
			(xy 315.038429 -57.836869) (xy 314.988829 -57.811368) (xy 314.943471 -57.778917) (xy 314.903322 -57.740208)
			(xy 314.869236 -57.696065) (xy 314.84194 -57.64743) (xy 314.822017 -57.595339) (xy 314.809891 -57.540902)
			(xy 314.80582 -57.48528) (xy 311.60085 -57.48528) (xy 311.60085 -58.076084) (xy 315.557914 -58.076084)
			(xy 315.561985 -58.020462) (xy 315.574111 -57.966025) (xy 315.594034 -57.913934) (xy 315.62133 -57.865299)
			(xy 315.655416 -57.821156) (xy 315.695565 -57.782447) (xy 315.740923 -57.749996) (xy 315.790523 -57.724495)
			(xy 315.843307 -57.706488) (xy 315.89815 -57.696358) (xy 315.953884 -57.694321) (xy 316.009321 -57.700421)
			(xy 316.063278 -57.714527) (xy 316.114607 -57.736339) (xy 316.162213 -57.765393) (xy 316.205081 -57.801068)
			(xy 316.242298 -57.842605) (xy 316.258634 -57.867296) (xy 317.842644 -57.867296) (xy 317.846717 -57.811637)
			(xy 317.858852 -57.757164) (xy 317.878788 -57.705038) (xy 317.906102 -57.65637) (xy 317.94021 -57.612198)
			(xy 317.980387 -57.573463) (xy 318.025775 -57.540991) (xy 318.075407 -57.515473) (xy 318.128227 -57.497454)
			(xy 318.183106 -57.487317) (xy 318.238877 -57.485279) (xy 318.294351 -57.491382) (xy 318.348344 -57.505498)
			(xy 318.399707 -57.527325) (xy 318.447345 -57.556398) (xy 318.490241 -57.592097) (xy 318.527483 -57.633661)
			(xy 318.558277 -57.680205) (xy 318.581965 -57.730736) (xy 318.598043 -57.784178) (xy 318.606169 -57.839392)
			(xy 318.606678 -57.867296) (xy 318.606169 -57.8952) (xy 318.598043 -57.950414) (xy 318.581965 -58.003856)
			(xy 318.558277 -58.054387) (xy 318.527483 -58.100931) (xy 318.490241 -58.142495) (xy 318.447345 -58.178194)
			(xy 318.399707 -58.207267) (xy 318.348344 -58.229094) (xy 318.294351 -58.24321) (xy 318.238877 -58.249313)
			(xy 318.183106 -58.247275) (xy 318.128227 -58.237138) (xy 318.075407 -58.219119) (xy 318.025775 -58.193601)
			(xy 317.980387 -58.161129) (xy 317.94021 -58.122394) (xy 317.906102 -58.078222) (xy 317.878788 -58.029554)
			(xy 317.858852 -57.977428) (xy 317.846717 -57.922955) (xy 317.842644 -57.867296) (xy 316.258634 -57.867296)
			(xy 316.273071 -57.889118) (xy 316.296743 -57.939615) (xy 316.312811 -57.993022) (xy 316.320931 -58.048198)
			(xy 316.32144 -58.076084) (xy 316.320931 -58.10397) (xy 316.312811 -58.159146) (xy 316.296743 -58.212553)
			(xy 316.273071 -58.26305) (xy 316.242298 -58.309563) (xy 316.205081 -58.3511) (xy 316.162213 -58.386775)
			(xy 316.114607 -58.415829) (xy 316.063278 -58.437641) (xy 316.009321 -58.451747) (xy 315.953884 -58.457847)
			(xy 315.89815 -58.45581) (xy 315.843307 -58.44568) (xy 315.790523 -58.427673) (xy 315.740923 -58.402172)
			(xy 315.695565 -58.369721) (xy 315.655416 -58.331012) (xy 315.62133 -58.286869) (xy 315.594034 -58.238234)
			(xy 315.574111 -58.186143) (xy 315.561985 -58.131706) (xy 315.557914 -58.076084) (xy 311.60085 -58.076084)
			(xy 311.60085 -58.561224) (xy 316.762128 -58.561224) (xy 316.766199 -58.505602) (xy 316.778325 -58.451165)
			(xy 316.798248 -58.399074) (xy 316.825544 -58.350439) (xy 316.85963 -58.306296) (xy 316.899779 -58.267587)
			(xy 316.945137 -58.235136) (xy 316.994737 -58.209635) (xy 317.047521 -58.191628) (xy 317.102364 -58.181498)
			(xy 317.158098 -58.179461) (xy 317.213535 -58.185561) (xy 317.267492 -58.199667) (xy 317.318821 -58.221479)
			(xy 317.366427 -58.250533) (xy 317.409295 -58.286208) (xy 317.446512 -58.327745) (xy 317.477285 -58.374258)
			(xy 317.500957 -58.424755) (xy 317.508467 -58.449718) (xy 319.008758 -58.449718) (xy 319.012829 -58.394096)
			(xy 319.024955 -58.339659) (xy 319.044878 -58.287568) (xy 319.072174 -58.238933) (xy 319.10626 -58.19479)
			(xy 319.146409 -58.156081) (xy 319.191767 -58.12363) (xy 319.241367 -58.098129) (xy 319.294151 -58.080122)
			(xy 319.348994 -58.069992) (xy 319.404728 -58.067955) (xy 319.460165 -58.074055) (xy 319.514122 -58.088161)
			(xy 319.565451 -58.109973) (xy 319.613057 -58.139027) (xy 319.655925 -58.174702) (xy 319.693142 -58.216239)
			(xy 319.723915 -58.262752) (xy 319.747587 -58.313249) (xy 319.763655 -58.366656) (xy 319.771775 -58.421832)
			(xy 319.772284 -58.449718) (xy 319.771775 -58.477604) (xy 319.763655 -58.53278) (xy 319.747587 -58.586187)
			(xy 319.723915 -58.636684) (xy 319.693142 -58.683197) (xy 319.655925 -58.724734) (xy 319.613057 -58.760409)
			(xy 319.565451 -58.789463) (xy 319.514122 -58.811275) (xy 319.460165 -58.825381) (xy 319.404728 -58.831481)
			(xy 319.348994 -58.829444) (xy 319.294151 -58.819314) (xy 319.241367 -58.801307) (xy 319.191767 -58.775806)
			(xy 319.146409 -58.743355) (xy 319.10626 -58.704646) (xy 319.072174 -58.660503) (xy 319.044878 -58.611868)
			(xy 319.024955 -58.559777) (xy 319.012829 -58.50534) (xy 319.008758 -58.449718) (xy 317.508467 -58.449718)
			(xy 317.517025 -58.478162) (xy 317.525145 -58.533338) (xy 317.525654 -58.561224) (xy 317.525145 -58.58911)
			(xy 317.517025 -58.644286) (xy 317.500957 -58.697693) (xy 317.477285 -58.74819) (xy 317.446512 -58.794703)
			(xy 317.409295 -58.83624) (xy 317.366427 -58.871915) (xy 317.318821 -58.900969) (xy 317.267492 -58.922781)
			(xy 317.213535 -58.936887) (xy 317.158098 -58.942987) (xy 317.102364 -58.94095) (xy 317.047521 -58.93082)
			(xy 316.994737 -58.912813) (xy 316.945137 -58.887312) (xy 316.899779 -58.854861) (xy 316.85963 -58.816152)
			(xy 316.825544 -58.772009) (xy 316.798248 -58.723374) (xy 316.778325 -58.671283) (xy 316.766199 -58.616846)
			(xy 316.762128 -58.561224) (xy 311.60085 -58.561224) (xy 311.60085 -59.974734) (xy 315.286898 -59.974734)
			(xy 315.28733 -59.947907) (xy 315.294851 -59.894783) (xy 315.309734 -59.843234) (xy 315.331688 -59.794277)
			(xy 315.360278 -59.748875) (xy 315.394943 -59.707923) (xy 315.435 -59.672227) (xy 315.457078 -59.65698)
			(xy 315.468648 -59.648765) (xy 315.48706 -59.627187) (xy 315.498818 -59.601373) (xy 315.503015 -59.573319)
			(xy 315.499325 -59.545195) (xy 315.488033 -59.519174) (xy 315.470014 -59.497267) (xy 315.458602 -59.488832)
			(xy 315.437151 -59.473472) (xy 315.398237 -59.437847) (xy 315.364603 -59.397199) (xy 315.336891 -59.352305)
			(xy 315.31563 -59.304021) (xy 315.301225 -59.253267) (xy 315.29395 -59.201013) (xy 315.293502 -59.174634)
			(xy 315.293988 -59.147383) (xy 315.301744 -59.093435) (xy 315.317099 -59.04114) (xy 315.339741 -58.991563)
			(xy 315.369207 -58.945713) (xy 315.404898 -58.904522) (xy 315.446089 -58.868831) (xy 315.491939 -58.839365)
			(xy 315.541516 -58.816723) (xy 315.593811 -58.801368) (xy 315.647759 -58.793612) (xy 315.702261 -58.793612)
			(xy 315.756209 -58.801368) (xy 315.808504 -58.816723) (xy 315.858081 -58.839365) (xy 315.903931 -58.868831)
			(xy 315.945122 -58.904522) (xy 315.980813 -58.945713) (xy 316.010279 -58.991563) (xy 316.032921 -59.04114)
			(xy 316.048276 -59.093435) (xy 316.056032 -59.147383) (xy 316.056518 -59.174634) (xy 316.056054 -59.20146)
			(xy 316.048538 -59.254582) (xy 316.03366 -59.30613) (xy 316.011712 -59.355087) (xy 315.983126 -59.400489)
			(xy 315.948466 -59.441442) (xy 315.908413 -59.47714) (xy 315.886338 -59.492388) (xy 315.874806 -59.500647)
			(xy 315.85641 -59.522221) (xy 315.844661 -59.548023) (xy 315.840464 -59.576063) (xy 315.844145 -59.604175)
			(xy 315.855418 -59.630188) (xy 315.873415 -59.652096) (xy 315.884814 -59.660536) (xy 315.906301 -59.675849)
			(xy 315.945213 -59.711482) (xy 315.978843 -59.752138) (xy 316.006551 -59.79704) (xy 316.027806 -59.845332)
			(xy 316.042204 -59.896093) (xy 316.04947 -59.948353) (xy 316.049914 -59.974734) (xy 316.049428 -60.001985)
			(xy 316.041672 -60.055933) (xy 316.026317 -60.108228) (xy 316.003675 -60.157805) (xy 315.974209 -60.203655)
			(xy 315.938518 -60.244846) (xy 315.897327 -60.280537) (xy 315.851477 -60.310003) (xy 315.8019 -60.332645)
			(xy 315.749605 -60.348) (xy 315.695657 -60.355756) (xy 315.641155 -60.355756) (xy 315.587207 -60.348)
			(xy 315.534912 -60.332645) (xy 315.485335 -60.310003) (xy 315.439485 -60.280537) (xy 315.398294 -60.244846)
			(xy 315.362603 -60.203655) (xy 315.333137 -60.157805) (xy 315.310495 -60.108228) (xy 315.29514 -60.055933)
			(xy 315.287384 -60.001985) (xy 315.286898 -59.974734) (xy 311.60085 -59.974734) (xy 311.60085 -60.601606)
			(xy 314.533024 -60.601606) (xy 314.537095 -60.545984) (xy 314.549221 -60.491547) (xy 314.569144 -60.439456)
			(xy 314.59644 -60.390821) (xy 314.630526 -60.346678) (xy 314.670675 -60.307969) (xy 314.716033 -60.275518)
			(xy 314.765633 -60.250017) (xy 314.818417 -60.23201) (xy 314.87326 -60.22188) (xy 314.928994 -60.219843)
			(xy 314.984431 -60.225943) (xy 315.038388 -60.240049) (xy 315.089717 -60.261861) (xy 315.137323 -60.290915)
			(xy 315.180191 -60.32659) (xy 315.217408 -60.368127) (xy 315.248181 -60.41464) (xy 315.271853 -60.465137)
			(xy 315.287921 -60.518544) (xy 315.296041 -60.57372) (xy 315.29655 -60.601606) (xy 315.296086 -60.627006)
			(xy 316.921132 -60.627006) (xy 316.925203 -60.571384) (xy 316.937329 -60.516947) (xy 316.957252 -60.464856)
			(xy 316.984548 -60.416221) (xy 317.018634 -60.372078) (xy 317.058783 -60.333369) (xy 317.104141 -60.300918)
			(xy 317.153741 -60.275417) (xy 317.206525 -60.25741) (xy 317.261368 -60.24728) (xy 317.317102 -60.245243)
			(xy 317.372539 -60.251343) (xy 317.426496 -60.265449) (xy 317.477825 -60.287261) (xy 317.525431 -60.316315)
			(xy 317.568299 -60.35199) (xy 317.605516 -60.393527) (xy 317.636289 -60.44004) (xy 317.659961 -60.490537)
			(xy 317.676029 -60.543944) (xy 317.684149 -60.59912) (xy 317.684658 -60.627006) (xy 317.684542 -60.633356)
			(xy 319.012822 -60.633356) (xy 319.016893 -60.577734) (xy 319.029019 -60.523297) (xy 319.048942 -60.471206)
			(xy 319.076238 -60.422571) (xy 319.110324 -60.378428) (xy 319.150473 -60.339719) (xy 319.195831 -60.307268)
			(xy 319.245431 -60.281767) (xy 319.298215 -60.26376) (xy 319.353058 -60.25363) (xy 319.408792 -60.251593)
			(xy 319.464229 -60.257693) (xy 319.518186 -60.271799) (xy 319.569515 -60.293611) (xy 319.617121 -60.322665)
			(xy 319.659989 -60.35834) (xy 319.697206 -60.399877) (xy 319.727979 -60.44639) (xy 319.751651 -60.496887)
			(xy 319.767719 -60.550294) (xy 319.775839 -60.60547) (xy 319.776348 -60.633356) (xy 319.775839 -60.661242)
			(xy 319.767719 -60.716418) (xy 319.751651 -60.769825) (xy 319.727979 -60.820322) (xy 319.697206 -60.866835)
			(xy 319.659989 -60.908372) (xy 319.617121 -60.944047) (xy 319.569515 -60.973101) (xy 319.518186 -60.994913)
			(xy 319.464229 -61.009019) (xy 319.408792 -61.015119) (xy 319.353058 -61.013082) (xy 319.298215 -61.002952)
			(xy 319.245431 -60.984945) (xy 319.195831 -60.959444) (xy 319.150473 -60.926993) (xy 319.110324 -60.888284)
			(xy 319.076238 -60.844141) (xy 319.048942 -60.795506) (xy 319.029019 -60.743415) (xy 319.016893 -60.688978)
			(xy 319.012822 -60.633356) (xy 317.684542 -60.633356) (xy 317.684149 -60.654892) (xy 317.676029 -60.710068)
			(xy 317.659961 -60.763475) (xy 317.636289 -60.813972) (xy 317.605516 -60.860485) (xy 317.568299 -60.902022)
			(xy 317.525431 -60.937697) (xy 317.477825 -60.966751) (xy 317.426496 -60.988563) (xy 317.372539 -61.002669)
			(xy 317.317102 -61.008769) (xy 317.261368 -61.006732) (xy 317.206525 -60.996602) (xy 317.153741 -60.978595)
			(xy 317.104141 -60.953094) (xy 317.058783 -60.920643) (xy 317.018634 -60.881934) (xy 316.984548 -60.837791)
			(xy 316.957252 -60.789156) (xy 316.937329 -60.737065) (xy 316.925203 -60.682628) (xy 316.921132 -60.627006)
			(xy 315.296086 -60.627006) (xy 315.296041 -60.629492) (xy 315.287921 -60.684668) (xy 315.271853 -60.738075)
			(xy 315.248181 -60.788572) (xy 315.217408 -60.835085) (xy 315.180191 -60.876622) (xy 315.137323 -60.912297)
			(xy 315.089717 -60.941351) (xy 315.038388 -60.963163) (xy 314.984431 -60.977269) (xy 314.928994 -60.983369)
			(xy 314.87326 -60.981332) (xy 314.818417 -60.971202) (xy 314.765633 -60.953195) (xy 314.716033 -60.927694)
			(xy 314.670675 -60.895243) (xy 314.630526 -60.856534) (xy 314.59644 -60.812391) (xy 314.569144 -60.763756)
			(xy 314.549221 -60.711665) (xy 314.537095 -60.657228) (xy 314.533024 -60.601606) (xy 311.60085 -60.601606)
			(xy 311.60085 -61.333126) (xy 311.601279 -61.343193) (xy 311.609006 -61.361786) (xy 311.615836 -61.369194)
			(xy 311.814718 -61.568076) (xy 311.834784 -61.575696) (xy 311.845706 -61.575188) (xy 311.861708 -61.57468)
			(xy 314.384944 -61.57468) (xy 314.419742 -61.576712) (xy 314.42279 -61.576966) (xy 315.225684 -61.576966)
		)
		(stroke
			(width 0)
			(type solid)
		)
		(fill yes)
		(layer "In9.Cu")
		(net "P3V3_SSD11")
	)
	(gr_poly
		(pts
			(xy 27.66695 -61.571632) (xy 30.181804 -61.571632) (xy 30.189424 -61.571886) (xy 31.047436 -61.571886)
			(xy 31.048452 -61.571632) (xy 32.203644 -61.571632) (xy 32.213431 -61.571186) (xy 32.231586 -61.56387)
			(xy 32.23895 -61.557408) (xy 32.255714 -61.541406) (xy 32.29102 -61.50737) (xy 32.294044 -61.504157)
			(xy 32.299027 -61.496875) (xy 32.300926 -61.492892) (xy 32.30499 -61.484002) (xy 32.305244 -61.473588)
			(xy 32.30679 -61.445754) (xy 32.316954 -61.390943) (xy 32.334985 -61.338195) (xy 32.360501 -61.288632)
			(xy 32.392958 -61.24331) (xy 32.431665 -61.203195) (xy 32.475799 -61.169139) (xy 32.524418 -61.141869)
			(xy 32.576489 -61.121964) (xy 32.630901 -61.109849) (xy 32.686498 -61.105782) (xy 32.742095 -61.109849)
			(xy 32.796507 -61.121964) (xy 32.848578 -61.141869) (xy 32.897197 -61.169139) (xy 32.941331 -61.203195)
			(xy 32.980038 -61.24331) (xy 33.012495 -61.288632) (xy 33.038011 -61.338195) (xy 33.056042 -61.390943)
			(xy 33.066206 -61.445754) (xy 33.067752 -61.473588) (xy 33.067752 -61.473842) (xy 33.06826 -61.484256)
			(xy 33.07207 -61.492892) (xy 33.073948 -61.496784) (xy 33.078799 -61.503933) (xy 33.081722 -61.507116)
			(xy 33.126172 -61.549788) (xy 33.134046 -61.557408) (xy 33.141396 -61.563893) (xy 33.159559 -61.571214)
			(xy 33.169352 -61.571632) (xy 34.746946 -61.571632) (xy 34.7599 -61.569092) (xy 34.766443 -61.566698)
			(xy 34.778025 -61.558964) (xy 34.78276 -61.553852) (xy 34.814764 -61.516006) (xy 34.833306 -61.493908)
			(xy 34.836642 -61.489713) (xy 34.841637 -61.480235) (xy 34.843212 -61.475112) (xy 34.846006 -61.464698)
			(xy 34.844228 -61.453522) (xy 34.841688 -61.43625) (xy 34.840672 -61.426852) (xy 34.839148 -61.391546)
			(xy 34.839637 -61.363879) (xy 34.847621 -61.309125) (xy 34.863429 -61.256097) (xy 34.886728 -61.205908)
			(xy 34.917032 -61.15961) (xy 34.953703 -61.118173) (xy 34.97453 -61.099954) (xy 34.978848 -61.096144)
			(xy 34.985452 -61.087508) (xy 34.987992 -61.08192) (xy 34.989959 -61.077202) (xy 34.992143 -61.067217)
			(xy 34.99231 -61.062108) (xy 34.991548 -61.032136) (xy 34.991548 -61.031628) (xy 34.98977 -60.98032)
			(xy 34.988754 -60.971938) (xy 34.98469 -60.959746) (xy 34.984182 -60.95873) (xy 34.981134 -60.952888)
			(xy 34.973768 -60.944252) (xy 34.968942 -60.940696) (xy 34.945278 -60.922583) (xy 34.903343 -60.880245)
			(xy 34.868503 -60.831901) (xy 34.841604 -60.778727) (xy 34.823302 -60.722017) (xy 34.814042 -60.663151)
			(xy 34.813494 -60.633356) (xy 34.81398 -60.606105) (xy 34.821736 -60.552157) (xy 34.837091 -60.499862)
			(xy 34.859733 -60.450285) (xy 34.889199 -60.404435) (xy 34.92489 -60.363244) (xy 34.966081 -60.327553)
			(xy 35.011931 -60.298087) (xy 35.061508 -60.275445) (xy 35.113803 -60.26009) (xy 35.167751 -60.252334)
			(xy 35.222253 -60.252334) (xy 35.276201 -60.26009) (xy 35.328496 -60.275445) (xy 35.378073 -60.298087)
			(xy 35.423923 -60.327553) (xy 35.465114 -60.363244) (xy 35.500805 -60.404435) (xy 35.530271 -60.450285)
			(xy 35.552913 -60.499862) (xy 35.568268 -60.552157) (xy 35.576024 -60.606105) (xy 35.57651 -60.633356)
			(xy 35.576021 -60.661023) (xy 35.568037 -60.715779) (xy 35.552231 -60.768808) (xy 35.528934 -60.818999)
			(xy 35.498634 -60.8653) (xy 35.461965 -60.906741) (xy 35.441128 -60.924948) (xy 35.43681 -60.928758)
			(xy 35.430206 -60.937394) (xy 35.427666 -60.942982) (xy 35.425756 -60.947584) (xy 35.423588 -60.957309)
			(xy 35.423348 -60.962286) (xy 35.425888 -61.045852) (xy 35.426904 -61.05271) (xy 35.426904 -61.053218)
			(xy 35.430968 -61.065156) (xy 35.431476 -61.066172) (xy 35.434524 -61.072014) (xy 35.44189 -61.08065)
			(xy 35.446716 -61.084206) (xy 35.470377 -61.102321) (xy 35.512306 -61.144661) (xy 35.547141 -61.193006)
			(xy 35.574034 -61.246179) (xy 35.592333 -61.302888) (xy 35.601592 -61.361752) (xy 35.602164 -61.391546)
			(xy 35.60201 -61.407112) (xy 35.599465 -61.438139) (xy 35.597084 -61.453522) (xy 35.595306 -61.464698)
			(xy 35.5981 -61.475112) (xy 35.599683 -61.48023) (xy 35.604685 -61.489703) (xy 35.608006 -61.493908)
			(xy 35.626548 -61.516006) (xy 35.658552 -61.553852) (xy 35.663248 -61.559007) (xy 35.674849 -61.566733)
			(xy 35.681412 -61.569092) (xy 35.694366 -61.571632) (xy 36.759388 -61.571632) (xy 36.766246 -61.571124)
			(xy 36.774107 -61.569817) (xy 36.788478 -61.56295) (xy 36.79444 -61.557662) (xy 37.005006 -61.346842)
			(xy 37.421566 -60.930282) (xy 37.428377 -60.922937) (xy 37.436109 -60.904475) (xy 37.436552 -60.894468)
			(xy 37.436552 -38.896036) (xy 37.435282 -38.88486) (xy 37.433567 -38.878316) (xy 37.427267 -38.866349)
			(xy 37.422836 -38.861238) (xy 37.391042 -38.833103) (xy 37.332108 -38.771984) (xy 37.278924 -38.705801)
			(xy 37.231921 -38.635093) (xy 37.191482 -38.560437) (xy 37.157938 -38.48244) (xy 37.13156 -38.401737)
			(xy 37.112564 -38.318985) (xy 37.101104 -38.234857) (xy 37.097274 -38.150039) (xy 37.101105 -38.065221)
			(xy 37.112565 -37.981093) (xy 37.131561 -37.898341) (xy 37.157939 -37.817637) (xy 37.191484 -37.73964)
			(xy 37.231922 -37.664984) (xy 37.278925 -37.594277) (xy 37.33211 -37.528095) (xy 37.391044 -37.466975)
			(xy 37.422836 -37.438838) (xy 37.427312 -37.433757) (xy 37.433612 -37.421779) (xy 37.435282 -37.415216)
			(xy 37.436552 -37.40404) (xy 37.436552 -31.789624) (xy 37.432996 -31.780734) (xy 37.424773 -31.758593)
			(xy 37.413231 -31.712794) (xy 37.407428 -31.66592) (xy 37.407088 -31.642304) (xy 37.407423 -31.618687)
			(xy 37.41322 -31.571812) (xy 37.424761 -31.526011) (xy 37.432996 -31.503874) (xy 37.436552 -31.494984)
			(xy 37.436552 -31.233364) (xy 37.436674 -31.22841) (xy 37.438597 -31.218691) (xy 37.440362 -31.21406)
			(xy 37.445442 -31.201868) (xy 37.447213 -31.19724) (xy 37.449127 -31.187518) (xy 37.449252 -31.182564)
			(xy 37.449252 -29.848556) (xy 37.439092 -29.818076) (xy 37.423223 -29.796007) (xy 37.397227 -29.74827)
			(xy 37.378274 -29.697325) (xy 37.366747 -29.644205) (xy 37.36288 -29.589987) (xy 37.366751 -29.535769)
			(xy 37.378281 -29.48265) (xy 37.397238 -29.431707) (xy 37.423237 -29.383971) (xy 37.439092 -29.361892)
			(xy 37.449252 -29.331412) (xy 37.449252 -28.107894) (xy 37.449282 -28.104161) (xy 37.450304 -28.096765)
			(xy 37.451284 -28.093162) (xy 37.452677 -28.088209) (xy 37.453705 -28.077972) (xy 37.453316 -28.072842)
			(xy 37.450014 -28.044648) (xy 37.440108 -28.019756) (xy 37.422055 -27.994779) (xy 37.393394 -27.940225)
			(xy 37.373861 -27.881777) (xy 37.363964 -27.820952) (xy 37.3634 -27.79014) (xy 37.363861 -27.762885)
			(xy 37.371613 -27.708931) (xy 37.386966 -27.656628) (xy 37.409606 -27.607044) (xy 37.439073 -27.561186)
			(xy 37.474767 -27.519989) (xy 37.515961 -27.484292) (xy 37.561816 -27.454821) (xy 37.611398 -27.432177)
			(xy 37.663699 -27.41682) (xy 37.717654 -27.409063) (xy 37.744908 -27.408632) (xy 37.770456 -27.409041)
			(xy 37.821094 -27.415858) (xy 37.870371 -27.429367) (xy 37.917405 -27.449329) (xy 37.961357 -27.475386)
			(xy 37.981636 -27.490928) (xy 38.013132 -27.50185) (xy 38.023096 -27.501369) (xy 38.041524 -27.493784)
			(xy 38.048946 -27.487118) (xy 38.193472 -27.342592) (xy 38.200875 -27.335758) (xy 38.219473 -27.328051)
			(xy 38.22954 -27.327606) (xy 38.416484 -27.327606) (xy 38.41877 -27.327352) (xy 42.47642 -27.327352)
			(xy 42.485637 -27.326297) (xy 42.502446 -27.318485) (xy 42.509186 -27.312112) (xy 42.515724 -27.304781)
			(xy 42.523155 -27.286617) (xy 42.523664 -27.276806) (xy 42.523664 -26.479246) (xy 42.523877 -26.457072)
			(xy 42.528079 -26.412925) (xy 42.532046 -26.391108) (xy 42.532046 -26.3906) (xy 42.5323 -26.389584)
			(xy 42.532808 -26.387298) (xy 42.533316 -26.385266) (xy 42.533991 -26.380054) (xy 42.533486 -26.369558)
			(xy 42.5323 -26.364438) (xy 42.530268 -26.358088) (xy 42.52468 -26.344626) (xy 42.516044 -26.33853)
			(xy 42.507662 -26.332688) (xy 42.50182 -26.329132) (xy 42.491914 -26.326846) (xy 42.46809 -26.341236)
			(xy 42.417272 -26.363935) (xy 42.363782 -26.379317) (xy 42.308669 -26.38708) (xy 42.28084 -26.387552)
			(xy 42.25244 -26.387072) (xy 42.196217 -26.378994) (xy 42.141716 -26.362996) (xy 42.090046 -26.339405)
			(xy 42.042261 -26.3087) (xy 41.999331 -26.271506) (xy 41.962132 -26.228582) (xy 41.931421 -26.1808)
			(xy 41.907822 -26.129134) (xy 41.891817 -26.074635) (xy 41.883732 -26.018413) (xy 41.88373 -25.961612)
			(xy 41.891812 -25.90539) (xy 41.907814 -25.85089) (xy 41.931409 -25.799222) (xy 41.962117 -25.751439)
			(xy 41.999313 -25.708512) (xy 42.04224 -25.671316) (xy 42.090024 -25.640608) (xy 42.141692 -25.617013)
			(xy 42.196192 -25.601012) (xy 42.252414 -25.59293) (xy 42.309215 -25.592932) (xy 42.365437 -25.601018)
			(xy 42.419936 -25.617023) (xy 42.471602 -25.640622) (xy 42.519383 -25.671333) (xy 42.562308 -25.708533)
			(xy 42.599501 -25.751462) (xy 42.630206 -25.799248) (xy 42.645184 -25.832054) (xy 44.18787 -25.832054)
			(xy 44.191941 -25.776432) (xy 44.204067 -25.721995) (xy 44.22399 -25.669904) (xy 44.251286 -25.621269)
			(xy 44.285372 -25.577126) (xy 44.325521 -25.538417) (xy 44.370879 -25.505966) (xy 44.420479 -25.480465)
			(xy 44.473263 -25.462458) (xy 44.528106 -25.452328) (xy 44.58384 -25.450291) (xy 44.639277 -25.456391)
			(xy 44.693234 -25.470497) (xy 44.744563 -25.492309) (xy 44.792169 -25.521363) (xy 44.835037 -25.557038)
			(xy 44.836571 -25.55875) (xy 48.64227 -25.55875) (xy 48.642756 -25.531499) (xy 48.650512 -25.477551)
			(xy 48.665867 -25.425256) (xy 48.688509 -25.375679) (xy 48.717975 -25.329829) (xy 48.753666 -25.288638)
			(xy 48.794857 -25.252947) (xy 48.840707 -25.223481) (xy 48.890284 -25.200839) (xy 48.942579 -25.185484)
			(xy 48.996527 -25.177728) (xy 49.051029 -25.177728) (xy 49.104977 -25.185484) (xy 49.157272 -25.200839)
			(xy 49.206849 -25.223481) (xy 49.252699 -25.252947) (xy 49.29389 -25.288638) (xy 49.329581 -25.329829)
			(xy 49.359047 -25.375679) (xy 49.381689 -25.425256) (xy 49.397044 -25.477551) (xy 49.4048 -25.531499)
			(xy 49.405286 -25.55875) (xy 49.404721 -25.589012) (xy 49.39517 -25.648778) (xy 49.376299 -25.706285)
			(xy 49.348584 -25.76009) (xy 49.331118 -25.78481) (xy 49.322808 -25.796939) (xy 49.312851 -25.824589)
			(xy 49.311181 -25.853929) (xy 49.317937 -25.88253) (xy 49.33256 -25.908022) (xy 49.353837 -25.928294)
			(xy 49.380006 -25.941666) (xy 49.394364 -25.94483) (xy 49.420267 -25.950127) (xy 49.470389 -25.966952)
			(xy 49.517708 -25.990538) (xy 49.561315 -26.020433) (xy 49.600376 -26.056065) (xy 49.63414 -26.09675)
			(xy 49.661962 -26.141708) (xy 49.683308 -26.190079) (xy 49.697768 -26.240934) (xy 49.705066 -26.293299)
			(xy 49.705514 -26.319734) (xy 50.841908 -26.319734) (xy 50.845979 -26.264112) (xy 50.858105 -26.209675)
			(xy 50.878028 -26.157584) (xy 50.905324 -26.108949) (xy 50.93941 -26.064806) (xy 50.979559 -26.026097)
			(xy 51.024917 -25.993646) (xy 51.074517 -25.968145) (xy 51.127301 -25.950138) (xy 51.182144 -25.940008)
			(xy 51.237878 -25.937971) (xy 51.293315 -25.944071) (xy 51.347272 -25.958177) (xy 51.398601 -25.979989)
			(xy 51.446207 -26.009043) (xy 51.489075 -26.044718) (xy 51.526292 -26.086255) (xy 51.557065 -26.132768)
			(xy 51.580737 -26.183265) (xy 51.596805 -26.236672) (xy 51.604925 -26.291848) (xy 51.605434 -26.319734)
			(xy 51.604925 -26.34762) (xy 51.596805 -26.402796) (xy 51.580737 -26.456203) (xy 51.557065 -26.5067)
			(xy 51.526292 -26.553213) (xy 51.489075 -26.59475) (xy 51.446207 -26.630425) (xy 51.398601 -26.659479)
			(xy 51.347272 -26.681291) (xy 51.293315 -26.695397) (xy 51.237878 -26.701497) (xy 51.182144 -26.69946)
			(xy 51.127301 -26.68933) (xy 51.074517 -26.671323) (xy 51.024917 -26.645822) (xy 50.979559 -26.613371)
			(xy 50.93941 -26.574662) (xy 50.905324 -26.530519) (xy 50.878028 -26.481884) (xy 50.858105 -26.429793)
			(xy 50.845979 -26.375356) (xy 50.841908 -26.319734) (xy 49.705514 -26.319734) (xy 49.705028 -26.346985)
			(xy 49.697272 -26.400933) (xy 49.681917 -26.453228) (xy 49.659275 -26.502805) (xy 49.629809 -26.548655)
			(xy 49.594118 -26.589846) (xy 49.552927 -26.625537) (xy 49.507077 -26.655003) (xy 49.4575 -26.677645)
			(xy 49.405205 -26.693) (xy 49.351257 -26.700756) (xy 49.296755 -26.700756) (xy 49.242807 -26.693)
			(xy 49.190512 -26.677645) (xy 49.140935 -26.655003) (xy 49.095085 -26.625537) (xy 49.053894 -26.589846)
			(xy 49.018203 -26.548655) (xy 48.988737 -26.502805) (xy 48.966095 -26.453228) (xy 48.95074 -26.400933)
			(xy 48.942984 -26.346985) (xy 48.942498 -26.319734) (xy 48.943058 -26.289472) (xy 48.952611 -26.229706)
			(xy 48.971483 -26.172199) (xy 48.9992 -26.118394) (xy 49.016666 -26.093674) (xy 49.025005 -26.081563)
			(xy 49.034963 -26.053907) (xy 49.036631 -26.024561) (xy 49.02987 -25.995955) (xy 49.015242 -25.970459)
			(xy 48.993958 -25.950186) (xy 48.967781 -25.936816) (xy 48.95342 -25.933654) (xy 48.927527 -25.92831)
			(xy 48.877403 -25.911496) (xy 48.830083 -25.887918) (xy 48.786473 -25.85803) (xy 48.74741 -25.822404)
			(xy 48.713644 -25.781723) (xy 48.68582 -25.736768) (xy 48.664474 -25.6884) (xy 48.650014 -25.637547)
			(xy 48.642717 -25.585184) (xy 48.64227 -25.55875) (xy 44.836571 -25.55875) (xy 44.872254 -25.598575)
			(xy 44.903027 -25.645088) (xy 44.926699 -25.695585) (xy 44.942767 -25.748992) (xy 44.950887 -25.804168)
			(xy 44.951396 -25.832054) (xy 44.950887 -25.85994) (xy 44.942767 -25.915116) (xy 44.926699 -25.968523)
			(xy 44.903027 -26.01902) (xy 44.872254 -26.065533) (xy 44.835037 -26.10707) (xy 44.792169 -26.142745)
			(xy 44.744563 -26.171799) (xy 44.693234 -26.193611) (xy 44.639277 -26.207717) (xy 44.58384 -26.213817)
			(xy 44.528106 -26.21178) (xy 44.473263 -26.20165) (xy 44.420479 -26.183643) (xy 44.370879 -26.158142)
			(xy 44.325521 -26.125691) (xy 44.285372 -26.086982) (xy 44.251286 -26.042839) (xy 44.22399 -25.994204)
			(xy 44.204067 -25.942113) (xy 44.191941 -25.887676) (xy 44.18787 -25.832054) (xy 42.645184 -25.832054)
			(xy 42.653797 -25.850918) (xy 42.669794 -25.905419) (xy 42.677872 -25.961642) (xy 42.67835 -25.990042)
			(xy 42.678025 -26.011229) (xy 42.673442 -26.053354) (xy 42.669206 -26.074116) (xy 42.671718 -26.077309)
			(xy 42.677588 -26.082925) (xy 42.68089 -26.085292) (xy 42.686478 -26.089102) (xy 42.692474 -26.092779)
			(xy 42.705875 -26.097033) (xy 42.712894 -26.097484) (xy 42.727372 -26.097738) (xy 42.74058 -26.08961)
			(xy 42.768767 -26.07285) (xy 42.828897 -26.046684) (xy 42.892144 -26.029358) (xy 42.957215 -26.021229)
			(xy 42.990008 -26.021284) (xy 42.99331 -26.021538) (xy 43.022744 -26.022767) (xy 43.08095 -26.031854)
			(xy 43.13751 -26.048332) (xy 43.191489 -26.07193) (xy 43.241995 -26.102256) (xy 43.288194 -26.138811)
			(xy 43.329322 -26.18099) (xy 43.3647 -26.228096) (xy 43.393743 -26.279351) (xy 43.415971 -26.333908)
			(xy 43.423096 -26.360882) (xy 46.10557 -26.360882) (xy 46.109641 -26.30526) (xy 46.121767 -26.250823)
			(xy 46.14169 -26.198732) (xy 46.168986 -26.150097) (xy 46.203072 -26.105954) (xy 46.243221 -26.067245)
			(xy 46.288579 -26.034794) (xy 46.338179 -26.009293) (xy 46.390963 -25.991286) (xy 46.445806 -25.981156)
			(xy 46.50154 -25.979119) (xy 46.556977 -25.985219) (xy 46.610934 -25.999325) (xy 46.662263 -26.021137)
			(xy 46.709869 -26.050191) (xy 46.752737 -26.085866) (xy 46.789954 -26.127403) (xy 46.820727 -26.173916)
			(xy 46.844399 -26.224413) (xy 46.860467 -26.27782) (xy 46.868587 -26.332996) (xy 46.869096 -26.360882)
			(xy 46.868587 -26.388768) (xy 46.860467 -26.443944) (xy 46.844399 -26.497351) (xy 46.820727 -26.547848)
			(xy 46.789954 -26.594361) (xy 46.752737 -26.635898) (xy 46.709869 -26.671573) (xy 46.662263 -26.700627)
			(xy 46.610934 -26.722439) (xy 46.556977 -26.736545) (xy 46.50154 -26.742645) (xy 46.445806 -26.740608)
			(xy 46.390963 -26.730478) (xy 46.338179 -26.712471) (xy 46.288579 -26.68697) (xy 46.243221 -26.654519)
			(xy 46.203072 -26.61581) (xy 46.168986 -26.571667) (xy 46.14169 -26.523032) (xy 46.121767 -26.470941)
			(xy 46.109641 -26.416504) (xy 46.10557 -26.360882) (xy 43.423096 -26.360882) (xy 43.431017 -26.390866)
			(xy 43.438633 -26.449283) (xy 43.43908 -26.478738) (xy 43.43908 -27.276806) (xy 43.439582 -27.286616)
			(xy 43.44703 -27.304773) (xy 43.453558 -27.312112) (xy 43.460307 -27.318476) (xy 43.477108 -27.326306)
			(xy 43.486324 -27.327352) (xy 52.698904 -27.327352) (xy 52.708008 -27.326369) (xy 52.724677 -27.31882)
			(xy 52.731416 -27.31262) (xy 53.09616 -26.947876) (xy 53.101139 -26.942445) (xy 53.107982 -26.929405)
			(xy 53.109622 -26.922222) (xy 53.109622 -26.921714) (xy 53.110638 -26.912316) (xy 53.110638 -24.983186)
			(xy 53.110145 -24.972344) (xy 53.101203 -24.952592) (xy 53.093366 -24.945086) (xy 53.028088 -24.887428)
			(xy 53.00726 -24.881078) (xy 52.996592 -24.882602) (xy 52.98489 -24.883929) (xy 52.961379 -24.885325)
			(xy 52.949602 -24.885396) (xy 52.922349 -24.884933) (xy 52.868399 -24.877176) (xy 52.816101 -24.86182)
			(xy 52.766522 -24.839177) (xy 52.720669 -24.809709) (xy 52.679477 -24.774015) (xy 52.643785 -24.732823)
			(xy 52.614318 -24.686969) (xy 52.591676 -24.637389) (xy 52.576322 -24.585091) (xy 52.568566 -24.531141)
			(xy 52.568094 -24.503888) (xy 52.568172 -24.492877) (xy 52.569443 -24.470892) (xy 52.570634 -24.459946)
			(xy 52.571904 -24.449024) (xy 52.5653 -24.427942) (xy 52.506118 -24.363172) (xy 52.498412 -24.355474)
			(xy 52.4784 -24.346926) (xy 52.46751 -24.346662) (xy 52.459382 -24.346662) (xy 52.432135 -24.346175)
			(xy 52.378196 -24.338417) (xy 52.32591 -24.323062) (xy 52.276341 -24.300423) (xy 52.230499 -24.27096)
			(xy 52.189316 -24.235274) (xy 52.153631 -24.194089) (xy 52.12417 -24.148246) (xy 52.101532 -24.098676)
			(xy 52.08618 -24.04639) (xy 52.078424 -23.99245) (xy 52.078424 -23.937956) (xy 52.086178 -23.884017)
			(xy 52.10153 -23.83173) (xy 52.124167 -23.78216) (xy 52.153627 -23.736316) (xy 52.189311 -23.695131)
			(xy 52.230494 -23.659444) (xy 52.276336 -23.62998) (xy 52.325904 -23.60734) (xy 52.37819 -23.591984)
			(xy 52.432128 -23.584226) (xy 52.486622 -23.584222) (xy 52.540562 -23.591974) (xy 52.59285 -23.607323)
			(xy 52.642421 -23.629956) (xy 52.688267 -23.659414) (xy 52.729454 -23.695096) (xy 52.765144 -23.736277)
			(xy 52.79461 -23.782117) (xy 52.817253 -23.831684) (xy 52.832611 -23.883969) (xy 52.840373 -23.937907)
			(xy 52.84089 -23.965154) (xy 52.84081 -23.976165) (xy 52.839537 -23.998149) (xy 52.83835 -24.009096)
			(xy 52.83708 -24.020018) (xy 52.843684 -24.0411) (xy 52.902866 -24.10587) (xy 52.910574 -24.113566)
			(xy 52.930584 -24.122112) (xy 52.941474 -24.12238) (xy 52.949602 -24.12238) (xy 52.977796 -24.123396)
			(xy 52.98948 -24.124158) (xy 53.010816 -24.115776) (xy 53.072792 -24.04872) (xy 53.080026 -24.039846)
			(xy 53.086609 -24.017951) (xy 53.085492 -24.006556) (xy 53.085492 -24.006302) (xy 53.08348 -23.992608)
			(xy 53.081192 -23.965022) (xy 53.08092 -23.951184) (xy 53.08092 -23.947628) (xy 53.081229 -23.92375)
			(xy 53.087059 -23.876353) (xy 53.098744 -23.830051) (xy 53.107082 -23.807674) (xy 53.110638 -23.798784)
			(xy 53.110638 -22.255988) (xy 53.110282 -22.248771) (xy 53.106032 -22.234969) (xy 53.102256 -22.22881)
			(xy 53.101748 -22.228556) (xy 53.101748 -22.228302) (xy 53.078888 -22.210014) (xy 53.072284 -22.20722)
			(xy 53.046722 -22.195904) (xy 52.99894 -22.16689) (xy 52.955904 -22.131215) (xy 52.918534 -22.089641)
			(xy 52.88763 -22.04306) (xy 52.863855 -21.992467) (xy 52.847716 -21.938947) (xy 52.83956 -21.883644)
			(xy 52.839561 -21.827743) (xy 52.847719 -21.772441) (xy 52.863859 -21.718921) (xy 52.887636 -21.66833)
			(xy 52.918541 -21.621749) (xy 52.955913 -21.580177) (xy 52.998951 -21.544502) (xy 53.046733 -21.51549)
			(xy 53.072284 -21.504148) (xy 53.078888 -21.501354) (xy 53.101748 -21.483066) (xy 53.101748 -21.482812)
			(xy 53.102256 -21.482558) (xy 53.106022 -21.476392) (xy 53.110291 -21.462596) (xy 53.110638 -21.45538)
			(xy 53.110638 -15.81658) (xy 53.11013 -15.806401) (xy 53.102136 -15.787673) (xy 53.095144 -15.780258)
			(xy 53.05425 -15.74038) (xy 53.04282 -15.729204) (xy 53.039137 -15.725762) (xy 53.030695 -15.720254)
			(xy 53.026056 -15.718282) (xy 53.016912 -15.714726) (xy 53.006244 -15.71498) (xy 52.996084 -15.715234)
			(xy 52.995576 -15.715234) (xy 52.965981 -15.714658) (xy 52.907506 -15.70548) (xy 52.851151 -15.68738)
			(xy 52.798269 -15.660791) (xy 52.750128 -15.626353) (xy 52.728622 -15.606014) (xy 52.727606 -15.604998)
			(xy 52.723905 -15.601678) (xy 52.715456 -15.596437) (xy 52.710842 -15.594584) (xy 52.701444 -15.591028)
			(xy 52.65293 -15.593568) (xy 52.615592 -15.595346) (xy 52.61031 -15.595744) (xy 52.600065 -15.598426)
			(xy 52.595272 -15.60068) (xy 52.586128 -15.605252) (xy 52.57927 -15.613634) (xy 52.561056 -15.634863)
			(xy 52.519473 -15.672275) (xy 52.472871 -15.703212) (xy 52.422251 -15.72701) (xy 52.368698 -15.74316)
			(xy 52.31336 -15.751314) (xy 52.285392 -15.75181) (xy 52.258141 -15.751324) (xy 52.204194 -15.743566)
			(xy 52.1519 -15.72821) (xy 52.102323 -15.705569) (xy 52.056474 -15.676102) (xy 52.015284 -15.64041)
			(xy 51.979593 -15.59922) (xy 51.950128 -15.55337) (xy 51.927487 -15.503793) (xy 51.912132 -15.451498)
			(xy 51.904376 -15.397551) (xy 51.904376 -15.343049) (xy 51.912132 -15.289102) (xy 51.927487 -15.236807)
			(xy 51.950128 -15.18723) (xy 51.979593 -15.14138) (xy 52.015284 -15.10019) (xy 52.056474 -15.064498)
			(xy 52.102323 -15.035031) (xy 52.1519 -15.01239) (xy 52.204194 -14.997034) (xy 52.258141 -14.989276)
			(xy 52.285392 -14.988794) (xy 52.315012 -14.989354) (xy 52.373539 -14.998512) (xy 52.429947 -15.016609)
			(xy 52.482878 -15.043209) (xy 52.531061 -15.077674) (xy 52.5526 -15.098014) (xy 52.553616 -15.09903)
			(xy 52.557315 -15.102354) (xy 52.56576 -15.107604) (xy 52.57038 -15.109444) (xy 52.579778 -15.113)
			(xy 52.628292 -15.11046) (xy 52.66563 -15.108682) (xy 52.670911 -15.108281) (xy 52.681153 -15.105592)
			(xy 52.68595 -15.103348) (xy 52.69484 -15.09903) (xy 52.701952 -15.090394) (xy 52.720166 -15.069165)
			(xy 52.761748 -15.031753) (xy 52.80835 -15.000816) (xy 52.85897 -14.977019) (xy 52.912524 -14.960871)
			(xy 52.967862 -14.952719) (xy 52.99583 -14.952218) (xy 53.008276 -14.952218) (xy 53.017928 -14.952472)
			(xy 53.026056 -14.94917) (xy 53.03062 -14.947162) (xy 53.038935 -14.941664) (xy 53.042566 -14.938248)
			(xy 53.095144 -14.887194) (xy 53.102166 -14.879797) (xy 53.110172 -14.861059) (xy 53.110638 -14.850872)
			(xy 53.110638 -13.72616) (xy 53.110472 -13.72015) (xy 53.107652 -13.708466) (xy 53.10505 -13.703046)
			(xy 53.103207 -13.699575) (xy 53.098607 -13.693202) (xy 53.095906 -13.690346) (xy 52.79009 -13.38453)
			(xy 52.787239 -13.381825) (xy 52.780859 -13.377233) (xy 52.77739 -13.375386) (xy 52.771964 -13.3728)
			(xy 52.760284 -13.36997) (xy 52.754276 -13.369798) (xy 48.047656 -13.369798) (xy 48.041646 -13.369965)
			(xy 48.029963 -13.372787) (xy 48.024542 -13.375386) (xy 48.021065 -13.377222) (xy 48.01468 -13.381809)
			(xy 48.011842 -13.38453) (xy 47.29607 -14.100302) (xy 52.043074 -14.100302) (xy 52.047145 -14.04468)
			(xy 52.059271 -13.990243) (xy 52.079194 -13.938152) (xy 52.10649 -13.889517) (xy 52.140576 -13.845374)
			(xy 52.180725 -13.806665) (xy 52.226083 -13.774214) (xy 52.275683 -13.748713) (xy 52.328467 -13.730706)
			(xy 52.38331 -13.720576) (xy 52.439044 -13.718539) (xy 52.494481 -13.724639) (xy 52.548438 -13.738745)
			(xy 52.599767 -13.760557) (xy 52.647373 -13.789611) (xy 52.690241 -13.825286) (xy 52.727458 -13.866823)
			(xy 52.758231 -13.913336) (xy 52.781903 -13.963833) (xy 52.797971 -14.01724) (xy 52.806091 -14.072416)
			(xy 52.8066 -14.100302) (xy 52.806091 -14.128188) (xy 52.797971 -14.183364) (xy 52.781903 -14.236771)
			(xy 52.758231 -14.287268) (xy 52.727458 -14.333781) (xy 52.690241 -14.375318) (xy 52.647373 -14.410993)
			(xy 52.599767 -14.440047) (xy 52.548438 -14.461859) (xy 52.494481 -14.475965) (xy 52.439044 -14.482065)
			(xy 52.38331 -14.480028) (xy 52.328467 -14.469898) (xy 52.275683 -14.451891) (xy 52.226083 -14.42639)
			(xy 52.180725 -14.393939) (xy 52.140576 -14.35523) (xy 52.10649 -14.311087) (xy 52.079194 -14.262452)
			(xy 52.059271 -14.210361) (xy 52.047145 -14.155924) (xy 52.043074 -14.100302) (xy 47.29607 -14.100302)
			(xy 46.705774 -14.690598) (xy 46.700561 -14.695507) (xy 46.688056 -14.702471) (xy 46.681136 -14.704314)
			(xy 46.678596 -14.704822) (xy 46.670523 -14.707442) (xy 46.656632 -14.717175) (xy 46.651418 -14.723872)
			(xy 46.60011 -14.800326) (xy 46.597317 -14.805199) (xy 46.593722 -14.815838) (xy 46.592998 -14.821408)
			(xy 46.591728 -14.8336) (xy 46.596554 -14.845284) (xy 46.621968 -14.909157) (xy 46.665503 -15.039564)
			(xy 46.70055 -15.172503) (xy 46.726963 -15.307424) (xy 46.744633 -15.443765) (xy 46.753486 -15.580961)
			(xy 46.754034 -15.649702) (xy 46.754034 -15.649956) (xy 46.753528 -15.715692) (xy 46.745435 -15.846913)
			(xy 46.729278 -15.977388) (xy 46.705121 -16.106621) (xy 46.673053 -16.234121) (xy 46.633197 -16.359405)
			(xy 46.585704 -16.481999) (xy 46.530755 -16.601436) (xy 46.468556 -16.717263) (xy 46.399346 -16.829042)
			(xy 46.323385 -16.936349) (xy 46.240963 -17.038775) (xy 46.152391 -17.135934) (xy 46.058006 -17.227455)
			(xy 45.958167 -17.312993) (xy 45.85325 -17.392222) (xy 45.743656 -17.464842) (xy 45.629798 -17.530577)
			(xy 45.51211 -17.589179) (xy 45.391038 -17.640425) (xy 45.26704 -17.68412) (xy 45.140588 -17.720099)
			(xy 45.01216 -17.748225) (xy 44.882245 -17.768391) (xy 44.751335 -17.780522) (xy 44.619926 -17.784571)
			(xy 44.488517 -17.780522) (xy 44.357607 -17.768391) (xy 44.227692 -17.748225) (xy 44.099264 -17.720099)
			(xy 43.972812 -17.68412) (xy 43.848814 -17.640425) (xy 43.727742 -17.589179) (xy 43.610054 -17.530577)
			(xy 43.496196 -17.464842) (xy 43.386602 -17.392222) (xy 43.281685 -17.312993) (xy 43.181846 -17.227455)
			(xy 43.087461 -17.135934) (xy 42.998889 -17.038775) (xy 42.916467 -16.936349) (xy 42.840506 -16.829042)
			(xy 42.771296 -16.717263) (xy 42.709097 -16.601436) (xy 42.654148 -16.481999) (xy 42.606655 -16.359405)
			(xy 42.566799 -16.234121) (xy 42.534731 -16.106621) (xy 42.510574 -15.977388) (xy 42.494417 -15.846913)
			(xy 42.486324 -15.715692) (xy 42.485818 -15.649956) (xy 42.486376 -15.581216) (xy 42.495244 -15.444022)
			(xy 42.512921 -15.307683) (xy 42.539334 -15.172764) (xy 42.574374 -15.039824) (xy 42.617895 -14.909414)
			(xy 42.643298 -14.845538) (xy 42.643298 -14.845284) (xy 42.645482 -14.839513) (xy 42.647278 -14.82731)
			(xy 42.646854 -14.821154) (xy 42.645584 -14.808708) (xy 42.591228 -14.727936) (xy 42.583743 -14.71797)
			(xy 42.561765 -14.706276) (xy 42.549318 -14.705584) (xy 40.73398 -14.705584) (xy 40.725344 -14.706346)
			(xy 40.721302 -14.70713) (xy 40.713516 -14.709807) (xy 40.70985 -14.71168) (xy 40.70985 -14.711934)
			(xy 40.703346 -14.715829) (xy 40.692764 -14.726676) (xy 40.689022 -14.73327) (xy 40.648128 -14.814042)
			(xy 40.645108 -14.820333) (xy 40.642277 -14.833992) (xy 40.64254 -14.840966) (xy 40.643302 -14.848332)
			(xy 40.647874 -14.861032) (xy 40.652192 -14.866874) (xy 40.676671 -14.901315) (xy 40.720042 -14.973838)
			(xy 40.756728 -15.049961) (xy 40.786434 -15.12907) (xy 40.808919 -15.210526) (xy 40.824002 -15.293671)
			(xy 40.831561 -15.377835) (xy 40.832024 -15.420086) (xy 40.832024 -15.42034) (xy 40.831465 -15.466046)
			(xy 40.822567 -15.557023) (xy 40.804888 -15.646709) (xy 40.778596 -15.734258) (xy 40.743936 -15.818844)
			(xy 40.723058 -15.859506) (xy 40.722804 -15.860014) (xy 40.720156 -15.865621) (xy 40.717331 -15.87769)
			(xy 40.717216 -15.88389) (xy 40.717216 -15.896082) (xy 40.763698 -15.982188) (xy 40.764206 -15.98295)
			(xy 40.772334 -15.993872) (xy 40.780716 -16.00073) (xy 40.790622 -16.00708) (xy 40.803576 -16.00835)
			(xy 40.848072 -16.012959) (xy 40.936015 -16.029376) (xy 41.022063 -16.053855) (xy 41.105478 -16.086187)
			(xy 41.185546 -16.126094) (xy 41.261581 -16.173235) (xy 41.33293 -16.227205) (xy 41.398982 -16.287542)
			(xy 41.459172 -16.353729) (xy 41.512983 -16.425199) (xy 41.559954 -16.501338) (xy 41.599682 -16.581495)
			(xy 41.631828 -16.664983) (xy 41.656115 -16.751085) (xy 41.672336 -16.839064) (xy 41.680351 -16.928167)
			(xy 41.680091 -17.017629) (xy 41.67156 -17.106683) (xy 41.65483 -17.194567) (xy 41.630044 -17.280527)
			(xy 41.597415 -17.363827) (xy 41.557222 -17.443752) (xy 41.509811 -17.519618) (xy 41.455587 -17.590774)
			(xy 41.395015 -17.656611) (xy 41.328614 -17.716564) (xy 41.293034 -17.743678) (xy 41.257811 -17.769395)
			(xy 41.183521 -17.815091) (xy 41.105413 -17.853903) (xy 41.024124 -17.885514) (xy 40.940316 -17.909666)
			(xy 40.854671 -17.926163) (xy 40.767888 -17.934871) (xy 40.680673 -17.935719) (xy 40.593737 -17.928699)
			(xy 40.507788 -17.913869) (xy 40.423527 -17.89135) (xy 40.341639 -17.861325) (xy 40.262791 -17.824039)
			(xy 40.187627 -17.779795) (xy 40.116759 -17.728954) (xy 40.050763 -17.671931) (xy 39.990178 -17.609188)
			(xy 39.935496 -17.541239) (xy 39.887164 -17.468636) (xy 39.845576 -17.391971) (xy 39.811069 -17.311869)
			(xy 39.783925 -17.228981) (xy 39.764366 -17.143983) (xy 39.752551 -17.057568) (xy 39.748575 -16.97044)
			(xy 39.752471 -16.883308) (xy 39.764208 -16.796882) (xy 39.78369 -16.711867) (xy 39.810758 -16.628955)
			(xy 39.845192 -16.54882) (xy 39.865554 -16.510254) (xy 39.865554 -16.51) (xy 39.865808 -16.51) (xy 39.867078 -16.50746)
			(xy 39.869331 -16.502156) (xy 39.871646 -16.49087) (xy 39.87165 -16.485108) (xy 39.871396 -16.471646)
			(xy 39.819834 -16.385032) (xy 39.817635 -16.381491) (xy 39.812273 -16.37511) (xy 39.809166 -16.372332)
			(xy 39.802079 -16.366749) (xy 39.785161 -16.360514) (xy 39.776146 -16.36014) (xy 38.03777 -16.36014)
			(xy 37.994333 -16.359637) (xy 37.90783 -16.351619) (xy 37.822435 -16.335653) (xy 37.738878 -16.311876)
			(xy 37.657872 -16.280492) (xy 37.580106 -16.241766) (xy 37.506246 -16.196031) (xy 37.43692 -16.143676)
			(xy 37.372721 -16.085148) (xy 37.314196 -16.020946) (xy 37.261844 -15.951618) (xy 37.216112 -15.877755)
			(xy 37.177391 -15.799988) (xy 37.14601 -15.71898) (xy 37.122237 -15.635422) (xy 37.106275 -15.550027)
			(xy 37.098261 -15.463523) (xy 37.097716 -15.420086) (xy 37.097716 -15.419578) (xy 37.098186 -15.377362)
			(xy 37.105778 -15.293273) (xy 37.120879 -15.210203) (xy 37.143369 -15.128822) (xy 37.173066 -15.049786)
			(xy 37.209732 -14.973731) (xy 37.253069 -14.901271) (xy 37.277548 -14.866874) (xy 37.281866 -14.861032)
			(xy 37.286438 -14.848332) (xy 37.2872 -14.840966) (xy 37.287472 -14.833992) (xy 37.284638 -14.820331)
			(xy 37.281612 -14.814042) (xy 37.276024 -14.80312) (xy 37.23894 -14.729968) (xy 37.23581 -14.725297)
			(xy 37.227868 -14.717341) (xy 37.223192 -14.71422) (xy 37.21735 -14.710918) (xy 37.212083 -14.708483)
			(xy 37.200797 -14.705798) (xy 37.194998 -14.705584) (xy 37.059616 -14.705584) (xy 37.051013 -14.705921)
			(xy 37.034785 -14.711637) (xy 37.027866 -14.71676) (xy 37.027358 -14.717268) (xy 37.023802 -14.720316)
			(xy 33.329372 -18.414746) (xy 33.321244 -18.425668) (xy 33.321244 -18.425922) (xy 33.31646 -18.435942)
			(xy 33.315965 -18.44421) (xy 48.276254 -18.44421) (xy 48.280325 -18.388588) (xy 48.292451 -18.334151)
			(xy 48.312374 -18.28206) (xy 48.33967 -18.233425) (xy 48.373756 -18.189282) (xy 48.413905 -18.150573)
			(xy 48.459263 -18.118122) (xy 48.508863 -18.092621) (xy 48.561647 -18.074614) (xy 48.61649 -18.064484)
			(xy 48.672224 -18.062447) (xy 48.727661 -18.068547) (xy 48.781618 -18.082653) (xy 48.832947 -18.104465)
			(xy 48.880553 -18.133519) (xy 48.923421 -18.169194) (xy 48.960638 -18.210731) (xy 48.991411 -18.257244)
			(xy 49.015083 -18.307741) (xy 49.031151 -18.361148) (xy 49.039271 -18.416324) (xy 49.03978 -18.44421)
			(xy 49.039271 -18.472096) (xy 49.031151 -18.527272) (xy 49.015083 -18.580679) (xy 48.991411 -18.631176)
			(xy 48.960638 -18.677689) (xy 48.923421 -18.719226) (xy 48.880553 -18.754901) (xy 48.832947 -18.783955)
			(xy 48.781618 -18.805767) (xy 48.727661 -18.819873) (xy 48.672224 -18.825973) (xy 48.61649 -18.823936)
			(xy 48.561647 -18.813806) (xy 48.508863 -18.795799) (xy 48.459263 -18.770298) (xy 48.413905 -18.737847)
			(xy 48.373756 -18.699138) (xy 48.33967 -18.654995) (xy 48.312374 -18.60636) (xy 48.292451 -18.554269)
			(xy 48.280325 -18.499832) (xy 48.276254 -18.44421) (xy 33.315965 -18.44421) (xy 33.315134 -18.458081)
			(xy 33.318704 -18.468594) (xy 33.35274 -18.555208) (xy 33.355351 -18.561354) (xy 33.363207 -18.572147)
			(xy 33.368234 -18.576544) (xy 33.371028 -18.578322) (xy 33.376756 -18.582066) (xy 33.389627 -18.586704)
			(xy 33.396428 -18.587466) (xy 33.461889 -18.590303) (xy 33.592313 -18.603006) (xy 33.721711 -18.623689)
			(xy 33.849596 -18.652274) (xy 33.975486 -18.688654) (xy 34.098906 -18.73269) (xy 34.219391 -18.784218)
			(xy 34.336486 -18.843042) (xy 34.449751 -18.908942) (xy 34.558759 -18.981668) (xy 34.663097 -19.060947)
			(xy 34.762374 -19.146479) (xy 34.856215 -19.237943) (xy 34.944266 -19.334994) (xy 35.026195 -19.437265)
			(xy 35.101693 -19.544371) (xy 35.170476 -19.655908) (xy 35.232284 -19.771456) (xy 35.286885 -19.89058)
			(xy 35.334073 -20.01283) (xy 35.373669 -20.137745) (xy 35.405525 -20.264855) (xy 35.42952 -20.39368)
			(xy 35.445565 -20.523735) (xy 35.453597 -20.65453) (xy 35.454082 -20.72005) (xy 35.453595 -20.784521)
			(xy 35.44581 -20.913229) (xy 35.430268 -21.041231) (xy 35.407025 -21.168061) (xy 35.376167 -21.293257)
			(xy 35.337806 -21.416361) (xy 35.292083 -21.536925) (xy 35.239163 -21.654507) (xy 35.195167 -21.738336)
			(xy 37.41674 -21.738336) (xy 37.417241 -21.709596) (xy 37.425871 -21.652769) (xy 37.442928 -21.597878)
			(xy 37.468024 -21.546167) (xy 37.500592 -21.498805) (xy 37.519864 -21.477478) (xy 37.526468 -21.47062)
			(xy 37.53358 -21.452586) (xy 37.53358 -21.363686) (xy 37.526468 -21.345652) (xy 37.519864 -21.338794)
			(xy 37.500627 -21.317437) (xy 37.468057 -21.270081) (xy 37.442961 -21.218374) (xy 37.425907 -21.163488)
			(xy 37.41728 -21.106664) (xy 37.417276 -21.049189) (xy 37.425895 -20.992363) (xy 37.442942 -20.937475)
			(xy 37.468031 -20.885764) (xy 37.500594 -20.838404) (xy 37.519864 -20.817078) (xy 37.526468 -20.81022)
			(xy 37.53358 -20.792186) (xy 37.53358 -20.703286) (xy 37.526468 -20.685252) (xy 37.519864 -20.678394)
			(xy 37.500627 -20.657037) (xy 37.468057 -20.609681) (xy 37.442961 -20.557974) (xy 37.425907 -20.503088)
			(xy 37.41728 -20.446264) (xy 37.417276 -20.388789) (xy 37.425895 -20.331963) (xy 37.442942 -20.277075)
			(xy 37.468031 -20.225364) (xy 37.500594 -20.178004) (xy 37.519864 -20.156678) (xy 37.526468 -20.14982)
			(xy 37.53358 -20.131786) (xy 37.53358 -20.042886) (xy 37.526468 -20.024852) (xy 37.519864 -20.017994)
			(xy 37.500627 -19.996637) (xy 37.468057 -19.949281) (xy 37.442961 -19.897574) (xy 37.425907 -19.842688)
			(xy 37.41728 -19.785864) (xy 37.417276 -19.728389) (xy 37.425895 -19.671563) (xy 37.442942 -19.616675)
			(xy 37.468031 -19.564964) (xy 37.500594 -19.517604) (xy 37.519864 -19.496278) (xy 37.526468 -19.48942)
			(xy 37.53358 -19.471386) (xy 37.53358 -19.382486) (xy 37.526468 -19.364452) (xy 37.519864 -19.357594)
			(xy 37.500615 -19.336248) (xy 37.468044 -19.288892) (xy 37.442947 -19.237185) (xy 37.425892 -19.182298)
			(xy 37.417264 -19.125474) (xy 37.41674 -19.096736) (xy 37.417226 -19.069485) (xy 37.424982 -19.015537)
			(xy 37.440337 -18.963242) (xy 37.462979 -18.913665) (xy 37.492445 -18.867815) (xy 37.528136 -18.826624)
			(xy 37.569327 -18.790933) (xy 37.615177 -18.761467) (xy 37.664754 -18.738825) (xy 37.717049 -18.72347)
			(xy 37.770997 -18.715714) (xy 37.825499 -18.715714) (xy 37.879447 -18.72347) (xy 37.931742 -18.738825)
			(xy 37.981319 -18.761467) (xy 38.027169 -18.790933) (xy 38.06836 -18.826624) (xy 38.104051 -18.867815)
			(xy 38.133517 -18.913665) (xy 38.156159 -18.963242) (xy 38.171514 -19.015537) (xy 38.17927 -19.069485)
			(xy 38.179756 -19.096736) (xy 38.179239 -19.125475) (xy 38.170613 -19.182302) (xy 38.15356 -19.237192)
			(xy 38.128467 -19.288904) (xy 38.095902 -19.336267) (xy 38.076632 -19.357594) (xy 38.070028 -19.364452)
			(xy 38.062916 -19.382486) (xy 38.062916 -19.471386) (xy 38.070028 -19.48942) (xy 38.076632 -19.496278)
			(xy 38.095936 -19.517575) (xy 38.128495 -19.564944) (xy 38.153581 -19.616661) (xy 38.170626 -19.671556)
			(xy 38.179244 -19.728386) (xy 38.17924 -19.785866) (xy 38.170614 -19.842695) (xy 38.153562 -19.897588)
			(xy 38.128469 -19.949301) (xy 38.095903 -19.996666) (xy 38.076632 -20.017994) (xy 38.070028 -20.024852)
			(xy 38.062916 -20.042886) (xy 38.062916 -20.131786) (xy 38.070028 -20.14982) (xy 38.076632 -20.156678)
			(xy 38.095936 -20.177975) (xy 38.128495 -20.225344) (xy 38.153581 -20.277061) (xy 38.170626 -20.331956)
			(xy 38.179244 -20.388786) (xy 38.17924 -20.446266) (xy 38.170614 -20.503095) (xy 38.153562 -20.557988)
			(xy 38.128469 -20.609701) (xy 38.095903 -20.657066) (xy 38.076632 -20.678394) (xy 38.070028 -20.685252)
			(xy 38.062916 -20.703286) (xy 38.062916 -20.792186) (xy 38.070028 -20.81022) (xy 38.076632 -20.817078)
			(xy 38.095936 -20.838375) (xy 38.128495 -20.885744) (xy 38.153581 -20.937461) (xy 38.170626 -20.992356)
			(xy 38.179244 -21.049186) (xy 38.17924 -21.106666) (xy 38.170614 -21.163495) (xy 38.153562 -21.218388)
			(xy 38.128469 -21.270101) (xy 38.095903 -21.317466) (xy 38.076632 -21.338794) (xy 38.070028 -21.345652)
			(xy 38.062916 -21.363686) (xy 38.062916 -21.452586) (xy 38.070028 -21.47062) (xy 38.076632 -21.477478)
			(xy 38.095915 -21.498795) (xy 38.128481 -21.546159) (xy 38.153571 -21.597873) (xy 38.166351 -21.639022)
			(xy 42.07383 -21.639022) (xy 42.074386 -21.610285) (xy 42.083003 -21.553459) (xy 42.100047 -21.49857)
			(xy 42.125131 -21.446858) (xy 42.157688 -21.399493) (xy 42.176954 -21.378164) (xy 42.183558 -21.371306)
			(xy 42.19067 -21.353272) (xy 42.19067 -21.264372) (xy 42.183558 -21.246338) (xy 42.176954 -21.23948)
			(xy 42.157704 -21.218135) (xy 42.125135 -21.170777) (xy 42.10004 -21.119068) (xy 42.082987 -21.06418)
			(xy 42.074362 -21.007354) (xy 42.07436 -20.949878) (xy 42.08298 -20.893052) (xy 42.100029 -20.838162)
			(xy 42.125119 -20.786451) (xy 42.157683 -20.73909) (xy 42.176954 -20.717764) (xy 42.183558 -20.710906)
			(xy 42.19067 -20.692872) (xy 42.19067 -20.603972) (xy 42.183558 -20.585938) (xy 42.176954 -20.57908)
			(xy 42.157704 -20.557735) (xy 42.125135 -20.510377) (xy 42.10004 -20.458668) (xy 42.082987 -20.40378)
			(xy 42.074362 -20.346954) (xy 42.07436 -20.289478) (xy 42.08298 -20.232652) (xy 42.100029 -20.177762)
			(xy 42.125119 -20.126051) (xy 42.157683 -20.07869) (xy 42.176954 -20.057364) (xy 42.183558 -20.050506)
			(xy 42.19067 -20.032472) (xy 42.19067 -19.943572) (xy 42.183558 -19.925538) (xy 42.176954 -19.91868)
			(xy 42.157704 -19.897335) (xy 42.125135 -19.849977) (xy 42.10004 -19.798268) (xy 42.082987 -19.74338)
			(xy 42.074362 -19.686554) (xy 42.07436 -19.629078) (xy 42.08298 -19.572252) (xy 42.100029 -19.517362)
			(xy 42.125119 -19.465651) (xy 42.157683 -19.41829) (xy 42.176954 -19.396964) (xy 42.183558 -19.390106)
			(xy 42.19067 -19.372072) (xy 42.19067 -19.283172) (xy 42.183558 -19.265138) (xy 42.176954 -19.25828)
			(xy 42.157696 -19.236942) (xy 42.125128 -19.189583) (xy 42.100032 -19.137874) (xy 42.082979 -19.082986)
			(xy 42.074353 -19.02616) (xy 42.07383 -18.997422) (xy 42.074316 -18.970171) (xy 42.082072 -18.916223)
			(xy 42.097427 -18.863928) (xy 42.120069 -18.814351) (xy 42.149535 -18.768501) (xy 42.185226 -18.72731)
			(xy 42.226417 -18.691619) (xy 42.272267 -18.662153) (xy 42.321844 -18.639511) (xy 42.374139 -18.624156)
			(xy 42.428087 -18.6164) (xy 42.482589 -18.6164) (xy 42.536537 -18.624156) (xy 42.588832 -18.639511)
			(xy 42.638409 -18.662153) (xy 42.684259 -18.691619) (xy 42.72545 -18.72731) (xy 42.761141 -18.768501)
			(xy 42.790607 -18.814351) (xy 42.813249 -18.863928) (xy 42.828604 -18.916223) (xy 42.83636 -18.970171)
			(xy 42.836846 -18.997422) (xy 42.836323 -19.026161) (xy 42.827699 -19.082988) (xy 42.810648 -19.137878)
			(xy 42.785556 -19.18959) (xy 42.752992 -19.236953) (xy 42.733722 -19.25828) (xy 42.727118 -19.265138)
			(xy 42.720006 -19.283172) (xy 42.720006 -19.366853) (xy 47.579238 -19.366853) (xy 47.579238 -19.312347)
			(xy 47.586995 -19.258395) (xy 47.60235 -19.206097) (xy 47.624992 -19.156515) (xy 47.65446 -19.110661)
			(xy 47.690153 -19.069467) (xy 47.731345 -19.033772) (xy 47.777198 -19.004302) (xy 47.826778 -18.981657)
			(xy 47.879076 -18.966299) (xy 47.933027 -18.958539) (xy 47.96028 -18.958052) (xy 47.98705 -18.958543)
			(xy 48.040064 -18.966037) (xy 48.09151 -18.980869) (xy 48.140377 -19.002746) (xy 48.185707 -19.031238)
			(xy 48.226609 -19.065787) (xy 48.26228 -19.105714) (xy 48.277526 -19.127724) (xy 48.27778 -19.127978)
			(xy 48.284011 -19.136372) (xy 48.30159 -19.147647) (xy 48.311816 -19.149822) (xy 48.384968 -19.16176)
			(xy 48.395417 -19.162905) (xy 48.415749 -19.15766) (xy 48.424338 -19.1516) (xy 48.444454 -19.136476)
			(xy 48.487933 -19.111125) (xy 48.534371 -19.09172) (xy 48.58296 -19.078598) (xy 48.632853 -19.071987)
			(xy 48.658018 -19.07159) (xy 48.658272 -19.07159) (xy 48.685526 -19.072055) (xy 48.73948 -19.079809)
			(xy 48.791781 -19.095163) (xy 48.841364 -19.117803) (xy 48.88722 -19.147271) (xy 48.928416 -19.182964)
			(xy 48.964113 -19.224157) (xy 48.993583 -19.270011) (xy 49.016228 -19.319593) (xy 49.031585 -19.371893)
			(xy 49.039343 -19.425846) (xy 49.039343 -19.480354) (xy 49.031585 -19.534307) (xy 49.016228 -19.586607)
			(xy 48.993583 -19.636189) (xy 48.964113 -19.682043) (xy 48.928416 -19.723236) (xy 48.88722 -19.758929)
			(xy 48.841364 -19.788397) (xy 48.791781 -19.811037) (xy 48.73948 -19.826391) (xy 48.685526 -19.834145)
			(xy 48.658272 -19.834606) (xy 48.6315 -19.834171) (xy 48.578483 -19.826668) (xy 48.527035 -19.811828)
			(xy 48.478167 -19.789943) (xy 48.432838 -19.761442) (xy 48.391937 -19.726884) (xy 48.356269 -19.686948)
			(xy 48.341026 -19.664934) (xy 48.340772 -19.66468) (xy 48.334507 -19.656315) (xy 48.316953 -19.645023)
			(xy 48.306736 -19.642836) (xy 48.233584 -19.630898) (xy 48.223134 -19.629772) (xy 48.202803 -19.635002)
			(xy 48.194214 -19.641058) (xy 48.174077 -19.656153) (xy 48.130604 -19.681509) (xy 48.084172 -19.700921)
			(xy 48.035587 -19.71405) (xy 47.985698 -19.720668) (xy 47.960534 -19.721068) (xy 47.96028 -19.721068)
			(xy 47.933027 -19.720661) (xy 47.879076 -19.712901) (xy 47.826778 -19.697543) (xy 47.777198 -19.674898)
			(xy 47.731345 -19.645428) (xy 47.690153 -19.609733) (xy 47.65446 -19.568539) (xy 47.624992 -19.522685)
			(xy 47.60235 -19.473103) (xy 47.586995 -19.420805) (xy 47.579238 -19.366853) (xy 42.720006 -19.366853)
			(xy 42.720006 -19.372072) (xy 42.727118 -19.390106) (xy 42.733722 -19.396964) (xy 42.753013 -19.418273)
			(xy 42.785573 -19.46564) (xy 42.810661 -19.517355) (xy 42.827707 -19.572248) (xy 42.836326 -19.629077)
			(xy 42.836324 -19.686555) (xy 42.8277 -19.743384) (xy 42.810649 -19.798275) (xy 42.785557 -19.849988)
			(xy 42.752992 -19.897352) (xy 42.733722 -19.91868) (xy 42.727118 -19.925538) (xy 42.720006 -19.943572)
			(xy 42.720006 -20.032472) (xy 42.727118 -20.050506) (xy 42.733722 -20.057364) (xy 42.753013 -20.078673)
			(xy 42.785573 -20.12604) (xy 42.810661 -20.177755) (xy 42.827707 -20.232648) (xy 42.836326 -20.289477)
			(xy 42.836324 -20.346955) (xy 42.835018 -20.35556) (xy 47.578262 -20.35556) (xy 47.582333 -20.299938)
			(xy 47.594459 -20.245501) (xy 47.614382 -20.19341) (xy 47.641678 -20.144775) (xy 47.675764 -20.100632)
			(xy 47.715913 -20.061923) (xy 47.761271 -20.029472) (xy 47.810871 -20.003971) (xy 47.863655 -19.985964)
			(xy 47.918498 -19.975834) (xy 47.974232 -19.973797) (xy 48.029669 -19.979897) (xy 48.083626 -19.994003)
			(xy 48.134955 -20.015815) (xy 48.182561 -20.044869) (xy 48.225429 -20.080544) (xy 48.262646 -20.122081)
			(xy 48.293419 -20.168594) (xy 48.317091 -20.219091) (xy 48.333159 -20.272498) (xy 48.341279 -20.327674)
			(xy 48.341788 -20.35556) (xy 48.341279 -20.383446) (xy 48.333159 -20.438622) (xy 48.317091 -20.492029)
			(xy 48.293419 -20.542526) (xy 48.262646 -20.589039) (xy 48.225429 -20.630576) (xy 48.182561 -20.666251)
			(xy 48.134955 -20.695305) (xy 48.083626 -20.717117) (xy 48.029669 -20.731223) (xy 47.974232 -20.737323)
			(xy 47.918498 -20.735286) (xy 47.863655 -20.725156) (xy 47.810871 -20.707149) (xy 47.761271 -20.681648)
			(xy 47.715913 -20.649197) (xy 47.675764 -20.610488) (xy 47.641678 -20.566345) (xy 47.614382 -20.51771)
			(xy 47.594459 -20.465619) (xy 47.582333 -20.411182) (xy 47.578262 -20.35556) (xy 42.835018 -20.35556)
			(xy 42.8277 -20.403784) (xy 42.810649 -20.458675) (xy 42.785557 -20.510388) (xy 42.752992 -20.557752)
			(xy 42.733722 -20.57908) (xy 42.727118 -20.585938) (xy 42.720006 -20.603972) (xy 42.720006 -20.692872)
			(xy 42.727118 -20.710906) (xy 42.733722 -20.717764) (xy 42.753013 -20.739073) (xy 42.785573 -20.78644)
			(xy 42.810661 -20.838155) (xy 42.827707 -20.893048) (xy 42.836326 -20.949877) (xy 42.836324 -21.007355)
			(xy 42.8277 -21.064184) (xy 42.810649 -21.119075) (xy 42.785557 -21.170788) (xy 42.752992 -21.218152)
			(xy 42.733722 -21.23948) (xy 42.727118 -21.246338) (xy 42.720006 -21.264372) (xy 42.720006 -21.353272)
			(xy 42.727118 -21.371306) (xy 42.727363 -21.37156) (xy 47.578262 -21.37156) (xy 47.582333 -21.315938)
			(xy 47.594459 -21.261501) (xy 47.614382 -21.20941) (xy 47.641678 -21.160775) (xy 47.675764 -21.116632)
			(xy 47.715913 -21.077923) (xy 47.761271 -21.045472) (xy 47.810871 -21.019971) (xy 47.863655 -21.001964)
			(xy 47.918498 -20.991834) (xy 47.974232 -20.989797) (xy 48.029669 -20.995897) (xy 48.083626 -21.010003)
			(xy 48.134955 -21.031815) (xy 48.182561 -21.060869) (xy 48.225429 -21.096544) (xy 48.262646 -21.138081)
			(xy 48.293419 -21.184594) (xy 48.317091 -21.235091) (xy 48.333159 -21.288498) (xy 48.341279 -21.343674)
			(xy 48.341788 -21.37156) (xy 48.341279 -21.399446) (xy 48.333159 -21.454622) (xy 48.317091 -21.508029)
			(xy 48.293419 -21.558526) (xy 48.262646 -21.605039) (xy 48.225429 -21.646576) (xy 48.182561 -21.682251)
			(xy 48.134955 -21.711305) (xy 48.083626 -21.733117) (xy 48.029669 -21.747223) (xy 47.974232 -21.753323)
			(xy 47.918498 -21.751286) (xy 47.863655 -21.741156) (xy 47.810871 -21.723149) (xy 47.761271 -21.697648)
			(xy 47.715913 -21.665197) (xy 47.675764 -21.626488) (xy 47.641678 -21.582345) (xy 47.614382 -21.53371)
			(xy 47.594459 -21.481619) (xy 47.582333 -21.427182) (xy 47.578262 -21.37156) (xy 42.727363 -21.37156)
			(xy 42.733722 -21.378164) (xy 42.752997 -21.399488) (xy 42.785564 -21.44685) (xy 42.810656 -21.498562)
			(xy 42.827706 -21.553454) (xy 42.836327 -21.610283) (xy 42.836846 -21.639022) (xy 42.83636 -21.666273)
			(xy 42.828604 -21.720221) (xy 42.813249 -21.772516) (xy 42.811807 -21.775674) (xy 51.935886 -21.775674)
			(xy 51.939957 -21.720052) (xy 51.952083 -21.665615) (xy 51.972006 -21.613524) (xy 51.999302 -21.564889)
			(xy 52.033388 -21.520746) (xy 52.073537 -21.482037) (xy 52.118895 -21.449586) (xy 52.168495 -21.424085)
			(xy 52.221279 -21.406078) (xy 52.276122 -21.395948) (xy 52.331856 -21.393911) (xy 52.387293 -21.400011)
			(xy 52.44125 -21.414117) (xy 52.492579 -21.435929) (xy 52.540185 -21.464983) (xy 52.583053 -21.500658)
			(xy 52.62027 -21.542195) (xy 52.651043 -21.588708) (xy 52.674715 -21.639205) (xy 52.690783 -21.692612)
			(xy 52.698903 -21.747788) (xy 52.699412 -21.775674) (xy 52.698903 -21.80356) (xy 52.690783 -21.858736)
			(xy 52.674715 -21.912143) (xy 52.651043 -21.96264) (xy 52.62027 -22.009153) (xy 52.583053 -22.05069)
			(xy 52.540185 -22.086365) (xy 52.492579 -22.115419) (xy 52.44125 -22.137231) (xy 52.387293 -22.151337)
			(xy 52.331856 -22.157437) (xy 52.276122 -22.1554) (xy 52.221279 -22.14527) (xy 52.168495 -22.127263)
			(xy 52.118895 -22.101762) (xy 52.073537 -22.069311) (xy 52.033388 -22.030602) (xy 51.999302 -21.986459)
			(xy 51.972006 -21.937824) (xy 51.952083 -21.885733) (xy 51.939957 -21.831296) (xy 51.935886 -21.775674)
			(xy 42.811807 -21.775674) (xy 42.790607 -21.822093) (xy 42.761141 -21.867943) (xy 42.72545 -21.909134)
			(xy 42.684259 -21.944825) (xy 42.638409 -21.974291) (xy 42.588832 -21.996933) (xy 42.536537 -22.012288)
			(xy 42.482589 -22.020044) (xy 42.428087 -22.020044) (xy 42.374139 -22.012288) (xy 42.321844 -21.996933)
			(xy 42.272267 -21.974291) (xy 42.226417 -21.944825) (xy 42.185226 -21.909134) (xy 42.149535 -21.867943)
			(xy 42.120069 -21.822093) (xy 42.097427 -21.772516) (xy 42.082072 -21.720221) (xy 42.074316 -21.666273)
			(xy 42.07383 -21.639022) (xy 38.166351 -21.639022) (xy 38.170619 -21.652766) (xy 38.179238 -21.709596)
			(xy 38.179756 -21.738336) (xy 38.17927 -21.765587) (xy 38.171514 -21.819535) (xy 38.156159 -21.87183)
			(xy 38.133517 -21.921407) (xy 38.104051 -21.967257) (xy 38.06836 -22.008448) (xy 38.027169 -22.044139)
			(xy 37.981319 -22.073605) (xy 37.931742 -22.096247) (xy 37.879447 -22.111602) (xy 37.825499 -22.119358)
			(xy 37.770997 -22.119358) (xy 37.717049 -22.111602) (xy 37.664754 -22.096247) (xy 37.615177 -22.073605)
			(xy 37.569327 -22.044139) (xy 37.528136 -22.008448) (xy 37.492445 -21.967257) (xy 37.462979 -21.921407)
			(xy 37.440337 -21.87183) (xy 37.424982 -21.819535) (xy 37.417226 -21.765587) (xy 37.41674 -21.738336)
			(xy 35.195167 -21.738336) (xy 35.179241 -21.76868) (xy 35.112534 -21.879027) (xy 35.039286 -21.985145)
			(xy 34.959765 -22.086646) (xy 34.87426 -22.183161) (xy 34.783084 -22.274338) (xy 34.686569 -22.359842)
			(xy 34.585068 -22.439364) (xy 34.47895 -22.512612) (xy 34.368604 -22.579319) (xy 34.254431 -22.639241)
			(xy 34.136848 -22.692161) (xy 34.016285 -22.737885) (xy 33.893181 -22.776246) (xy 33.767985 -22.807104)
			(xy 33.641155 -22.830347) (xy 33.513153 -22.845889) (xy 33.384445 -22.853675) (xy 33.319974 -22.854158)
			(xy 33.254508 -22.853663) (xy 33.123823 -22.84564) (xy 32.993875 -22.82962) (xy 32.865154 -22.805663)
			(xy 32.738144 -22.773859) (xy 32.613322 -22.734328) (xy 32.491159 -22.687218) (xy 32.372115 -22.632708)
			(xy 32.256636 -22.571001) (xy 32.145157 -22.50233) (xy 32.038099 -22.426954) (xy 31.935863 -22.345156)
			(xy 31.838835 -22.257244) (xy 31.747379 -22.163548) (xy 31.661839 -22.064422) (xy 31.582538 -21.960237)
			(xy 31.509774 -21.851387) (xy 31.44382 -21.73828) (xy 31.384925 -21.621342) (xy 31.33331 -21.501014)
			(xy 31.28917 -21.377747) (xy 31.25267 -21.252006) (xy 31.223947 -21.124263) (xy 31.203111 -20.995)
			(xy 31.190239 -20.864703) (xy 31.18739 -20.799298) (xy 31.187136 -20.795742) (xy 31.186353 -20.789154)
			(xy 31.181841 -20.776682) (xy 31.178246 -20.771104) (xy 31.165546 -20.758404) (xy 31.155132 -20.752816)
			(xy 31.108904 -20.734528) (xy 31.068518 -20.71878) (xy 31.056983 -20.714999) (xy 31.032859 -20.717382)
			(xy 31.02229 -20.723352) (xy 31.017718 -20.7264) (xy 28.719018 -23.0251) (xy 37.362382 -23.0251)
			(xy 37.366453 -22.969478) (xy 37.378579 -22.915041) (xy 37.398502 -22.86295) (xy 37.425798 -22.814315)
			(xy 37.459884 -22.770172) (xy 37.500033 -22.731463) (xy 37.545391 -22.699012) (xy 37.594991 -22.673511)
			(xy 37.647775 -22.655504) (xy 37.702618 -22.645374) (xy 37.758352 -22.643337) (xy 37.813789 -22.649437)
			(xy 37.867746 -22.663543) (xy 37.919075 -22.685355) (xy 37.966681 -22.714409) (xy 38.009549 -22.750084)
			(xy 38.046766 -22.791621) (xy 38.077539 -22.838134) (xy 38.101211 -22.888631) (xy 38.117279 -22.942038)
			(xy 38.125399 -22.997214) (xy 38.125908 -23.0251) (xy 38.125399 -23.052986) (xy 38.117279 -23.108162)
			(xy 38.101211 -23.161569) (xy 38.077539 -23.212066) (xy 38.046766 -23.258579) (xy 38.009549 -23.300116)
			(xy 37.966681 -23.335791) (xy 37.919075 -23.364845) (xy 37.867746 -23.386657) (xy 37.813789 -23.400763)
			(xy 37.758352 -23.406863) (xy 37.702618 -23.404826) (xy 37.647775 -23.394696) (xy 37.594991 -23.376689)
			(xy 37.545391 -23.351188) (xy 37.500033 -23.318737) (xy 37.459884 -23.280028) (xy 37.425798 -23.235885)
			(xy 37.398502 -23.18725) (xy 37.378579 -23.135159) (xy 37.366453 -23.080722) (xy 37.362382 -23.0251)
			(xy 28.719018 -23.0251) (xy 28.187756 -23.556362) (xy 38.066023 -23.556362) (xy 38.073777 -23.502423)
			(xy 38.089128 -23.450136) (xy 38.111763 -23.400567) (xy 38.141222 -23.354722) (xy 38.176905 -23.313537)
			(xy 38.218087 -23.277849) (xy 38.263927 -23.248384) (xy 38.313495 -23.225743) (xy 38.365779 -23.210387)
			(xy 38.419717 -23.202627) (xy 38.446964 -23.202138) (xy 38.470994 -23.202496) (xy 38.518672 -23.208542)
			(xy 38.565213 -23.22053) (xy 38.58768 -23.229062) (xy 38.600815 -23.233896) (xy 38.628648 -23.236788)
			(xy 38.656223 -23.232026) (xy 38.681474 -23.219967) (xy 38.70251 -23.201513) (xy 38.717756 -23.178048)
			(xy 38.726069 -23.151328) (xy 38.726826 -23.123355) (xy 38.723824 -23.109682) (xy 38.718373 -23.086699)
			(xy 38.712512 -23.039828) (xy 38.71214 -23.01621) (xy 38.712567 -22.988959) (xy 38.720322 -22.93501)
			(xy 38.735676 -22.882715) (xy 38.758315 -22.833137) (xy 38.78778 -22.787285) (xy 38.82347 -22.746093)
			(xy 38.864659 -22.710399) (xy 38.910508 -22.680931) (xy 38.960084 -22.658287) (xy 39.012378 -22.642929)
			(xy 39.066326 -22.635169) (xy 39.120829 -22.635166) (xy 39.174777 -22.642919) (xy 39.227073 -22.658271)
			(xy 39.276652 -22.680909) (xy 39.322505 -22.710372) (xy 39.363698 -22.746061) (xy 39.399393 -22.787248)
			(xy 39.428863 -22.833097) (xy 39.451509 -22.882672) (xy 39.466868 -22.934966) (xy 39.47463 -22.988913)
			(xy 39.474635 -23.043416) (xy 39.466883 -23.097365) (xy 39.451533 -23.149661) (xy 39.428897 -23.199241)
			(xy 39.399435 -23.245095) (xy 39.363748 -23.286289) (xy 39.322562 -23.321985) (xy 39.276714 -23.351457)
			(xy 39.22714 -23.374104) (xy 39.174846 -23.389466) (xy 39.120899 -23.397229) (xy 39.093648 -23.397718)
			(xy 39.069618 -23.397353) (xy 39.021941 -23.391309) (xy 38.9754 -23.379324) (xy 38.952932 -23.370794)
			(xy 38.939778 -23.366025) (xy 38.911956 -23.363134) (xy 38.884392 -23.367893) (xy 38.85915 -23.379944)
			(xy 38.83812 -23.398386) (xy 38.822875 -23.421839) (xy 38.814559 -23.448545) (xy 38.813792 -23.476506)
			(xy 38.816788 -23.490174) (xy 38.822249 -23.513155) (xy 38.828104 -23.560028) (xy 38.828472 -23.583646)
			(xy 38.828356 -23.589996) (xy 42.084496 -23.589996) (xy 42.088567 -23.534374) (xy 42.100693 -23.479937)
			(xy 42.120616 -23.427846) (xy 42.147912 -23.379211) (xy 42.181998 -23.335068) (xy 42.222147 -23.296359)
			(xy 42.267505 -23.263908) (xy 42.317105 -23.238407) (xy 42.369889 -23.2204) (xy 42.424732 -23.21027)
			(xy 42.480466 -23.208233) (xy 42.535903 -23.214333) (xy 42.58986 -23.228439) (xy 42.641189 -23.250251)
			(xy 42.688795 -23.279305) (xy 42.731663 -23.31498) (xy 42.768017 -23.355554) (xy 51.330606 -23.355554)
			(xy 51.331071 -23.328743) (xy 51.338579 -23.275648) (xy 51.353454 -23.22413) (xy 51.375402 -23.175204)
			(xy 51.40399 -23.129838) (xy 51.438654 -23.088926) (xy 51.47871 -23.053276) (xy 51.500786 -23.038054)
			(xy 51.512329 -23.029768) (xy 51.530735 -23.008139) (xy 51.542474 -22.982277) (xy 51.546638 -22.954184)
			(xy 51.542906 -22.926029) (xy 51.531565 -22.899991) (xy 51.513493 -22.878082) (xy 51.502056 -22.869652)
			(xy 51.480604 -22.854293) (xy 51.441692 -22.818666) (xy 51.40806 -22.778018) (xy 51.380349 -22.733124)
			(xy 51.359088 -22.68484) (xy 51.344682 -22.634087) (xy 51.337406 -22.581833) (xy 51.336956 -22.555454)
			(xy 51.337442 -22.528203) (xy 51.345198 -22.474255) (xy 51.360553 -22.42196) (xy 51.383195 -22.372383)
			(xy 51.412661 -22.326533) (xy 51.448352 -22.285342) (xy 51.489543 -22.249651) (xy 51.535393 -22.220185)
			(xy 51.58497 -22.197543) (xy 51.637265 -22.182188) (xy 51.691213 -22.174432) (xy 51.745715 -22.174432)
			(xy 51.799663 -22.182188) (xy 51.851958 -22.197543) (xy 51.901535 -22.220185) (xy 51.947385 -22.249651)
			(xy 51.988576 -22.285342) (xy 52.024267 -22.326533) (xy 52.053733 -22.372383) (xy 52.076375 -22.42196)
			(xy 52.09173 -22.474255) (xy 52.099486 -22.528203) (xy 52.099972 -22.555454) (xy 52.099478 -22.582264)
			(xy 52.091971 -22.635356) (xy 52.077099 -22.686872) (xy 52.055155 -22.735796) (xy 52.026572 -22.781162)
			(xy 51.991914 -22.822076) (xy 51.951865 -22.85773) (xy 51.929792 -22.872954) (xy 51.918243 -22.881231)
			(xy 51.89984 -22.902864) (xy 51.888105 -22.928727) (xy 51.883942 -22.956821) (xy 51.887676 -22.984975)
			(xy 51.899015 -23.011014) (xy 51.917086 -23.032925) (xy 51.928522 -23.041356) (xy 51.949973 -23.056717)
			(xy 51.988886 -23.092342) (xy 52.022518 -23.13299) (xy 52.05023 -23.177884) (xy 52.071491 -23.226168)
			(xy 52.085897 -23.276921) (xy 52.093173 -23.329175) (xy 52.093622 -23.355554) (xy 52.093136 -23.382805)
			(xy 52.08538 -23.436753) (xy 52.070025 -23.489048) (xy 52.047383 -23.538625) (xy 52.017917 -23.584475)
			(xy 51.982226 -23.625666) (xy 51.941035 -23.661357) (xy 51.895185 -23.690823) (xy 51.845608 -23.713465)
			(xy 51.793313 -23.72882) (xy 51.739365 -23.736576) (xy 51.684863 -23.736576) (xy 51.630915 -23.72882)
			(xy 51.57862 -23.713465) (xy 51.529043 -23.690823) (xy 51.483193 -23.661357) (xy 51.442002 -23.625666)
			(xy 51.406311 -23.584475) (xy 51.376845 -23.538625) (xy 51.354203 -23.489048) (xy 51.338848 -23.436753)
			(xy 51.331092 -23.382805) (xy 51.330606 -23.355554) (xy 42.768017 -23.355554) (xy 42.76888 -23.356517)
			(xy 42.799653 -23.40303) (xy 42.823325 -23.453527) (xy 42.839393 -23.506934) (xy 42.847513 -23.56211)
			(xy 42.848022 -23.589996) (xy 42.847513 -23.617882) (xy 42.839393 -23.673058) (xy 42.823325 -23.726465)
			(xy 42.799653 -23.776962) (xy 42.76888 -23.823475) (xy 42.731663 -23.865012) (xy 42.713271 -23.880318)
			(xy 43.240704 -23.880318) (xy 43.244775 -23.824696) (xy 43.256901 -23.770259) (xy 43.276824 -23.718168)
			(xy 43.30412 -23.669533) (xy 43.338206 -23.62539) (xy 43.378355 -23.586681) (xy 43.423713 -23.55423)
			(xy 43.473313 -23.528729) (xy 43.526097 -23.510722) (xy 43.58094 -23.500592) (xy 43.636674 -23.498555)
			(xy 43.692111 -23.504655) (xy 43.746068 -23.518761) (xy 43.797397 -23.540573) (xy 43.845003 -23.569627)
			(xy 43.887871 -23.605302) (xy 43.925088 -23.646839) (xy 43.955861 -23.693352) (xy 43.979533 -23.743849)
			(xy 43.995601 -23.797256) (xy 44.003721 -23.852432) (xy 44.00423 -23.880318) (xy 44.256704 -23.880318)
			(xy 44.260775 -23.824696) (xy 44.272901 -23.770259) (xy 44.292824 -23.718168) (xy 44.32012 -23.669533)
			(xy 44.354206 -23.62539) (xy 44.394355 -23.586681) (xy 44.439713 -23.55423) (xy 44.489313 -23.528729)
			(xy 44.542097 -23.510722) (xy 44.59694 -23.500592) (xy 44.652674 -23.498555) (xy 44.708111 -23.504655)
			(xy 44.762068 -23.518761) (xy 44.813397 -23.540573) (xy 44.861003 -23.569627) (xy 44.903871 -23.605302)
			(xy 44.941088 -23.646839) (xy 44.971861 -23.693352) (xy 44.995533 -23.743849) (xy 45.011601 -23.797256)
			(xy 45.019721 -23.852432) (xy 45.02023 -23.880318) (xy 45.272704 -23.880318) (xy 45.276775 -23.824696)
			(xy 45.288901 -23.770259) (xy 45.308824 -23.718168) (xy 45.33612 -23.669533) (xy 45.370206 -23.62539)
			(xy 45.410355 -23.586681) (xy 45.455713 -23.55423) (xy 45.505313 -23.528729) (xy 45.558097 -23.510722)
			(xy 45.61294 -23.500592) (xy 45.668674 -23.498555) (xy 45.724111 -23.504655) (xy 45.778068 -23.518761)
			(xy 45.829397 -23.540573) (xy 45.877003 -23.569627) (xy 45.919871 -23.605302) (xy 45.957088 -23.646839)
			(xy 45.987861 -23.693352) (xy 46.011533 -23.743849) (xy 46.027601 -23.797256) (xy 46.035721 -23.852432)
			(xy 46.03623 -23.880318) (xy 46.29099 -23.880318) (xy 46.295061 -23.824696) (xy 46.307187 -23.770259)
			(xy 46.32711 -23.718168) (xy 46.354406 -23.669533) (xy 46.388492 -23.62539) (xy 46.428641 -23.586681)
			(xy 46.473999 -23.55423) (xy 46.523599 -23.528729) (xy 46.576383 -23.510722) (xy 46.631226 -23.500592)
			(xy 46.68696 -23.498555) (xy 46.742397 -23.504655) (xy 46.796354 -23.518761) (xy 46.847683 -23.540573)
			(xy 46.895289 -23.569627) (xy 46.938157 -23.605302) (xy 46.975374 -23.646839) (xy 47.006147 -23.693352)
			(xy 47.029819 -23.743849) (xy 47.045887 -23.797256) (xy 47.054007 -23.852432) (xy 47.054516 -23.880318)
			(xy 47.054007 -23.908204) (xy 47.045887 -23.96338) (xy 47.029819 -24.016787) (xy 47.006147 -24.067284)
			(xy 46.975374 -24.113797) (xy 46.938157 -24.155334) (xy 46.895289 -24.191009) (xy 46.847683 -24.220063)
			(xy 46.796354 -24.241875) (xy 46.742397 -24.255981) (xy 46.68696 -24.262081) (xy 46.631226 -24.260044)
			(xy 46.576383 -24.249914) (xy 46.523599 -24.231907) (xy 46.473999 -24.206406) (xy 46.428641 -24.173955)
			(xy 46.388492 -24.135246) (xy 46.354406 -24.091103) (xy 46.32711 -24.042468) (xy 46.307187 -23.990377)
			(xy 46.295061 -23.93594) (xy 46.29099 -23.880318) (xy 46.03623 -23.880318) (xy 46.035721 -23.908204)
			(xy 46.027601 -23.96338) (xy 46.011533 -24.016787) (xy 45.987861 -24.067284) (xy 45.957088 -24.113797)
			(xy 45.919871 -24.155334) (xy 45.877003 -24.191009) (xy 45.829397 -24.220063) (xy 45.778068 -24.241875)
			(xy 45.724111 -24.255981) (xy 45.668674 -24.262081) (xy 45.61294 -24.260044) (xy 45.558097 -24.249914)
			(xy 45.505313 -24.231907) (xy 45.455713 -24.206406) (xy 45.410355 -24.173955) (xy 45.370206 -24.135246)
			(xy 45.33612 -24.091103) (xy 45.308824 -24.042468) (xy 45.288901 -23.990377) (xy 45.276775 -23.93594)
			(xy 45.272704 -23.880318) (xy 45.02023 -23.880318) (xy 45.019721 -23.908204) (xy 45.011601 -23.96338)
			(xy 44.995533 -24.016787) (xy 44.971861 -24.067284) (xy 44.941088 -24.113797) (xy 44.903871 -24.155334)
			(xy 44.861003 -24.191009) (xy 44.813397 -24.220063) (xy 44.762068 -24.241875) (xy 44.708111 -24.255981)
			(xy 44.652674 -24.262081) (xy 44.59694 -24.260044) (xy 44.542097 -24.249914) (xy 44.489313 -24.231907)
			(xy 44.439713 -24.206406) (xy 44.394355 -24.173955) (xy 44.354206 -24.135246) (xy 44.32012 -24.091103)
			(xy 44.292824 -24.042468) (xy 44.272901 -23.990377) (xy 44.260775 -23.93594) (xy 44.256704 -23.880318)
			(xy 44.00423 -23.880318) (xy 44.003721 -23.908204) (xy 43.995601 -23.96338) (xy 43.979533 -24.016787)
			(xy 43.955861 -24.067284) (xy 43.925088 -24.113797) (xy 43.887871 -24.155334) (xy 43.845003 -24.191009)
			(xy 43.797397 -24.220063) (xy 43.746068 -24.241875) (xy 43.692111 -24.255981) (xy 43.636674 -24.262081)
			(xy 43.58094 -24.260044) (xy 43.526097 -24.249914) (xy 43.473313 -24.231907) (xy 43.423713 -24.206406)
			(xy 43.378355 -24.173955) (xy 43.338206 -24.135246) (xy 43.30412 -24.091103) (xy 43.276824 -24.042468)
			(xy 43.256901 -23.990377) (xy 43.244775 -23.93594) (xy 43.240704 -23.880318) (xy 42.713271 -23.880318)
			(xy 42.688795 -23.900687) (xy 42.641189 -23.929741) (xy 42.58986 -23.951553) (xy 42.535903 -23.965659)
			(xy 42.480466 -23.971759) (xy 42.424732 -23.969722) (xy 42.369889 -23.959592) (xy 42.317105 -23.941585)
			(xy 42.267505 -23.916084) (xy 42.222147 -23.883633) (xy 42.181998 -23.844924) (xy 42.147912 -23.800781)
			(xy 42.120616 -23.752146) (xy 42.100693 -23.700055) (xy 42.088567 -23.645618) (xy 42.084496 -23.589996)
			(xy 38.828356 -23.589996) (xy 38.827973 -23.610893) (xy 38.820211 -23.66483) (xy 38.804853 -23.717115)
			(xy 38.782211 -23.766681) (xy 38.752745 -23.812521) (xy 38.717056 -23.853702) (xy 38.67587 -23.889384)
			(xy 38.630025 -23.918842) (xy 38.580454 -23.941476) (xy 38.528167 -23.956825) (xy 38.474228 -23.964577)
			(xy 38.419735 -23.964575) (xy 38.365796 -23.956817) (xy 38.313511 -23.941463) (xy 38.263943 -23.918824)
			(xy 38.2181 -23.889361) (xy 38.176918 -23.853675) (xy 38.141233 -23.812491) (xy 38.111771 -23.766649)
			(xy 38.089134 -23.71708) (xy 38.073781 -23.664794) (xy 38.066025 -23.610855) (xy 38.066023 -23.556362)
			(xy 28.187756 -23.556362) (xy 27.585924 -24.158194) (xy 33.450782 -24.158194) (xy 33.454853 -24.102572)
			(xy 33.466979 -24.048135) (xy 33.486902 -23.996044) (xy 33.514198 -23.947409) (xy 33.548284 -23.903266)
			(xy 33.588433 -23.864557) (xy 33.633791 -23.832106) (xy 33.683391 -23.806605) (xy 33.736175 -23.788598)
			(xy 33.791018 -23.778468) (xy 33.846752 -23.776431) (xy 33.902189 -23.782531) (xy 33.956146 -23.796637)
			(xy 34.007475 -23.818449) (xy 34.055081 -23.847503) (xy 34.097949 -23.883178) (xy 34.135166 -23.924715)
			(xy 34.165939 -23.971228) (xy 34.189611 -24.021725) (xy 34.205679 -24.075132) (xy 34.213799 -24.130308)
			(xy 34.214308 -24.158194) (xy 34.213799 -24.18608) (xy 34.21323 -24.189944) (xy 37.298882 -24.189944)
			(xy 37.302953 -24.134322) (xy 37.315079 -24.079885) (xy 37.335002 -24.027794) (xy 37.362298 -23.979159)
			(xy 37.396384 -23.935016) (xy 37.436533 -23.896307) (xy 37.481891 -23.863856) (xy 37.531491 -23.838355)
			(xy 37.584275 -23.820348) (xy 37.639118 -23.810218) (xy 37.694852 -23.808181) (xy 37.750289 -23.814281)
			(xy 37.804246 -23.828387) (xy 37.855575 -23.850199) (xy 37.903181 -23.879253) (xy 37.946049 -23.914928)
			(xy 37.983266 -23.956465) (xy 38.014039 -24.002978) (xy 38.037711 -24.053475) (xy 38.053779 -24.106882)
			(xy 38.061899 -24.162058) (xy 38.062408 -24.189944) (xy 39.821864 -24.189944) (xy 39.825935 -24.134322)
			(xy 39.838061 -24.079885) (xy 39.857984 -24.027794) (xy 39.88528 -23.979159) (xy 39.919366 -23.935016)
			(xy 39.959515 -23.896307) (xy 40.004873 -23.863856) (xy 40.054473 -23.838355) (xy 40.107257 -23.820348)
			(xy 40.1621 -23.810218) (xy 40.217834 -23.808181) (xy 40.273271 -23.814281) (xy 40.327228 -23.828387)
			(xy 40.378557 -23.850199) (xy 40.426163 -23.879253) (xy 40.469031 -23.914928) (xy 40.506248 -23.956465)
			(xy 40.537021 -24.002978) (xy 40.560693 -24.053475) (xy 40.576761 -24.106882) (xy 40.584881 -24.162058)
			(xy 40.58539 -24.189944) (xy 40.584881 -24.21783) (xy 40.576761 -24.273006) (xy 40.560693 -24.326413)
			(xy 40.537021 -24.37691) (xy 40.506248 -24.423423) (xy 40.469031 -24.46496) (xy 40.426163 -24.500635)
			(xy 40.378557 -24.529689) (xy 40.327228 -24.551501) (xy 40.273271 -24.565607) (xy 40.217834 -24.571707)
			(xy 40.1621 -24.56967) (xy 40.107257 -24.55954) (xy 40.054473 -24.541533) (xy 40.004873 -24.516032)
			(xy 39.959515 -24.483581) (xy 39.919366 -24.444872) (xy 39.88528 -24.400729) (xy 39.857984 -24.352094)
			(xy 39.838061 -24.300003) (xy 39.825935 -24.245566) (xy 39.821864 -24.189944) (xy 38.062408 -24.189944)
			(xy 38.061899 -24.21783) (xy 38.053779 -24.273006) (xy 38.037711 -24.326413) (xy 38.014039 -24.37691)
			(xy 37.983266 -24.423423) (xy 37.946049 -24.46496) (xy 37.903181 -24.500635) (xy 37.855575 -24.529689)
			(xy 37.804246 -24.551501) (xy 37.750289 -24.565607) (xy 37.694852 -24.571707) (xy 37.639118 -24.56967)
			(xy 37.584275 -24.55954) (xy 37.531491 -24.541533) (xy 37.481891 -24.516032) (xy 37.436533 -24.483581)
			(xy 37.396384 -24.444872) (xy 37.362298 -24.400729) (xy 37.335002 -24.352094) (xy 37.315079 -24.300003)
			(xy 37.302953 -24.245566) (xy 37.298882 -24.189944) (xy 34.21323 -24.189944) (xy 34.205679 -24.241256)
			(xy 34.189611 -24.294663) (xy 34.165939 -24.34516) (xy 34.135166 -24.391673) (xy 34.097949 -24.43321)
			(xy 34.055081 -24.468885) (xy 34.007475 -24.497939) (xy 33.956146 -24.519751) (xy 33.902189 -24.533857)
			(xy 33.846752 -24.539957) (xy 33.791018 -24.53792) (xy 33.736175 -24.52779) (xy 33.683391 -24.509783)
			(xy 33.633791 -24.484282) (xy 33.588433 -24.451831) (xy 33.548284 -24.413122) (xy 33.514198 -24.368979)
			(xy 33.486902 -24.320344) (xy 33.466979 -24.268253) (xy 33.454853 -24.213816) (xy 33.450782 -24.158194)
			(xy 27.585924 -24.158194) (xy 27.42057 -24.323548) (xy 27.417052 -24.32728) (xy 27.411429 -24.335857)
			(xy 27.409394 -24.340566) (xy 27.405838 -24.349202) (xy 27.405838 -24.807418) (xy 34.620198 -24.807418)
			(xy 34.624269 -24.751796) (xy 34.636395 -24.697359) (xy 34.656318 -24.645268) (xy 34.683614 -24.596633)
			(xy 34.7177 -24.55249) (xy 34.757849 -24.513781) (xy 34.803207 -24.48133) (xy 34.852807 -24.455829)
			(xy 34.905591 -24.437822) (xy 34.960434 -24.427692) (xy 35.016168 -24.425655) (xy 35.071605 -24.431755)
			(xy 35.125562 -24.445861) (xy 35.176891 -24.467673) (xy 35.224497 -24.496727) (xy 35.267365 -24.532402)
			(xy 35.304582 -24.573939) (xy 35.335355 -24.620452) (xy 35.359027 -24.670949) (xy 35.375095 -24.724356)
			(xy 35.380142 -24.75865) (xy 46.868586 -24.75865) (xy 46.872657 -24.703028) (xy 46.884783 -24.648591)
			(xy 46.904706 -24.5965) (xy 46.932002 -24.547865) (xy 46.966088 -24.503722) (xy 47.006237 -24.465013)
			(xy 47.051595 -24.432562) (xy 47.101195 -24.407061) (xy 47.153979 -24.389054) (xy 47.208822 -24.378924)
			(xy 47.264556 -24.376887) (xy 47.319993 -24.382987) (xy 47.37395 -24.397093) (xy 47.425279 -24.418905)
			(xy 47.472885 -24.447959) (xy 47.515753 -24.483634) (xy 47.55297 -24.525171) (xy 47.583743 -24.571684)
			(xy 47.607415 -24.622181) (xy 47.623483 -24.675588) (xy 47.631603 -24.730764) (xy 47.632112 -24.75865)
			(xy 47.631603 -24.786536) (xy 47.623483 -24.841712) (xy 47.607415 -24.895119) (xy 47.583743 -24.945616)
			(xy 47.55297 -24.992129) (xy 47.515753 -25.033666) (xy 47.472885 -25.069341) (xy 47.425279 -25.098395)
			(xy 47.37395 -25.120207) (xy 47.319993 -25.134313) (xy 47.264556 -25.140413) (xy 47.208822 -25.138376)
			(xy 47.153979 -25.128246) (xy 47.101195 -25.110239) (xy 47.051595 -25.084738) (xy 47.006237 -25.052287)
			(xy 46.966088 -25.013578) (xy 46.932002 -24.969435) (xy 46.904706 -24.9208) (xy 46.884783 -24.868709)
			(xy 46.872657 -24.814272) (xy 46.868586 -24.75865) (xy 35.380142 -24.75865) (xy 35.383215 -24.779532)
			(xy 35.383724 -24.807418) (xy 35.383215 -24.835304) (xy 35.375095 -24.89048) (xy 35.359027 -24.943887)
			(xy 35.335355 -24.994384) (xy 35.304582 -25.040897) (xy 35.267365 -25.082434) (xy 35.224497 -25.118109)
			(xy 35.176891 -25.147163) (xy 35.125562 -25.168975) (xy 35.071605 -25.183081) (xy 35.016168 -25.189181)
			(xy 34.960434 -25.187144) (xy 34.905591 -25.177014) (xy 34.852807 -25.159007) (xy 34.803207 -25.133506)
			(xy 34.757849 -25.101055) (xy 34.7177 -25.062346) (xy 34.683614 -25.018203) (xy 34.656318 -24.969568)
			(xy 34.636395 -24.917477) (xy 34.624269 -24.86304) (xy 34.620198 -24.807418) (xy 27.405838 -24.807418)
			(xy 27.405838 -25.390094) (xy 39.809674 -25.390094) (xy 39.81016 -25.362843) (xy 39.817916 -25.308895)
			(xy 39.833271 -25.2566) (xy 39.855913 -25.207023) (xy 39.885379 -25.161173) (xy 39.92107 -25.119982)
			(xy 39.962261 -25.084291) (xy 40.008111 -25.054825) (xy 40.057688 -25.032183) (xy 40.109983 -25.016828)
			(xy 40.163931 -25.009072) (xy 40.218433 -25.009072) (xy 40.272381 -25.016828) (xy 40.324676 -25.032183)
			(xy 40.374253 -25.054825) (xy 40.420103 -25.084291) (xy 40.461294 -25.119982) (xy 40.496985 -25.161173)
			(xy 40.526451 -25.207023) (xy 40.549093 -25.2566) (xy 40.564448 -25.308895) (xy 40.572204 -25.362843)
			(xy 40.57269 -25.390094) (xy 40.572104 -25.419113) (xy 40.563314 -25.476482) (xy 40.545938 -25.531858)
			(xy 40.520376 -25.583963) (xy 40.487217 -25.631596) (xy 40.447226 -25.673658) (xy 40.424608 -25.691846)
			(xy 40.414062 -25.700615) (xy 40.397618 -25.722549) (xy 40.387612 -25.748071) (xy 40.384764 -25.775336)
			(xy 40.389282 -25.802374) (xy 40.400839 -25.827233) (xy 40.418599 -25.848115) (xy 40.429688 -25.856184)
			(xy 40.451324 -25.87151) (xy 40.490581 -25.907146) (xy 40.524525 -25.947876) (xy 40.5525 -25.992915)
			(xy 40.573967 -26.041394) (xy 40.588512 -26.09238) (xy 40.595856 -26.144888) (xy 40.596312 -26.171398)
			(xy 40.595826 -26.198649) (xy 40.58807 -26.252597) (xy 40.572715 -26.304892) (xy 40.550073 -26.354469)
			(xy 40.520607 -26.400319) (xy 40.484916 -26.44151) (xy 40.443725 -26.477201) (xy 40.397875 -26.506667)
			(xy 40.348298 -26.529309) (xy 40.296003 -26.544664) (xy 40.242055 -26.55242) (xy 40.187553 -26.55242)
			(xy 40.133605 -26.544664) (xy 40.08131 -26.529309) (xy 40.031733 -26.506667) (xy 39.985883 -26.477201)
			(xy 39.944692 -26.44151) (xy 39.909001 -26.400319) (xy 39.879535 -26.354469) (xy 39.856893 -26.304892)
			(xy 39.841538 -26.252597) (xy 39.833782 -26.198649) (xy 39.833296 -26.171398) (xy 39.833844 -26.142377)
			(xy 39.842636 -26.085005) (xy 39.860018 -26.029627) (xy 39.885587 -25.977521) (xy 39.918755 -25.929889)
			(xy 39.958755 -25.887832) (xy 39.981378 -25.869646) (xy 39.991934 -25.860888) (xy 40.00838 -25.838952)
			(xy 40.018388 -25.813427) (xy 40.021234 -25.786159) (xy 40.016714 -25.759118) (xy 40.005154 -25.734258)
			(xy 39.987389 -25.713377) (xy 39.976298 -25.705308) (xy 39.954655 -25.689991) (xy 39.915398 -25.654353)
			(xy 39.881456 -25.613621) (xy 39.853482 -25.568581) (xy 39.832016 -25.5201) (xy 39.817472 -25.469114)
			(xy 39.810129 -25.416604) (xy 39.809674 -25.390094) (xy 27.405838 -25.390094) (xy 27.405838 -25.971246)
			(xy 27.95981 -25.971246) (xy 27.963881 -25.915624) (xy 27.976007 -25.861187) (xy 27.99593 -25.809096)
			(xy 28.023226 -25.760461) (xy 28.057312 -25.716318) (xy 28.097461 -25.677609) (xy 28.142819 -25.645158)
			(xy 28.192419 -25.619657) (xy 28.245203 -25.60165) (xy 28.300046 -25.59152) (xy 28.35578 -25.589483)
			(xy 28.411217 -25.595583) (xy 28.465174 -25.609689) (xy 28.516503 -25.631501) (xy 28.564109 -25.660555)
			(xy 28.606977 -25.69623) (xy 28.644194 -25.737767) (xy 28.674967 -25.78428) (xy 28.698639 -25.834777)
			(xy 28.714707 -25.888184) (xy 28.722827 -25.94336) (xy 28.723336 -25.971246) (xy 28.97581 -25.971246)
			(xy 28.979881 -25.915624) (xy 28.992007 -25.861187) (xy 29.01193 -25.809096) (xy 29.039226 -25.760461)
			(xy 29.073312 -25.716318) (xy 29.113461 -25.677609) (xy 29.158819 -25.645158) (xy 29.208419 -25.619657)
			(xy 29.261203 -25.60165) (xy 29.316046 -25.59152) (xy 29.37178 -25.589483) (xy 29.427217 -25.595583)
			(xy 29.481174 -25.609689) (xy 29.532503 -25.631501) (xy 29.580109 -25.660555) (xy 29.622977 -25.69623)
			(xy 29.660194 -25.737767) (xy 29.690967 -25.78428) (xy 29.714639 -25.834777) (xy 29.730707 -25.888184)
			(xy 29.738827 -25.94336) (xy 29.739336 -25.971246) (xy 29.99181 -25.971246) (xy 29.995881 -25.915624)
			(xy 30.008007 -25.861187) (xy 30.02793 -25.809096) (xy 30.055226 -25.760461) (xy 30.089312 -25.716318)
			(xy 30.129461 -25.677609) (xy 30.174819 -25.645158) (xy 30.224419 -25.619657) (xy 30.277203 -25.60165)
			(xy 30.332046 -25.59152) (xy 30.38778 -25.589483) (xy 30.443217 -25.595583) (xy 30.497174 -25.609689)
			(xy 30.548503 -25.631501) (xy 30.596109 -25.660555) (xy 30.638977 -25.69623) (xy 30.676194 -25.737767)
			(xy 30.706967 -25.78428) (xy 30.730639 -25.834777) (xy 30.746707 -25.888184) (xy 30.754827 -25.94336)
			(xy 30.755336 -25.971246) (xy 30.754827 -25.999132) (xy 30.749735 -26.03373) (xy 31.267906 -26.03373)
			(xy 31.271977 -25.978108) (xy 31.284103 -25.923671) (xy 31.304026 -25.87158) (xy 31.331322 -25.822945)
			(xy 31.365408 -25.778802) (xy 31.405557 -25.740093) (xy 31.450915 -25.707642) (xy 31.500515 -25.682141)
			(xy 31.553299 -25.664134) (xy 31.608142 -25.654004) (xy 31.663876 -25.651967) (xy 31.719313 -25.658067)
			(xy 31.77327 -25.672173) (xy 31.824599 -25.693985) (xy 31.872205 -25.723039) (xy 31.915073 -25.758714)
			(xy 31.95229 -25.800251) (xy 31.983063 -25.846764) (xy 32.006735 -25.897261) (xy 32.022803 -25.950668)
			(xy 32.030923 -26.005844) (xy 32.031432 -26.03373) (xy 32.030923 -26.061616) (xy 32.022803 -26.116792)
			(xy 32.006735 -26.170199) (xy 31.983063 -26.220696) (xy 31.952829 -26.266394) (xy 34.520632 -26.266394)
			(xy 34.52105 -26.239139) (xy 34.528809 -26.185185) (xy 34.544168 -26.132883) (xy 34.566814 -26.083301)
			(xy 34.596286 -26.037446) (xy 34.631985 -25.996252) (xy 34.673182 -25.960558) (xy 34.719041 -25.931092)
			(xy 34.768627 -25.908451) (xy 34.82093 -25.893099) (xy 34.874885 -25.885347) (xy 34.90214 -25.884886)
			(xy 34.931464 -25.885444) (xy 34.989421 -25.894418) (xy 35.04532 -25.912162) (xy 35.097841 -25.938259)
			(xy 35.122104 -25.954736) (xy 35.132604 -25.961211) (xy 35.157028 -25.964391) (xy 35.16884 -25.960832)
			(xy 35.247326 -25.931622) (xy 35.258748 -25.926776) (xy 35.275392 -25.908416) (xy 35.279076 -25.89657)
			(xy 35.286475 -25.869501) (xy 35.30803 -25.817692) (xy 35.336944 -25.769601) (xy 35.372594 -25.726266)
			(xy 35.414208 -25.688623) (xy 35.46089 -25.657484) (xy 35.511631 -25.633522) (xy 35.565335 -25.617254)
			(xy 35.620843 -25.609032) (xy 35.6489 -25.608534) (xy 35.676154 -25.608936) (xy 35.730108 -25.616693)
			(xy 35.782408 -25.63205) (xy 35.831991 -25.654694) (xy 35.877847 -25.684163) (xy 35.919041 -25.719859)
			(xy 35.954737 -25.761053) (xy 35.984206 -25.806909) (xy 36.00685 -25.856492) (xy 36.022207 -25.908792)
			(xy 36.029964 -25.962746) (xy 36.029964 -25.990042) (xy 37.298882 -25.990042) (xy 37.302953 -25.93442)
			(xy 37.315079 -25.879983) (xy 37.335002 -25.827892) (xy 37.362298 -25.779257) (xy 37.396384 -25.735114)
			(xy 37.436533 -25.696405) (xy 37.481891 -25.663954) (xy 37.531491 -25.638453) (xy 37.584275 -25.620446)
			(xy 37.639118 -25.610316) (xy 37.694852 -25.608279) (xy 37.750289 -25.614379) (xy 37.804246 -25.628485)
			(xy 37.855575 -25.650297) (xy 37.903181 -25.679351) (xy 37.946049 -25.715026) (xy 37.983266 -25.756563)
			(xy 38.014039 -25.803076) (xy 38.037711 -25.853573) (xy 38.053779 -25.90698) (xy 38.061899 -25.962156)
			(xy 38.062408 -25.990042) (xy 38.061899 -26.017928) (xy 38.053779 -26.073104) (xy 38.037711 -26.126511)
			(xy 38.014039 -26.177008) (xy 37.983266 -26.223521) (xy 37.946049 -26.265058) (xy 37.903181 -26.300733)
			(xy 37.855575 -26.329787) (xy 37.804246 -26.351599) (xy 37.750289 -26.365705) (xy 37.694852 -26.371805)
			(xy 37.639118 -26.369768) (xy 37.584275 -26.359638) (xy 37.531491 -26.341631) (xy 37.481891 -26.31613)
			(xy 37.436533 -26.283679) (xy 37.396384 -26.24497) (xy 37.362298 -26.200827) (xy 37.335002 -26.152192)
			(xy 37.315079 -26.100101) (xy 37.302953 -26.045664) (xy 37.298882 -25.990042) (xy 36.029964 -25.990042)
			(xy 36.029964 -26.017254) (xy 36.022207 -26.071208) (xy 36.00685 -26.123508) (xy 35.984206 -26.173091)
			(xy 35.954737 -26.218947) (xy 35.919041 -26.260141) (xy 35.877847 -26.295837) (xy 35.831991 -26.325306)
			(xy 35.782408 -26.34795) (xy 35.730108 -26.363307) (xy 35.676154 -26.371064) (xy 35.6489 -26.37155)
			(xy 35.619575 -26.371015) (xy 35.561618 -26.362033) (xy 35.505719 -26.344282) (xy 35.453198 -26.318179)
			(xy 35.428936 -26.3017) (xy 35.418422 -26.295251) (xy 35.39401 -26.292054) (xy 35.3822 -26.295604)
			(xy 35.303714 -26.324814) (xy 35.29227 -26.329619) (xy 35.275638 -26.348009) (xy 35.271964 -26.359866)
			(xy 35.265178 -26.384897) (xy 35.245763 -26.432988) (xy 35.220007 -26.478002) (xy 35.188386 -26.519109)
			(xy 35.151483 -26.555549) (xy 35.130994 -26.571448) (xy 35.121326 -26.579428) (xy 35.110676 -26.602091)
			(xy 35.110674 -26.614628) (xy 35.115246 -26.698956) (xy 35.116483 -26.711393) (xy 35.129286 -26.73283)
			(xy 35.13963 -26.73985) (xy 35.163373 -26.754744) (xy 35.206607 -26.790413) (xy 35.244157 -26.832023)
			(xy 35.275216 -26.878679) (xy 35.299114 -26.929376) (xy 35.315339 -26.983025) (xy 35.323539 -27.03847)
			(xy 35.324034 -27.066494) (xy 35.323548 -27.093745) (xy 35.315792 -27.147693) (xy 35.300437 -27.199988)
			(xy 35.277795 -27.249565) (xy 35.248329 -27.295415) (xy 35.212638 -27.336606) (xy 35.171447 -27.372297)
			(xy 35.125597 -27.401763) (xy 35.07602 -27.424405) (xy 35.023725 -27.43976) (xy 34.969777 -27.447516)
			(xy 34.915275 -27.447516) (xy 34.861327 -27.43976) (xy 34.809032 -27.424405) (xy 34.759455 -27.401763)
			(xy 34.713605 -27.372297) (xy 34.672414 -27.336606) (xy 34.636723 -27.295415) (xy 34.607257 -27.249565)
			(xy 34.584615 -27.199988) (xy 34.56926 -27.147693) (xy 34.561504 -27.093745) (xy 34.561018 -27.066494)
			(xy 34.561554 -27.037005) (xy 34.570651 -26.978734) (xy 34.588612 -26.922558) (xy 34.615008 -26.869818)
			(xy 34.64921 -26.82177) (xy 34.690402 -26.779562) (xy 34.713672 -26.76144) (xy 34.72334 -26.75346)
			(xy 34.733992 -26.730798) (xy 34.733992 -26.71826) (xy 34.72942 -26.633932) (xy 34.728162 -26.6215)
			(xy 34.715371 -26.600064) (xy 34.705036 -26.593038) (xy 34.681302 -26.578128) (xy 34.638065 -26.542465)
			(xy 34.600512 -26.500859) (xy 34.569451 -26.454206) (xy 34.545551 -26.40351) (xy 34.529326 -26.349862)
			(xy 34.521126 -26.294418) (xy 34.520632 -26.266394) (xy 31.952829 -26.266394) (xy 31.95229 -26.267209)
			(xy 31.915073 -26.308746) (xy 31.872205 -26.344421) (xy 31.824599 -26.373475) (xy 31.77327 -26.395287)
			(xy 31.719313 -26.409393) (xy 31.663876 -26.415493) (xy 31.608142 -26.413456) (xy 31.553299 -26.403326)
			(xy 31.500515 -26.385319) (xy 31.450915 -26.359818) (xy 31.405557 -26.327367) (xy 31.365408 -26.288658)
			(xy 31.331322 -26.244515) (xy 31.304026 -26.19588) (xy 31.284103 -26.143789) (xy 31.271977 -26.089352)
			(xy 31.267906 -26.03373) (xy 30.749735 -26.03373) (xy 30.746707 -26.054308) (xy 30.730639 -26.107715)
			(xy 30.706967 -26.158212) (xy 30.676194 -26.204725) (xy 30.638977 -26.246262) (xy 30.596109 -26.281937)
			(xy 30.548503 -26.310991) (xy 30.497174 -26.332803) (xy 30.443217 -26.346909) (xy 30.38778 -26.353009)
			(xy 30.332046 -26.350972) (xy 30.277203 -26.340842) (xy 30.224419 -26.322835) (xy 30.174819 -26.297334)
			(xy 30.129461 -26.264883) (xy 30.089312 -26.226174) (xy 30.055226 -26.182031) (xy 30.02793 -26.133396)
			(xy 30.008007 -26.081305) (xy 29.995881 -26.026868) (xy 29.99181 -25.971246) (xy 29.739336 -25.971246)
			(xy 29.738827 -25.999132) (xy 29.730707 -26.054308) (xy 29.714639 -26.107715) (xy 29.690967 -26.158212)
			(xy 29.660194 -26.204725) (xy 29.622977 -26.246262) (xy 29.580109 -26.281937) (xy 29.532503 -26.310991)
			(xy 29.481174 -26.332803) (xy 29.427217 -26.346909) (xy 29.37178 -26.353009) (xy 29.316046 -26.350972)
			(xy 29.261203 -26.340842) (xy 29.208419 -26.322835) (xy 29.158819 -26.297334) (xy 29.113461 -26.264883)
			(xy 29.073312 -26.226174) (xy 29.039226 -26.182031) (xy 29.01193 -26.133396) (xy 28.992007 -26.081305)
			(xy 28.979881 -26.026868) (xy 28.97581 -25.971246) (xy 28.723336 -25.971246) (xy 28.722827 -25.999132)
			(xy 28.714707 -26.054308) (xy 28.698639 -26.107715) (xy 28.674967 -26.158212) (xy 28.644194 -26.204725)
			(xy 28.606977 -26.246262) (xy 28.564109 -26.281937) (xy 28.516503 -26.310991) (xy 28.465174 -26.332803)
			(xy 28.411217 -26.346909) (xy 28.35578 -26.353009) (xy 28.300046 -26.350972) (xy 28.245203 -26.340842)
			(xy 28.192419 -26.322835) (xy 28.142819 -26.297334) (xy 28.097461 -26.264883) (xy 28.057312 -26.226174)
			(xy 28.023226 -26.182031) (xy 27.99593 -26.133396) (xy 27.976007 -26.081305) (xy 27.963881 -26.026868)
			(xy 27.95981 -25.971246) (xy 27.405838 -25.971246) (xy 27.405838 -27.649932) (xy 27.405978 -27.655516)
			(xy 27.408402 -27.666416) (xy 27.410664 -27.671522) (xy 27.434794 -27.695652) (xy 27.44216 -27.699208)
			(xy 27.46805 -27.712876) (xy 27.515667 -27.746935) (xy 27.525914 -27.756956) (xy 30.759043 -27.756956)
			(xy 30.759043 -27.702444) (xy 30.766801 -27.648487) (xy 30.78216 -27.596184) (xy 30.804807 -27.546599)
			(xy 30.83428 -27.500743) (xy 30.86998 -27.459547) (xy 30.911179 -27.423853) (xy 30.95704 -27.394385)
			(xy 31.006627 -27.371744) (xy 31.058932 -27.356392) (xy 31.11289 -27.34864) (xy 31.140146 -27.34818)
			(xy 31.154231 -27.348279) (xy 31.182327 -27.350314) (xy 31.19628 -27.352244) (xy 31.21025 -27.354276)
			(xy 31.235904 -27.343862) (xy 31.298134 -27.261058) (xy 31.303268 -27.253536) (xy 31.308333 -27.236056)
			(xy 31.306952 -27.21791) (xy 31.303468 -27.209496) (xy 31.303468 -27.209242) (xy 31.292427 -27.184112)
			(xy 31.276823 -27.131489) (xy 31.268916 -27.077174) (xy 31.268416 -27.04973) (xy 31.268902 -27.022479)
			(xy 31.276658 -26.968531) (xy 31.292013 -26.916236) (xy 31.314655 -26.866659) (xy 31.344121 -26.820809)
			(xy 31.379812 -26.779618) (xy 31.421003 -26.743927) (xy 31.466853 -26.714461) (xy 31.51643 -26.691819)
			(xy 31.568725 -26.676464) (xy 31.622673 -26.668708) (xy 31.677175 -26.668708) (xy 31.731123 -26.676464)
			(xy 31.783418 -26.691819) (xy 31.832995 -26.714461) (xy 31.878845 -26.743927) (xy 31.920036 -26.779618)
			(xy 31.955727 -26.820809) (xy 31.985193 -26.866659) (xy 32.007835 -26.916236) (xy 32.02319 -26.968531)
			(xy 32.030946 -27.022479) (xy 32.031432 -27.04973) (xy 32.031432 -27.050238) (xy 32.030772 -27.081568)
			(xy 32.020484 -27.143379) (xy 32.000239 -27.20268) (xy 31.985966 -27.230578) (xy 31.980632 -27.24023)
			(xy 31.979108 -27.26182) (xy 32.013398 -27.354276) (xy 32.028384 -27.369516) (xy 32.038544 -27.37358)
			(xy 32.039052 -27.37358) (xy 32.065673 -27.384365) (xy 32.115586 -27.412784) (xy 32.160676 -27.448363)
			(xy 32.199924 -27.490299) (xy 32.232443 -27.537643) (xy 32.257498 -27.589327) (xy 32.274523 -27.644182)
			(xy 32.283134 -27.70097) (xy 32.283654 -27.729688) (xy 32.283111 -27.756937) (xy 32.275357 -27.81088)
			(xy 32.260006 -27.863171) (xy 32.237369 -27.912745) (xy 32.207909 -27.958593) (xy 32.172223 -27.999782)
			(xy 32.13104 -28.035474) (xy 32.085196 -28.064942) (xy 32.035625 -28.087585) (xy 31.983337 -28.102945)
			(xy 31.929395 -28.110707) (xy 31.902146 -28.111196) (xy 31.87323 -28.110646) (xy 31.81606 -28.101924)
			(xy 31.760862 -28.084672) (xy 31.7089 -28.059287) (xy 31.661366 -28.026349) (xy 31.619347 -27.986613)
			(xy 31.601156 -27.96413) (xy 31.59357 -27.955301) (xy 31.572653 -27.945132) (xy 31.561024 -27.944572)
			(xy 31.481268 -27.944572) (xy 31.469632 -27.945082) (xy 31.448721 -27.955289) (xy 31.441136 -27.96413)
			(xy 31.422932 -27.986602) (xy 31.380914 -28.026337) (xy 31.333382 -28.059276) (xy 31.281423 -28.084666)
			(xy 31.226228 -28.101926) (xy 31.169061 -28.110659) (xy 31.140146 -28.111196) (xy 31.11289 -28.11076)
			(xy 31.058932 -28.103008) (xy 31.006627 -28.087656) (xy 30.95704 -28.065015) (xy 30.911179 -28.035547)
			(xy 30.86998 -27.999853) (xy 30.83428 -27.958657) (xy 30.804807 -27.912801) (xy 30.78216 -27.863216)
			(xy 30.766801 -27.810913) (xy 30.759043 -27.756956) (xy 27.525914 -27.756956) (xy 27.557523 -27.787868)
			(xy 27.57551 -27.810968) (xy 27.581606 -27.819096) (xy 27.589988 -27.824176) (xy 27.593734 -27.8263)
			(xy 27.601781 -27.829364) (xy 27.60599 -27.830272) (xy 27.676856 -27.840686) (xy 27.68981 -27.842718)
			(xy 27.70886 -27.837892) (xy 27.717242 -27.831796) (xy 27.717242 -27.831542) (xy 27.741887 -27.814153)
			(xy 27.795518 -27.786557) (xy 27.852827 -27.767758) (xy 27.912383 -27.758227) (xy 27.94254 -27.757628)
			(xy 27.943302 -27.757628) (xy 27.972109 -27.758154) (xy 28.029067 -27.766816) (xy 28.084076 -27.783942)
			(xy 28.135885 -27.809144) (xy 28.183316 -27.841848) (xy 28.225291 -27.881311) (xy 28.260857 -27.926636)
			(xy 28.275534 -27.95143) (xy 28.281884 -27.95905) (xy 28.286456 -27.963622) (xy 28.292298 -27.966924)
			(xy 28.298174 -27.970074) (xy 28.311036 -27.97356) (xy 28.317698 -27.973782) (xy 28.405582 -27.973782)
			(xy 28.40863 -27.973528) (xy 28.409646 -27.973528) (xy 28.414748 -27.973022) (xy 28.424602 -27.9702)
			(xy 28.429204 -27.96794) (xy 28.436824 -27.963622) (xy 28.445968 -27.954224) (xy 28.449524 -27.948382)
			(xy 28.449778 -27.947874) (xy 28.464543 -27.923476) (xy 28.500175 -27.878953) (xy 28.542032 -27.840224)
			(xy 28.589182 -27.80815) (xy 28.640578 -27.783444) (xy 28.695076 -27.766655) (xy 28.751465 -27.758157)
			(xy 28.779978 -27.757628) (xy 28.807229 -27.75809) (xy 28.861178 -27.765843) (xy 28.913473 -27.781196)
			(xy 28.963051 -27.803835) (xy 29.008903 -27.8333) (xy 29.050094 -27.86899) (xy 29.085787 -27.91018)
			(xy 29.115254 -27.956029) (xy 29.137896 -28.005606) (xy 29.153252 -28.057901) (xy 29.161009 -28.111849)
			(xy 29.161009 -28.139136) (xy 29.66796 -28.139136) (xy 29.672031 -28.083514) (xy 29.684157 -28.029077)
			(xy 29.70408 -27.976986) (xy 29.731376 -27.928351) (xy 29.765462 -27.884208) (xy 29.805611 -27.845499)
			(xy 29.850969 -27.813048) (xy 29.900569 -27.787547) (xy 29.953353 -27.76954) (xy 30.008196 -27.75941)
			(xy 30.06393 -27.757373) (xy 30.119367 -27.763473) (xy 30.173324 -27.777579) (xy 30.224653 -27.799391)
			(xy 30.272259 -27.828445) (xy 30.315127 -27.86412) (xy 30.352344 -27.905657) (xy 30.383117 -27.95217)
			(xy 30.406789 -28.002667) (xy 30.422857 -28.056074) (xy 30.430977 -28.11125) (xy 30.431486 -28.139136)
			(xy 30.430977 -28.167022) (xy 30.422857 -28.222198) (xy 30.406789 -28.275605) (xy 30.383117 -28.326102)
			(xy 30.352344 -28.372615) (xy 30.315127 -28.414152) (xy 30.272259 -28.449827) (xy 30.224653 -28.478881)
			(xy 30.173324 -28.500693) (xy 30.119367 -28.514799) (xy 30.06393 -28.520899) (xy 30.008196 -28.518862)
			(xy 29.953353 -28.508732) (xy 29.900569 -28.490725) (xy 29.850969 -28.465224) (xy 29.805611 -28.432773)
			(xy 29.765462 -28.394064) (xy 29.731376 -28.349921) (xy 29.70408 -28.301286) (xy 29.684157 -28.249195)
			(xy 29.672031 -28.194758) (xy 29.66796 -28.139136) (xy 29.161009 -28.139136) (xy 29.161009 -28.166351)
			(xy 29.153252 -28.220299) (xy 29.137896 -28.272594) (xy 29.115254 -28.322171) (xy 29.085787 -28.36802)
			(xy 29.050094 -28.40921) (xy 29.008903 -28.4449) (xy 28.963051 -28.474365) (xy 28.913473 -28.497004)
			(xy 28.861178 -28.512357) (xy 28.807229 -28.52011) (xy 28.779978 -28.520644) (xy 28.751142 -28.520116)
			(xy 28.694127 -28.511442) (xy 28.639064 -28.494295) (xy 28.587205 -28.469065) (xy 28.539728 -28.436325)
			(xy 28.497714 -28.396819) (xy 28.462116 -28.351445) (xy 28.447492 -28.326588) (xy 28.440395 -28.317269)
			(xy 28.420021 -28.305758) (xy 28.408376 -28.30449) (xy 28.314904 -28.30449) (xy 28.303245 -28.305714)
			(xy 28.282861 -28.317238) (xy 28.275788 -28.326588) (xy 28.261155 -28.351443) (xy 28.225573 -28.396834)
			(xy 28.183566 -28.436355) (xy 28.136091 -28.469106) (xy 28.084229 -28.494341) (xy 28.029161 -28.511485)
			(xy 27.97214 -28.520148) (xy 27.943302 -28.520644) (xy 27.914101 -28.520087) (xy 27.85638 -28.511182)
			(xy 27.800693 -28.49358) (xy 27.748341 -28.467693) (xy 27.700548 -28.434127) (xy 27.658432 -28.393665)
			(xy 27.64028 -28.370784) (xy 27.639772 -28.370022) (xy 27.636724 -28.36672) (xy 27.628088 -28.358084)
			(xy 27.622903 -28.35444) (xy 27.611211 -28.34956) (xy 27.604974 -28.348432) (xy 27.53868 -28.338526)
			(xy 27.538172 -28.338526) (xy 27.5336 -28.337764) (xy 27.528817 -28.337303) (xy 27.519231 -28.337948)
			(xy 27.51455 -28.339034) (xy 27.514296 -28.339034) (xy 27.504898 -28.34132) (xy 27.496516 -28.347416)
			(xy 27.493976 -28.349194) (xy 27.49296 -28.35021) (xy 27.487118 -28.35402) (xy 27.485086 -28.355544)
			(xy 27.48407 -28.356306) (xy 27.478482 -28.360116) (xy 27.47518 -28.363672) (xy 27.469592 -28.371292)
			(xy 27.45613 -28.396184) (xy 27.453721 -28.401394) (xy 27.451023 -28.412547) (xy 27.450796 -28.418282)
			(xy 27.450796 -28.42387) (xy 27.451006 -28.429607) (xy 27.453704 -28.440764) (xy 27.45613 -28.445968)
			(xy 27.469592 -28.47086) (xy 27.47518 -28.47848) (xy 27.478482 -28.482036) (xy 27.48407 -28.485846)
			(xy 27.50587 -28.501147) (xy 27.545413 -28.536825) (xy 27.579613 -28.577653) (xy 27.607807 -28.622838)
			(xy 27.629446 -28.671504) (xy 27.644111 -28.722704) (xy 27.651517 -28.775446) (xy 27.651964 -28.802076)
			(xy 27.651508 -28.82893) (xy 27.643982 -28.882109) (xy 27.629075 -28.933708) (xy 27.607081 -28.982706)
			(xy 27.578434 -29.028138) (xy 27.543702 -29.069104) (xy 27.503569 -29.104797) (xy 27.458828 -29.134511)
			(xy 27.434794 -29.1465) (xy 27.43454 -29.146754) (xy 27.428187 -29.149995) (xy 27.417478 -29.159405)
			(xy 27.413458 -29.165296) (xy 27.409648 -29.171138) (xy 27.407616 -29.17825) (xy 27.405838 -29.191458)
			(xy 27.405838 -29.224732) (xy 27.406088 -29.231912) (xy 27.410091 -29.245704) (xy 27.413712 -29.25191)
			(xy 27.417522 -29.257752) (xy 27.427936 -29.26715) (xy 27.434794 -29.270452) (xy 27.459106 -29.282601)
			(xy 27.504324 -29.312751) (xy 27.544808 -29.349009) (xy 27.579742 -29.390642) (xy 27.608418 -29.436808)
			(xy 27.630257 -29.486575) (xy 27.644817 -29.538936) (xy 27.651803 -29.592833) (xy 27.651076 -29.647176)
			(xy 27.642648 -29.700866) (xy 27.626692 -29.752819) (xy 27.603529 -29.801983) (xy 27.588972 -29.824934)
			(xy 27.572385 -29.849159) (xy 27.532963 -29.892661) (xy 27.510486 -29.911548) (xy 27.504644 -29.91612)
			(xy 27.48788 -29.939996) (xy 27.48788 -29.94025) (xy 27.486722 -29.944085) (xy 27.485454 -29.951994)
			(xy 27.48534 -29.955998) (xy 27.48534 -30.036516) (xy 27.485848 -30.043374) (xy 27.487712 -30.052892)
			(xy 27.4975 -30.069616) (xy 27.504898 -30.075886) (xy 27.527381 -30.094077) (xy 27.567116 -30.136095)
			(xy 27.600053 -30.18363) (xy 27.625437 -30.235592) (xy 27.642686 -30.290791) (xy 27.651404 -30.34796)
			(xy 27.651964 -30.376876) (xy 27.651508 -30.40373) (xy 27.643982 -30.456909) (xy 27.629075 -30.508508)
			(xy 27.607081 -30.557506) (xy 27.578434 -30.602938) (xy 27.543702 -30.643904) (xy 27.503569 -30.679597)
			(xy 27.458828 -30.709311) (xy 27.434794 -30.7213) (xy 27.43454 -30.721554) (xy 27.428187 -30.724795)
			(xy 27.417478 -30.734205) (xy 27.413458 -30.740096) (xy 27.409648 -30.745938) (xy 27.407616 -30.75305)
			(xy 27.405838 -30.766258) (xy 27.405838 -31.142432) (xy 27.406512 -31.153824) (xy 27.416437 -31.174338)
			(xy 27.434241 -31.188563) (xy 27.445208 -31.191708) (xy 27.445716 -31.191962) (xy 27.447748 -31.192216)
			(xy 27.473864 -31.197343) (xy 27.524452 -31.213878) (xy 27.572249 -31.237287) (xy 27.616327 -31.267113)
			(xy 27.655831 -31.302778) (xy 27.689992 -31.343589) (xy 27.718148 -31.388753) (xy 27.739751 -31.437392)
			(xy 27.754381 -31.488563) (xy 27.761755 -31.541271) (xy 27.7622 -31.567882) (xy 27.761741 -31.594477)
			(xy 27.754356 -31.647152) (xy 27.739727 -31.698292) (xy 27.730412 -31.719266) (xy 28.285438 -31.719266)
			(xy 28.289509 -31.663644) (xy 28.301635 -31.609207) (xy 28.321558 -31.557116) (xy 28.348854 -31.508481)
			(xy 28.38294 -31.464338) (xy 28.423089 -31.425629) (xy 28.468447 -31.393178) (xy 28.518047 -31.367677)
			(xy 28.570831 -31.34967) (xy 28.625674 -31.33954) (xy 28.681408 -31.337503) (xy 28.736845 -31.343603)
			(xy 28.790802 -31.357709) (xy 28.842131 -31.379521) (xy 28.889737 -31.408575) (xy 28.932605 -31.44425)
			(xy 28.969822 -31.485787) (xy 29.000595 -31.5323) (xy 29.024267 -31.582797) (xy 29.040335 -31.636204)
			(xy 29.044485 -31.664402) (xy 29.561026 -31.664402) (xy 29.565097 -31.60878) (xy 29.577223 -31.554343)
			(xy 29.597146 -31.502252) (xy 29.624442 -31.453617) (xy 29.658528 -31.409474) (xy 29.698677 -31.370765)
			(xy 29.744035 -31.338314) (xy 29.793635 -31.312813) (xy 29.846419 -31.294806) (xy 29.901262 -31.284676)
			(xy 29.956996 -31.282639) (xy 30.012433 -31.288739) (xy 30.06639 -31.302845) (xy 30.117719 -31.324657)
			(xy 30.165325 -31.353711) (xy 30.208193 -31.389386) (xy 30.24541 -31.430923) (xy 30.276183 -31.477436)
			(xy 30.299855 -31.527933) (xy 30.315923 -31.58134) (xy 30.324043 -31.636516) (xy 30.324552 -31.664402)
			(xy 30.324043 -31.692288) (xy 30.315923 -31.747464) (xy 30.306983 -31.777178) (xy 30.8262 -31.777178)
			(xy 30.830271 -31.721556) (xy 30.842397 -31.667119) (xy 30.86232 -31.615028) (xy 30.889616 -31.566393)
			(xy 30.923702 -31.52225) (xy 30.963851 -31.483541) (xy 31.009209 -31.45109) (xy 31.058809 -31.425589)
			(xy 31.111593 -31.407582) (xy 31.166436 -31.397452) (xy 31.22217 -31.395415) (xy 31.277607 -31.401515)
			(xy 31.331564 -31.415621) (xy 31.382893 -31.437433) (xy 31.430499 -31.466487) (xy 31.473367 -31.502162)
			(xy 31.510584 -31.543699) (xy 31.541357 -31.590212) (xy 31.565029 -31.640709) (xy 31.581097 -31.694116)
			(xy 31.589217 -31.749292) (xy 31.589726 -31.777178) (xy 31.589217 -31.805064) (xy 31.581097 -31.86024)
			(xy 31.565029 -31.913647) (xy 31.541357 -31.964144) (xy 31.510584 -32.010657) (xy 31.473367 -32.052194)
			(xy 31.430499 -32.087869) (xy 31.382893 -32.116923) (xy 31.331564 -32.138735) (xy 31.277607 -32.152841)
			(xy 31.22217 -32.158941) (xy 31.166436 -32.156904) (xy 31.111593 -32.146774) (xy 31.058809 -32.128767)
			(xy 31.009209 -32.103266) (xy 30.963851 -32.070815) (xy 30.923702 -32.032106) (xy 30.889616 -31.987963)
			(xy 30.86232 -31.939328) (xy 30.842397 -31.887237) (xy 30.830271 -31.8328) (xy 30.8262 -31.777178)
			(xy 30.306983 -31.777178) (xy 30.299855 -31.800871) (xy 30.276183 -31.851368) (xy 30.24541 -31.897881)
			(xy 30.208193 -31.939418) (xy 30.165325 -31.975093) (xy 30.117719 -32.004147) (xy 30.06639 -32.025959)
			(xy 30.012433 -32.040065) (xy 29.956996 -32.046165) (xy 29.901262 -32.044128) (xy 29.846419 -32.033998)
			(xy 29.793635 -32.015991) (xy 29.744035 -31.99049) (xy 29.698677 -31.958039) (xy 29.658528 -31.91933)
			(xy 29.624442 -31.875187) (xy 29.597146 -31.826552) (xy 29.577223 -31.774461) (xy 29.565097 -31.720024)
			(xy 29.561026 -31.664402) (xy 29.044485 -31.664402) (xy 29.048455 -31.69138) (xy 29.048964 -31.719266)
			(xy 29.048455 -31.747152) (xy 29.040335 -31.802328) (xy 29.024267 -31.855735) (xy 29.000595 -31.906232)
			(xy 28.969822 -31.952745) (xy 28.932605 -31.994282) (xy 28.889737 -32.029957) (xy 28.842131 -32.059011)
			(xy 28.790802 -32.080823) (xy 28.736845 -32.094929) (xy 28.681408 -32.101029) (xy 28.625674 -32.098992)
			(xy 28.570831 -32.088862) (xy 28.518047 -32.070855) (xy 28.468447 -32.045354) (xy 28.423089 -32.012903)
			(xy 28.38294 -31.974194) (xy 28.348854 -31.930051) (xy 28.321558 -31.881416) (xy 28.301635 -31.829325)
			(xy 28.289509 -31.774888) (xy 28.285438 -31.719266) (xy 27.730412 -31.719266) (xy 27.718138 -31.746904)
			(xy 27.690007 -31.792046) (xy 27.655879 -31.832845) (xy 27.616416 -31.868508) (xy 27.572383 -31.898345)
			(xy 27.524632 -31.921777) (xy 27.474089 -31.938351) (xy 27.448002 -31.943548) (xy 27.447748 -31.943548)
			(xy 27.444446 -31.944056) (xy 27.434065 -31.947101) (xy 27.417029 -31.960401) (xy 27.406958 -31.979526)
			(xy 27.405838 -31.990284) (xy 27.405838 -33.507426) (xy 27.406096 -33.514837) (xy 27.410362 -33.529033)
			(xy 27.41422 -33.535366) (xy 27.418512 -33.541424) (xy 27.429862 -33.550986) (xy 27.436572 -33.554162)
			(xy 27.522424 -33.590992) (xy 27.529328 -33.593689) (xy 27.544048 -33.595376) (xy 27.55138 -33.594294)
			(xy 27.558492 -33.593024) (xy 27.5717 -33.58642) (xy 27.577288 -33.581086) (xy 27.585369 -33.573552)
			(xy 27.602271 -33.559319) (xy 27.61107 -33.552638) (xy 27.618436 -33.54705) (xy 27.623262 -33.53943)
			(xy 27.625568 -33.535777) (xy 27.629017 -33.527858) (xy 27.63012 -33.523682) (xy 27.637486 -33.49117)
			(xy 27.644852 -33.458912) (xy 27.645762 -33.454462) (xy 27.646147 -33.445388) (xy 27.645614 -33.440878)
			(xy 27.644598 -33.43275) (xy 27.64028 -33.424368) (xy 27.626695 -33.39699) (xy 27.607454 -33.338982)
			(xy 27.597701 -33.27865) (xy 27.5971 -33.248092) (xy 27.597586 -33.220841) (xy 27.605342 -33.166893)
			(xy 27.620697 -33.114598) (xy 27.643339 -33.065021) (xy 27.672805 -33.019171) (xy 27.708496 -32.97798)
			(xy 27.749687 -32.942289) (xy 27.795537 -32.912823) (xy 27.845114 -32.890181) (xy 27.897409 -32.874826)
			(xy 27.951357 -32.86707) (xy 28.005859 -32.86707) (xy 28.059807 -32.874826) (xy 28.112102 -32.890181)
			(xy 28.161679 -32.912823) (xy 28.207529 -32.942289) (xy 28.24872 -32.97798) (xy 28.284411 -33.019171)
			(xy 28.313877 -33.065021) (xy 28.336519 -33.114598) (xy 28.351874 -33.166893) (xy 28.35963 -33.220841)
			(xy 28.360116 -33.248092) (xy 28.359568 -33.277568) (xy 28.350501 -33.335819) (xy 28.332581 -33.391983)
			(xy 28.306236 -33.444721) (xy 28.272091 -33.492779) (xy 28.230961 -33.535013) (xy 28.207716 -33.553146)
			(xy 28.203652 -33.556194) (xy 28.19781 -33.562544) (xy 28.195778 -33.565846) (xy 28.193379 -33.569678)
			(xy 28.1898 -33.57798) (xy 28.188666 -33.582356) (xy 28.173934 -33.647126) (xy 28.173028 -33.651576)
			(xy 28.17265 -33.660649) (xy 28.173172 -33.66516) (xy 28.174188 -33.673034) (xy 28.178506 -33.681416)
			(xy 28.185637 -33.695371) (xy 28.197847 -33.724236) (xy 28.20289 -33.739074) (xy 28.203398 -33.740852)
			(xy 28.204922 -33.745424) (xy 28.205938 -33.748218) (xy 28.211272 -33.755076) (xy 28.21392 -33.758223)
			(xy 28.220044 -33.763713) (xy 28.223464 -33.765998) (xy 28.224988 -33.767014) (xy 28.253436 -33.784032)
			(xy 28.253944 -33.784032) (xy 28.284424 -33.802574) (xy 28.287966 -33.804426) (xy 28.295494 -33.807111)
			(xy 28.29941 -33.807908) (xy 28.307538 -33.809432) (xy 28.31338 -33.808416) (xy 28.317444 -33.807654)
			(xy 28.334317 -33.804801) (xy 28.368404 -33.801746) (xy 28.385516 -33.801558) (xy 28.387548 -33.801558)
			(xy 28.414705 -33.802183) (xy 28.468432 -33.810175) (xy 28.520484 -33.825707) (xy 28.569806 -33.848463)
			(xy 28.58406 -33.857692) (xy 29.49016 -33.857692) (xy 29.494231 -33.80207) (xy 29.506357 -33.747633)
			(xy 29.52628 -33.695542) (xy 29.553576 -33.646907) (xy 29.587662 -33.602764) (xy 29.627811 -33.564055)
			(xy 29.673169 -33.531604) (xy 29.722769 -33.506103) (xy 29.775553 -33.488096) (xy 29.830396 -33.477966)
			(xy 29.88613 -33.475929) (xy 29.941567 -33.482029) (xy 29.995524 -33.496135) (xy 30.046853 -33.517947)
			(xy 30.094459 -33.547001) (xy 30.137327 -33.582676) (xy 30.174544 -33.624213) (xy 30.205317 -33.670726)
			(xy 30.228989 -33.721223) (xy 30.245057 -33.77463) (xy 30.253177 -33.829806) (xy 30.253686 -33.857692)
			(xy 30.253177 -33.885578) (xy 30.245057 -33.940754) (xy 30.228989 -33.994161) (xy 30.205317 -34.044658)
			(xy 30.174544 -34.091171) (xy 30.137327 -34.132708) (xy 30.094459 -34.168383) (xy 30.046853 -34.197437)
			(xy 29.995524 -34.219249) (xy 29.941567 -34.233355) (xy 29.88613 -34.239455) (xy 29.830396 -34.237418)
			(xy 29.775553 -34.227288) (xy 29.722769 -34.209281) (xy 29.673169 -34.18378) (xy 29.627811 -34.151329)
			(xy 29.587662 -34.11262) (xy 29.553576 -34.068477) (xy 29.52628 -34.019842) (xy 29.506357 -33.967751)
			(xy 29.494231 -33.913314) (xy 29.49016 -33.857692) (xy 28.58406 -33.857692) (xy 28.615403 -33.877985)
			(xy 28.656352 -33.913674) (xy 28.691825 -33.954811) (xy 28.721105 -34.000563) (xy 28.743601 -34.050005)
			(xy 28.758857 -34.102137) (xy 28.766566 -34.155906) (xy 28.767024 -34.183066) (xy 28.766563 -34.210321)
			(xy 28.758811 -34.264276) (xy 28.743458 -34.316579) (xy 28.720817 -34.366165) (xy 28.69135 -34.412023)
			(xy 28.655657 -34.453221) (xy 28.614463 -34.48892) (xy 28.568609 -34.518393) (xy 28.519026 -34.54104)
			(xy 28.466725 -34.5564) (xy 28.412771 -34.56416) (xy 28.385516 -34.564574) (xy 28.385516 -34.564828)
			(xy 28.357442 -34.564329) (xy 28.3019 -34.556091) (xy 28.248169 -34.539791) (xy 28.197412 -34.515783)
			(xy 28.150728 -34.484585) (xy 28.109128 -34.446874) (xy 28.073512 -34.403466) (xy 28.058618 -34.379662)
			(xy 28.047749 -34.361105) (xy 28.029799 -34.322021) (xy 28.022804 -34.301684) (xy 28.022296 -34.300414)
			(xy 28.022296 -34.30016) (xy 28.019315 -34.292805) (xy 28.009615 -34.280257) (xy 28.003246 -34.275522)
			(xy 27.94127 -34.238184) (xy 27.937727 -34.236334) (xy 27.930199 -34.233652) (xy 27.926284 -34.23285)
			(xy 27.918156 -34.231326) (xy 27.90825 -34.233104) (xy 27.89144 -34.235948) (xy 27.85748 -34.239)
			(xy 27.840432 -34.2392) (xy 27.840178 -34.2392) (xy 27.811167 -34.238658) (xy 27.753814 -34.229878)
			(xy 27.698449 -34.212523) (xy 27.646346 -34.186993) (xy 27.598704 -34.153875) (xy 27.577288 -34.134298)
			(xy 27.576526 -34.133536) (xy 27.571064 -34.128828) (xy 27.558169 -34.122389) (xy 27.551126 -34.120836)
			(xy 27.544014 -34.119566) (xy 27.536648 -34.120582) (xy 27.533056 -34.121023) (xy 27.526045 -34.122813)
			(xy 27.522678 -34.124138) (xy 27.436572 -34.161222) (xy 27.427682 -34.16553) (xy 27.413826 -34.179584)
			(xy 27.406321 -34.197837) (xy 27.405838 -34.207704) (xy 27.405838 -35.264852) (xy 29.902402 -35.264852)
			(xy 29.906473 -35.20923) (xy 29.918599 -35.154793) (xy 29.938522 -35.102702) (xy 29.965818 -35.054067)
			(xy 29.999904 -35.009924) (xy 30.040053 -34.971215) (xy 30.085411 -34.938764) (xy 30.135011 -34.913263)
			(xy 30.187795 -34.895256) (xy 30.242638 -34.885126) (xy 30.298372 -34.883089) (xy 30.353809 -34.889189)
			(xy 30.407766 -34.903295) (xy 30.459095 -34.925107) (xy 30.506701 -34.954161) (xy 30.549569 -34.989836)
			(xy 30.574403 -35.017553) (xy 32.219856 -35.017553) (xy 32.219856 -34.963047) (xy 32.227613 -34.909096)
			(xy 32.242969 -34.856799) (xy 32.265611 -34.807219) (xy 32.295079 -34.761365) (xy 32.330773 -34.720173)
			(xy 32.371965 -34.684479) (xy 32.417819 -34.655011) (xy 32.467399 -34.632369) (xy 32.519696 -34.617013)
			(xy 32.573647 -34.609256) (xy 32.6009 -34.60877) (xy 32.618012 -34.608956) (xy 32.652099 -34.612012)
			(xy 32.668972 -34.614866) (xy 32.680262 -34.616247) (xy 32.702154 -34.610163) (xy 32.711136 -34.603182)
			(xy 32.73552 -34.5821) (xy 32.743941 -34.574176) (xy 32.75321 -34.553021) (xy 32.7533 -34.54146)
			(xy 32.752792 -34.522664) (xy 32.752792 -33.65881) (xy 32.7533 -33.638744) (xy 32.753074 -33.627301)
			(xy 32.743984 -33.606331) (xy 32.735774 -33.598358) (xy 32.711136 -33.577022) (xy 32.702131 -33.569954)
			(xy 32.680053 -33.563994) (xy 32.668718 -33.565592) (xy 32.65191 -33.568451) (xy 32.617949 -33.571506)
			(xy 32.6009 -33.571688) (xy 32.573647 -33.571242) (xy 32.519697 -33.563485) (xy 32.467399 -33.548129)
			(xy 32.417819 -33.525487) (xy 32.371967 -33.496019) (xy 32.330774 -33.460326) (xy 32.295081 -33.419133)
			(xy 32.265613 -33.373281) (xy 32.242971 -33.323701) (xy 32.227615 -33.271403) (xy 32.219858 -33.217453)
			(xy 32.219858 -33.162947) (xy 32.227615 -33.108997) (xy 32.242971 -33.056699) (xy 32.265613 -33.007119)
			(xy 32.295081 -32.961267) (xy 32.330774 -32.920074) (xy 32.371967 -32.884381) (xy 32.417819 -32.854913)
			(xy 32.467399 -32.832271) (xy 32.519697 -32.816915) (xy 32.573647 -32.809158) (xy 32.6009 -32.808672)
			(xy 32.627908 -32.80912) (xy 32.681387 -32.816726) (xy 32.733257 -32.831801) (xy 32.782482 -32.854043)
			(xy 32.828077 -32.883007) (xy 32.869129 -32.918113) (xy 32.904819 -32.95866) (xy 32.934431 -33.003837)
			(xy 32.957374 -33.052739) (xy 32.973188 -33.104389) (xy 32.977836 -33.130998) (xy 32.97936 -33.141666)
			(xy 32.99079 -33.159446) (xy 33.062164 -33.206944) (xy 33.071085 -33.212308) (xy 33.091555 -33.215973)
			(xy 33.101788 -33.214056) (xy 33.10255 -33.214056) (xy 33.129119 -33.207937) (xy 33.183239 -33.201317)
			(xy 33.2105 -33.200848) (xy 33.237824 -33.20131) (xy 33.292072 -33.207927) (xy 33.318704 -33.214056)
			(xy 33.319212 -33.214056) (xy 33.329444 -33.215899) (xy 33.349889 -33.212237) (xy 33.358836 -33.206944)
			(xy 33.43021 -33.159446) (xy 33.44164 -33.141666) (xy 33.443164 -33.130998) (xy 33.447769 -33.104383)
			(xy 33.463603 -33.052741) (xy 33.486561 -33.003848) (xy 33.516184 -32.958681) (xy 33.551879 -32.918142)
			(xy 33.592934 -32.883041) (xy 33.638529 -32.85408) (xy 33.687751 -32.831837) (xy 33.739618 -32.816756)
			(xy 33.793093 -32.80914) (xy 33.8201 -32.808672) (xy 33.847471 -32.809121) (xy 33.901652 -32.81694)
			(xy 33.954156 -32.832432) (xy 34.003902 -32.855278) (xy 34.049868 -32.885008) (xy 34.070798 -32.902652)
			(xy 34.071052 -32.902906) (xy 34.078148 -32.908479) (xy 34.095057 -32.914734) (xy 34.104072 -32.915098)
			(xy 34.171128 -32.915098) (xy 34.180146 -32.914755) (xy 34.197063 -32.908498) (xy 34.204148 -32.902906)
			(xy 34.204148 -32.902652) (xy 34.204402 -32.902652) (xy 34.225329 -32.885007) (xy 34.271302 -32.855294)
			(xy 34.321051 -32.832458) (xy 34.373553 -32.816969) (xy 34.42773 -32.809144) (xy 34.4551 -32.808672)
			(xy 34.472212 -32.808858) (xy 34.506299 -32.811914) (xy 34.523172 -32.814768) (xy 34.534462 -32.816149)
			(xy 34.556353 -32.810065) (xy 34.565336 -32.803084) (xy 34.58972 -32.782002) (xy 34.59814 -32.774078)
			(xy 34.607409 -32.752923) (xy 34.6075 -32.741362) (xy 34.606992 -32.722566) (xy 34.606992 -31.858712)
			(xy 34.6075 -31.838646) (xy 34.607273 -31.827203) (xy 34.598183 -31.806234) (xy 34.589974 -31.79826)
			(xy 34.565336 -31.776924) (xy 34.55633 -31.769856) (xy 34.534253 -31.763896) (xy 34.522918 -31.765494)
			(xy 34.50611 -31.768353) (xy 34.472149 -31.771408) (xy 34.4551 -31.77159) (xy 34.42773 -31.771126)
			(xy 34.37355 -31.763308) (xy 34.321047 -31.747819) (xy 34.2713 -31.724976) (xy 34.225334 -31.695251)
			(xy 34.204402 -31.67761) (xy 34.197544 -31.671514) (xy 34.180526 -31.665164) (xy 34.095182 -31.665164)
			(xy 34.07791 -31.671768) (xy 34.071052 -31.677864) (xy 34.050119 -31.695502) (xy 34.00415 -31.725222)
			(xy 33.954403 -31.748062) (xy 33.901901 -31.763553) (xy 33.847724 -31.771375) (xy 33.820354 -31.771844)
			(xy 33.8201 -31.771844) (xy 33.793123 -31.771374) (xy 33.739703 -31.763793) (xy 33.687887 -31.748754)
			(xy 33.63871 -31.726557) (xy 33.593155 -31.697647) (xy 33.552132 -31.662601) (xy 33.516462 -31.62212)
			(xy 33.486857 -31.577013) (xy 33.46391 -31.528181) (xy 33.448079 -31.476602) (xy 33.443418 -31.450026)
			(xy 33.44124 -31.4398) (xy 33.42997 -31.422219) (xy 33.421574 -31.41599) (xy 33.3502 -31.368492)
			(xy 33.329118 -31.364682) (xy 33.318958 -31.367222) (xy 33.292257 -31.3733) (xy 33.237881 -31.379791)
			(xy 33.2105 -31.380176) (xy 33.183118 -31.379798) (xy 33.128742 -31.373305) (xy 33.102042 -31.367222)
			(xy 33.091882 -31.364682) (xy 33.0708 -31.368492) (xy 32.990536 -31.421832) (xy 32.97936 -31.439358)
			(xy 32.977582 -31.450026) (xy 32.972879 -31.476589) (xy 32.957024 -31.528151) (xy 32.934064 -31.576965)
			(xy 32.904455 -31.622057) (xy 32.868788 -31.662528) (xy 32.827776 -31.69757) (xy 32.782235 -31.726484)
			(xy 32.733075 -31.748694) (xy 32.681276 -31.763756) (xy 32.627872 -31.77137) (xy 32.6009 -31.771844)
			(xy 32.573651 -31.771286) (xy 32.519709 -31.76353) (xy 32.467419 -31.748176) (xy 32.417847 -31.725537)
			(xy 32.372001 -31.696074) (xy 32.330814 -31.660386) (xy 32.295126 -31.619199) (xy 32.265663 -31.573353)
			(xy 32.243024 -31.523781) (xy 32.22767 -31.471491) (xy 32.219914 -31.417549) (xy 32.219914 -31.363051)
			(xy 32.22767 -31.309109) (xy 32.243024 -31.256819) (xy 32.265663 -31.207247) (xy 32.295126 -31.161401)
			(xy 32.330814 -31.120214) (xy 32.372001 -31.084526) (xy 32.417847 -31.055063) (xy 32.467419 -31.032424)
			(xy 32.519709 -31.01707) (xy 32.573651 -31.009314) (xy 32.6009 -31.008828) (xy 32.618012 -31.009015)
			(xy 32.652099 -31.01207) (xy 32.668972 -31.014924) (xy 32.680262 -31.016315) (xy 32.702155 -31.010226)
			(xy 32.711136 -31.00324) (xy 32.73552 -30.982158) (xy 32.743961 -30.974252) (xy 32.753218 -30.953083)
			(xy 32.7533 -30.941518) (xy 32.752792 -30.922722) (xy 32.752792 -30.058868) (xy 32.7533 -30.038802)
			(xy 32.753098 -30.027357) (xy 32.743991 -30.006387) (xy 32.735774 -29.998416) (xy 32.711136 -29.97708)
			(xy 32.702126 -29.970018) (xy 32.680052 -29.964052) (xy 32.668718 -29.96565) (xy 32.65191 -29.96851)
			(xy 32.617949 -29.971564) (xy 32.6009 -29.971746) (xy 32.573651 -29.971184) (xy 32.519709 -29.963428)
			(xy 32.46742 -29.948075) (xy 32.417847 -29.925436) (xy 32.372002 -29.895972) (xy 32.330816 -29.860284)
			(xy 32.295128 -29.819098) (xy 32.265664 -29.773253) (xy 32.243025 -29.72368) (xy 32.227672 -29.671391)
			(xy 32.219916 -29.617449) (xy 32.219916 -29.562951) (xy 32.227672 -29.509009) (xy 32.243025 -29.45672)
			(xy 32.265664 -29.407147) (xy 32.295128 -29.361302) (xy 32.330816 -29.320116) (xy 32.372002 -29.284428)
			(xy 32.417847 -29.254964) (xy 32.46742 -29.232325) (xy 32.519709 -29.216972) (xy 32.573651 -29.209216)
			(xy 32.6009 -29.20873) (xy 32.627907 -29.209213) (xy 32.681382 -29.216818) (xy 32.73325 -29.231891)
			(xy 32.782472 -29.25413) (xy 32.828066 -29.28309) (xy 32.869118 -29.318193) (xy 32.904808 -29.358735)
			(xy 32.934421 -29.403906) (xy 32.957367 -29.452804) (xy 32.973185 -29.504449) (xy 32.977836 -29.531056)
			(xy 32.97936 -29.541724) (xy 32.99079 -29.559504) (xy 33.062164 -29.607002) (xy 33.071086 -29.612365)
			(xy 33.091556 -29.616032) (xy 33.101788 -29.614114) (xy 33.10255 -29.614114) (xy 33.129125 -29.608056)
			(xy 33.183246 -29.601567) (xy 33.2105 -29.60116) (xy 33.237818 -29.601541) (xy 33.292067 -29.608039)
			(xy 33.318704 -29.614114) (xy 33.319212 -29.614114) (xy 33.329445 -29.615948) (xy 33.349887 -29.612291)
			(xy 33.358836 -29.607002) (xy 33.43021 -29.559504) (xy 33.44164 -29.541724) (xy 33.443164 -29.531056)
			(xy 33.447813 -29.504449) (xy 33.46364 -29.452808) (xy 33.486591 -29.403914) (xy 33.516207 -29.358746)
			(xy 33.551898 -29.318205) (xy 33.592948 -29.283103) (xy 33.638538 -29.25414) (xy 33.687757 -29.231896)
			(xy 33.739621 -29.216815) (xy 33.793094 -29.209198) (xy 33.8201 -29.20873) (xy 33.847471 -29.209189)
			(xy 33.90165 -29.217007) (xy 33.954154 -29.232498) (xy 34.003901 -29.255341) (xy 34.049867 -29.285068)
			(xy 34.070798 -29.30271) (xy 34.071052 -29.302964) (xy 34.078143 -29.308544) (xy 34.095057 -29.314793)
			(xy 34.104072 -29.315156) (xy 34.171128 -29.315156) (xy 34.180147 -29.314822) (xy 34.197065 -29.30856)
			(xy 34.204148 -29.302964) (xy 34.204148 -29.30271) (xy 34.204402 -29.30271) (xy 34.225324 -29.285058)
			(xy 34.271299 -29.255348) (xy 34.321049 -29.232514) (xy 34.373552 -29.217026) (xy 34.42773 -29.209202)
			(xy 34.4551 -29.20873) (xy 34.472212 -29.208917) (xy 34.506299 -29.211972) (xy 34.523172 -29.214826)
			(xy 34.534462 -29.216216) (xy 34.556355 -29.210128) (xy 34.565336 -29.203142) (xy 34.58972 -29.18206)
			(xy 34.59816 -29.174153) (xy 34.607418 -29.152985) (xy 34.6075 -29.14142) (xy 34.606992 -29.122624)
			(xy 34.606992 -28.25877) (xy 34.6075 -28.238704) (xy 34.607297 -28.227259) (xy 34.59819 -28.206289)
			(xy 34.589974 -28.198318) (xy 34.565336 -28.176982) (xy 34.556326 -28.16992) (xy 34.534252 -28.163954)
			(xy 34.522918 -28.165552) (xy 34.50611 -28.168412) (xy 34.472149 -28.171466) (xy 34.4551 -28.171648)
			(xy 34.427852 -28.171082) (xy 34.37391 -28.163326) (xy 34.32162 -28.147973) (xy 34.272048 -28.125334)
			(xy 34.226203 -28.095871) (xy 34.185017 -28.060183) (xy 34.149329 -28.018997) (xy 34.119866 -27.973152)
			(xy 34.097227 -27.92358) (xy 34.081874 -27.87129) (xy 34.074118 -27.817348) (xy 34.074118 -27.762852)
			(xy 34.081874 -27.70891) (xy 34.097227 -27.65662) (xy 34.119866 -27.607048) (xy 34.149329 -27.561203)
			(xy 34.185017 -27.520017) (xy 34.226203 -27.484329) (xy 34.272048 -27.454866) (xy 34.32162 -27.432227)
			(xy 34.37391 -27.416874) (xy 34.427852 -27.409118) (xy 34.4551 -27.408632) (xy 34.482107 -27.409113)
			(xy 34.535582 -27.416719) (xy 34.58745 -27.431792) (xy 34.636673 -27.454031) (xy 34.682266 -27.482991)
			(xy 34.723318 -27.518094) (xy 34.759008 -27.558636) (xy 34.788622 -27.603808) (xy 34.811567 -27.652705)
			(xy 34.827385 -27.704351) (xy 34.832036 -27.730958) (xy 34.83356 -27.741626) (xy 34.84499 -27.759406)
			(xy 34.916364 -27.806904) (xy 34.925286 -27.812267) (xy 34.945756 -27.815934) (xy 34.955988 -27.814016)
			(xy 34.95675 -27.814016) (xy 34.983319 -27.807897) (xy 35.037439 -27.801277) (xy 35.0647 -27.800808)
			(xy 35.086878 -27.801109) (xy 35.131024 -27.805431) (xy 35.152838 -27.809444) (xy 35.162998 -27.811476)
			(xy 35.183064 -27.807412) (xy 35.25139 -27.760168) (xy 35.25956 -27.753963) (xy 35.270567 -27.73667)
			(xy 35.272726 -27.72664) (xy 35.27765 -27.700307) (xy 35.293864 -27.64925) (xy 35.317061 -27.600963)
			(xy 35.346787 -27.556397) (xy 35.382455 -27.516428) (xy 35.423364 -27.481842) (xy 35.468709 -27.45332)
			(xy 35.517599 -27.431422) (xy 35.569072 -27.41658) (xy 35.622115 -27.409085) (xy 35.6489 -27.408632)
			(xy 35.676154 -27.409038) (xy 35.730107 -27.416795) (xy 35.782408 -27.432152) (xy 35.83199 -27.454795)
			(xy 35.877845 -27.484265) (xy 35.91904 -27.51996) (xy 35.954735 -27.561155) (xy 35.984205 -27.60701)
			(xy 36.006848 -27.656592) (xy 36.022205 -27.708893) (xy 36.029962 -27.762846) (xy 36.029962 -27.817354)
			(xy 36.022205 -27.871307) (xy 36.006848 -27.923608) (xy 35.984205 -27.97319) (xy 35.954735 -28.019045)
			(xy 35.91904 -28.06024) (xy 35.877845 -28.095935) (xy 35.83199 -28.125405) (xy 35.782408 -28.148048)
			(xy 35.730107 -28.163405) (xy 35.676154 -28.171162) (xy 35.6489 -28.171648) (xy 35.648138 -28.171648)
			(xy 35.636806 -28.171534) (xy 35.614186 -28.170135) (xy 35.602926 -28.168854) (xy 35.592012 -28.168105)
			(xy 35.571215 -28.174824) (xy 35.562794 -28.181808) (xy 35.538664 -28.203652) (xy 35.530914 -28.211479)
			(xy 35.522362 -28.231755) (xy 35.522154 -28.242768) (xy 35.522408 -28.25877) (xy 35.522408 -29.12237)
			(xy 35.522154 -29.13761) (xy 35.522352 -29.14866) (xy 35.531064 -29.168949) (xy 35.538918 -29.176726)
			(xy 35.562794 -29.198316) (xy 35.571219 -29.205292) (xy 35.592013 -29.212007) (xy 35.602926 -29.21127)
			(xy 35.614185 -29.20998) (xy 35.636806 -29.20858) (xy 35.648138 -29.208476) (xy 35.6489 -29.208476)
			(xy 35.67615 -29.208994) (xy 35.730095 -29.21675) (xy 35.782388 -29.232105) (xy 35.831963 -29.254745)
			(xy 35.877811 -29.28421) (xy 35.919 -29.3199) (xy 35.95469 -29.361089) (xy 35.984155 -29.406937)
			(xy 36.006795 -29.456512) (xy 36.02215 -29.508805) (xy 36.029906 -29.56275) (xy 36.029906 -29.61725)
			(xy 36.02215 -29.671195) (xy 36.006795 -29.723488) (xy 35.984155 -29.773063) (xy 35.95469 -29.818911)
			(xy 35.919 -29.8601) (xy 35.877811 -29.89579) (xy 35.831963 -29.925255) (xy 35.782388 -29.947895)
			(xy 35.730095 -29.96325) (xy 35.67615 -29.971006) (xy 35.6489 -29.971492) (xy 35.622153 -29.971022)
			(xy 35.569185 -29.963529) (xy 35.517782 -29.948716) (xy 35.468948 -29.926875) (xy 35.423641 -29.898432)
			(xy 35.382747 -29.863945) (xy 35.347066 -29.824088) (xy 35.317297 -29.779641) (xy 35.294022 -29.731475)
			(xy 35.277697 -29.680531) (xy 35.272726 -29.654246) (xy 35.270948 -29.643832) (xy 35.26028 -29.627068)
			(xy 35.183318 -29.573728) (xy 35.163252 -29.569664) (xy 35.153092 -29.571696) (xy 35.131218 -29.575739)
			(xy 35.086943 -29.580068) (xy 35.0647 -29.580332) (xy 35.037312 -29.579892) (xy 34.982936 -29.573268)
			(xy 34.956242 -29.567124) (xy 34.946082 -29.564584) (xy 34.925 -29.568394) (xy 34.844736 -29.621734)
			(xy 34.83356 -29.63926) (xy 34.831782 -29.649928) (xy 34.82708 -29.676492) (xy 34.811226 -29.728054)
			(xy 34.788265 -29.776867) (xy 34.758656 -29.821959) (xy 34.722989 -29.86243) (xy 34.681976 -29.897472)
			(xy 34.636435 -29.926386) (xy 34.587275 -29.948596) (xy 34.535476 -29.963658) (xy 34.482072 -29.971272)
			(xy 34.4551 -29.971746) (xy 34.427729 -29.971293) (xy 34.373549 -29.963474) (xy 34.321045 -29.947983)
			(xy 34.271298 -29.925138) (xy 34.225333 -29.895409) (xy 34.204402 -29.877766) (xy 34.204148 -29.877512)
			(xy 34.197051 -29.871941) (xy 34.180142 -29.865684) (xy 34.171128 -29.86532) (xy 34.104072 -29.86532)
			(xy 34.095053 -29.865659) (xy 34.078136 -29.871919) (xy 34.071052 -29.877512) (xy 34.071052 -29.877766)
			(xy 34.070798 -29.877766) (xy 34.049873 -29.895414) (xy 34.003899 -29.925126) (xy 33.95415 -29.947961)
			(xy 33.901647 -29.963449) (xy 33.84747 -29.971274) (xy 33.8201 -29.971746) (xy 33.803052 -29.971541)
			(xy 33.769093 -29.968492) (xy 33.752282 -29.96565) (xy 33.740956 -29.96419) (xy 33.718936 -29.970142)
			(xy 33.709864 -29.97708) (xy 33.685226 -29.998416) (xy 33.676882 -30.006293) (xy 33.667763 -30.027327)
			(xy 33.6677 -30.038802) (xy 33.668208 -30.058868) (xy 33.668208 -30.922722) (xy 33.6677 -30.941518)
			(xy 33.667801 -30.953077) (xy 33.677063 -30.974234) (xy 33.68548 -30.982158) (xy 33.709864 -31.00324)
			(xy 33.718824 -31.010257) (xy 33.740731 -31.016314) (xy 33.752028 -31.014924) (xy 33.768898 -31.012048)
			(xy 33.802987 -31.009) (xy 33.8201 -31.008828) (xy 33.847471 -31.009287) (xy 33.90165 -31.017106)
			(xy 33.954154 -31.032596) (xy 34.0039 -31.055439) (xy 34.049867 -31.085166) (xy 34.070798 -31.102808)
			(xy 34.077656 -31.108904) (xy 34.094674 -31.115254) (xy 34.180018 -31.115254) (xy 34.19729 -31.10865)
			(xy 34.204148 -31.102554) (xy 34.225084 -31.084918) (xy 34.271052 -31.055197) (xy 34.320798 -31.032357)
			(xy 34.373299 -31.016866) (xy 34.427476 -31.009043) (xy 34.454846 -31.008574) (xy 34.4551 -31.008574)
			(xy 34.482108 -31.00902) (xy 34.535587 -31.016626) (xy 34.587457 -31.031701) (xy 34.636682 -31.053943)
			(xy 34.682277 -31.082907) (xy 34.72333 -31.118014) (xy 34.759019 -31.158561) (xy 34.788631 -31.203738)
			(xy 34.811574 -31.25264) (xy 34.827388 -31.30429) (xy 34.832036 -31.3309) (xy 34.83356 -31.341568)
			(xy 34.84499 -31.359348) (xy 34.916364 -31.406846) (xy 34.925285 -31.41221) (xy 34.945755 -31.415875)
			(xy 34.955988 -31.413958) (xy 34.95675 -31.413958) (xy 34.983325 -31.407901) (xy 35.037446 -31.401411)
			(xy 35.0647 -31.401004) (xy 35.086873 -31.401233) (xy 35.131019 -31.405431) (xy 35.152838 -31.409386)
			(xy 35.162998 -31.411418) (xy 35.183064 -31.407354) (xy 35.25139 -31.36011) (xy 35.259581 -31.353928)
			(xy 35.270576 -31.336618) (xy 35.272726 -31.326582) (xy 35.277606 -31.300241) (xy 35.293827 -31.249183)
			(xy 35.317032 -31.200897) (xy 35.346763 -31.156332) (xy 35.382436 -31.116364) (xy 35.42335 -31.08178)
			(xy 35.468699 -31.053259) (xy 35.517593 -31.031362) (xy 35.569068 -31.016521) (xy 35.622114 -31.009027)
			(xy 35.6489 -31.008574) (xy 35.67615 -31.009096) (xy 35.730095 -31.016852) (xy 35.782387 -31.032207)
			(xy 35.831962 -31.054847) (xy 35.87781 -31.084312) (xy 35.918999 -31.120001) (xy 35.954688 -31.16119)
			(xy 35.984153 -31.207038) (xy 36.006793 -31.256613) (xy 36.022148 -31.308905) (xy 36.029904 -31.36285)
			(xy 36.029904 -31.41735) (xy 36.022148 -31.471295) (xy 36.006793 -31.523587) (xy 35.984153 -31.573162)
			(xy 35.954688 -31.61901) (xy 35.918999 -31.660199) (xy 35.87781 -31.695888) (xy 35.831962 -31.725353)
			(xy 35.782387 -31.747993) (xy 35.730095 -31.763348) (xy 35.67615 -31.771104) (xy 35.6489 -31.77159)
			(xy 35.648138 -31.77159) (xy 35.636806 -31.771475) (xy 35.614186 -31.770077) (xy 35.602926 -31.768796)
			(xy 35.592012 -31.768036) (xy 35.571213 -31.774761) (xy 35.562794 -31.78175) (xy 35.538664 -31.803594)
			(xy 35.530895 -31.811405) (xy 35.522353 -31.831693) (xy 35.522154 -31.84271) (xy 35.522408 -31.858712)
			(xy 35.522408 -32.722312) (xy 35.522154 -32.737806) (xy 35.522355 -32.748856) (xy 35.531064 -32.769144)
			(xy 35.538918 -32.776922) (xy 35.562794 -32.798512) (xy 35.571219 -32.805488) (xy 35.592013 -32.812203)
			(xy 35.602926 -32.811466) (xy 35.614185 -32.810176) (xy 35.636806 -32.808776) (xy 35.648138 -32.808672)
			(xy 35.6489 -32.808672) (xy 35.67615 -32.809198) (xy 35.730095 -32.816954) (xy 35.782387 -32.832309)
			(xy 35.831961 -32.854949) (xy 35.877809 -32.884413) (xy 35.918997 -32.920103) (xy 35.954687 -32.961291)
			(xy 35.984151 -33.007139) (xy 36.006791 -33.056713) (xy 36.022146 -33.109005) (xy 36.029902 -33.16295)
			(xy 36.029902 -33.21745) (xy 36.022146 -33.271395) (xy 36.006791 -33.323687) (xy 35.984151 -33.373261)
			(xy 35.954687 -33.419109) (xy 35.918997 -33.460297) (xy 35.877809 -33.495987) (xy 35.831961 -33.525451)
			(xy 35.782387 -33.548091) (xy 35.730095 -33.563446) (xy 35.67615 -33.571202) (xy 35.6489 -33.571688)
			(xy 35.622132 -33.571317) (xy 35.569121 -33.563846) (xy 35.517675 -33.549036) (xy 35.468805 -33.527178)
			(xy 35.423471 -33.498702) (xy 35.382564 -33.464168) (xy 35.346887 -33.424253) (xy 35.317142 -33.379742)
			(xy 35.293912 -33.331509) (xy 35.277655 -33.280502) (xy 35.272726 -33.254188) (xy 35.270948 -33.243774)
			(xy 35.26028 -33.22701) (xy 35.183318 -33.17367) (xy 35.163252 -33.169606) (xy 35.153092 -33.171638)
			(xy 35.131212 -33.175614) (xy 35.086937 -33.179816) (xy 35.0647 -33.18002) (xy 35.037318 -33.179643)
			(xy 34.982942 -33.17315) (xy 34.956242 -33.167066) (xy 34.946082 -33.164526) (xy 34.925 -33.168336)
			(xy 34.844736 -33.221676) (xy 34.83356 -33.239202) (xy 34.831782 -33.24987) (xy 34.827036 -33.276426)
			(xy 34.811189 -33.327987) (xy 34.788235 -33.376802) (xy 34.758632 -33.421895) (xy 34.722971 -33.462367)
			(xy 34.681962 -33.49741) (xy 34.636425 -33.526326) (xy 34.587269 -33.548537) (xy 34.535473 -33.5636)
			(xy 34.482071 -33.571214) (xy 34.4551 -33.571688) (xy 34.42773 -33.571225) (xy 34.37355 -33.563407)
			(xy 34.321047 -33.547917) (xy 34.2713 -33.525075) (xy 34.225334 -33.49535) (xy 34.204402 -33.477708)
			(xy 34.204148 -33.477454) (xy 34.197056 -33.471876) (xy 34.180143 -33.465625) (xy 34.171128 -33.465262)
			(xy 34.104072 -33.465262) (xy 34.095055 -33.465614) (xy 34.078138 -33.471866) (xy 34.071052 -33.477454)
			(xy 34.071052 -33.477708) (xy 34.070798 -33.477708) (xy 34.049879 -33.495363) (xy 34.003902 -33.525072)
			(xy 33.954151 -33.547905) (xy 33.901648 -33.563392) (xy 33.84747 -33.571216) (xy 33.8201 -33.571688)
			(xy 33.803052 -33.571484) (xy 33.769093 -33.568434) (xy 33.752282 -33.565592) (xy 33.740957 -33.564123)
			(xy 33.718935 -33.57008) (xy 33.709864 -33.577022) (xy 33.685226 -33.598358) (xy 33.67691 -33.60626)
			(xy 33.667776 -33.627274) (xy 33.6677 -33.638744) (xy 33.668208 -33.65881) (xy 33.668208 -34.522664)
			(xy 33.6677 -34.54146) (xy 33.667835 -34.553016) (xy 33.677074 -34.574172) (xy 33.68548 -34.5821)
			(xy 33.709864 -34.603182) (xy 33.718828 -34.610193) (xy 33.740732 -34.616256) (xy 33.752028 -34.614866)
			(xy 33.768898 -34.611991) (xy 33.802987 -34.608942) (xy 33.8201 -34.60877) (xy 33.84735 -34.6093)
			(xy 33.901294 -34.617056) (xy 33.953586 -34.632411) (xy 34.00316 -34.65505) (xy 34.049008 -34.684515)
			(xy 34.090196 -34.720204) (xy 34.125885 -34.761392) (xy 34.15535 -34.80724) (xy 34.177989 -34.856814)
			(xy 34.193344 -34.909106) (xy 34.2011 -34.96305) (xy 34.2011 -34.990024) (xy 35.266882 -34.990024)
			(xy 35.270953 -34.934402) (xy 35.283079 -34.879965) (xy 35.303002 -34.827874) (xy 35.330298 -34.779239)
			(xy 35.364384 -34.735096) (xy 35.404533 -34.696387) (xy 35.449891 -34.663936) (xy 35.499491 -34.638435)
			(xy 35.552275 -34.620428) (xy 35.607118 -34.610298) (xy 35.662852 -34.608261) (xy 35.718289 -34.614361)
			(xy 35.772246 -34.628467) (xy 35.823575 -34.650279) (xy 35.871181 -34.679333) (xy 35.914049 -34.715008)
			(xy 35.951266 -34.756545) (xy 35.982039 -34.803058) (xy 36.005711 -34.853555) (xy 36.021779 -34.906962)
			(xy 36.029899 -34.962138) (xy 36.030408 -34.990024) (xy 36.029899 -35.01791) (xy 36.021779 -35.073086)
			(xy 36.005711 -35.126493) (xy 35.982039 -35.17699) (xy 35.951266 -35.223503) (xy 35.914049 -35.26504)
			(xy 35.871181 -35.300715) (xy 35.823575 -35.329769) (xy 35.772246 -35.351581) (xy 35.718289 -35.365687)
			(xy 35.662852 -35.371787) (xy 35.607118 -35.36975) (xy 35.552275 -35.35962) (xy 35.499491 -35.341613)
			(xy 35.449891 -35.316112) (xy 35.404533 -35.283661) (xy 35.364384 -35.244952) (xy 35.330298 -35.200809)
			(xy 35.303002 -35.152174) (xy 35.283079 -35.100083) (xy 35.270953 -35.045646) (xy 35.266882 -34.990024)
			(xy 34.2011 -34.990024) (xy 34.2011 -35.01755) (xy 34.193344 -35.071494) (xy 34.177989 -35.123786)
			(xy 34.15535 -35.17336) (xy 34.125885 -35.219208) (xy 34.090196 -35.260396) (xy 34.049008 -35.296085)
			(xy 34.00316 -35.32555) (xy 33.953586 -35.348189) (xy 33.901294 -35.363544) (xy 33.84735 -35.3713)
			(xy 33.8201 -35.371786) (xy 33.793124 -35.371281) (xy 33.739708 -35.3637) (xy 33.687895 -35.348663)
			(xy 33.63872 -35.32647) (xy 33.593166 -35.297563) (xy 33.552144 -35.262522) (xy 33.516473 -35.222045)
			(xy 33.486867 -35.176943) (xy 33.463917 -35.128117) (xy 33.448082 -35.076542) (xy 33.443418 -35.049968)
			(xy 33.441267 -35.039734) (xy 33.429978 -35.022157) (xy 33.421574 -35.015932) (xy 33.3502 -34.968434)
			(xy 33.329118 -34.964624) (xy 33.318958 -34.967164) (xy 33.292263 -34.973302) (xy 33.237888 -34.979925)
			(xy 33.2105 -34.980372) (xy 33.183112 -34.979931) (xy 33.128736 -34.973308) (xy 33.102042 -34.967164)
			(xy 33.091882 -34.964624) (xy 33.0708 -34.968434) (xy 32.990536 -35.021774) (xy 32.97936 -35.0393)
			(xy 32.977582 -35.049968) (xy 32.972911 -35.076537) (xy 32.957051 -35.128099) (xy 32.934085 -35.176913)
			(xy 32.904472 -35.222004) (xy 32.868801 -35.262474) (xy 32.827786 -35.297515) (xy 32.782242 -35.326428)
			(xy 32.73308 -35.348637) (xy 32.681279 -35.363699) (xy 32.627873 -35.371312) (xy 32.6009 -35.371786)
			(xy 32.573647 -35.371344) (xy 32.519696 -35.363587) (xy 32.467399 -35.348231) (xy 32.417819 -35.325589)
			(xy 32.371965 -35.296121) (xy 32.330773 -35.260427) (xy 32.295079 -35.219235) (xy 32.265611 -35.173381)
			(xy 32.242969 -35.123801) (xy 32.227613 -35.071504) (xy 32.219856 -35.017553) (xy 30.574403 -35.017553)
			(xy 30.586786 -35.031373) (xy 30.617559 -35.077886) (xy 30.641231 -35.128383) (xy 30.657299 -35.18179)
			(xy 30.665419 -35.236966) (xy 30.665928 -35.264852) (xy 30.665419 -35.292738) (xy 30.657299 -35.347914)
			(xy 30.641231 -35.401321) (xy 30.617559 -35.451818) (xy 30.586786 -35.498331) (xy 30.549569 -35.539868)
			(xy 30.506701 -35.575543) (xy 30.459095 -35.604597) (xy 30.407766 -35.626409) (xy 30.353809 -35.640515)
			(xy 30.298372 -35.646615) (xy 30.242638 -35.644578) (xy 30.187795 -35.634448) (xy 30.135011 -35.616441)
			(xy 30.085411 -35.59094) (xy 30.040053 -35.558489) (xy 29.999904 -35.51978) (xy 29.965818 -35.475637)
			(xy 29.938522 -35.427002) (xy 29.918599 -35.374911) (xy 29.906473 -35.320474) (xy 29.902402 -35.264852)
			(xy 27.405838 -35.264852) (xy 27.405838 -37.087048) (xy 31.200852 -37.087048) (xy 31.201314 -37.060444)
			(xy 31.208691 -37.007751) (xy 31.223321 -36.956594) (xy 31.244921 -36.907969) (xy 31.273071 -36.862818)
			(xy 31.307224 -36.822019) (xy 31.346718 -36.786364) (xy 31.368492 -36.771072) (xy 31.378417 -36.763543)
			(xy 31.390145 -36.741598) (xy 31.390844 -36.729162) (xy 31.390844 -36.644834) (xy 31.39021 -36.632378)
			(xy 31.378477 -36.610399) (xy 31.368492 -36.602924) (xy 31.346736 -36.58761) (xy 31.307254 -36.551948)
			(xy 31.273108 -36.511149) (xy 31.24496 -36.466002) (xy 31.223355 -36.417384) (xy 31.208713 -36.366236)
			(xy 31.201316 -36.313549) (xy 31.200852 -36.286948) (xy 31.2014 -36.259698) (xy 31.209149 -36.205752)
			(xy 31.224497 -36.153458) (xy 31.247131 -36.103881) (xy 31.27659 -36.05803) (xy 31.312275 -36.016838)
			(xy 31.353459 -35.981143) (xy 31.399304 -35.951673) (xy 31.448876 -35.929028) (xy 31.501166 -35.913668)
			(xy 31.55511 -35.905906) (xy 31.58236 -35.90544) (xy 31.586932 -35.90544) (xy 31.596142 -35.905169)
			(xy 31.61346 -35.898928) (xy 31.620714 -35.893248) (xy 31.671514 -35.84956) (xy 31.678221 -35.843324)
			(xy 31.68708 -35.827315) (xy 31.688786 -35.818318) (xy 31.688786 -35.818064) (xy 31.69313 -35.791133)
			(xy 31.70844 -35.738777) (xy 31.731052 -35.689135) (xy 31.760503 -35.64322) (xy 31.796194 -35.601968)
			(xy 31.837397 -35.56622) (xy 31.883271 -35.536705) (xy 31.932882 -35.514025) (xy 31.985217 -35.498642)
			(xy 32.03921 -35.49087) (xy 32.066484 -35.490404) (xy 32.093738 -35.490842) (xy 32.147693 -35.498597)
			(xy 32.199994 -35.513952) (xy 32.249578 -35.536595) (xy 32.295435 -35.566063) (xy 32.336631 -35.601758)
			(xy 32.372327 -35.642952) (xy 32.401798 -35.688808) (xy 32.424442 -35.738391) (xy 32.439799 -35.790691)
			(xy 32.447557 -35.844646) (xy 32.447557 -35.899154) (xy 32.439799 -35.953109) (xy 32.424442 -36.005409)
			(xy 32.401798 -36.054992) (xy 32.372327 -36.100848) (xy 32.336631 -36.142042) (xy 32.295435 -36.177737)
			(xy 32.249578 -36.207205) (xy 32.199994 -36.229848) (xy 32.147693 -36.245203) (xy 32.093738 -36.252958)
			(xy 32.066484 -36.25342) (xy 32.061912 -36.25342) (xy 32.052698 -36.25365) (xy 32.035379 -36.259918)
			(xy 32.02813 -36.265612) (xy 31.97733 -36.3093) (xy 31.970593 -36.315507) (xy 31.961753 -36.331538)
			(xy 31.960058 -36.340542) (xy 31.960058 -36.340796) (xy 31.955858 -36.366999) (xy 31.941174 -36.417993)
			(xy 31.919561 -36.466459) (xy 31.891438 -36.51146) (xy 31.888011 -36.515548) (xy 33.014156 -36.515548)
			(xy 33.018227 -36.459926) (xy 33.030353 -36.405489) (xy 33.050276 -36.353398) (xy 33.077572 -36.304763)
			(xy 33.111658 -36.26062) (xy 33.151807 -36.221911) (xy 33.197165 -36.18946) (xy 33.246765 -36.163959)
			(xy 33.299549 -36.145952) (xy 33.354392 -36.135822) (xy 33.410126 -36.133785) (xy 33.465563 -36.139885)
			(xy 33.51952 -36.153991) (xy 33.570849 -36.175803) (xy 33.618455 -36.204857) (xy 33.661323 -36.240532)
			(xy 33.69854 -36.282069) (xy 33.729313 -36.328582) (xy 33.752985 -36.379079) (xy 33.769053 -36.432486)
			(xy 33.777173 -36.487662) (xy 33.777682 -36.515548) (xy 33.777173 -36.543434) (xy 33.769053 -36.59861)
			(xy 33.752985 -36.652017) (xy 33.729313 -36.702514) (xy 33.69854 -36.749027) (xy 33.661323 -36.790564)
			(xy 33.618455 -36.826239) (xy 33.570849 -36.855293) (xy 33.51952 -36.877105) (xy 33.465563 -36.891211)
			(xy 33.410126 -36.897311) (xy 33.354392 -36.895274) (xy 33.299549 -36.885144) (xy 33.246765 -36.867137)
			(xy 33.197165 -36.841636) (xy 33.151807 -36.809185) (xy 33.111658 -36.770476) (xy 33.077572 -36.726333)
			(xy 33.050276 -36.677698) (xy 33.030353 -36.625607) (xy 33.018227 -36.57117) (xy 33.014156 -36.515548)
			(xy 31.888011 -36.515548) (xy 31.857346 -36.552127) (xy 31.817946 -36.587674) (xy 31.796228 -36.602924)
			(xy 31.786308 -36.610459) (xy 31.774577 -36.632399) (xy 31.773876 -36.644834) (xy 31.773876 -36.729162)
			(xy 31.774545 -36.741612) (xy 31.786256 -36.763589) (xy 31.796228 -36.771072) (xy 31.817987 -36.786383)
			(xy 31.857468 -36.822045) (xy 31.891613 -36.862846) (xy 31.91976 -36.907993) (xy 31.941365 -36.956612)
			(xy 31.956007 -37.00776) (xy 31.963403 -37.060447) (xy 31.963868 -37.087048) (xy 31.963868 -37.087302)
			(xy 31.96325 -37.119019) (xy 31.952748 -37.181577) (xy 31.93202 -37.241528) (xy 31.917386 -37.269674)
			(xy 31.912052 -37.27958) (xy 31.910528 -37.301678) (xy 31.942532 -37.384482) (xy 31.947024 -37.394569)
			(xy 31.962812 -37.409972) (xy 31.973012 -37.4142) (xy 31.997548 -37.423259) (xy 32.044078 -37.447144)
			(xy 32.086908 -37.477161) (xy 32.125237 -37.512748) (xy 32.158344 -37.553238) (xy 32.18561 -37.597871)
			(xy 32.206523 -37.64581) (xy 32.22069 -37.696157) (xy 32.227846 -37.747967) (xy 32.228282 -37.774118)
			(xy 32.227796 -37.801369) (xy 32.22004 -37.855317) (xy 32.204685 -37.907612) (xy 32.182043 -37.957189)
			(xy 32.152577 -38.003039) (xy 32.116886 -38.04423) (xy 32.075695 -38.079921) (xy 32.029845 -38.109387)
			(xy 31.980268 -38.132029) (xy 31.927973 -38.147384) (xy 31.874025 -38.15514) (xy 31.819523 -38.15514)
			(xy 31.765575 -38.147384) (xy 31.71328 -38.132029) (xy 31.663703 -38.109387) (xy 31.617853 -38.079921)
			(xy 31.576662 -38.04423) (xy 31.540971 -38.003039) (xy 31.511505 -37.957189) (xy 31.488863 -37.907612)
			(xy 31.473508 -37.855317) (xy 31.465752 -37.801369) (xy 31.465266 -37.774118) (xy 31.465266 -37.773864)
			(xy 31.465867 -37.742146) (xy 31.476375 -37.679587) (xy 31.49711 -37.619637) (xy 31.511748 -37.591492)
			(xy 31.517082 -37.581586) (xy 31.518606 -37.559488) (xy 31.486602 -37.476684) (xy 31.482151 -37.466575)
			(xy 31.466333 -37.451183) (xy 31.456122 -37.446966) (xy 31.431582 -37.437916) (xy 31.38505 -37.414033)
			(xy 31.342218 -37.384016) (xy 31.303888 -37.348428) (xy 31.27078 -37.307937) (xy 31.243515 -37.263302)
			(xy 31.222604 -37.215361) (xy 31.208439 -37.165012) (xy 31.201286 -37.1132) (xy 31.200852 -37.087048)
			(xy 27.405838 -37.087048) (xy 27.405838 -38.315138) (xy 32.418018 -38.315138) (xy 32.422089 -38.259516)
			(xy 32.434215 -38.205079) (xy 32.454138 -38.152988) (xy 32.481434 -38.104353) (xy 32.51552 -38.06021)
			(xy 32.555669 -38.021501) (xy 32.601027 -37.98905) (xy 32.650627 -37.963549) (xy 32.703411 -37.945542)
			(xy 32.758254 -37.935412) (xy 32.813988 -37.933375) (xy 32.869425 -37.939475) (xy 32.923382 -37.953581)
			(xy 32.974711 -37.975393) (xy 33.022317 -38.004447) (xy 33.065185 -38.040122) (xy 33.102402 -38.081659)
			(xy 33.133175 -38.128172) (xy 33.156847 -38.178669) (xy 33.172915 -38.232076) (xy 33.181035 -38.287252)
			(xy 33.181544 -38.315138) (xy 33.181035 -38.343024) (xy 33.172915 -38.3982) (xy 33.156847 -38.451607)
			(xy 33.133175 -38.502104) (xy 33.102402 -38.548617) (xy 33.065185 -38.590154) (xy 33.022317 -38.625829)
			(xy 32.974711 -38.654883) (xy 32.923382 -38.676695) (xy 32.869425 -38.690801) (xy 32.813988 -38.696901)
			(xy 32.758254 -38.694864) (xy 32.703411 -38.684734) (xy 32.650627 -38.666727) (xy 32.601027 -38.641226)
			(xy 32.555669 -38.608775) (xy 32.51552 -38.570066) (xy 32.481434 -38.525923) (xy 32.454138 -38.477288)
			(xy 32.434215 -38.425197) (xy 32.422089 -38.37076) (xy 32.418018 -38.315138) (xy 27.405838 -38.315138)
			(xy 27.405838 -42.432478) (xy 27.406125 -42.440353) (xy 27.410899 -42.455363) (xy 27.415236 -42.461942)
			(xy 27.419808 -42.468546) (xy 27.432254 -42.47769) (xy 27.440128 -42.480484) (xy 27.466204 -42.490053)
			(xy 27.515492 -42.515663) (xy 27.560545 -42.548151) (xy 27.600409 -42.586829) (xy 27.634242 -42.63088)
			(xy 27.661328 -42.679372) (xy 27.681095 -42.73128) (xy 27.693125 -42.785506) (xy 27.697163 -42.840903)
			(xy 27.693124 -42.896301) (xy 27.681094 -42.950526) (xy 27.661326 -43.002434) (xy 27.634238 -43.050925)
			(xy 27.600404 -43.094976) (xy 27.56054 -43.133653) (xy 27.515487 -43.16614) (xy 27.466198 -43.19175)
			(xy 27.440128 -43.201336) (xy 27.43962 -43.20159) (xy 27.432381 -43.204402) (xy 27.419962 -43.213715)
			(xy 27.415236 -43.219878) (xy 27.410664 -43.226482) (xy 27.408378 -43.233594) (xy 27.407216 -43.237428)
			(xy 27.40594 -43.245337) (xy 27.405838 -43.249342) (xy 27.405838 -43.448478) (xy 27.406125 -43.456353)
			(xy 27.410899 -43.471363) (xy 27.415236 -43.477942) (xy 27.419808 -43.484546) (xy 27.432254 -43.49369)
			(xy 27.440128 -43.496484) (xy 27.466204 -43.506053) (xy 27.515492 -43.531663) (xy 27.560545 -43.564151)
			(xy 27.600409 -43.602829) (xy 27.634242 -43.64688) (xy 27.661328 -43.695372) (xy 27.681095 -43.74728)
			(xy 27.693125 -43.801506) (xy 27.697163 -43.856903) (xy 27.693124 -43.912301) (xy 27.681094 -43.966526)
			(xy 27.661326 -44.018434) (xy 27.634238 -44.066925) (xy 27.600404 -44.110976) (xy 27.56054 -44.149653)
			(xy 27.515487 -44.18214) (xy 27.466198 -44.20775) (xy 27.440128 -44.217336) (xy 27.43962 -44.21759)
			(xy 27.432381 -44.220402) (xy 27.419962 -44.229715) (xy 27.415236 -44.235878) (xy 27.410664 -44.242482)
			(xy 27.408378 -44.249594) (xy 27.407216 -44.253428) (xy 27.40594 -44.261337) (xy 27.405838 -44.265342)
			(xy 27.405838 -44.464478) (xy 27.406125 -44.472353) (xy 27.410899 -44.487363) (xy 27.415236 -44.493942)
			(xy 27.419808 -44.500546) (xy 27.432254 -44.50969) (xy 27.440128 -44.512484) (xy 27.466204 -44.522053)
			(xy 27.515492 -44.547663) (xy 27.560545 -44.580151) (xy 27.600409 -44.618829) (xy 27.634242 -44.66288)
			(xy 27.661328 -44.711372) (xy 27.681095 -44.76328) (xy 27.693125 -44.817506) (xy 27.697163 -44.872903)
			(xy 27.693124 -44.928301) (xy 27.681094 -44.982526) (xy 27.661326 -45.034434) (xy 27.634238 -45.082925)
			(xy 27.600404 -45.126976) (xy 27.56054 -45.165653) (xy 27.515487 -45.19814) (xy 27.466198 -45.22375)
			(xy 27.440128 -45.233336) (xy 27.43962 -45.23359) (xy 27.432381 -45.236402) (xy 27.419962 -45.245715)
			(xy 27.415236 -45.251878) (xy 27.410664 -45.258482) (xy 27.408378 -45.265594) (xy 27.407216 -45.269428)
			(xy 27.40594 -45.277337) (xy 27.405838 -45.281342) (xy 27.405838 -45.480478) (xy 27.406125 -45.488353)
			(xy 27.410899 -45.503363) (xy 27.415236 -45.509942) (xy 27.419808 -45.516546) (xy 27.432254 -45.52569)
			(xy 27.440128 -45.528484) (xy 27.466204 -45.538053) (xy 27.515492 -45.563663) (xy 27.560545 -45.596151)
			(xy 27.600409 -45.634829) (xy 27.634242 -45.67888) (xy 27.661328 -45.727372) (xy 27.681095 -45.77928)
			(xy 27.693125 -45.833506) (xy 27.697163 -45.888903) (xy 27.693124 -45.944301) (xy 27.681094 -45.998526)
			(xy 27.661326 -46.050434) (xy 27.634238 -46.098925) (xy 27.600404 -46.142976) (xy 27.56054 -46.181653)
			(xy 27.515487 -46.21414) (xy 27.466198 -46.23975) (xy 27.440128 -46.249336) (xy 27.43962 -46.24959)
			(xy 27.432381 -46.252402) (xy 27.419962 -46.261715) (xy 27.415236 -46.267878) (xy 27.410664 -46.274482)
			(xy 27.408378 -46.281594) (xy 27.407216 -46.285428) (xy 27.40594 -46.293337) (xy 27.405838 -46.297342)
			(xy 27.405838 -47.02556) (xy 27.406508 -47.034917) (xy 27.413689 -47.052229) (xy 27.419808 -47.059342)
			(xy 27.442668 -47.065438) (xy 27.47002 -47.073141) (xy 27.522305 -47.09539) (xy 27.570795 -47.125012)
			(xy 27.614457 -47.161377) (xy 27.652362 -47.203708) (xy 27.683703 -47.251106) (xy 27.707811 -47.30256)
			(xy 27.724175 -47.356975) (xy 27.732444 -47.413192) (xy 27.732444 -47.470014) (xy 27.724173 -47.526231)
			(xy 27.707809 -47.580646) (xy 27.6837 -47.6321) (xy 27.652359 -47.679497) (xy 27.614453 -47.721828)
			(xy 27.57079 -47.758191) (xy 27.522299 -47.787813) (xy 27.470014 -47.810061) (xy 27.442668 -47.817786)
			(xy 27.419808 -47.823882) (xy 27.413656 -47.830969) (xy 27.4065 -47.848301) (xy 27.405838 -47.857664)
			(xy 27.405838 -48.528478) (xy 27.406125 -48.536353) (xy 27.410899 -48.551363) (xy 27.415236 -48.557942)
			(xy 27.419808 -48.564546) (xy 27.432254 -48.57369) (xy 27.440128 -48.576484) (xy 27.466204 -48.586053)
			(xy 27.515492 -48.611663) (xy 27.560545 -48.644151) (xy 27.600409 -48.682829) (xy 27.634242 -48.72688)
			(xy 27.661328 -48.775372) (xy 27.681095 -48.82728) (xy 27.693125 -48.881506) (xy 27.697163 -48.936903)
			(xy 27.693124 -48.992301) (xy 27.681094 -49.046526) (xy 27.661326 -49.098434) (xy 27.634238 -49.146925)
			(xy 27.600404 -49.190976) (xy 27.56054 -49.229653) (xy 27.515487 -49.26214) (xy 27.466198 -49.28775)
			(xy 27.440128 -49.297336) (xy 27.43962 -49.29759) (xy 27.432381 -49.300402) (xy 27.419962 -49.309715)
			(xy 27.415236 -49.315878) (xy 27.410664 -49.322482) (xy 27.408378 -49.329594) (xy 27.407216 -49.333428)
			(xy 27.40594 -49.341337) (xy 27.405838 -49.345342) (xy 27.405838 -49.544478) (xy 27.406125 -49.552353)
			(xy 27.410899 -49.567363) (xy 27.415236 -49.573942) (xy 27.419808 -49.580546) (xy 27.432254 -49.58969)
			(xy 27.440128 -49.592484) (xy 27.465934 -49.601954) (xy 28.290959 -49.601954) (xy 28.290959 -49.547446)
			(xy 28.298717 -49.493493) (xy 28.314074 -49.441194) (xy 28.336719 -49.391612) (xy 28.366189 -49.345758)
			(xy 28.401885 -49.304565) (xy 28.443081 -49.268872) (xy 28.488937 -49.239405) (xy 28.53852 -49.216765)
			(xy 28.590821 -49.201411) (xy 28.644774 -49.193657) (xy 28.672028 -49.193196) (xy 28.699399 -49.193647)
			(xy 28.753578 -49.201468) (xy 28.806082 -49.216961) (xy 28.855828 -49.239806) (xy 28.901795 -49.269534)
			(xy 28.922726 -49.287176) (xy 28.92298 -49.28743) (xy 28.930066 -49.293018) (xy 28.946983 -49.299263)
			(xy 28.956 -49.299622) (xy 29.023056 -49.299622) (xy 29.03207 -49.299239) (xy 29.048987 -49.293009)
			(xy 29.056076 -49.28743) (xy 29.056076 -49.287176) (xy 29.05633 -49.287176) (xy 29.077263 -49.269535)
			(xy 29.123231 -49.239811) (xy 29.172977 -49.216965) (xy 29.225479 -49.201469) (xy 29.279657 -49.19364)
			(xy 29.334399 -49.19364) (xy 29.388577 -49.201469) (xy 29.441079 -49.216965) (xy 29.490825 -49.239811)
			(xy 29.536793 -49.269535) (xy 29.557726 -49.287176) (xy 29.55798 -49.28743) (xy 29.565066 -49.293018)
			(xy 29.581983 -49.299263) (xy 29.591 -49.299622) (xy 29.658056 -49.299622) (xy 29.66707 -49.299239)
			(xy 29.683987 -49.293009) (xy 29.691076 -49.28743) (xy 29.691076 -49.287176) (xy 29.69133 -49.287176)
			(xy 29.712275 -49.269553) (xy 29.758244 -49.239839) (xy 29.807989 -49.217001) (xy 29.860486 -49.201506)
			(xy 29.91466 -49.193673) (xy 29.942028 -49.193196) (xy 29.968343 -49.193646) (xy 30.020472 -49.200885)
			(xy 30.071115 -49.215207) (xy 30.119314 -49.236343) (xy 30.164157 -49.263892) (xy 30.204796 -49.297333)
			(xy 30.222952 -49.316386) (xy 30.230454 -49.32381) (xy 30.249749 -49.332322) (xy 30.26029 -49.332896)
			(xy 30.334966 -49.332896) (xy 30.345515 -49.332363) (xy 30.364811 -49.323831) (xy 30.372304 -49.316386)
			(xy 30.390462 -49.297333) (xy 30.431091 -49.263876) (xy 30.475931 -49.236317) (xy 30.524132 -49.215178)
			(xy 30.574778 -49.20086) (xy 30.626912 -49.193635) (xy 30.653228 -49.193196) (xy 30.680478 -49.193676)
			(xy 30.734423 -49.201436) (xy 30.786715 -49.216793) (xy 30.83629 -49.239436) (xy 30.882137 -49.268904)
			(xy 30.923324 -49.304595) (xy 30.959013 -49.345785) (xy 30.988477 -49.391635) (xy 31.011117 -49.441211)
			(xy 31.02647 -49.493504) (xy 31.034226 -49.54745) (xy 31.034226 -49.60195) (xy 31.02647 -49.655896)
			(xy 31.011117 -49.708189) (xy 30.988477 -49.757765) (xy 30.959013 -49.803615) (xy 30.923324 -49.844805)
			(xy 30.882137 -49.880496) (xy 30.83629 -49.909964) (xy 30.786715 -49.932607) (xy 30.734423 -49.947964)
			(xy 30.680478 -49.955724) (xy 30.653228 -49.956212) (xy 30.626913 -49.955789) (xy 30.574782 -49.948544)
			(xy 30.524139 -49.934216) (xy 30.47594 -49.913076) (xy 30.431098 -49.885522) (xy 30.39046 -49.852077)
			(xy 30.372304 -49.833022) (xy 30.36478 -49.825623) (xy 30.345502 -49.817096) (xy 30.334966 -49.816512)
			(xy 30.26029 -49.816512) (xy 30.249738 -49.817018) (xy 30.230442 -49.825569) (xy 30.222952 -49.833022)
			(xy 30.204817 -49.852098) (xy 30.164182 -49.885552) (xy 30.119338 -49.913108) (xy 30.071133 -49.934243)
			(xy 30.020482 -49.948556) (xy 29.968345 -49.955776) (xy 29.942028 -49.956212) (xy 29.914659 -49.955727)
			(xy 29.86048 -49.947913) (xy 29.807978 -49.932428) (xy 29.75823 -49.909591) (xy 29.712263 -49.879871)
			(xy 29.69133 -49.862232) (xy 29.691076 -49.861978) (xy 29.684002 -49.856373) (xy 29.667076 -49.850138)
			(xy 29.658056 -49.849786) (xy 29.591 -49.849786) (xy 29.581984 -49.850146) (xy 29.565067 -49.856392)
			(xy 29.55798 -49.861978) (xy 29.55798 -49.862232) (xy 29.557726 -49.862232) (xy 29.536793 -49.879873)
			(xy 29.490825 -49.909597) (xy 29.441079 -49.932443) (xy 29.388577 -49.947939) (xy 29.334399 -49.955768)
			(xy 29.279657 -49.955768) (xy 29.225479 -49.947939) (xy 29.172977 -49.932443) (xy 29.123231 -49.909597)
			(xy 29.077263 -49.879873) (xy 29.05633 -49.862232) (xy 29.056076 -49.861978) (xy 29.049002 -49.856373)
			(xy 29.032076 -49.850138) (xy 29.023056 -49.849786) (xy 28.956 -49.849786) (xy 28.946984 -49.850146)
			(xy 28.930067 -49.856392) (xy 28.92298 -49.861978) (xy 28.92298 -49.862232) (xy 28.922726 -49.862232)
			(xy 28.901799 -49.879877) (xy 28.855824 -49.909587) (xy 28.806075 -49.932421) (xy 28.753574 -49.947911)
			(xy 28.699397 -49.955738) (xy 28.672028 -49.956212) (xy 28.644774 -49.955743) (xy 28.590821 -49.947989)
			(xy 28.53852 -49.932635) (xy 28.488937 -49.909995) (xy 28.443081 -49.880528) (xy 28.401885 -49.844835)
			(xy 28.366189 -49.803642) (xy 28.336719 -49.757788) (xy 28.314074 -49.708206) (xy 28.298717 -49.655907)
			(xy 28.290959 -49.601954) (xy 27.465934 -49.601954) (xy 27.466204 -49.602053) (xy 27.515492 -49.627663)
			(xy 27.560545 -49.660151) (xy 27.600409 -49.698829) (xy 27.634242 -49.74288) (xy 27.661328 -49.791372)
			(xy 27.681095 -49.84328) (xy 27.693125 -49.897506) (xy 27.697163 -49.952903) (xy 27.693124 -50.008301)
			(xy 27.681094 -50.062526) (xy 27.661326 -50.114434) (xy 27.634238 -50.162925) (xy 27.600404 -50.206976)
			(xy 27.56054 -50.245653) (xy 27.515487 -50.27814) (xy 27.466198 -50.30375) (xy 27.440128 -50.313336)
			(xy 27.43962 -50.31359) (xy 27.432381 -50.316402) (xy 27.419962 -50.325715) (xy 27.415236 -50.331878)
			(xy 27.410664 -50.338482) (xy 27.408378 -50.345594) (xy 27.407216 -50.349428) (xy 27.40594 -50.357337)
			(xy 27.405838 -50.361342) (xy 27.405838 -50.60823) (xy 27.406101 -50.615873) (xy 27.410633 -50.630472)
			(xy 27.414728 -50.636932) (xy 27.420316 -50.644552) (xy 27.433016 -50.65395) (xy 27.44089 -50.65649)
			(xy 27.467598 -50.665678) (xy 27.518176 -50.690812) (xy 27.564496 -50.723128) (xy 27.605547 -50.761918)
			(xy 27.640432 -50.806335) (xy 27.668389 -50.855409) (xy 27.688807 -50.908069) (xy 27.70124 -50.963162)
			(xy 27.705415 -51.019486) (xy 27.701244 -51.075811) (xy 27.688815 -51.130905) (xy 27.668401 -51.183566)
			(xy 27.640448 -51.232642) (xy 27.605566 -51.277062) (xy 27.564517 -51.315855) (xy 27.518199 -51.348174)
			(xy 27.467623 -51.373312) (xy 27.44089 -51.382422) (xy 27.433016 -51.384962) (xy 27.420316 -51.39436)
			(xy 27.414728 -51.40198) (xy 27.410623 -51.408434) (xy 27.406102 -51.423038) (xy 27.405838 -51.430682)
			(xy 27.405838 -51.62423) (xy 27.406101 -51.631873) (xy 27.410633 -51.646472) (xy 27.414728 -51.652932)
			(xy 27.420316 -51.660552) (xy 27.433016 -51.66995) (xy 27.44089 -51.67249) (xy 27.467598 -51.681678)
			(xy 27.482429 -51.689048) (xy 28.2555 -51.689048) (xy 28.2555 -51.634552) (xy 28.263255 -51.58061)
			(xy 28.278608 -51.528321) (xy 28.301245 -51.478749) (xy 28.330707 -51.432903) (xy 28.366393 -51.391716)
			(xy 28.407577 -51.356026) (xy 28.453421 -51.326561) (xy 28.502991 -51.303919) (xy 28.555279 -51.288562)
			(xy 28.60922 -51.280802) (xy 28.636468 -51.280314) (xy 28.663838 -51.280795) (xy 28.718016 -51.288609)
			(xy 28.770519 -51.304094) (xy 28.820266 -51.326933) (xy 28.866234 -51.356654) (xy 28.887166 -51.374294)
			(xy 28.88742 -51.374548) (xy 28.894492 -51.380155) (xy 28.91142 -51.386388) (xy 28.92044 -51.38674)
			(xy 28.987496 -51.38674) (xy 28.996514 -51.386394) (xy 29.013432 -51.38014) (xy 29.020516 -51.374548)
			(xy 29.020516 -51.374294) (xy 29.02077 -51.374294) (xy 29.041702 -51.356655) (xy 29.087675 -51.326943)
			(xy 29.137422 -51.304107) (xy 29.189923 -51.288616) (xy 29.244099 -51.280788) (xy 29.271468 -51.280314)
			(xy 29.289811 -51.280547) (xy 29.326324 -51.28411) (xy 29.344366 -51.287426) (xy 29.354996 -51.289037)
			(xy 29.375918 -51.284158) (xy 29.384752 -51.278028) (xy 29.45384 -51.225704) (xy 29.464254 -51.206908)
			(xy 29.465016 -51.195986) (xy 29.467916 -51.167703) (xy 29.480953 -51.112366) (xy 29.502048 -51.059572)
			(xy 29.530735 -51.010489) (xy 29.566381 -50.9662) (xy 29.586936 -50.946558) (xy 29.594349 -50.939045)
			(xy 29.602869 -50.919759) (xy 29.603446 -50.90922) (xy 29.603446 -50.834544) (xy 29.602893 -50.823998)
			(xy 29.594373 -50.804703) (xy 29.586936 -50.797206) (xy 29.567878 -50.779053) (xy 29.534424 -50.738421)
			(xy 29.506867 -50.69358) (xy 29.485729 -50.645379) (xy 29.471411 -50.594732) (xy 29.464186 -50.542598)
			(xy 29.463746 -50.516282) (xy 29.464232 -50.489031) (xy 29.471988 -50.435083) (xy 29.487343 -50.382788)
			(xy 29.509985 -50.333211) (xy 29.539451 -50.287361) (xy 29.575142 -50.24617) (xy 29.616333 -50.210479)
			(xy 29.662183 -50.181013) (xy 29.71176 -50.158371) (xy 29.764055 -50.143016) (xy 29.818003 -50.13526)
			(xy 29.872505 -50.13526) (xy 29.926453 -50.143016) (xy 29.978748 -50.158371) (xy 30.028325 -50.181013)
			(xy 30.074175 -50.210479) (xy 30.115366 -50.24617) (xy 30.151057 -50.287361) (xy 30.180523 -50.333211)
			(xy 30.203165 -50.382788) (xy 30.21852 -50.435083) (xy 30.226276 -50.489031) (xy 30.226762 -50.516282)
			(xy 30.226295 -50.542596) (xy 30.219062 -50.594725) (xy 30.204743 -50.645368) (xy 30.183611 -50.693568)
			(xy 30.156064 -50.738411) (xy 30.122624 -50.77905) (xy 30.103572 -50.797206) (xy 30.096176 -50.804733)
			(xy 30.087646 -50.824008) (xy 30.087062 -50.834544) (xy 30.087062 -50.90922) (xy 30.087632 -50.919765)
			(xy 30.09614 -50.93906) (xy 30.103572 -50.946558) (xy 30.122643 -50.964698) (xy 30.1561 -51.00533)
			(xy 30.183658 -51.050174) (xy 30.204794 -51.098378) (xy 30.219107 -51.149028) (xy 30.226327 -51.201165)
			(xy 30.226762 -51.227482) (xy 30.226328 -51.254736) (xy 30.218572 -51.308691) (xy 30.203216 -51.360992)
			(xy 30.180572 -51.410575) (xy 30.151102 -51.456431) (xy 30.115405 -51.497625) (xy 30.074208 -51.533319)
			(xy 30.028351 -51.562786) (xy 29.978766 -51.585426) (xy 29.926463 -51.600778) (xy 29.872509 -51.60853)
			(xy 29.845254 -51.60899) (xy 29.826911 -51.608753) (xy 29.790398 -51.605193) (xy 29.772356 -51.601878)
			(xy 29.761724 -51.600299) (xy 29.740808 -51.60516) (xy 29.73197 -51.611276) (xy 29.662882 -51.6636)
			(xy 29.652468 -51.682396) (xy 29.651706 -51.693318) (xy 29.648761 -51.721569) (xy 29.635731 -51.776851)
			(xy 29.61465 -51.82959) (xy 29.585983 -51.878621) (xy 29.550365 -51.92286) (xy 29.508581 -51.961331)
			(xy 29.461557 -51.993182) (xy 29.41033 -52.01771) (xy 29.356033 -52.034373) (xy 29.299866 -52.042803)
			(xy 29.271468 -52.04333) (xy 29.244096 -52.0429) (xy 29.189915 -52.035076) (xy 29.137411 -52.019579)
			(xy 29.087664 -51.996729) (xy 29.0417 -51.966996) (xy 29.02077 -51.94935) (xy 29.020516 -51.949096)
			(xy 29.013429 -51.94351) (xy 28.996513 -51.937263) (xy 28.987496 -51.936904) (xy 28.92044 -51.936904)
			(xy 28.911425 -51.93728) (xy 28.894508 -51.943514) (xy 28.88742 -51.949096) (xy 28.88742 -51.94935)
			(xy 28.887166 -51.94935) (xy 28.866213 -51.966964) (xy 28.820247 -51.996681) (xy 28.770505 -52.019523)
			(xy 28.718008 -52.03502) (xy 28.663836 -52.042853) (xy 28.636468 -52.04333) (xy 28.60922 -52.042798)
			(xy 28.555279 -52.035038) (xy 28.502991 -52.019681) (xy 28.453421 -51.997039) (xy 28.407577 -51.967574)
			(xy 28.366393 -51.931884) (xy 28.330707 -51.890697) (xy 28.301245 -51.844851) (xy 28.278608 -51.795279)
			(xy 28.263255 -51.74299) (xy 28.2555 -51.689048) (xy 27.482429 -51.689048) (xy 27.518176 -51.706812)
			(xy 27.564496 -51.739128) (xy 27.605547 -51.777918) (xy 27.640432 -51.822335) (xy 27.668389 -51.871409)
			(xy 27.688807 -51.924069) (xy 27.70124 -51.979162) (xy 27.705415 -52.035486) (xy 27.701244 -52.091811)
			(xy 27.688815 -52.146905) (xy 27.668401 -52.199566) (xy 27.640448 -52.248642) (xy 27.605566 -52.293062)
			(xy 27.564517 -52.331855) (xy 27.518199 -52.364174) (xy 27.467623 -52.389312) (xy 27.44089 -52.398422)
			(xy 27.433016 -52.400962) (xy 27.420316 -52.41036) (xy 27.414728 -52.41798) (xy 27.410623 -52.424434)
			(xy 27.406102 -52.439038) (xy 27.405838 -52.446682) (xy 27.405838 -52.564157) (xy 29.827107 -52.564157)
			(xy 29.827107 -52.509643) (xy 29.834865 -52.455683) (xy 29.850224 -52.403377) (xy 29.872871 -52.353789)
			(xy 29.902345 -52.30793) (xy 29.938045 -52.266731) (xy 29.979246 -52.231033) (xy 30.025107 -52.201562)
			(xy 30.074696 -52.178917) (xy 30.127003 -52.163561) (xy 30.180963 -52.155806) (xy 30.20822 -52.155344)
			(xy 30.235591 -52.155788) (xy 30.289772 -52.163609) (xy 30.342275 -52.179103) (xy 30.392022 -52.20195)
			(xy 30.437987 -52.23168) (xy 30.458918 -52.249324) (xy 30.459172 -52.249578) (xy 30.466256 -52.255168)
			(xy 30.483175 -52.261411) (xy 30.492192 -52.26177) (xy 30.559248 -52.26177) (xy 30.568263 -52.261395)
			(xy 30.585181 -52.25516) (xy 30.592268 -52.249578) (xy 30.592268 -52.249324) (xy 30.592522 -52.249324)
			(xy 30.613476 -52.231712) (xy 30.659442 -52.201995) (xy 30.709184 -52.179154) (xy 30.76168 -52.163656)
			(xy 30.815852 -52.155821) (xy 30.84322 -52.155344) (xy 30.870467 -52.155928) (xy 30.924406 -52.163685)
			(xy 30.976691 -52.17904) (xy 31.02626 -52.20168) (xy 31.072102 -52.231143) (xy 31.113284 -52.26683)
			(xy 31.148969 -52.308014) (xy 31.17843 -52.353858) (xy 31.201067 -52.403427) (xy 31.216419 -52.455714)
			(xy 31.224174 -52.509653) (xy 31.224174 -52.564147) (xy 31.216419 -52.618086) (xy 31.201067 -52.670373)
			(xy 31.17843 -52.719942) (xy 31.148969 -52.765786) (xy 31.113284 -52.80697) (xy 31.072102 -52.842657)
			(xy 31.02626 -52.87212) (xy 30.976691 -52.89476) (xy 30.924406 -52.910115) (xy 30.870467 -52.917872)
			(xy 30.84322 -52.91836) (xy 30.81585 -52.917892) (xy 30.76167 -52.910076) (xy 30.709167 -52.894588)
			(xy 30.65942 -52.871746) (xy 30.613453 -52.842022) (xy 30.592522 -52.82438) (xy 30.592268 -52.824126)
			(xy 30.585172 -52.818553) (xy 30.568262 -52.8123) (xy 30.559248 -52.811934) (xy 30.492192 -52.811934)
			(xy 30.483174 -52.81228) (xy 30.466256 -52.818534) (xy 30.459172 -52.824126) (xy 30.459172 -52.82438)
			(xy 30.458918 -52.82438) (xy 30.437987 -52.842021) (xy 30.392015 -52.871733) (xy 30.342267 -52.894569)
			(xy 30.289766 -52.91006) (xy 30.235589 -52.917887) (xy 30.20822 -52.91836) (xy 30.180963 -52.917994)
			(xy 30.127003 -52.910239) (xy 30.074696 -52.894883) (xy 30.025107 -52.872238) (xy 29.979246 -52.842767)
			(xy 29.938045 -52.807069) (xy 29.902345 -52.76587) (xy 29.872871 -52.720011) (xy 29.850224 -52.670423)
			(xy 29.834865 -52.618117) (xy 29.827107 -52.564157) (xy 27.405838 -52.564157) (xy 27.405838 -52.64023)
			(xy 27.406101 -52.647873) (xy 27.410633 -52.662472) (xy 27.414728 -52.668932) (xy 27.420316 -52.676552)
			(xy 27.433016 -52.68595) (xy 27.44089 -52.68849) (xy 27.467598 -52.697678) (xy 27.518176 -52.722812)
			(xy 27.564496 -52.755128) (xy 27.605547 -52.793918) (xy 27.640432 -52.838335) (xy 27.668389 -52.887409)
			(xy 27.688807 -52.940069) (xy 27.70124 -52.995162) (xy 27.705415 -53.051486) (xy 27.701244 -53.107811)
			(xy 27.688815 -53.162905) (xy 27.668401 -53.215566) (xy 27.640448 -53.264642) (xy 27.605566 -53.309062)
			(xy 27.564517 -53.347855) (xy 27.518199 -53.380174) (xy 27.467623 -53.405312) (xy 27.44089 -53.414422)
			(xy 27.433016 -53.416962) (xy 27.420316 -53.42636) (xy 27.414728 -53.43398) (xy 27.410623 -53.440434)
			(xy 27.406102 -53.455038) (xy 27.405838 -53.462682) (xy 27.405838 -53.65623) (xy 27.406101 -53.663873)
			(xy 27.410633 -53.678472) (xy 27.414728 -53.684932) (xy 27.420316 -53.692552) (xy 27.433016 -53.70195)
			(xy 27.44089 -53.70449) (xy 27.467598 -53.713678) (xy 27.518176 -53.738812) (xy 27.564496 -53.771128)
			(xy 27.605547 -53.809918) (xy 27.640432 -53.854335) (xy 27.668389 -53.903409) (xy 27.688807 -53.956069)
			(xy 27.70124 -54.011162) (xy 27.705415 -54.067486) (xy 27.701244 -54.123811) (xy 27.688815 -54.178905)
			(xy 27.668401 -54.231566) (xy 27.66422 -54.238906) (xy 34.38601 -54.238906) (xy 34.390081 -54.183284)
			(xy 34.402207 -54.128847) (xy 34.42213 -54.076756) (xy 34.449426 -54.028121) (xy 34.483512 -53.983978)
			(xy 34.523661 -53.945269) (xy 34.569019 -53.912818) (xy 34.618619 -53.887317) (xy 34.671403 -53.86931)
			(xy 34.726246 -53.85918) (xy 34.78198 -53.857143) (xy 34.837417 -53.863243) (xy 34.891374 -53.877349)
			(xy 34.942703 -53.899161) (xy 34.990309 -53.928215) (xy 35.033177 -53.96389) (xy 35.070394 -54.005427)
			(xy 35.101167 -54.05194) (xy 35.124839 -54.102437) (xy 35.140907 -54.155844) (xy 35.149027 -54.21102)
			(xy 35.149536 -54.238906) (xy 35.149027 -54.266792) (xy 35.140907 -54.321968) (xy 35.124839 -54.375375)
			(xy 35.101167 -54.425872) (xy 35.070394 -54.472385) (xy 35.033177 -54.513922) (xy 34.990309 -54.549597)
			(xy 34.942703 -54.578651) (xy 34.891374 -54.600463) (xy 34.837417 -54.614569) (xy 34.78198 -54.620669)
			(xy 34.726246 -54.618632) (xy 34.671403 -54.608502) (xy 34.618619 -54.590495) (xy 34.569019 -54.564994)
			(xy 34.523661 -54.532543) (xy 34.483512 -54.493834) (xy 34.449426 -54.449691) (xy 34.42213 -54.401056)
			(xy 34.402207 -54.348965) (xy 34.390081 -54.294528) (xy 34.38601 -54.238906) (xy 27.66422 -54.238906)
			(xy 27.640448 -54.280642) (xy 27.605566 -54.325062) (xy 27.564517 -54.363855) (xy 27.518199 -54.396174)
			(xy 27.467623 -54.421312) (xy 27.44089 -54.430422) (xy 27.433016 -54.432962) (xy 27.420316 -54.44236)
			(xy 27.414728 -54.44998) (xy 27.410623 -54.456434) (xy 27.406102 -54.471038) (xy 27.405838 -54.478682)
			(xy 27.405838 -54.67223) (xy 27.406101 -54.679873) (xy 27.410633 -54.694472) (xy 27.414728 -54.700932)
			(xy 27.420316 -54.708552) (xy 27.433016 -54.71795) (xy 27.44089 -54.72049) (xy 27.467598 -54.729678)
			(xy 27.518176 -54.754812) (xy 27.564496 -54.787128) (xy 27.605547 -54.825918) (xy 27.640432 -54.870335)
			(xy 27.668389 -54.919409) (xy 27.688807 -54.972069) (xy 27.69264 -54.989055) (xy 29.901045 -54.989055)
			(xy 29.901045 -54.934545) (xy 29.908803 -54.880589) (xy 29.924161 -54.828287) (xy 29.946807 -54.778704)
			(xy 29.976279 -54.732848) (xy 30.011977 -54.691653) (xy 30.053175 -54.655958) (xy 30.099034 -54.62649)
			(xy 30.148619 -54.603849) (xy 30.200923 -54.588496) (xy 30.254879 -54.580743) (xy 30.282134 -54.580282)
			(xy 30.310226 -54.58075) (xy 30.365805 -54.588982) (xy 30.419575 -54.605278) (xy 30.470372 -54.629285)
			(xy 30.517098 -54.660484) (xy 30.558743 -54.698199) (xy 30.594404 -54.741616) (xy 30.609286 -54.765448)
			(xy 30.61462 -54.774338) (xy 30.631638 -54.78653) (xy 30.724856 -54.80685) (xy 30.74543 -54.802532)
			(xy 30.754066 -54.79669) (xy 30.778137 -54.780701) (xy 30.830066 -54.755356) (xy 30.885222 -54.738127)
			(xy 30.942344 -54.729409) (xy 30.971236 -54.728872) (xy 30.998487 -54.729344) (xy 31.052434 -54.737105)
			(xy 31.104728 -54.752464) (xy 31.154304 -54.775108) (xy 31.200153 -54.804576) (xy 31.241343 -54.840269)
			(xy 31.277034 -54.881459) (xy 31.3065 -54.92731) (xy 31.329142 -54.976887) (xy 31.344498 -55.029181)
			(xy 31.352257 -55.083129) (xy 31.352744 -55.11038) (xy 31.35228 -55.13775) (xy 31.344464 -55.19193)
			(xy 31.328975 -55.244434) (xy 31.306132 -55.294181) (xy 31.276406 -55.340147) (xy 31.258764 -55.361078)
			(xy 31.25851 -55.361332) (xy 31.252947 -55.368435) (xy 31.246686 -55.385339) (xy 31.246318 -55.394352)
			(xy 31.246318 -55.461408) (xy 31.246667 -55.470426) (xy 31.25292 -55.487343) (xy 31.25851 -55.494428)
			(xy 31.258764 -55.494428) (xy 31.258764 -55.494682) (xy 31.276385 -55.51563) (xy 31.306112 -55.561595)
			(xy 31.328959 -55.611339) (xy 31.344457 -55.663839) (xy 31.352288 -55.718015) (xy 31.35229 -55.772755)
			(xy 31.344463 -55.826932) (xy 31.328969 -55.879433) (xy 31.306126 -55.929178) (xy 31.276404 -55.975145)
			(xy 31.258764 -55.996078) (xy 31.25851 -55.996332) (xy 31.252947 -56.003435) (xy 31.246686 -56.020339)
			(xy 31.246318 -56.029352) (xy 31.246318 -56.096408) (xy 31.246667 -56.105426) (xy 31.25292 -56.122343)
			(xy 31.25851 -56.129428) (xy 31.258764 -56.129428) (xy 31.258764 -56.129682) (xy 31.276403 -56.150615)
			(xy 31.306116 -56.196587) (xy 31.328952 -56.246334) (xy 31.344443 -56.298835) (xy 31.352271 -56.353011)
			(xy 31.352744 -56.38038) (xy 31.352258 -56.407631) (xy 31.344502 -56.461579) (xy 31.329147 -56.513874)
			(xy 31.306505 -56.563451) (xy 31.277039 -56.609301) (xy 31.241348 -56.650492) (xy 31.200157 -56.686183)
			(xy 31.154307 -56.715649) (xy 31.10473 -56.738291) (xy 31.052435 -56.753646) (xy 30.998487 -56.761402)
			(xy 30.943985 -56.761402) (xy 30.890037 -56.753646) (xy 30.837742 -56.738291) (xy 30.788165 -56.715649)
			(xy 30.742315 -56.686183) (xy 30.701124 -56.650492) (xy 30.665433 -56.609301) (xy 30.635967 -56.563451)
			(xy 30.613325 -56.513874) (xy 30.59797 -56.461579) (xy 30.590214 -56.407631) (xy 30.589728 -56.38038)
			(xy 30.590176 -56.353009) (xy 30.597997 -56.298829) (xy 30.61349 -56.246325) (xy 30.636336 -56.196579)
			(xy 30.666065 -56.150613) (xy 30.683708 -56.129682) (xy 30.683962 -56.129428) (xy 30.68955 -56.122343)
			(xy 30.695794 -56.105425) (xy 30.696154 -56.096408) (xy 30.696154 -56.029352) (xy 30.695782 -56.020336)
			(xy 30.689546 -56.003419) (xy 30.683962 -55.996332) (xy 30.683708 -55.996332) (xy 30.683708 -55.996078)
			(xy 30.666049 -55.975161) (xy 30.636326 -55.92919) (xy 30.613483 -55.879441) (xy 30.597989 -55.826937)
			(xy 30.590163 -55.772756) (xy 30.590165 -55.718014) (xy 30.597995 -55.663834) (xy 30.613494 -55.611331)
			(xy 30.63634 -55.561584) (xy 30.666067 -55.515615) (xy 30.683708 -55.494682) (xy 30.683962 -55.494428)
			(xy 30.68955 -55.487343) (xy 30.695794 -55.470425) (xy 30.696154 -55.461408) (xy 30.696154 -55.394352)
			(xy 30.695782 -55.385336) (xy 30.689546 -55.368419) (xy 30.683962 -55.361332) (xy 30.683708 -55.360824)
			(xy 30.672765 -55.348089) (xy 30.652923 -55.320998) (xy 30.644084 -55.306722) (xy 30.63875 -55.297832)
			(xy 30.621732 -55.28564) (xy 30.528514 -55.26532) (xy 30.50794 -55.269638) (xy 30.499304 -55.27548)
			(xy 30.475239 -55.291478) (xy 30.423308 -55.316822) (xy 30.368151 -55.334048) (xy 30.311026 -55.342763)
			(xy 30.282134 -55.343298) (xy 30.254879 -55.342857) (xy 30.200923 -55.335104) (xy 30.148619 -55.319751)
			(xy 30.099034 -55.29711) (xy 30.053175 -55.267642) (xy 30.011977 -55.231947) (xy 29.976279 -55.190752)
			(xy 29.946807 -55.144896) (xy 29.924161 -55.095313) (xy 29.908803 -55.043011) (xy 29.901045 -54.989055)
			(xy 27.69264 -54.989055) (xy 27.70124 -55.027162) (xy 27.705415 -55.083486) (xy 27.701244 -55.139811)
			(xy 27.688815 -55.194905) (xy 27.668401 -55.247566) (xy 27.640448 -55.296642) (xy 27.605566 -55.341062)
			(xy 27.564517 -55.379855) (xy 27.518199 -55.412174) (xy 27.500733 -55.420855) (xy 28.224645 -55.420855)
			(xy 28.224645 -55.366345) (xy 28.232403 -55.312389) (xy 28.247761 -55.260087) (xy 28.270407 -55.210504)
			(xy 28.299879 -55.164648) (xy 28.335577 -55.123453) (xy 28.376775 -55.087758) (xy 28.422634 -55.05829)
			(xy 28.472219 -55.035649) (xy 28.524523 -55.020296) (xy 28.578479 -55.012543) (xy 28.605734 -55.012082)
			(xy 28.632048 -55.012533) (xy 28.684177 -55.019772) (xy 28.73482 -55.034094) (xy 28.783019 -55.05523)
			(xy 28.827862 -55.082779) (xy 28.868502 -55.11622) (xy 28.886658 -55.135272) (xy 28.894197 -55.142653)
			(xy 28.913464 -55.15119) (xy 28.923996 -55.151782) (xy 28.998672 -55.151782) (xy 29.009222 -55.151257)
			(xy 29.028518 -55.142719) (xy 29.03601 -55.135272) (xy 29.054162 -55.116213) (xy 29.094793 -55.082757)
			(xy 29.139634 -55.0552) (xy 29.187836 -55.034062) (xy 29.238484 -55.019745) (xy 29.290618 -55.012521)
			(xy 29.316934 -55.012082) (xy 29.344183 -55.012591) (xy 29.398125 -55.020351) (xy 29.450415 -55.035708)
			(xy 29.499986 -55.058351) (xy 29.545831 -55.087817) (xy 29.587016 -55.123508) (xy 29.622703 -55.164696)
			(xy 29.652165 -55.210544) (xy 29.674803 -55.260117) (xy 29.690156 -55.312408) (xy 29.697912 -55.366351)
			(xy 29.697912 -55.420849) (xy 29.690156 -55.474792) (xy 29.674803 -55.527083) (xy 29.652165 -55.576656)
			(xy 29.622703 -55.622504) (xy 29.587016 -55.663692) (xy 29.545831 -55.699383) (xy 29.499986 -55.728849)
			(xy 29.450415 -55.751492) (xy 29.398125 -55.766849) (xy 29.344183 -55.774609) (xy 29.316934 -55.775098)
			(xy 29.290619 -55.774675) (xy 29.238488 -55.767431) (xy 29.187844 -55.753104) (xy 29.139646 -55.731963)
			(xy 29.094803 -55.704409) (xy 29.054165 -55.670963) (xy 29.03601 -55.651908) (xy 29.028485 -55.64451)
			(xy 29.009208 -55.635983) (xy 28.998672 -55.635398) (xy 28.923996 -55.635398) (xy 28.913445 -55.635912)
			(xy 28.894149 -55.644458) (xy 28.886658 -55.651908) (xy 28.868517 -55.670978) (xy 28.827884 -55.704434)
			(xy 28.783041 -55.731991) (xy 28.734837 -55.753127) (xy 28.684187 -55.767441) (xy 28.632051 -55.774662)
			(xy 28.605734 -55.775098) (xy 28.578479 -55.774657) (xy 28.524523 -55.766904) (xy 28.472219 -55.751551)
			(xy 28.422634 -55.72891) (xy 28.376775 -55.699442) (xy 28.335577 -55.663747) (xy 28.299879 -55.622552)
			(xy 28.270407 -55.576696) (xy 28.247761 -55.527113) (xy 28.232403 -55.474811) (xy 28.224645 -55.420855)
			(xy 27.500733 -55.420855) (xy 27.467623 -55.437312) (xy 27.44089 -55.446422) (xy 27.433016 -55.448962)
			(xy 27.420316 -55.45836) (xy 27.414728 -55.46598) (xy 27.410623 -55.472434) (xy 27.406102 -55.487038)
			(xy 27.405838 -55.494682) (xy 27.405838 -55.94223) (xy 27.406101 -55.949873) (xy 27.410633 -55.964472)
			(xy 27.414728 -55.970932) (xy 27.420316 -55.978552) (xy 27.433016 -55.98795) (xy 27.44089 -55.99049)
			(xy 27.467598 -55.999678) (xy 27.518176 -56.024812) (xy 27.564496 -56.057128) (xy 27.605547 -56.095918)
			(xy 27.640432 -56.140335) (xy 27.668389 -56.189409) (xy 27.688807 -56.242069) (xy 27.70124 -56.297162)
			(xy 27.705415 -56.353486) (xy 27.701244 -56.409811) (xy 27.688815 -56.464905) (xy 27.668401 -56.517566)
			(xy 27.640448 -56.566642) (xy 27.605566 -56.611062) (xy 27.564517 -56.649855) (xy 27.518199 -56.682174)
			(xy 27.467623 -56.707312) (xy 27.44089 -56.716422) (xy 27.433016 -56.718962) (xy 27.420316 -56.72836)
			(xy 27.414728 -56.73598) (xy 27.410623 -56.742434) (xy 27.406102 -56.757038) (xy 27.405838 -56.764682)
			(xy 27.405838 -57.48528) (xy 30.605982 -57.48528) (xy 30.610053 -57.429658) (xy 30.622179 -57.375221)
			(xy 30.642102 -57.32313) (xy 30.669398 -57.274495) (xy 30.703484 -57.230352) (xy 30.743633 -57.191643)
			(xy 30.788991 -57.159192) (xy 30.838591 -57.133691) (xy 30.891375 -57.115684) (xy 30.946218 -57.105554)
			(xy 31.001952 -57.103517) (xy 31.057389 -57.109617) (xy 31.111346 -57.123723) (xy 31.162675 -57.145535)
			(xy 31.210281 -57.174589) (xy 31.253149 -57.210264) (xy 31.290366 -57.251801) (xy 31.321139 -57.298314)
			(xy 31.344811 -57.348811) (xy 31.360879 -57.402218) (xy 31.368999 -57.457394) (xy 31.369508 -57.48528)
			(xy 31.368999 -57.513166) (xy 31.360879 -57.568342) (xy 31.344811 -57.621749) (xy 31.321139 -57.672246)
			(xy 31.290366 -57.718759) (xy 31.253149 -57.760296) (xy 31.210281 -57.795971) (xy 31.162675 -57.825025)
			(xy 31.111346 -57.846837) (xy 31.057389 -57.860943) (xy 31.001952 -57.867043) (xy 30.946218 -57.865006)
			(xy 30.891375 -57.854876) (xy 30.838591 -57.836869) (xy 30.788991 -57.811368) (xy 30.743633 -57.778917)
			(xy 30.703484 -57.740208) (xy 30.669398 -57.696065) (xy 30.642102 -57.64743) (xy 30.622179 -57.595339)
			(xy 30.610053 -57.540902) (xy 30.605982 -57.48528) (xy 27.405838 -57.48528) (xy 27.405838 -58.076084)
			(xy 31.358076 -58.076084) (xy 31.362147 -58.020462) (xy 31.374273 -57.966025) (xy 31.394196 -57.913934)
			(xy 31.421492 -57.865299) (xy 31.455578 -57.821156) (xy 31.495727 -57.782447) (xy 31.541085 -57.749996)
			(xy 31.590685 -57.724495) (xy 31.643469 -57.706488) (xy 31.698312 -57.696358) (xy 31.754046 -57.694321)
			(xy 31.809483 -57.700421) (xy 31.86344 -57.714527) (xy 31.914769 -57.736339) (xy 31.962375 -57.765393)
			(xy 32.005243 -57.801068) (xy 32.04246 -57.842605) (xy 32.058796 -57.867296) (xy 33.642806 -57.867296)
			(xy 33.646879 -57.811637) (xy 33.659014 -57.757164) (xy 33.67895 -57.705038) (xy 33.706264 -57.65637)
			(xy 33.740372 -57.612198) (xy 33.780549 -57.573463) (xy 33.825937 -57.540991) (xy 33.875569 -57.515473)
			(xy 33.928389 -57.497454) (xy 33.983268 -57.487317) (xy 34.039039 -57.485279) (xy 34.094513 -57.491382)
			(xy 34.148506 -57.505498) (xy 34.199869 -57.527325) (xy 34.247507 -57.556398) (xy 34.290403 -57.592097)
			(xy 34.327645 -57.633661) (xy 34.358439 -57.680205) (xy 34.382127 -57.730736) (xy 34.398205 -57.784178)
			(xy 34.406331 -57.839392) (xy 34.40684 -57.867296) (xy 34.406331 -57.8952) (xy 34.398205 -57.950414)
			(xy 34.382127 -58.003856) (xy 34.358439 -58.054387) (xy 34.327645 -58.100931) (xy 34.290403 -58.142495)
			(xy 34.247507 -58.178194) (xy 34.199869 -58.207267) (xy 34.148506 -58.229094) (xy 34.094513 -58.24321)
			(xy 34.039039 -58.249313) (xy 33.983268 -58.247275) (xy 33.928389 -58.237138) (xy 33.875569 -58.219119)
			(xy 33.825937 -58.193601) (xy 33.780549 -58.161129) (xy 33.740372 -58.122394) (xy 33.706264 -58.078222)
			(xy 33.67895 -58.029554) (xy 33.659014 -57.977428) (xy 33.646879 -57.922955) (xy 33.642806 -57.867296)
			(xy 32.058796 -57.867296) (xy 32.073233 -57.889118) (xy 32.096905 -57.939615) (xy 32.112973 -57.993022)
			(xy 32.121093 -58.048198) (xy 32.121602 -58.076084) (xy 32.121093 -58.10397) (xy 32.112973 -58.159146)
			(xy 32.096905 -58.212553) (xy 32.073233 -58.26305) (xy 32.04246 -58.309563) (xy 32.005243 -58.3511)
			(xy 31.962375 -58.386775) (xy 31.914769 -58.415829) (xy 31.86344 -58.437641) (xy 31.809483 -58.451747)
			(xy 31.754046 -58.457847) (xy 31.698312 -58.45581) (xy 31.643469 -58.44568) (xy 31.590685 -58.427673)
			(xy 31.541085 -58.402172) (xy 31.495727 -58.369721) (xy 31.455578 -58.331012) (xy 31.421492 -58.286869)
			(xy 31.394196 -58.238234) (xy 31.374273 -58.186143) (xy 31.362147 -58.131706) (xy 31.358076 -58.076084)
			(xy 27.405838 -58.076084) (xy 27.405838 -58.561224) (xy 32.56229 -58.561224) (xy 32.566361 -58.505602)
			(xy 32.578487 -58.451165) (xy 32.59841 -58.399074) (xy 32.625706 -58.350439) (xy 32.659792 -58.306296)
			(xy 32.699941 -58.267587) (xy 32.745299 -58.235136) (xy 32.794899 -58.209635) (xy 32.847683 -58.191628)
			(xy 32.902526 -58.181498) (xy 32.95826 -58.179461) (xy 33.013697 -58.185561) (xy 33.067654 -58.199667)
			(xy 33.118983 -58.221479) (xy 33.166589 -58.250533) (xy 33.209457 -58.286208) (xy 33.246674 -58.327745)
			(xy 33.277447 -58.374258) (xy 33.301119 -58.424755) (xy 33.308629 -58.449718) (xy 34.80892 -58.449718)
			(xy 34.812991 -58.394096) (xy 34.825117 -58.339659) (xy 34.84504 -58.287568) (xy 34.872336 -58.238933)
			(xy 34.906422 -58.19479) (xy 34.946571 -58.156081) (xy 34.991929 -58.12363) (xy 35.041529 -58.098129)
			(xy 35.094313 -58.080122) (xy 35.149156 -58.069992) (xy 35.20489 -58.067955) (xy 35.260327 -58.074055)
			(xy 35.314284 -58.088161) (xy 35.365613 -58.109973) (xy 35.413219 -58.139027) (xy 35.456087 -58.174702)
			(xy 35.493304 -58.216239) (xy 35.524077 -58.262752) (xy 35.547749 -58.313249) (xy 35.563817 -58.366656)
			(xy 35.571937 -58.421832) (xy 35.572446 -58.449718) (xy 35.571937 -58.477604) (xy 35.563817 -58.53278)
			(xy 35.547749 -58.586187) (xy 35.524077 -58.636684) (xy 35.493304 -58.683197) (xy 35.456087 -58.724734)
			(xy 35.413219 -58.760409) (xy 35.365613 -58.789463) (xy 35.314284 -58.811275) (xy 35.260327 -58.825381)
			(xy 35.20489 -58.831481) (xy 35.149156 -58.829444) (xy 35.094313 -58.819314) (xy 35.041529 -58.801307)
			(xy 34.991929 -58.775806) (xy 34.946571 -58.743355) (xy 34.906422 -58.704646) (xy 34.872336 -58.660503)
			(xy 34.84504 -58.611868) (xy 34.825117 -58.559777) (xy 34.812991 -58.50534) (xy 34.80892 -58.449718)
			(xy 33.308629 -58.449718) (xy 33.317187 -58.478162) (xy 33.325307 -58.533338) (xy 33.325816 -58.561224)
			(xy 33.325307 -58.58911) (xy 33.317187 -58.644286) (xy 33.301119 -58.697693) (xy 33.277447 -58.74819)
			(xy 33.246674 -58.794703) (xy 33.209457 -58.83624) (xy 33.166589 -58.871915) (xy 33.118983 -58.900969)
			(xy 33.067654 -58.922781) (xy 33.013697 -58.936887) (xy 32.95826 -58.942987) (xy 32.902526 -58.94095)
			(xy 32.847683 -58.93082) (xy 32.794899 -58.912813) (xy 32.745299 -58.887312) (xy 32.699941 -58.854861)
			(xy 32.659792 -58.816152) (xy 32.625706 -58.772009) (xy 32.59841 -58.723374) (xy 32.578487 -58.671283)
			(xy 32.566361 -58.616846) (xy 32.56229 -58.561224) (xy 27.405838 -58.561224) (xy 27.405838 -59.974734)
			(xy 31.08706 -59.974734) (xy 31.087509 -59.947908) (xy 31.095029 -59.894785) (xy 31.109911 -59.843238)
			(xy 31.131861 -59.794281) (xy 31.160449 -59.748879) (xy 31.195111 -59.707926) (xy 31.235164 -59.672228)
			(xy 31.25724 -59.65698) (xy 31.268805 -59.648762) (xy 31.287205 -59.62718) (xy 31.298956 -59.601368)
			(xy 31.30315 -59.573319) (xy 31.299462 -59.545199) (xy 31.288178 -59.51918) (xy 31.27017 -59.497271)
			(xy 31.258764 -59.488832) (xy 31.237304 -59.473483) (xy 31.198393 -59.437855) (xy 31.164761 -59.397205)
			(xy 31.137051 -59.352309) (xy 31.115791 -59.304023) (xy 31.101386 -59.253269) (xy 31.094112 -59.201013)
			(xy 31.093664 -59.174634) (xy 31.09415 -59.147383) (xy 31.101906 -59.093435) (xy 31.117261 -59.04114)
			(xy 31.139903 -58.991563) (xy 31.169369 -58.945713) (xy 31.20506 -58.904522) (xy 31.246251 -58.868831)
			(xy 31.292101 -58.839365) (xy 31.341678 -58.816723) (xy 31.393973 -58.801368) (xy 31.447921 -58.793612)
			(xy 31.502423 -58.793612) (xy 31.556371 -58.801368) (xy 31.608666 -58.816723) (xy 31.658243 -58.839365)
			(xy 31.704093 -58.868831) (xy 31.745284 -58.904522) (xy 31.780975 -58.945713) (xy 31.810441 -58.991563)
			(xy 31.833083 -59.04114) (xy 31.848438 -59.093435) (xy 31.856194 -59.147383) (xy 31.85668 -59.174634)
			(xy 31.856233 -59.201461) (xy 31.848716 -59.254585) (xy 31.833836 -59.306133) (xy 31.811886 -59.355091)
			(xy 31.783297 -59.400493) (xy 31.748633 -59.441445) (xy 31.708577 -59.477141) (xy 31.6865 -59.492388)
			(xy 31.674963 -59.500644) (xy 31.656556 -59.522215) (xy 31.644799 -59.548019) (xy 31.640599 -59.576063)
			(xy 31.644283 -59.604179) (xy 31.655564 -59.630195) (xy 31.673571 -59.6521) (xy 31.684976 -59.660536)
			(xy 31.706476 -59.67583) (xy 31.745385 -59.711469) (xy 31.779013 -59.752129) (xy 31.806717 -59.797034)
			(xy 31.827971 -59.845329) (xy 31.842367 -59.896091) (xy 31.849632 -59.948352) (xy 31.850076 -59.974734)
			(xy 31.84959 -60.001985) (xy 31.841834 -60.055933) (xy 31.826479 -60.108228) (xy 31.803837 -60.157805)
			(xy 31.774371 -60.203655) (xy 31.73868 -60.244846) (xy 31.697489 -60.280537) (xy 31.651639 -60.310003)
			(xy 31.602062 -60.332645) (xy 31.549767 -60.348) (xy 31.495819 -60.355756) (xy 31.441317 -60.355756)
			(xy 31.387369 -60.348) (xy 31.335074 -60.332645) (xy 31.285497 -60.310003) (xy 31.239647 -60.280537)
			(xy 31.198456 -60.244846) (xy 31.162765 -60.203655) (xy 31.133299 -60.157805) (xy 31.110657 -60.108228)
			(xy 31.095302 -60.055933) (xy 31.087546 -60.001985) (xy 31.08706 -59.974734) (xy 27.405838 -59.974734)
			(xy 27.405838 -60.601606) (xy 30.333186 -60.601606) (xy 30.337257 -60.545984) (xy 30.349383 -60.491547)
			(xy 30.369306 -60.439456) (xy 30.396602 -60.390821) (xy 30.430688 -60.346678) (xy 30.470837 -60.307969)
			(xy 30.516195 -60.275518) (xy 30.565795 -60.250017) (xy 30.618579 -60.23201) (xy 30.673422 -60.22188)
			(xy 30.729156 -60.219843) (xy 30.784593 -60.225943) (xy 30.83855 -60.240049) (xy 30.889879 -60.261861)
			(xy 30.937485 -60.290915) (xy 30.980353 -60.32659) (xy 31.01757 -60.368127) (xy 31.048343 -60.41464)
			(xy 31.072015 -60.465137) (xy 31.088083 -60.518544) (xy 31.096203 -60.57372) (xy 31.096712 -60.601606)
			(xy 31.096248 -60.627006) (xy 32.721294 -60.627006) (xy 32.725365 -60.571384) (xy 32.737491 -60.516947)
			(xy 32.757414 -60.464856) (xy 32.78471 -60.416221) (xy 32.818796 -60.372078) (xy 32.858945 -60.333369)
			(xy 32.904303 -60.300918) (xy 32.953903 -60.275417) (xy 33.006687 -60.25741) (xy 33.06153 -60.24728)
			(xy 33.117264 -60.245243) (xy 33.172701 -60.251343) (xy 33.226658 -60.265449) (xy 33.277987 -60.287261)
			(xy 33.325593 -60.316315) (xy 33.368461 -60.35199) (xy 33.405678 -60.393527) (xy 33.436451 -60.44004)
			(xy 33.460123 -60.490537) (xy 33.476191 -60.543944) (xy 33.484311 -60.59912) (xy 33.48482 -60.627006)
			(xy 33.484311 -60.654892) (xy 33.476191 -60.710068) (xy 33.460123 -60.763475) (xy 33.436451 -60.813972)
			(xy 33.405678 -60.860485) (xy 33.368461 -60.902022) (xy 33.325593 -60.937697) (xy 33.277987 -60.966751)
			(xy 33.226658 -60.988563) (xy 33.172701 -61.002669) (xy 33.117264 -61.008769) (xy 33.06153 -61.006732)
			(xy 33.006687 -60.996602) (xy 32.953903 -60.978595) (xy 32.904303 -60.953094) (xy 32.858945 -60.920643)
			(xy 32.818796 -60.881934) (xy 32.78471 -60.837791) (xy 32.757414 -60.789156) (xy 32.737491 -60.737065)
			(xy 32.725365 -60.682628) (xy 32.721294 -60.627006) (xy 31.096248 -60.627006) (xy 31.096203 -60.629492)
			(xy 31.088083 -60.684668) (xy 31.072015 -60.738075) (xy 31.048343 -60.788572) (xy 31.01757 -60.835085)
			(xy 30.980353 -60.876622) (xy 30.937485 -60.912297) (xy 30.889879 -60.941351) (xy 30.83855 -60.963163)
			(xy 30.784593 -60.977269) (xy 30.729156 -60.983369) (xy 30.673422 -60.981332) (xy 30.618579 -60.971202)
			(xy 30.565795 -60.953195) (xy 30.516195 -60.927694) (xy 30.470837 -60.895243) (xy 30.430688 -60.856534)
			(xy 30.396602 -60.812391) (xy 30.369306 -60.763756) (xy 30.349383 -60.711665) (xy 30.337257 -60.657228)
			(xy 30.333186 -60.601606) (xy 27.405838 -60.601606) (xy 27.405838 -61.328046) (xy 27.406854 -61.337444)
			(xy 27.406854 -61.337952) (xy 27.408553 -61.345114) (xy 27.415376 -61.35815) (xy 27.420316 -61.363606)
			(xy 27.614118 -61.557408) (xy 27.621495 -61.564001) (xy 27.639795 -61.571471) (xy 27.649678 -61.571886)
			(xy 27.65933 -61.571886)
		)
		(stroke
			(width 0)
			(type solid)
		)
		(fill yes)
		(layer "In9.Cu")
		(net "P3V3_SSD1")
	)
	(gr_poly
		(pts
			(xy 199.128888 -61.576712) (xy 199.163432 -61.57468) (xy 200.297288 -61.57468) (xy 200.306432 -61.573918)
			(xy 200.31075 -61.573156) (xy 200.318058 -61.571551) (xy 200.33135 -61.564699) (xy 200.336912 -61.559694)
			(xy 200.384918 -61.51372) (xy 200.391555 -61.506755) (xy 200.399536 -61.489264) (xy 200.400412 -61.479684)
			(xy 200.400412 -61.478668) (xy 200.401918 -61.451595) (xy 200.411625 -61.398249) (xy 200.42878 -61.346813)
			(xy 200.453039 -61.298321) (xy 200.483913 -61.253748) (xy 200.502012 -61.233558) (xy 200.50252 -61.23305)
			(xy 200.503282 -61.232288) (xy 200.504806 -61.23051) (xy 200.505314 -61.230002) (xy 200.506584 -61.228478)
			(xy 200.524714 -61.209567) (xy 200.565257 -61.176388) (xy 200.609956 -61.149065) (xy 200.657972 -61.12811)
			(xy 200.708401 -61.113917) (xy 200.760298 -61.106752) (xy 200.786492 -61.106304) (xy 200.813504 -61.106772)
			(xy 200.866987 -61.11439) (xy 200.918862 -61.129475) (xy 200.96809 -61.151726) (xy 201.013688 -61.180698)
			(xy 201.054744 -61.21581) (xy 201.090438 -61.256363) (xy 201.120055 -61.301544) (xy 201.143005 -61.350451)
			(xy 201.158827 -61.402105) (xy 201.167205 -61.455475) (xy 201.168 -61.482478) (xy 201.168254 -61.492892)
			(xy 201.176128 -61.51118) (xy 201.220324 -61.553852) (xy 201.226166 -61.55944) (xy 201.231764 -61.564538)
			(xy 201.24519 -61.571521) (xy 201.252582 -61.573156) (xy 201.261472 -61.57468) (xy 202.243182 -61.57468)
			(xy 202.252156 -61.574729) (xy 202.270074 -61.575744) (xy 202.278996 -61.576712) (xy 203.143104 -61.576712)
			(xy 203.152026 -61.575744) (xy 203.169944 -61.574725) (xy 203.178918 -61.57468) (xy 204.853286 -61.57468)
			(xy 204.859581 -61.574494) (xy 204.871789 -61.571411) (xy 204.877416 -61.568584) (xy 204.88402 -61.565028)
			(xy 205.512416 -60.936632) (xy 205.515464 -60.93333) (xy 205.525878 -60.922916) (xy 205.528552 -60.917445)
			(xy 205.531506 -60.905634) (xy 205.53172 -60.899548) (xy 205.53172 -38.90645) (xy 205.530958 -38.897306)
			(xy 205.528164 -38.882574) (xy 205.519782 -38.867842) (xy 205.513178 -38.862) (xy 205.480519 -38.83269)
			(xy 205.420212 -38.768934) (xy 205.366109 -38.699836) (xy 205.318681 -38.625996) (xy 205.27834 -38.548058)
			(xy 205.245439 -38.466699) (xy 205.220262 -38.382628) (xy 205.20303 -38.296577) (xy 205.193893 -38.209295)
			(xy 205.192929 -38.12154) (xy 205.200148 -38.034078) (xy 205.215486 -37.94767) (xy 205.23881 -37.863066)
			(xy 205.269917 -37.781005) (xy 205.308536 -37.702199) (xy 205.354332 -37.627336) (xy 205.406904 -37.557066)
			(xy 205.435962 -37.524182) (xy 205.440534 -37.519102) (xy 205.440788 -37.518594) (xy 205.452456 -37.505892)
			(xy 205.476592 -37.481248) (xy 205.489048 -37.469318) (xy 205.50251 -37.457126) (xy 205.502764 -37.456872)
			(xy 205.507082 -37.452808) (xy 205.511146 -37.448998) (xy 205.517242 -37.440616) (xy 205.527402 -37.417248)
			(xy 205.529404 -37.412408) (xy 205.53158 -37.402164) (xy 205.53172 -37.396928) (xy 205.53172 -31.777432)
			(xy 205.528926 -31.769304) (xy 205.51877 -31.738539) (xy 205.507792 -31.674694) (xy 205.507082 -31.642304)
			(xy 205.507792 -31.609914) (xy 205.518779 -31.546072) (xy 205.528926 -31.515304) (xy 205.53172 -31.507176)
			(xy 205.53172 -31.238444) (xy 205.531834 -31.233488) (xy 205.533742 -31.223763) (xy 205.53553 -31.21914)
			(xy 205.54061 -31.207202) (xy 205.542408 -31.202515) (xy 205.544326 -31.192663) (xy 205.54442 -31.187644)
			(xy 205.54442 -29.841952) (xy 205.544158 -29.834014) (xy 205.539375 -29.818878) (xy 205.535022 -29.812234)
			(xy 205.518169 -29.787795) (xy 205.49143 -29.734798) (xy 205.473217 -29.6783) (xy 205.463969 -29.619664)
			(xy 205.463394 -29.589984) (xy 205.463976 -29.560303) (xy 205.473209 -29.501664) (xy 205.491417 -29.445164)
			(xy 205.518162 -29.392168) (xy 205.535022 -29.367734) (xy 205.539386 -29.361094) (xy 205.544189 -29.345957)
			(xy 205.54442 -29.338016) (xy 205.54442 -28.112974) (xy 205.54454 -28.108426) (xy 205.546194 -28.099479)
			(xy 205.547722 -28.095194) (xy 205.549487 -28.090051) (xy 205.55102 -28.07929) (xy 205.55077 -28.073858)
			(xy 205.548484 -28.044394) (xy 205.547749 -28.037201) (xy 205.542716 -28.023653) (xy 205.538578 -28.017724)
			(xy 205.520891 -27.992879) (xy 205.492804 -27.938748) (xy 205.473676 -27.880842) (xy 205.463994 -27.820632)
			(xy 205.463394 -27.79014) (xy 205.463855 -27.762885) (xy 205.471607 -27.70893) (xy 205.48696 -27.656628)
			(xy 205.5096 -27.607043) (xy 205.539067 -27.561185) (xy 205.57476 -27.519987) (xy 205.615954 -27.48429)
			(xy 205.661809 -27.454818) (xy 205.711392 -27.432173) (xy 205.763693 -27.416815) (xy 205.817647 -27.409057)
			(xy 205.844902 -27.408632) (xy 205.87045 -27.409041) (xy 205.921088 -27.415856) (xy 205.970365 -27.429365)
			(xy 206.0174 -27.449326) (xy 206.061353 -27.475383) (xy 206.08163 -27.490928) (xy 206.097124 -27.50312)
			(xy 206.135224 -27.501088) (xy 206.28864 -27.347672) (xy 206.296037 -27.340824) (xy 206.314636 -27.333093)
			(xy 206.324708 -27.332686) (xy 206.470758 -27.332686) (xy 206.476092 -27.33167) (xy 206.476854 -27.33167)
			(xy 206.48041 -27.330908) (xy 206.481172 -27.330908) (xy 206.484728 -27.3304) (xy 206.484982 -27.3304)
			(xy 206.485236 -27.3304) (xy 206.502762 -27.328368) (xy 206.5274 -27.327352) (xy 210.572858 -27.327352)
			(xy 210.582835 -27.326942) (xy 210.601275 -27.319318) (xy 210.615391 -27.305215) (xy 210.623032 -27.286783)
			(xy 210.623404 -27.276806) (xy 210.623404 -26.479246) (xy 210.623576 -26.463316) (xy 210.625864 -26.431537)
			(xy 210.627976 -26.415746) (xy 210.627976 -26.415238) (xy 210.628992 -26.409396) (xy 210.628992 -26.408888)
			(xy 210.631532 -26.39441) (xy 210.632802 -26.387044) (xy 210.631278 -26.372566) (xy 210.628484 -26.365708)
			(xy 210.625498 -26.358991) (xy 210.61634 -26.3475) (xy 210.61045 -26.343102) (xy 210.60283 -26.337768)
			(xy 210.576668 -26.31948) (xy 210.553969 -26.333025) (xy 210.505625 -26.3544) (xy 210.454789 -26.368879)
			(xy 210.402437 -26.376182) (xy 210.376008 -26.37663) (xy 210.348756 -26.376145) (xy 210.294806 -26.368389)
			(xy 210.242509 -26.353035) (xy 210.192929 -26.330395) (xy 210.147076 -26.300929) (xy 210.105883 -26.265238)
			(xy 210.070189 -26.224048) (xy 210.04072 -26.178197) (xy 210.018075 -26.128619) (xy 210.002717 -26.076323)
			(xy 209.994957 -26.022374) (xy 209.9945 -25.995122) (xy 209.99504 -25.965825) (xy 210.004006 -25.907922)
			(xy 210.021716 -25.852068) (xy 210.047753 -25.799578) (xy 210.081506 -25.751682) (xy 210.101434 -25.7302)
			(xy 210.102196 -25.729438) (xy 210.102704 -25.72893) (xy 210.120807 -25.710287) (xy 210.161187 -25.677579)
			(xy 210.205632 -25.650653) (xy 210.25332 -25.630007) (xy 210.303368 -25.616025) (xy 210.354852 -25.608964)
			(xy 210.380834 -25.608534) (xy 210.409783 -25.609073) (xy 210.467016 -25.617826) (xy 210.52227 -25.635124)
			(xy 210.574276 -25.660572) (xy 210.62184 -25.693585) (xy 210.663871 -25.733405) (xy 210.699404 -25.779118)
			(xy 210.727622 -25.829675) (xy 210.72851 -25.832054) (xy 212.287864 -25.832054) (xy 212.291935 -25.776432)
			(xy 212.304061 -25.721995) (xy 212.323984 -25.669904) (xy 212.35128 -25.621269) (xy 212.385366 -25.577126)
			(xy 212.425515 -25.538417) (xy 212.470873 -25.505966) (xy 212.520473 -25.480465) (xy 212.573257 -25.462458)
			(xy 212.6281 -25.452328) (xy 212.683834 -25.450291) (xy 212.739271 -25.456391) (xy 212.793228 -25.470497)
			(xy 212.844557 -25.492309) (xy 212.892163 -25.521363) (xy 212.935031 -25.557038) (xy 212.936565 -25.55875)
			(xy 216.742264 -25.55875) (xy 216.74275 -25.531499) (xy 216.750506 -25.477551) (xy 216.765861 -25.425256)
			(xy 216.788503 -25.375679) (xy 216.817969 -25.329829) (xy 216.85366 -25.288638) (xy 216.894851 -25.252947)
			(xy 216.940701 -25.223481) (xy 216.990278 -25.200839) (xy 217.042573 -25.185484) (xy 217.096521 -25.177728)
			(xy 217.151023 -25.177728) (xy 217.204971 -25.185484) (xy 217.257266 -25.200839) (xy 217.306843 -25.223481)
			(xy 217.352693 -25.252947) (xy 217.393884 -25.288638) (xy 217.429575 -25.329829) (xy 217.459041 -25.375679)
			(xy 217.481683 -25.425256) (xy 217.497038 -25.477551) (xy 217.504794 -25.531499) (xy 217.50528 -25.55875)
			(xy 217.504716 -25.589012) (xy 217.495165 -25.648778) (xy 217.476294 -25.706285) (xy 217.448578 -25.76009)
			(xy 217.431112 -25.78481) (xy 217.422806 -25.796941) (xy 217.41285 -25.82459) (xy 217.41118 -25.85393)
			(xy 217.417936 -25.88253) (xy 217.432557 -25.908021) (xy 217.453833 -25.928293) (xy 217.480001 -25.941666)
			(xy 217.494358 -25.94483) (xy 217.52026 -25.950132) (xy 217.570383 -25.966955) (xy 217.617701 -25.99054)
			(xy 217.661309 -26.020435) (xy 217.700369 -26.056066) (xy 217.734134 -26.096751) (xy 217.761956 -26.141709)
			(xy 217.783302 -26.190079) (xy 217.797762 -26.240934) (xy 217.80506 -26.293299) (xy 217.805508 -26.319734)
			(xy 218.941902 -26.319734) (xy 218.945973 -26.264112) (xy 218.958099 -26.209675) (xy 218.978022 -26.157584)
			(xy 219.005318 -26.108949) (xy 219.039404 -26.064806) (xy 219.079553 -26.026097) (xy 219.124911 -25.993646)
			(xy 219.174511 -25.968145) (xy 219.227295 -25.950138) (xy 219.282138 -25.940008) (xy 219.337872 -25.937971)
			(xy 219.393309 -25.944071) (xy 219.447266 -25.958177) (xy 219.498595 -25.979989) (xy 219.546201 -26.009043)
			(xy 219.589069 -26.044718) (xy 219.626286 -26.086255) (xy 219.657059 -26.132768) (xy 219.680731 -26.183265)
			(xy 219.696799 -26.236672) (xy 219.704919 -26.291848) (xy 219.705428 -26.319734) (xy 219.704919 -26.34762)
			(xy 219.696799 -26.402796) (xy 219.680731 -26.456203) (xy 219.657059 -26.5067) (xy 219.626286 -26.553213)
			(xy 219.589069 -26.59475) (xy 219.546201 -26.630425) (xy 219.498595 -26.659479) (xy 219.447266 -26.681291)
			(xy 219.393309 -26.695397) (xy 219.337872 -26.701497) (xy 219.282138 -26.69946) (xy 219.227295 -26.68933)
			(xy 219.174511 -26.671323) (xy 219.124911 -26.645822) (xy 219.079553 -26.613371) (xy 219.039404 -26.574662)
			(xy 219.005318 -26.530519) (xy 218.978022 -26.481884) (xy 218.958099 -26.429793) (xy 218.945973 -26.375356)
			(xy 218.941902 -26.319734) (xy 217.805508 -26.319734) (xy 217.805022 -26.346985) (xy 217.797266 -26.400933)
			(xy 217.781911 -26.453228) (xy 217.759269 -26.502805) (xy 217.729803 -26.548655) (xy 217.694112 -26.589846)
			(xy 217.652921 -26.625537) (xy 217.607071 -26.655003) (xy 217.557494 -26.677645) (xy 217.505199 -26.693)
			(xy 217.451251 -26.700756) (xy 217.396749 -26.700756) (xy 217.342801 -26.693) (xy 217.290506 -26.677645)
			(xy 217.240929 -26.655003) (xy 217.195079 -26.625537) (xy 217.153888 -26.589846) (xy 217.118197 -26.548655)
			(xy 217.088731 -26.502805) (xy 217.066089 -26.453228) (xy 217.050734 -26.400933) (xy 217.042978 -26.346985)
			(xy 217.042492 -26.319734) (xy 217.043053 -26.289472) (xy 217.052606 -26.229706) (xy 217.071478 -26.172199)
			(xy 217.099194 -26.118394) (xy 217.11666 -26.093674) (xy 217.125003 -26.081565) (xy 217.134961 -26.053909)
			(xy 217.136629 -26.024561) (xy 217.129869 -25.995954) (xy 217.11524 -25.970458) (xy 217.093954 -25.950185)
			(xy 217.067776 -25.936815) (xy 217.053414 -25.933654) (xy 217.02752 -25.928315) (xy 216.977396 -25.911499)
			(xy 216.930076 -25.887921) (xy 216.886466 -25.858032) (xy 216.847404 -25.822406) (xy 216.813637 -25.781725)
			(xy 216.785814 -25.736769) (xy 216.764468 -25.688401) (xy 216.750008 -25.637548) (xy 216.742711 -25.585185)
			(xy 216.742264 -25.55875) (xy 212.936565 -25.55875) (xy 212.972248 -25.598575) (xy 213.003021 -25.645088)
			(xy 213.026693 -25.695585) (xy 213.042761 -25.748992) (xy 213.050881 -25.804168) (xy 213.05139 -25.832054)
			(xy 213.050881 -25.85994) (xy 213.042761 -25.915116) (xy 213.026693 -25.968523) (xy 213.003021 -26.01902)
			(xy 212.972248 -26.065533) (xy 212.935031 -26.10707) (xy 212.892163 -26.142745) (xy 212.844557 -26.171799)
			(xy 212.793228 -26.193611) (xy 212.739271 -26.207717) (xy 212.683834 -26.213817) (xy 212.6281 -26.21178)
			(xy 212.573257 -26.20165) (xy 212.520473 -26.183643) (xy 212.470873 -26.158142) (xy 212.425515 -26.125691)
			(xy 212.385366 -26.086982) (xy 212.35128 -26.042839) (xy 212.323984 -25.994204) (xy 212.304061 -25.942113)
			(xy 212.291935 -25.887676) (xy 212.287864 -25.832054) (xy 210.72851 -25.832054) (xy 210.747878 -25.883914)
			(xy 210.759707 -25.940592) (xy 210.761834 -25.969468) (xy 210.761834 -25.969976) (xy 210.763269 -25.982101)
			(xy 210.775747 -26.003046) (xy 210.78571 -26.010108) (xy 210.821016 -26.031952) (xy 210.866736 -26.0604)
			(xy 210.891374 -26.062432) (xy 210.902804 -26.057606) (xy 210.930799 -26.046253) (xy 210.989034 -26.030179)
			(xy 211.048877 -26.02191) (xy 211.07908 -26.021284) (xy 211.081366 -26.021284) (xy 211.111352 -26.021751)
			(xy 211.170811 -26.029575) (xy 211.228741 -26.045095) (xy 211.284148 -26.068043) (xy 211.336086 -26.098028)
			(xy 211.383665 -26.134537) (xy 211.426071 -26.176944) (xy 211.462578 -26.224524) (xy 211.492562 -26.276463)
			(xy 211.515509 -26.331871) (xy 211.52328 -26.360882) (xy 214.205564 -26.360882) (xy 214.209635 -26.30526)
			(xy 214.221761 -26.250823) (xy 214.241684 -26.198732) (xy 214.26898 -26.150097) (xy 214.303066 -26.105954)
			(xy 214.343215 -26.067245) (xy 214.388573 -26.034794) (xy 214.438173 -26.009293) (xy 214.490957 -25.991286)
			(xy 214.5458 -25.981156) (xy 214.601534 -25.979119) (xy 214.656971 -25.985219) (xy 214.710928 -25.999325)
			(xy 214.762257 -26.021137) (xy 214.809863 -26.050191) (xy 214.852731 -26.085866) (xy 214.889948 -26.127403)
			(xy 214.920721 -26.173916) (xy 214.944393 -26.224413) (xy 214.960461 -26.27782) (xy 214.968581 -26.332996)
			(xy 214.96909 -26.360882) (xy 214.968581 -26.388768) (xy 214.960461 -26.443944) (xy 214.944393 -26.497351)
			(xy 214.920721 -26.547848) (xy 214.889948 -26.594361) (xy 214.852731 -26.635898) (xy 214.809863 -26.671573)
			(xy 214.762257 -26.700627) (xy 214.710928 -26.722439) (xy 214.656971 -26.736545) (xy 214.601534 -26.742645)
			(xy 214.5458 -26.740608) (xy 214.490957 -26.730478) (xy 214.438173 -26.712471) (xy 214.388573 -26.68697)
			(xy 214.343215 -26.654519) (xy 214.303066 -26.61581) (xy 214.26898 -26.571667) (xy 214.241684 -26.523032)
			(xy 214.221761 -26.470941) (xy 214.209635 -26.416504) (xy 214.205564 -26.360882) (xy 211.52328 -26.360882)
			(xy 211.531027 -26.3898) (xy 211.53885 -26.44926) (xy 211.539328 -26.479246) (xy 211.539328 -27.276806)
			(xy 211.539715 -27.28679) (xy 211.547318 -27.305251) (xy 211.561432 -27.319371) (xy 211.57989 -27.326981)
			(xy 211.589874 -27.327352) (xy 220.79585 -27.327352) (xy 220.805726 -27.326887) (xy 220.824021 -27.319442)
			(xy 220.83141 -27.312874) (xy 220.831664 -27.31262) (xy 221.19082 -26.953464) (xy 221.19767 -26.946067)
			(xy 221.205404 -26.927468) (xy 221.205806 -26.917396) (xy 221.205806 -25.054052) (xy 221.205323 -25.043716)
			(xy 221.197203 -25.024705) (xy 221.190058 -25.017222) (xy 221.129098 -24.959056) (xy 221.109794 -24.951944)
			(xy 221.099126 -24.952452) (xy 221.08033 -24.95296) (xy 221.053077 -24.952499) (xy 220.999125 -24.944745)
			(xy 220.946827 -24.929391) (xy 220.897246 -24.90675) (xy 220.851392 -24.877282) (xy 220.8102 -24.841587)
			(xy 220.774508 -24.800393) (xy 220.745042 -24.754538) (xy 220.722403 -24.704956) (xy 220.707051 -24.652657)
			(xy 220.6993 -24.598705) (xy 220.698822 -24.571452) (xy 220.699218 -24.546196) (xy 220.705851 -24.496122)
			(xy 220.71203 -24.47163) (xy 220.715332 -24.459438) (xy 220.709744 -24.435054) (xy 220.638624 -24.351996)
			(xy 220.615256 -24.342852) (xy 220.602556 -24.344122) (xy 220.591799 -24.345293) (xy 220.570196 -24.346563)
			(xy 220.559376 -24.346662) (xy 220.532129 -24.346174) (xy 220.478191 -24.338416) (xy 220.425905 -24.32306)
			(xy 220.376337 -24.300421) (xy 220.330495 -24.270957) (xy 220.289313 -24.23527) (xy 220.253628 -24.194085)
			(xy 220.224168 -24.148242) (xy 220.201531 -24.098672) (xy 220.186179 -24.046385) (xy 220.178424 -23.992446)
			(xy 220.178424 -23.937952) (xy 220.186179 -23.884013) (xy 220.201531 -23.831727) (xy 220.224168 -23.782157)
			(xy 220.253629 -23.736314) (xy 220.289313 -23.695129) (xy 220.330496 -23.659442) (xy 220.376338 -23.629979)
			(xy 220.425906 -23.607339) (xy 220.478192 -23.591984) (xy 220.53213 -23.584226) (xy 220.586624 -23.584222)
			(xy 220.640564 -23.591974) (xy 220.692851 -23.607323) (xy 220.742422 -23.629957) (xy 220.788268 -23.659415)
			(xy 220.829454 -23.695097) (xy 220.865144 -23.736277) (xy 220.89461 -23.782117) (xy 220.917253 -23.831684)
			(xy 220.932611 -23.883969) (xy 220.940373 -23.937907) (xy 220.940884 -23.965154) (xy 220.940494 -23.990411)
			(xy 220.933874 -24.040488) (xy 220.927676 -24.064976) (xy 220.924374 -24.077168) (xy 220.929962 -24.101552)
			(xy 221.001082 -24.18461) (xy 221.02445 -24.193754) (xy 221.03715 -24.192484) (xy 221.047907 -24.191313)
			(xy 221.06951 -24.190044) (xy 221.08033 -24.189944) (xy 221.096864 -24.190155) (xy 221.129803 -24.193083)
			(xy 221.146116 -24.195786) (xy 221.150688 -24.196548) (xy 221.155006 -24.196548) (xy 221.165016 -24.19606)
			(xy 221.183514 -24.188401) (xy 221.197677 -24.17425) (xy 221.205351 -24.155758) (xy 221.205806 -24.145748)
			(xy 221.205806 -24.082756) (xy 221.202758 -24.074374) (xy 221.193224 -24.045782) (xy 221.182271 -23.986516)
			(xy 221.180783 -23.926264) (xy 221.184216 -23.89632) (xy 221.190566 -23.860252) (xy 221.19082 -23.859998)
			(xy 221.19331 -23.849699) (xy 221.199282 -23.829367) (xy 221.202758 -23.819358) (xy 221.205806 -23.810976)
			(xy 221.205806 -22.239478) (xy 221.188788 -22.214078) (xy 221.174564 -22.207982) (xy 221.148799 -22.196774)
			(xy 221.100602 -22.167897) (xy 221.057164 -22.13226) (xy 221.019427 -22.090634) (xy 220.988207 -22.04392)
			(xy 220.964182 -21.99313) (xy 220.94787 -21.939364) (xy 220.939625 -21.883787) (xy 220.939626 -21.827601)
			(xy 220.947872 -21.772024) (xy 220.964186 -21.718258) (xy 220.988213 -21.667469) (xy 221.019435 -21.620757)
			(xy 221.057173 -21.579132) (xy 221.100612 -21.543495) (xy 221.14881 -21.51462) (xy 221.174564 -21.503386)
			(xy 221.188788 -21.49729) (xy 221.205806 -21.47189) (xy 221.205806 -15.83563) (xy 221.205806 -15.832074)
			(xy 221.204028 -15.808198) (xy 221.176342 -15.783306) (xy 221.17431 -15.781274) (xy 221.133924 -15.740634)
			(xy 221.11589 -15.733014) (xy 221.10573 -15.73276) (xy 221.080012 -15.73191) (xy 221.029144 -15.724149)
			(xy 220.97978 -15.709627) (xy 220.932813 -15.688606) (xy 220.889094 -15.661468) (xy 220.849417 -15.628704)
			(xy 220.831664 -15.610078) (xy 220.824044 -15.60195) (xy 220.803978 -15.593568) (xy 220.705426 -15.596108)
			(xy 220.685868 -15.605506) (xy 220.678756 -15.614142) (xy 220.660545 -15.635291) (xy 220.618998 -15.672554)
			(xy 220.572466 -15.703369) (xy 220.521942 -15.727078) (xy 220.468504 -15.743174) (xy 220.413291 -15.751316)
			(xy 220.385386 -15.75181) (xy 220.358135 -15.751323) (xy 220.304189 -15.743565) (xy 220.251895 -15.728209)
			(xy 220.20232 -15.705567) (xy 220.156471 -15.6761) (xy 220.115282 -15.640408) (xy 220.079592 -15.599218)
			(xy 220.050127 -15.553368) (xy 220.027486 -15.503791) (xy 220.012132 -15.451498) (xy 220.004376 -15.397551)
			(xy 220.004376 -15.343049) (xy 220.012132 -15.289102) (xy 220.027486 -15.236809) (xy 220.050127 -15.187232)
			(xy 220.079592 -15.141382) (xy 220.115282 -15.100192) (xy 220.156471 -15.0645) (xy 220.20232 -15.035033)
			(xy 220.251895 -15.012391) (xy 220.304189 -14.997035) (xy 220.358135 -14.989277) (xy 220.385386 -14.988794)
			(xy 220.411623 -14.98923) (xy 220.463601 -14.996426) (xy 220.514101 -15.010682) (xy 220.562168 -15.031731)
			(xy 220.606894 -15.059173) (xy 220.647434 -15.092491) (xy 220.665548 -15.111476) (xy 220.673168 -15.119604)
			(xy 220.693234 -15.127986) (xy 220.791786 -15.125446) (xy 220.811344 -15.116048) (xy 220.818456 -15.107412)
			(xy 220.836336 -15.086649) (xy 220.877031 -15.049959) (xy 220.922552 -15.019461) (xy 220.971964 -14.995781)
			(xy 221.024253 -14.979406) (xy 221.078345 -14.970672) (xy 221.10573 -14.969744) (xy 221.115636 -14.969744)
			(xy 221.134178 -14.96187) (xy 221.178628 -14.916912) (xy 221.191074 -14.904212) (xy 221.197131 -14.897551)
			(xy 221.204538 -14.881155) (xy 221.205552 -14.872208) (xy 221.205806 -14.868652) (xy 221.205806 -13.73124)
			(xy 221.205372 -13.721174) (xy 221.197643 -13.702585) (xy 221.19082 -13.695172) (xy 220.885512 -13.389864)
			(xy 220.878117 -13.383009) (xy 220.859519 -13.37526) (xy 220.849444 -13.374878) (xy 216.142824 -13.374878)
			(xy 216.132759 -13.375314) (xy 216.114173 -13.383046) (xy 216.106756 -13.389864) (xy 215.396318 -14.100302)
			(xy 220.143068 -14.100302) (xy 220.147139 -14.04468) (xy 220.159265 -13.990243) (xy 220.179188 -13.938152)
			(xy 220.206484 -13.889517) (xy 220.24057 -13.845374) (xy 220.280719 -13.806665) (xy 220.326077 -13.774214)
			(xy 220.375677 -13.748713) (xy 220.428461 -13.730706) (xy 220.483304 -13.720576) (xy 220.539038 -13.718539)
			(xy 220.594475 -13.724639) (xy 220.648432 -13.738745) (xy 220.699761 -13.760557) (xy 220.747367 -13.789611)
			(xy 220.790235 -13.825286) (xy 220.827452 -13.866823) (xy 220.858225 -13.913336) (xy 220.881897 -13.963833)
			(xy 220.897965 -14.01724) (xy 220.906085 -14.072416) (xy 220.906594 -14.100302) (xy 220.906085 -14.128188)
			(xy 220.897965 -14.183364) (xy 220.881897 -14.236771) (xy 220.858225 -14.287268) (xy 220.827452 -14.333781)
			(xy 220.790235 -14.375318) (xy 220.747367 -14.410993) (xy 220.699761 -14.440047) (xy 220.648432 -14.461859)
			(xy 220.594475 -14.475965) (xy 220.539038 -14.482065) (xy 220.483304 -14.480028) (xy 220.428461 -14.469898)
			(xy 220.375677 -14.451891) (xy 220.326077 -14.42639) (xy 220.280719 -14.393939) (xy 220.24057 -14.35523)
			(xy 220.206484 -14.311087) (xy 220.179188 -14.262452) (xy 220.159265 -14.210361) (xy 220.147139 -14.155924)
			(xy 220.143068 -14.100302) (xy 215.396318 -14.100302) (xy 214.800942 -14.695678) (xy 214.795729 -14.700588)
			(xy 214.783225 -14.707557) (xy 214.776304 -14.709394) (xy 214.766652 -14.71168) (xy 214.751158 -14.722348)
			(xy 214.693754 -14.807438) (xy 214.691214 -14.83233) (xy 214.69604 -14.844268) (xy 214.721535 -14.908231)
			(xy 214.765213 -15.038831) (xy 214.800375 -15.171977) (xy 214.826875 -15.307113) (xy 214.844602 -15.443677)
			(xy 214.853482 -15.581101) (xy 214.854028 -15.649956) (xy 214.853493 -15.717668) (xy 214.844909 -15.852819)
			(xy 214.827772 -15.987154) (xy 214.802152 -16.120132) (xy 214.768151 -16.251218) (xy 214.725907 -16.379884)
			(xy 214.67559 -16.505613) (xy 214.617402 -16.627898) (xy 214.551576 -16.746248) (xy 214.478379 -16.860185)
			(xy 214.398105 -16.969252) (xy 214.311076 -17.073009) (xy 214.264748 -17.122394) (xy 214.218506 -17.170481)
			(xy 214.120898 -17.261444) (xy 214.017797 -17.34613) (xy 213.909607 -17.42421) (xy 213.796749 -17.495378)
			(xy 213.679666 -17.559356) (xy 213.558815 -17.615893) (xy 213.434667 -17.66477) (xy 213.307708 -17.705795)
			(xy 213.178434 -17.738807) (xy 213.04735 -17.763678) (xy 212.914968 -17.780311) (xy 212.781805 -17.78864)
			(xy 212.715094 -17.789144) (xy 212.650622 -17.788657) (xy 212.521915 -17.780871) (xy 212.393912 -17.765329)
			(xy 212.267081 -17.742086) (xy 212.141885 -17.711228) (xy 212.01878 -17.672867) (xy 211.898216 -17.627144)
			(xy 211.780633 -17.574224) (xy 211.666459 -17.514302) (xy 211.556112 -17.447595) (xy 211.449994 -17.374347)
			(xy 211.348491 -17.294826) (xy 211.251976 -17.209322) (xy 211.160799 -17.118146) (xy 211.075293 -17.021632)
			(xy 210.99577 -16.92013) (xy 210.922521 -16.814013) (xy 210.855813 -16.703667) (xy 210.795889 -16.589494)
			(xy 210.742968 -16.471911) (xy 210.697243 -16.351348) (xy 210.65888 -16.228244) (xy 210.62802 -16.103048)
			(xy 210.604776 -15.976218) (xy 210.589231 -15.848215) (xy 210.581444 -15.719508) (xy 210.580986 -15.655036)
			(xy 210.581538 -15.586705) (xy 210.590297 -15.450325) (xy 210.60777 -15.314786) (xy 210.633884 -15.180643)
			(xy 210.668533 -15.048447) (xy 210.711573 -14.91874) (xy 210.736688 -14.85519) (xy 210.738466 -14.850618)
			(xy 210.740498 -14.83995) (xy 210.742052 -14.830042) (xy 210.738135 -14.810389) (xy 210.732878 -14.80185)
			(xy 210.686396 -14.733016) (xy 210.678866 -14.722999) (xy 210.656749 -14.711276) (xy 210.644232 -14.710664)
			(xy 208.829402 -14.710664) (xy 208.820055 -14.71113) (xy 208.802624 -14.717898) (xy 208.788752 -14.730435)
			(xy 208.78419 -14.738604) (xy 208.740248 -14.825218) (xy 208.742534 -14.853666) (xy 208.750916 -14.86535)
			(xy 208.77729 -14.902352) (xy 208.823601 -14.98054) (xy 208.862157 -15.062827) (xy 208.892602 -15.148449)
			(xy 208.91465 -15.236607) (xy 208.928097 -15.326479) (xy 208.931002 -15.371826) (xy 208.931764 -15.389352)
			(xy 208.932582 -15.423761) (xy 208.929785 -15.492537) (xy 208.926176 -15.526766) (xy 208.922688 -15.555337)
			(xy 208.91265 -15.61202) (xy 208.90611 -15.64005) (xy 208.897474 -15.673324) (xy 208.897474 -15.673578)
			(xy 208.896204 -15.677642) (xy 208.881575 -15.726548) (xy 208.843132 -15.821119) (xy 208.819496 -15.866364)
			(xy 208.8134 -15.877794) (xy 208.8134 -15.903194) (xy 208.86166 -15.992602) (xy 208.882996 -16.006572)
			(xy 208.89595 -16.007588) (xy 208.939341 -16.011726) (xy 209.025191 -16.02684) (xy 209.10933 -16.049628)
			(xy 209.191073 -16.079906) (xy 209.269754 -16.117427) (xy 209.344735 -16.161886) (xy 209.415404 -16.212921)
			(xy 209.481186 -16.270116) (xy 209.541546 -16.333007) (xy 209.595993 -16.401082) (xy 209.644084 -16.473786)
			(xy 209.685427 -16.550529) (xy 209.719687 -16.630684) (xy 209.746583 -16.713601) (xy 209.765898 -16.798605)
			(xy 209.777474 -16.885003) (xy 209.781218 -16.972093) (xy 209.777097 -17.059166) (xy 209.765147 -17.145513)
			(xy 209.745464 -17.230432) (xy 209.718208 -17.313231) (xy 209.683602 -17.393238) (xy 209.641927 -17.4698)
			(xy 209.593522 -17.542296) (xy 209.53878 -17.610134) (xy 209.508852 -17.641824) (xy 209.508598 -17.642078)
			(xy 209.477311 -17.674111) (xy 209.409738 -17.732872) (xy 209.337016 -17.785124) (xy 209.259768 -17.83042)
			(xy 209.178659 -17.868369) (xy 209.094384 -17.898646) (xy 209.007669 -17.92099) (xy 208.919257 -17.93521)
			(xy 208.829908 -17.941184) (xy 208.74039 -17.938859) (xy 208.651472 -17.928257) (xy 208.563917 -17.909468)
			(xy 208.478477 -17.882654) (xy 208.436972 -17.865852) (xy 208.39591 -17.848109) (xy 208.316946 -17.806071)
			(xy 208.24221 -17.756908) (xy 208.172341 -17.701043) (xy 208.10794 -17.638954) (xy 208.049559 -17.571174)
			(xy 207.997698 -17.498283) (xy 207.952802 -17.420908) (xy 207.915256 -17.339712) (xy 207.885382 -17.255391)
			(xy 207.863437 -17.168668) (xy 207.849607 -17.080286) (xy 207.844013 -16.991004) (xy 207.846702 -16.901588)
			(xy 207.857651 -16.812804) (xy 207.876765 -16.725413) (xy 207.903882 -16.640165) (xy 207.938769 -16.557791)
			(xy 207.959452 -16.518128) (xy 207.959706 -16.517366) (xy 207.96123 -16.514318) (xy 207.962754 -16.510762)
			(xy 207.967103 -16.499101) (xy 207.965119 -16.474322) (xy 207.958944 -16.463518) (xy 207.958182 -16.462502)
			(xy 207.915002 -16.390112) (xy 207.910204 -16.382736) (xy 207.896651 -16.371532) (xy 207.880106 -16.365577)
			(xy 207.871314 -16.36522) (xy 206.132938 -16.36522) (xy 206.089499 -16.364735) (xy 206.00299 -16.356722)
			(xy 205.91759 -16.340761) (xy 205.834027 -16.316988) (xy 205.753015 -16.285605) (xy 205.675243 -16.246881)
			(xy 205.601377 -16.201147) (xy 205.532046 -16.148791) (xy 205.467841 -16.090262) (xy 205.409312 -16.026057)
			(xy 205.356956 -15.956726) (xy 205.311221 -15.88286) (xy 205.272496 -15.805089) (xy 205.241114 -15.724076)
			(xy 205.21734 -15.640514) (xy 205.201379 -15.555114) (xy 205.193365 -15.468605) (xy 205.192884 -15.425166)
			(xy 205.192884 -15.424658) (xy 205.193368 -15.382462) (xy 205.200981 -15.298413) (xy 205.216099 -15.215385)
			(xy 205.238598 -15.134047) (xy 205.268297 -15.055052) (xy 205.304959 -14.979038) (xy 205.348286 -14.906617)
			(xy 205.372716 -14.872208) (xy 205.381098 -14.860524) (xy 205.383384 -14.831822) (xy 205.371192 -14.8082)
			(xy 205.33614 -14.738858) (xy 205.332412 -14.732254) (xy 205.321822 -14.721411) (xy 205.315312 -14.717522)
			(xy 205.314804 -14.717014) (xy 205.30902 -14.714035) (xy 205.296416 -14.710826) (xy 205.289912 -14.710664)
			(xy 195.969636 -14.710664) (xy 195.959572 -14.7111) (xy 195.940991 -14.718838) (xy 195.933568 -14.72565)
			(xy 195.739258 -14.91996) (xy 195.732386 -14.927515) (xy 195.724762 -14.946443) (xy 195.725105 -14.966846)
			(xy 195.728844 -14.976348) (xy 195.728844 -14.976602) (xy 195.766944 -15.062708) (xy 195.770394 -15.069801)
			(xy 195.780865 -15.081586) (xy 195.787518 -15.085822) (xy 195.79463 -15.09014) (xy 195.808854 -15.093696)
			(xy 195.81622 -15.093188) (xy 195.817744 -15.093188) (xy 195.836794 -15.09268) (xy 195.864048 -15.093142)
			(xy 195.918001 -15.100899) (xy 195.970302 -15.116255) (xy 196.019884 -15.138898) (xy 196.06574 -15.168367)
			(xy 196.106934 -15.204062) (xy 196.14263 -15.245256) (xy 196.172099 -15.291111) (xy 196.194743 -15.340693)
			(xy 196.2101 -15.392993) (xy 196.217857 -15.446946) (xy 196.217857 -15.501454) (xy 196.2101 -15.555407)
			(xy 196.194743 -15.607707) (xy 196.172099 -15.657289) (xy 196.14263 -15.703144) (xy 196.106934 -15.744338)
			(xy 196.06574 -15.780033) (xy 196.019884 -15.809502) (xy 195.970302 -15.832145) (xy 195.918001 -15.847501)
			(xy 195.864048 -15.855258) (xy 195.836794 -15.855696) (xy 195.806804 -15.855141) (xy 195.747564 -15.845748)
			(xy 195.690531 -15.827179) (xy 195.663566 -15.81404) (xy 195.651628 -15.807944) (xy 195.625466 -15.80896)
			(xy 195.540122 -15.861284) (xy 195.532955 -15.866113) (xy 195.52211 -15.879553) (xy 195.516337 -15.89583)
			(xy 195.515992 -15.904464) (xy 195.515992 -18.44421) (xy 216.376248 -18.44421) (xy 216.380319 -18.388588)
			(xy 216.392445 -18.334151) (xy 216.412368 -18.28206) (xy 216.439664 -18.233425) (xy 216.47375 -18.189282)
			(xy 216.513899 -18.150573) (xy 216.559257 -18.118122) (xy 216.608857 -18.092621) (xy 216.661641 -18.074614)
			(xy 216.716484 -18.064484) (xy 216.772218 -18.062447) (xy 216.827655 -18.068547) (xy 216.881612 -18.082653)
			(xy 216.932941 -18.104465) (xy 216.980547 -18.133519) (xy 217.023415 -18.169194) (xy 217.060632 -18.210731)
			(xy 217.091405 -18.257244) (xy 217.115077 -18.307741) (xy 217.131145 -18.361148) (xy 217.139265 -18.416324)
			(xy 217.139774 -18.44421) (xy 217.139265 -18.472096) (xy 217.131145 -18.527272) (xy 217.115077 -18.580679)
			(xy 217.091405 -18.631176) (xy 217.060632 -18.677689) (xy 217.023415 -18.719226) (xy 216.980547 -18.754901)
			(xy 216.932941 -18.783955) (xy 216.881612 -18.805767) (xy 216.827655 -18.819873) (xy 216.772218 -18.825973)
			(xy 216.716484 -18.823936) (xy 216.661641 -18.813806) (xy 216.608857 -18.795799) (xy 216.559257 -18.770298)
			(xy 216.513899 -18.737847) (xy 216.47375 -18.699138) (xy 216.439664 -18.654995) (xy 216.412368 -18.60636)
			(xy 216.392445 -18.554269) (xy 216.380319 -18.499832) (xy 216.376248 -18.44421) (xy 195.515992 -18.44421)
			(xy 195.515992 -20.72513) (xy 199.280538 -20.72513) (xy 199.284508 -20.594996) (xy 199.296404 -20.465346)
			(xy 199.316183 -20.336663) (xy 199.343769 -20.209424) (xy 199.379062 -20.084105) (xy 199.421928 -19.961169)
			(xy 199.47221 -19.841076) (xy 199.529719 -19.724272) (xy 199.594243 -19.61119) (xy 199.66554 -19.502253)
			(xy 199.743345 -19.397865) (xy 199.82737 -19.298414) (xy 199.917302 -19.204271) (xy 200.012806 -19.115786)
			(xy 200.113526 -19.033287) (xy 200.219088 -18.957082) (xy 200.3291 -18.887455) (xy 200.443152 -18.824664)
			(xy 200.56082 -18.768942) (xy 200.681666 -18.720498) (xy 200.805241 -18.679511) (xy 200.931084 -18.646134)
			(xy 201.058729 -18.620491) (xy 201.187699 -18.602677) (xy 201.317515 -18.592759) (xy 201.447694 -18.590774)
			(xy 201.577753 -18.596728) (xy 201.707206 -18.610601) (xy 201.835573 -18.632339) (xy 201.962376 -18.661863)
			(xy 202.087143 -18.699062) (xy 202.20941 -18.743798) (xy 202.328723 -18.795906) (xy 202.444636 -18.855189)
			(xy 202.556721 -18.92143) (xy 202.664558 -18.99438) (xy 202.767747 -19.073768) (xy 202.865905 -19.1593)
			(xy 202.958666 -19.250657) (xy 203.045685 -19.347499) (xy 203.126638 -19.449466) (xy 203.201224 -19.556178)
			(xy 203.269165 -19.667239) (xy 203.33021 -19.782235) (xy 203.384131 -19.900739) (xy 203.430726 -20.02231)
			(xy 203.469824 -20.146495) (xy 203.501278 -20.272833) (xy 203.524972 -20.400854) (xy 203.540816 -20.53008)
			(xy 203.548754 -20.660033) (xy 203.54925 -20.72513) (xy 203.548754 -20.790227) (xy 203.540816 -20.92018)
			(xy 203.524972 -21.049406) (xy 203.501278 -21.177427) (xy 203.469824 -21.303765) (xy 203.430726 -21.42795)
			(xy 203.384131 -21.549521) (xy 203.33021 -21.668025) (xy 203.292886 -21.738336) (xy 205.516734 -21.738336)
			(xy 205.517236 -21.709597) (xy 205.525867 -21.652769) (xy 205.542923 -21.597879) (xy 205.568019 -21.546167)
			(xy 205.600586 -21.498805) (xy 205.619858 -21.477478) (xy 205.626462 -21.470366) (xy 205.633574 -21.45284)
			(xy 205.633574 -21.363432) (xy 205.626462 -21.345906) (xy 205.619858 -21.338794) (xy 205.600621 -21.317437)
			(xy 205.568052 -21.270081) (xy 205.542956 -21.218374) (xy 205.525902 -21.163488) (xy 205.517275 -21.106664)
			(xy 205.517271 -21.049189) (xy 205.52589 -20.992364) (xy 205.542937 -20.937475) (xy 205.568026 -20.885765)
			(xy 205.600588 -20.838404) (xy 205.619858 -20.817078) (xy 205.626462 -20.809966) (xy 205.633574 -20.79244)
			(xy 205.633574 -20.703032) (xy 205.626462 -20.685506) (xy 205.619858 -20.678394) (xy 205.600621 -20.657037)
			(xy 205.568052 -20.609681) (xy 205.542956 -20.557974) (xy 205.525902 -20.503088) (xy 205.517275 -20.446264)
			(xy 205.517271 -20.388789) (xy 205.52589 -20.331964) (xy 205.542937 -20.277075) (xy 205.568026 -20.225365)
			(xy 205.600588 -20.178004) (xy 205.619858 -20.156678) (xy 205.626462 -20.149566) (xy 205.633574 -20.13204)
			(xy 205.633574 -20.042632) (xy 205.626462 -20.025106) (xy 205.619858 -20.017994) (xy 205.600621 -19.996637)
			(xy 205.568052 -19.949281) (xy 205.542956 -19.897574) (xy 205.525902 -19.842688) (xy 205.517275 -19.785864)
			(xy 205.517271 -19.728389) (xy 205.52589 -19.671564) (xy 205.542937 -19.616675) (xy 205.568026 -19.564965)
			(xy 205.600588 -19.517604) (xy 205.619858 -19.496278) (xy 205.626462 -19.489166) (xy 205.633574 -19.47164)
			(xy 205.633574 -19.382232) (xy 205.626462 -19.364706) (xy 205.619858 -19.357594) (xy 205.600608 -19.336249)
			(xy 205.568038 -19.288892) (xy 205.542941 -19.237185) (xy 205.525886 -19.182298) (xy 205.517258 -19.125474)
			(xy 205.516734 -19.096736) (xy 205.51722 -19.069485) (xy 205.524976 -19.015537) (xy 205.540331 -18.963242)
			(xy 205.562973 -18.913665) (xy 205.592439 -18.867815) (xy 205.62813 -18.826624) (xy 205.669321 -18.790933)
			(xy 205.715171 -18.761467) (xy 205.764748 -18.738825) (xy 205.817043 -18.72347) (xy 205.870991 -18.715714)
			(xy 205.925493 -18.715714) (xy 205.979441 -18.72347) (xy 206.031736 -18.738825) (xy 206.081313 -18.761467)
			(xy 206.127163 -18.790933) (xy 206.168354 -18.826624) (xy 206.204045 -18.867815) (xy 206.233511 -18.913665)
			(xy 206.256153 -18.963242) (xy 206.271508 -19.015537) (xy 206.279264 -19.069485) (xy 206.27975 -19.096736)
			(xy 206.279235 -19.125475) (xy 206.270608 -19.182302) (xy 206.253555 -19.237193) (xy 206.228462 -19.288904)
			(xy 206.195897 -19.336267) (xy 206.176626 -19.357594) (xy 206.170022 -19.364706) (xy 206.16291 -19.382232)
			(xy 206.16291 -19.47164) (xy 206.170022 -19.489166) (xy 206.176626 -19.496278) (xy 206.19593 -19.517575)
			(xy 206.22849 -19.564944) (xy 206.253576 -19.616661) (xy 206.270621 -19.671556) (xy 206.279239 -19.728386)
			(xy 206.279235 -19.785866) (xy 206.27061 -19.842696) (xy 206.253557 -19.897588) (xy 206.228464 -19.949302)
			(xy 206.195897 -19.996666) (xy 206.176626 -20.017994) (xy 206.170022 -20.025106) (xy 206.16291 -20.042632)
			(xy 206.16291 -20.13204) (xy 206.170022 -20.149566) (xy 206.176626 -20.156678) (xy 206.19593 -20.177975)
			(xy 206.22849 -20.225344) (xy 206.253576 -20.277061) (xy 206.270621 -20.331956) (xy 206.279239 -20.388786)
			(xy 206.279235 -20.446266) (xy 206.27061 -20.503096) (xy 206.253557 -20.557988) (xy 206.228464 -20.609702)
			(xy 206.195897 -20.657066) (xy 206.176626 -20.678394) (xy 206.170022 -20.685506) (xy 206.16291 -20.703032)
			(xy 206.16291 -20.79244) (xy 206.170022 -20.809966) (xy 206.176626 -20.817078) (xy 206.19593 -20.838375)
			(xy 206.22849 -20.885744) (xy 206.253576 -20.937461) (xy 206.270621 -20.992356) (xy 206.279239 -21.049186)
			(xy 206.279235 -21.106666) (xy 206.27061 -21.163496) (xy 206.253557 -21.218388) (xy 206.228464 -21.270102)
			(xy 206.195897 -21.317466) (xy 206.176626 -21.338794) (xy 206.170022 -21.345906) (xy 206.16291 -21.363432)
			(xy 206.16291 -21.45284) (xy 206.170022 -21.470366) (xy 206.176626 -21.477478) (xy 206.195908 -21.498796)
			(xy 206.228474 -21.54616) (xy 206.253565 -21.597873) (xy 206.266344 -21.639022) (xy 210.173824 -21.639022)
			(xy 210.174381 -21.610285) (xy 210.182999 -21.55346) (xy 210.200042 -21.49857) (xy 210.225126 -21.446858)
			(xy 210.257682 -21.399493) (xy 210.276948 -21.378164) (xy 210.283552 -21.371052) (xy 210.290664 -21.353526)
			(xy 210.290664 -21.264118) (xy 210.283552 -21.246592) (xy 210.276948 -21.23948) (xy 210.257698 -21.218135)
			(xy 210.22513 -21.170776) (xy 210.200036 -21.119068) (xy 210.182983 -21.064179) (xy 210.174358 -21.007354)
			(xy 210.174355 -20.949878) (xy 210.182976 -20.893052) (xy 210.200024 -20.838162) (xy 210.225114 -20.786452)
			(xy 210.257678 -20.73909) (xy 210.276948 -20.717764) (xy 210.283552 -20.710652) (xy 210.290664 -20.693126)
			(xy 210.290664 -20.603718) (xy 210.283552 -20.586192) (xy 210.276948 -20.57908) (xy 210.257698 -20.557735)
			(xy 210.22513 -20.510376) (xy 210.200036 -20.458668) (xy 210.182983 -20.403779) (xy 210.174358 -20.346954)
			(xy 210.174355 -20.289478) (xy 210.182976 -20.232652) (xy 210.200024 -20.177762) (xy 210.225114 -20.126052)
			(xy 210.257678 -20.07869) (xy 210.276948 -20.057364) (xy 210.283552 -20.050252) (xy 210.290664 -20.032726)
			(xy 210.290664 -19.943318) (xy 210.283552 -19.925792) (xy 210.276948 -19.91868) (xy 210.257698 -19.897335)
			(xy 210.22513 -19.849976) (xy 210.200036 -19.798268) (xy 210.182983 -19.743379) (xy 210.174358 -19.686554)
			(xy 210.174355 -19.629078) (xy 210.182976 -19.572252) (xy 210.200024 -19.517362) (xy 210.225114 -19.465652)
			(xy 210.257678 -19.41829) (xy 210.276948 -19.396964) (xy 210.283552 -19.389852) (xy 210.290664 -19.372326)
			(xy 210.290664 -19.282918) (xy 210.283552 -19.265392) (xy 210.276948 -19.25828) (xy 210.257689 -19.236942)
			(xy 210.225121 -19.189584) (xy 210.200026 -19.137875) (xy 210.182973 -19.082986) (xy 210.174347 -19.02616)
			(xy 210.173824 -18.997422) (xy 210.17431 -18.970171) (xy 210.182066 -18.916223) (xy 210.197421 -18.863928)
			(xy 210.220063 -18.814351) (xy 210.249529 -18.768501) (xy 210.28522 -18.72731) (xy 210.326411 -18.691619)
			(xy 210.372261 -18.662153) (xy 210.421838 -18.639511) (xy 210.474133 -18.624156) (xy 210.528081 -18.6164)
			(xy 210.582583 -18.6164) (xy 210.636531 -18.624156) (xy 210.688826 -18.639511) (xy 210.738403 -18.662153)
			(xy 210.784253 -18.691619) (xy 210.825444 -18.72731) (xy 210.861135 -18.768501) (xy 210.890601 -18.814351)
			(xy 210.913243 -18.863928) (xy 210.928598 -18.916223) (xy 210.936354 -18.970171) (xy 210.93684 -18.997422)
			(xy 210.936319 -19.026161) (xy 210.927694 -19.082988) (xy 210.910643 -19.137878) (xy 210.885551 -19.18959)
			(xy 210.852986 -19.236953) (xy 210.833716 -19.25828) (xy 210.827112 -19.265392) (xy 210.82 -19.282918)
			(xy 210.82 -19.366853) (xy 215.679238 -19.366853) (xy 215.679238 -19.312347) (xy 215.686994 -19.258396)
			(xy 215.70235 -19.206098) (xy 215.724991 -19.156517) (xy 215.754458 -19.110663) (xy 215.790151 -19.069469)
			(xy 215.831342 -19.033774) (xy 215.877194 -19.004304) (xy 215.926773 -18.981659) (xy 215.979071 -18.9663)
			(xy 216.033021 -18.95854) (xy 216.060274 -18.958052) (xy 216.087044 -18.958547) (xy 216.140058 -18.966041)
			(xy 216.191503 -18.980872) (xy 216.24037 -19.002748) (xy 216.2857 -19.03124) (xy 216.326603 -19.065788)
			(xy 216.362274 -19.105714) (xy 216.37752 -19.127724) (xy 216.383616 -19.136614) (xy 216.401142 -19.148044)
			(xy 216.49563 -19.163284) (xy 216.51595 -19.158204) (xy 216.524332 -19.1516) (xy 216.544471 -19.136464)
			(xy 216.587997 -19.111093) (xy 216.634486 -19.09168) (xy 216.683129 -19.078564) (xy 216.733076 -19.071972)
			(xy 216.758266 -19.07159) (xy 216.78552 -19.072055) (xy 216.839475 -19.079808) (xy 216.891776 -19.095161)
			(xy 216.94136 -19.117801) (xy 216.987218 -19.147268) (xy 217.028414 -19.182962) (xy 217.064111 -19.224155)
			(xy 217.093582 -19.27001) (xy 217.116227 -19.319592) (xy 217.131585 -19.371892) (xy 217.139343 -19.425846)
			(xy 217.139343 -19.480354) (xy 217.131585 -19.534308) (xy 217.116227 -19.586608) (xy 217.093582 -19.63619)
			(xy 217.064111 -19.682045) (xy 217.028414 -19.723238) (xy 216.987218 -19.758932) (xy 216.94136 -19.788399)
			(xy 216.891776 -19.811039) (xy 216.839475 -19.826392) (xy 216.78552 -19.834145) (xy 216.758266 -19.834606)
			(xy 216.731493 -19.834175) (xy 216.678476 -19.826672) (xy 216.627029 -19.811831) (xy 216.57816 -19.789945)
			(xy 216.532831 -19.761443) (xy 216.491931 -19.726885) (xy 216.456263 -19.686948) (xy 216.44102 -19.664934)
			(xy 216.434924 -19.656044) (xy 216.417398 -19.644614) (xy 216.32291 -19.629374) (xy 216.30259 -19.634454)
			(xy 216.294208 -19.641058) (xy 216.274052 -19.65617) (xy 216.230531 -19.681546) (xy 216.184046 -19.700964)
			(xy 216.135407 -19.714086) (xy 216.085463 -19.720683) (xy 216.060274 -19.721068) (xy 216.033021 -19.72066)
			(xy 215.979071 -19.7129) (xy 215.926773 -19.697541) (xy 215.877194 -19.674896) (xy 215.831342 -19.645426)
			(xy 215.790151 -19.609731) (xy 215.754458 -19.568537) (xy 215.724991 -19.522683) (xy 215.70235 -19.473102)
			(xy 215.686994 -19.420804) (xy 215.679238 -19.366853) (xy 210.82 -19.366853) (xy 210.82 -19.372326)
			(xy 210.827112 -19.389852) (xy 210.833716 -19.396964) (xy 210.853007 -19.418273) (xy 210.885568 -19.465639)
			(xy 210.910656 -19.517354) (xy 210.927702 -19.572248) (xy 210.936322 -19.629077) (xy 210.936319 -19.686556)
			(xy 210.927695 -19.743384) (xy 210.910644 -19.798275) (xy 210.885552 -19.849988) (xy 210.852987 -19.897352)
			(xy 210.833716 -19.91868) (xy 210.827112 -19.925792) (xy 210.82 -19.943318) (xy 210.82 -20.032726)
			(xy 210.827112 -20.050252) (xy 210.833716 -20.057364) (xy 210.853007 -20.078673) (xy 210.885568 -20.126039)
			(xy 210.910656 -20.177754) (xy 210.927702 -20.232648) (xy 210.936322 -20.289477) (xy 210.936319 -20.346956)
			(xy 210.935013 -20.35556) (xy 215.678256 -20.35556) (xy 215.682327 -20.299938) (xy 215.694453 -20.245501)
			(xy 215.714376 -20.19341) (xy 215.741672 -20.144775) (xy 215.775758 -20.100632) (xy 215.815907 -20.061923)
			(xy 215.861265 -20.029472) (xy 215.910865 -20.003971) (xy 215.963649 -19.985964) (xy 216.018492 -19.975834)
			(xy 216.074226 -19.973797) (xy 216.129663 -19.979897) (xy 216.18362 -19.994003) (xy 216.234949 -20.015815)
			(xy 216.282555 -20.044869) (xy 216.325423 -20.080544) (xy 216.36264 -20.122081) (xy 216.393413 -20.168594)
			(xy 216.417085 -20.219091) (xy 216.433153 -20.272498) (xy 216.441273 -20.327674) (xy 216.441782 -20.35556)
			(xy 216.441273 -20.383446) (xy 216.433153 -20.438622) (xy 216.417085 -20.492029) (xy 216.393413 -20.542526)
			(xy 216.36264 -20.589039) (xy 216.325423 -20.630576) (xy 216.282555 -20.666251) (xy 216.234949 -20.695305)
			(xy 216.18362 -20.717117) (xy 216.129663 -20.731223) (xy 216.074226 -20.737323) (xy 216.018492 -20.735286)
			(xy 215.963649 -20.725156) (xy 215.910865 -20.707149) (xy 215.861265 -20.681648) (xy 215.815907 -20.649197)
			(xy 215.775758 -20.610488) (xy 215.741672 -20.566345) (xy 215.714376 -20.51771) (xy 215.694453 -20.465619)
			(xy 215.682327 -20.411182) (xy 215.678256 -20.35556) (xy 210.935013 -20.35556) (xy 210.927695 -20.403784)
			(xy 210.910644 -20.458675) (xy 210.885552 -20.510388) (xy 210.852987 -20.557752) (xy 210.833716 -20.57908)
			(xy 210.827112 -20.586192) (xy 210.82 -20.603718) (xy 210.82 -20.693126) (xy 210.827112 -20.710652)
			(xy 210.833716 -20.717764) (xy 210.853007 -20.739073) (xy 210.885568 -20.786439) (xy 210.910656 -20.838154)
			(xy 210.927702 -20.893048) (xy 210.936322 -20.949877) (xy 210.936319 -21.007356) (xy 210.927695 -21.064184)
			(xy 210.910644 -21.119075) (xy 210.885552 -21.170788) (xy 210.852987 -21.218152) (xy 210.833716 -21.23948)
			(xy 210.827112 -21.246592) (xy 210.82 -21.264118) (xy 210.82 -21.353526) (xy 210.827112 -21.371052)
			(xy 210.827584 -21.37156) (xy 215.678256 -21.37156) (xy 215.682327 -21.315938) (xy 215.694453 -21.261501)
			(xy 215.714376 -21.20941) (xy 215.741672 -21.160775) (xy 215.775758 -21.116632) (xy 215.815907 -21.077923)
			(xy 215.861265 -21.045472) (xy 215.910865 -21.019971) (xy 215.963649 -21.001964) (xy 216.018492 -20.991834)
			(xy 216.074226 -20.989797) (xy 216.129663 -20.995897) (xy 216.18362 -21.010003) (xy 216.234949 -21.031815)
			(xy 216.282555 -21.060869) (xy 216.325423 -21.096544) (xy 216.36264 -21.138081) (xy 216.393413 -21.184594)
			(xy 216.417085 -21.235091) (xy 216.433153 -21.288498) (xy 216.441273 -21.343674) (xy 216.441782 -21.37156)
			(xy 216.441273 -21.399446) (xy 216.433153 -21.454622) (xy 216.417085 -21.508029) (xy 216.393413 -21.558526)
			(xy 216.36264 -21.605039) (xy 216.325423 -21.646576) (xy 216.282555 -21.682251) (xy 216.234949 -21.711305)
			(xy 216.18362 -21.733117) (xy 216.129663 -21.747223) (xy 216.074226 -21.753323) (xy 216.018492 -21.751286)
			(xy 215.963649 -21.741156) (xy 215.910865 -21.723149) (xy 215.861265 -21.697648) (xy 215.815907 -21.665197)
			(xy 215.775758 -21.626488) (xy 215.741672 -21.582345) (xy 215.714376 -21.53371) (xy 215.694453 -21.481619)
			(xy 215.682327 -21.427182) (xy 215.678256 -21.37156) (xy 210.827584 -21.37156) (xy 210.833716 -21.378164)
			(xy 210.85299 -21.399489) (xy 210.885557 -21.446851) (xy 210.91065 -21.498563) (xy 210.9277 -21.553454)
			(xy 210.936321 -21.610283) (xy 210.93684 -21.639022) (xy 210.936354 -21.666273) (xy 210.928598 -21.720221)
			(xy 210.913243 -21.772516) (xy 210.911801 -21.775674) (xy 220.03588 -21.775674) (xy 220.039951 -21.720052)
			(xy 220.052077 -21.665615) (xy 220.072 -21.613524) (xy 220.099296 -21.564889) (xy 220.133382 -21.520746)
			(xy 220.173531 -21.482037) (xy 220.218889 -21.449586) (xy 220.268489 -21.424085) (xy 220.321273 -21.406078)
			(xy 220.376116 -21.395948) (xy 220.43185 -21.393911) (xy 220.487287 -21.400011) (xy 220.541244 -21.414117)
			(xy 220.592573 -21.435929) (xy 220.640179 -21.464983) (xy 220.683047 -21.500658) (xy 220.720264 -21.542195)
			(xy 220.751037 -21.588708) (xy 220.774709 -21.639205) (xy 220.790777 -21.692612) (xy 220.798897 -21.747788)
			(xy 220.799406 -21.775674) (xy 220.798897 -21.80356) (xy 220.790777 -21.858736) (xy 220.774709 -21.912143)
			(xy 220.751037 -21.96264) (xy 220.720264 -22.009153) (xy 220.683047 -22.05069) (xy 220.640179 -22.086365)
			(xy 220.592573 -22.115419) (xy 220.541244 -22.137231) (xy 220.487287 -22.151337) (xy 220.43185 -22.157437)
			(xy 220.376116 -22.1554) (xy 220.321273 -22.14527) (xy 220.268489 -22.127263) (xy 220.218889 -22.101762)
			(xy 220.173531 -22.069311) (xy 220.133382 -22.030602) (xy 220.099296 -21.986459) (xy 220.072 -21.937824)
			(xy 220.052077 -21.885733) (xy 220.039951 -21.831296) (xy 220.03588 -21.775674) (xy 210.911801 -21.775674)
			(xy 210.890601 -21.822093) (xy 210.861135 -21.867943) (xy 210.825444 -21.909134) (xy 210.784253 -21.944825)
			(xy 210.738403 -21.974291) (xy 210.688826 -21.996933) (xy 210.636531 -22.012288) (xy 210.582583 -22.020044)
			(xy 210.528081 -22.020044) (xy 210.474133 -22.012288) (xy 210.421838 -21.996933) (xy 210.372261 -21.974291)
			(xy 210.326411 -21.944825) (xy 210.28522 -21.909134) (xy 210.249529 -21.867943) (xy 210.220063 -21.822093)
			(xy 210.197421 -21.772516) (xy 210.182066 -21.720221) (xy 210.17431 -21.666273) (xy 210.173824 -21.639022)
			(xy 206.266344 -21.639022) (xy 206.270613 -21.652767) (xy 206.279232 -21.709596) (xy 206.27975 -21.738336)
			(xy 206.279264 -21.765587) (xy 206.271508 -21.819535) (xy 206.256153 -21.87183) (xy 206.233511 -21.921407)
			(xy 206.204045 -21.967257) (xy 206.168354 -22.008448) (xy 206.127163 -22.044139) (xy 206.081313 -22.073605)
			(xy 206.031736 -22.096247) (xy 205.979441 -22.111602) (xy 205.925493 -22.119358) (xy 205.870991 -22.119358)
			(xy 205.817043 -22.111602) (xy 205.764748 -22.096247) (xy 205.715171 -22.073605) (xy 205.669321 -22.044139)
			(xy 205.62813 -22.008448) (xy 205.592439 -21.967257) (xy 205.562973 -21.921407) (xy 205.540331 -21.87183)
			(xy 205.524976 -21.819535) (xy 205.51722 -21.765587) (xy 205.516734 -21.738336) (xy 203.292886 -21.738336)
			(xy 203.269165 -21.783021) (xy 203.201224 -21.894082) (xy 203.126638 -22.000794) (xy 203.045685 -22.102761)
			(xy 202.958666 -22.199603) (xy 202.865905 -22.29096) (xy 202.767747 -22.376492) (xy 202.664558 -22.45588)
			(xy 202.556721 -22.52883) (xy 202.444636 -22.595071) (xy 202.328723 -22.654354) (xy 202.20941 -22.706462)
			(xy 202.087143 -22.751198) (xy 201.962376 -22.788397) (xy 201.835573 -22.817921) (xy 201.707206 -22.839659)
			(xy 201.577753 -22.853532) (xy 201.447694 -22.859486) (xy 201.317515 -22.857501) (xy 201.187699 -22.847583)
			(xy 201.058729 -22.829769) (xy 200.931084 -22.804126) (xy 200.805241 -22.770749) (xy 200.681666 -22.729762)
			(xy 200.56082 -22.681318) (xy 200.443152 -22.625596) (xy 200.3291 -22.562805) (xy 200.219088 -22.493178)
			(xy 200.113526 -22.416973) (xy 200.012806 -22.334474) (xy 199.917302 -22.245989) (xy 199.82737 -22.151846)
			(xy 199.743345 -22.052395) (xy 199.66554 -21.948007) (xy 199.594243 -21.83907) (xy 199.529719 -21.725988)
			(xy 199.47221 -21.609184) (xy 199.421928 -21.489091) (xy 199.379062 -21.366155) (xy 199.343769 -21.240836)
			(xy 199.316183 -21.113597) (xy 199.296404 -20.984914) (xy 199.284508 -20.855264) (xy 199.280538 -20.72513)
			(xy 195.515992 -20.72513) (xy 195.515992 -21.487638) (xy 195.516141 -21.49371) (xy 195.518973 -21.505519)
			(xy 195.52158 -21.511006) (xy 195.534788 -21.536406) (xy 195.542154 -21.545042) (xy 195.54698 -21.548598)
			(xy 195.568812 -21.565279) (xy 195.607911 -21.603879) (xy 195.641067 -21.647689) (xy 195.667595 -21.695803)
			(xy 195.686947 -21.747224) (xy 195.698721 -21.80089) (xy 195.70205 -21.847048) (xy 196.172834 -21.847048)
			(xy 196.176905 -21.791426) (xy 196.189031 -21.736989) (xy 196.208954 -21.684898) (xy 196.23625 -21.636263)
			(xy 196.270336 -21.59212) (xy 196.310485 -21.553411) (xy 196.355843 -21.52096) (xy 196.405443 -21.495459)
			(xy 196.458227 -21.477452) (xy 196.51307 -21.467322) (xy 196.568804 -21.465285) (xy 196.624241 -21.471385)
			(xy 196.678198 -21.485491) (xy 196.729527 -21.507303) (xy 196.777133 -21.536357) (xy 196.820001 -21.572032)
			(xy 196.857218 -21.613569) (xy 196.887991 -21.660082) (xy 196.911663 -21.710579) (xy 196.927731 -21.763986)
			(xy 196.935851 -21.819162) (xy 196.93636 -21.847048) (xy 196.935851 -21.874934) (xy 196.927731 -21.93011)
			(xy 196.911663 -21.983517) (xy 196.887991 -22.034014) (xy 196.857218 -22.080527) (xy 196.820001 -22.122064)
			(xy 196.777133 -22.157739) (xy 196.729527 -22.186793) (xy 196.678198 -22.208605) (xy 196.624241 -22.222711)
			(xy 196.568804 -22.228811) (xy 196.51307 -22.226774) (xy 196.458227 -22.216644) (xy 196.405443 -22.198637)
			(xy 196.355843 -22.173136) (xy 196.310485 -22.140685) (xy 196.270336 -22.101976) (xy 196.23625 -22.057833)
			(xy 196.208954 -22.009198) (xy 196.189031 -21.957107) (xy 196.176905 -21.90267) (xy 196.172834 -21.847048)
			(xy 195.70205 -21.847048) (xy 195.702673 -21.85569) (xy 195.698723 -21.910491) (xy 195.686952 -21.964157)
			(xy 195.667603 -22.01558) (xy 195.641078 -22.063695) (xy 195.607923 -22.107506) (xy 195.568826 -22.146108)
			(xy 195.54698 -22.16277) (xy 195.542154 -22.166326) (xy 195.534788 -22.174962) (xy 195.52158 -22.200362)
			(xy 195.518978 -22.205849) (xy 195.516159 -22.217659) (xy 195.515992 -22.22373) (xy 195.515992 -23.0251)
			(xy 205.462376 -23.0251) (xy 205.466447 -22.969478) (xy 205.478573 -22.915041) (xy 205.498496 -22.86295)
			(xy 205.525792 -22.814315) (xy 205.559878 -22.770172) (xy 205.600027 -22.731463) (xy 205.645385 -22.699012)
			(xy 205.694985 -22.673511) (xy 205.747769 -22.655504) (xy 205.802612 -22.645374) (xy 205.858346 -22.643337)
			(xy 205.913783 -22.649437) (xy 205.96774 -22.663543) (xy 206.019069 -22.685355) (xy 206.066675 -22.714409)
			(xy 206.109543 -22.750084) (xy 206.14676 -22.791621) (xy 206.177533 -22.838134) (xy 206.201205 -22.888631)
			(xy 206.217273 -22.942038) (xy 206.225393 -22.997214) (xy 206.225902 -23.0251) (xy 206.225393 -23.052986)
			(xy 206.217273 -23.108162) (xy 206.201205 -23.161569) (xy 206.177533 -23.212066) (xy 206.14676 -23.258579)
			(xy 206.109543 -23.300116) (xy 206.066675 -23.335791) (xy 206.019069 -23.364845) (xy 205.96774 -23.386657)
			(xy 205.913783 -23.400763) (xy 205.858346 -23.406863) (xy 205.802612 -23.404826) (xy 205.747769 -23.394696)
			(xy 205.694985 -23.376689) (xy 205.645385 -23.351188) (xy 205.600027 -23.318737) (xy 205.559878 -23.280028)
			(xy 205.525792 -23.235885) (xy 205.498496 -23.18725) (xy 205.478573 -23.135159) (xy 205.466447 -23.080722)
			(xy 205.462376 -23.0251) (xy 195.515992 -23.0251) (xy 195.515992 -23.504144) (xy 195.523612 -23.522178)
			(xy 195.530724 -23.529544) (xy 195.557304 -23.556366) (xy 206.166023 -23.556366) (xy 206.173776 -23.502427)
			(xy 206.189126 -23.450141) (xy 206.211761 -23.400571) (xy 206.241219 -23.354726) (xy 206.276902 -23.313541)
			(xy 206.318082 -23.277852) (xy 206.363923 -23.248387) (xy 206.413489 -23.225745) (xy 206.465774 -23.210388)
			(xy 206.519711 -23.202627) (xy 206.546958 -23.202138) (xy 206.570988 -23.202497) (xy 206.618666 -23.208543)
			(xy 206.665207 -23.220531) (xy 206.687674 -23.229062) (xy 206.700811 -23.233889) (xy 206.728644 -23.236782)
			(xy 206.756218 -23.232022) (xy 206.781469 -23.219963) (xy 206.802505 -23.201511) (xy 206.81775 -23.178046)
			(xy 206.826063 -23.151327) (xy 206.82682 -23.123354) (xy 206.823818 -23.109682) (xy 206.818367 -23.086699)
			(xy 206.812506 -23.039828) (xy 206.812134 -23.01621) (xy 206.812567 -22.988959) (xy 206.820322 -22.93501)
			(xy 206.835676 -22.882714) (xy 206.858315 -22.833136) (xy 206.88778 -22.787284) (xy 206.92347 -22.746092)
			(xy 206.96466 -22.710399) (xy 207.010509 -22.68093) (xy 207.060086 -22.658286) (xy 207.11238 -22.642929)
			(xy 207.166328 -22.635169) (xy 207.220831 -22.635166) (xy 207.274779 -22.64292) (xy 207.327076 -22.658272)
			(xy 207.376655 -22.68091) (xy 207.422507 -22.710374) (xy 207.4637 -22.746063) (xy 207.499395 -22.787251)
			(xy 207.528865 -22.8331) (xy 207.55151 -22.882676) (xy 207.566869 -22.93497) (xy 207.57463 -22.988917)
			(xy 207.574634 -23.04342) (xy 207.566882 -23.097369) (xy 207.551532 -23.149666) (xy 207.528895 -23.199245)
			(xy 207.499433 -23.245099) (xy 207.463745 -23.286293) (xy 207.422558 -23.321989) (xy 207.37671 -23.35146)
			(xy 207.327134 -23.374106) (xy 207.274841 -23.389467) (xy 207.220893 -23.397229) (xy 207.193642 -23.397718)
			(xy 207.169612 -23.397355) (xy 207.121935 -23.39131) (xy 207.075394 -23.379324) (xy 207.052926 -23.370794)
			(xy 207.039774 -23.366019) (xy 207.011951 -23.363129) (xy 206.984387 -23.367888) (xy 206.959145 -23.37994)
			(xy 206.938114 -23.398384) (xy 206.92287 -23.421837) (xy 206.914553 -23.448544) (xy 206.913786 -23.476505)
			(xy 206.916782 -23.490174) (xy 206.922243 -23.513155) (xy 206.928098 -23.560028) (xy 206.928466 -23.583646)
			(xy 206.928351 -23.589996) (xy 210.18449 -23.589996) (xy 210.188561 -23.534374) (xy 210.200687 -23.479937)
			(xy 210.22061 -23.427846) (xy 210.247906 -23.379211) (xy 210.281992 -23.335068) (xy 210.322141 -23.296359)
			(xy 210.367499 -23.263908) (xy 210.417099 -23.238407) (xy 210.469883 -23.2204) (xy 210.524726 -23.21027)
			(xy 210.58046 -23.208233) (xy 210.635897 -23.214333) (xy 210.689854 -23.228439) (xy 210.741183 -23.250251)
			(xy 210.788789 -23.279305) (xy 210.831657 -23.31498) (xy 210.868011 -23.355554) (xy 219.4306 -23.355554)
			(xy 219.431068 -23.328743) (xy 219.438575 -23.275648) (xy 219.45345 -23.22413) (xy 219.475398 -23.175205)
			(xy 219.503985 -23.129839) (xy 219.538649 -23.088926) (xy 219.578704 -23.053276) (xy 219.60078 -23.038054)
			(xy 219.612324 -23.029768) (xy 219.630731 -23.008139) (xy 219.642471 -22.982278) (xy 219.646635 -22.954184)
			(xy 219.642902 -22.926029) (xy 219.631561 -22.89999) (xy 219.613488 -22.878081) (xy 219.60205 -22.869652)
			(xy 219.580597 -22.854295) (xy 219.541685 -22.818668) (xy 219.508053 -22.778019) (xy 219.480343 -22.733124)
			(xy 219.459082 -22.68484) (xy 219.444676 -22.634087) (xy 219.4374 -22.581833) (xy 219.43695 -22.555454)
			(xy 219.437436 -22.528203) (xy 219.445192 -22.474255) (xy 219.460547 -22.42196) (xy 219.483189 -22.372383)
			(xy 219.512655 -22.326533) (xy 219.548346 -22.285342) (xy 219.589537 -22.249651) (xy 219.635387 -22.220185)
			(xy 219.684964 -22.197543) (xy 219.737259 -22.182188) (xy 219.791207 -22.174432) (xy 219.845709 -22.174432)
			(xy 219.899657 -22.182188) (xy 219.951952 -22.197543) (xy 220.001529 -22.220185) (xy 220.047379 -22.249651)
			(xy 220.08857 -22.285342) (xy 220.124261 -22.326533) (xy 220.153727 -22.372383) (xy 220.176369 -22.42196)
			(xy 220.191724 -22.474255) (xy 220.19948 -22.528203) (xy 220.199966 -22.555454) (xy 220.199475 -22.582264)
			(xy 220.191968 -22.635356) (xy 220.177095 -22.686873) (xy 220.155151 -22.735797) (xy 220.126567 -22.781163)
			(xy 220.091908 -22.822076) (xy 220.051859 -22.85773) (xy 220.029786 -22.872954) (xy 220.018237 -22.881232)
			(xy 219.999836 -22.902864) (xy 219.988101 -22.928727) (xy 219.983939 -22.956821) (xy 219.987672 -22.984975)
			(xy 219.999011 -23.011013) (xy 220.01708 -23.032924) (xy 220.028516 -23.041356) (xy 220.049966 -23.056718)
			(xy 220.088879 -23.092344) (xy 220.122512 -23.132991) (xy 220.150224 -23.177885) (xy 220.171485 -23.226169)
			(xy 220.185891 -23.276921) (xy 220.193167 -23.329175) (xy 220.193616 -23.355554) (xy 220.19313 -23.382805)
			(xy 220.185374 -23.436753) (xy 220.170019 -23.489048) (xy 220.147377 -23.538625) (xy 220.117911 -23.584475)
			(xy 220.08222 -23.625666) (xy 220.041029 -23.661357) (xy 219.995179 -23.690823) (xy 219.945602 -23.713465)
			(xy 219.893307 -23.72882) (xy 219.839359 -23.736576) (xy 219.784857 -23.736576) (xy 219.730909 -23.72882)
			(xy 219.678614 -23.713465) (xy 219.629037 -23.690823) (xy 219.583187 -23.661357) (xy 219.541996 -23.625666)
			(xy 219.506305 -23.584475) (xy 219.476839 -23.538625) (xy 219.454197 -23.489048) (xy 219.438842 -23.436753)
			(xy 219.431086 -23.382805) (xy 219.4306 -23.355554) (xy 210.868011 -23.355554) (xy 210.868874 -23.356517)
			(xy 210.899647 -23.40303) (xy 210.923319 -23.453527) (xy 210.939387 -23.506934) (xy 210.947507 -23.56211)
			(xy 210.948016 -23.589996) (xy 210.947507 -23.617882) (xy 210.939387 -23.673058) (xy 210.923319 -23.726465)
			(xy 210.899647 -23.776962) (xy 210.868874 -23.823475) (xy 210.831657 -23.865012) (xy 210.813265 -23.880318)
			(xy 211.340698 -23.880318) (xy 211.344769 -23.824696) (xy 211.356895 -23.770259) (xy 211.376818 -23.718168)
			(xy 211.404114 -23.669533) (xy 211.4382 -23.62539) (xy 211.478349 -23.586681) (xy 211.523707 -23.55423)
			(xy 211.573307 -23.528729) (xy 211.626091 -23.510722) (xy 211.680934 -23.500592) (xy 211.736668 -23.498555)
			(xy 211.792105 -23.504655) (xy 211.846062 -23.518761) (xy 211.897391 -23.540573) (xy 211.944997 -23.569627)
			(xy 211.987865 -23.605302) (xy 212.025082 -23.646839) (xy 212.055855 -23.693352) (xy 212.079527 -23.743849)
			(xy 212.095595 -23.797256) (xy 212.103715 -23.852432) (xy 212.104224 -23.880318) (xy 212.356698 -23.880318)
			(xy 212.360769 -23.824696) (xy 212.372895 -23.770259) (xy 212.392818 -23.718168) (xy 212.420114 -23.669533)
			(xy 212.4542 -23.62539) (xy 212.494349 -23.586681) (xy 212.539707 -23.55423) (xy 212.589307 -23.528729)
			(xy 212.642091 -23.510722) (xy 212.696934 -23.500592) (xy 212.752668 -23.498555) (xy 212.808105 -23.504655)
			(xy 212.862062 -23.518761) (xy 212.913391 -23.540573) (xy 212.960997 -23.569627) (xy 213.003865 -23.605302)
			(xy 213.041082 -23.646839) (xy 213.071855 -23.693352) (xy 213.095527 -23.743849) (xy 213.111595 -23.797256)
			(xy 213.119715 -23.852432) (xy 213.120224 -23.880318) (xy 213.372698 -23.880318) (xy 213.376769 -23.824696)
			(xy 213.388895 -23.770259) (xy 213.408818 -23.718168) (xy 213.436114 -23.669533) (xy 213.4702 -23.62539)
			(xy 213.510349 -23.586681) (xy 213.555707 -23.55423) (xy 213.605307 -23.528729) (xy 213.658091 -23.510722)
			(xy 213.712934 -23.500592) (xy 213.768668 -23.498555) (xy 213.824105 -23.504655) (xy 213.878062 -23.518761)
			(xy 213.929391 -23.540573) (xy 213.976997 -23.569627) (xy 214.019865 -23.605302) (xy 214.057082 -23.646839)
			(xy 214.087855 -23.693352) (xy 214.111527 -23.743849) (xy 214.127595 -23.797256) (xy 214.135715 -23.852432)
			(xy 214.136224 -23.880318) (xy 214.390984 -23.880318) (xy 214.395055 -23.824696) (xy 214.407181 -23.770259)
			(xy 214.427104 -23.718168) (xy 214.4544 -23.669533) (xy 214.488486 -23.62539) (xy 214.528635 -23.586681)
			(xy 214.573993 -23.55423) (xy 214.623593 -23.528729) (xy 214.676377 -23.510722) (xy 214.73122 -23.500592)
			(xy 214.786954 -23.498555) (xy 214.842391 -23.504655) (xy 214.896348 -23.518761) (xy 214.947677 -23.540573)
			(xy 214.995283 -23.569627) (xy 215.038151 -23.605302) (xy 215.075368 -23.646839) (xy 215.106141 -23.693352)
			(xy 215.129813 -23.743849) (xy 215.145881 -23.797256) (xy 215.154001 -23.852432) (xy 215.15451 -23.880318)
			(xy 215.154001 -23.908204) (xy 215.145881 -23.96338) (xy 215.129813 -24.016787) (xy 215.106141 -24.067284)
			(xy 215.075368 -24.113797) (xy 215.038151 -24.155334) (xy 214.995283 -24.191009) (xy 214.947677 -24.220063)
			(xy 214.896348 -24.241875) (xy 214.842391 -24.255981) (xy 214.786954 -24.262081) (xy 214.73122 -24.260044)
			(xy 214.676377 -24.249914) (xy 214.623593 -24.231907) (xy 214.573993 -24.206406) (xy 214.528635 -24.173955)
			(xy 214.488486 -24.135246) (xy 214.4544 -24.091103) (xy 214.427104 -24.042468) (xy 214.407181 -23.990377)
			(xy 214.395055 -23.93594) (xy 214.390984 -23.880318) (xy 214.136224 -23.880318) (xy 214.135715 -23.908204)
			(xy 214.127595 -23.96338) (xy 214.111527 -24.016787) (xy 214.087855 -24.067284) (xy 214.057082 -24.113797)
			(xy 214.019865 -24.155334) (xy 213.976997 -24.191009) (xy 213.929391 -24.220063) (xy 213.878062 -24.241875)
			(xy 213.824105 -24.255981) (xy 213.768668 -24.262081) (xy 213.712934 -24.260044) (xy 213.658091 -24.249914)
			(xy 213.605307 -24.231907) (xy 213.555707 -24.206406) (xy 213.510349 -24.173955) (xy 213.4702 -24.135246)
			(xy 213.436114 -24.091103) (xy 213.408818 -24.042468) (xy 213.388895 -23.990377) (xy 213.376769 -23.93594)
			(xy 213.372698 -23.880318) (xy 213.120224 -23.880318) (xy 213.119715 -23.908204) (xy 213.111595 -23.96338)
			(xy 213.095527 -24.016787) (xy 213.071855 -24.067284) (xy 213.041082 -24.113797) (xy 213.003865 -24.155334)
			(xy 212.960997 -24.191009) (xy 212.913391 -24.220063) (xy 212.862062 -24.241875) (xy 212.808105 -24.255981)
			(xy 212.752668 -24.262081) (xy 212.696934 -24.260044) (xy 212.642091 -24.249914) (xy 212.589307 -24.231907)
			(xy 212.539707 -24.206406) (xy 212.494349 -24.173955) (xy 212.4542 -24.135246) (xy 212.420114 -24.091103)
			(xy 212.392818 -24.042468) (xy 212.372895 -23.990377) (xy 212.360769 -23.93594) (xy 212.356698 -23.880318)
			(xy 212.104224 -23.880318) (xy 212.103715 -23.908204) (xy 212.095595 -23.96338) (xy 212.079527 -24.016787)
			(xy 212.055855 -24.067284) (xy 212.025082 -24.113797) (xy 211.987865 -24.155334) (xy 211.944997 -24.191009)
			(xy 211.897391 -24.220063) (xy 211.846062 -24.241875) (xy 211.792105 -24.255981) (xy 211.736668 -24.262081)
			(xy 211.680934 -24.260044) (xy 211.626091 -24.249914) (xy 211.573307 -24.231907) (xy 211.523707 -24.206406)
			(xy 211.478349 -24.173955) (xy 211.4382 -24.135246) (xy 211.404114 -24.091103) (xy 211.376818 -24.042468)
			(xy 211.356895 -23.990377) (xy 211.344769 -23.93594) (xy 211.340698 -23.880318) (xy 210.813265 -23.880318)
			(xy 210.788789 -23.900687) (xy 210.741183 -23.929741) (xy 210.689854 -23.951553) (xy 210.635897 -23.965659)
			(xy 210.58046 -23.971759) (xy 210.524726 -23.969722) (xy 210.469883 -23.959592) (xy 210.417099 -23.941585)
			(xy 210.367499 -23.916084) (xy 210.322141 -23.883633) (xy 210.281992 -23.844924) (xy 210.247906 -23.800781)
			(xy 210.22061 -23.752146) (xy 210.200687 -23.700055) (xy 210.188561 -23.645618) (xy 210.18449 -23.589996)
			(xy 206.928351 -23.589996) (xy 206.927973 -23.610893) (xy 206.920211 -23.66483) (xy 206.904853 -23.717114)
			(xy 206.882211 -23.766681) (xy 206.852746 -23.812521) (xy 206.817057 -23.853701) (xy 206.775871 -23.889383)
			(xy 206.730026 -23.918841) (xy 206.680456 -23.941475) (xy 206.628169 -23.956825) (xy 206.57423 -23.964577)
			(xy 206.519737 -23.964575) (xy 206.465799 -23.956818) (xy 206.413513 -23.941464) (xy 206.363945 -23.918825)
			(xy 206.318103 -23.889363) (xy 206.27692 -23.853677) (xy 206.241234 -23.812494) (xy 206.211773 -23.766652)
			(xy 206.189135 -23.717083) (xy 206.173782 -23.664798) (xy 206.166025 -23.610859) (xy 206.166023 -23.556366)
			(xy 195.557304 -23.556366) (xy 195.558664 -23.557738) (xy 195.575428 -23.565358) (xy 195.58508 -23.56612)
			(xy 195.613838 -23.568362) (xy 195.670246 -23.580418) (xy 195.724196 -23.600828) (xy 195.774459 -23.629126)
			(xy 195.81989 -23.664668) (xy 195.859454 -23.706643) (xy 195.892249 -23.754095) (xy 195.917527 -23.805942)
			(xy 195.934714 -23.861004) (xy 195.943416 -23.918025) (xy 195.943982 -23.946866) (xy 195.943536 -23.970996)
			(xy 196.172834 -23.970996) (xy 196.176905 -23.915374) (xy 196.189031 -23.860937) (xy 196.208954 -23.808846)
			(xy 196.23625 -23.760211) (xy 196.270336 -23.716068) (xy 196.310485 -23.677359) (xy 196.355843 -23.644908)
			(xy 196.405443 -23.619407) (xy 196.458227 -23.6014) (xy 196.51307 -23.59127) (xy 196.568804 -23.589233)
			(xy 196.624241 -23.595333) (xy 196.678198 -23.609439) (xy 196.729527 -23.631251) (xy 196.777133 -23.660305)
			(xy 196.820001 -23.69598) (xy 196.857218 -23.737517) (xy 196.887991 -23.78403) (xy 196.911663 -23.834527)
			(xy 196.927731 -23.887934) (xy 196.935851 -23.94311) (xy 196.93636 -23.970996) (xy 196.935851 -23.998882)
			(xy 196.927731 -24.054058) (xy 196.911663 -24.107465) (xy 196.887991 -24.157962) (xy 196.887838 -24.158194)
			(xy 201.550776 -24.158194) (xy 201.554847 -24.102572) (xy 201.566973 -24.048135) (xy 201.586896 -23.996044)
			(xy 201.614192 -23.947409) (xy 201.648278 -23.903266) (xy 201.688427 -23.864557) (xy 201.733785 -23.832106)
			(xy 201.783385 -23.806605) (xy 201.836169 -23.788598) (xy 201.891012 -23.778468) (xy 201.946746 -23.776431)
			(xy 202.002183 -23.782531) (xy 202.05614 -23.796637) (xy 202.107469 -23.818449) (xy 202.155075 -23.847503)
			(xy 202.197943 -23.883178) (xy 202.23516 -23.924715) (xy 202.265933 -23.971228) (xy 202.289605 -24.021725)
			(xy 202.305673 -24.075132) (xy 202.313793 -24.130308) (xy 202.314302 -24.158194) (xy 202.313793 -24.18608)
			(xy 202.313224 -24.189944) (xy 205.398876 -24.189944) (xy 205.402947 -24.134322) (xy 205.415073 -24.079885)
			(xy 205.434996 -24.027794) (xy 205.462292 -23.979159) (xy 205.496378 -23.935016) (xy 205.536527 -23.896307)
			(xy 205.581885 -23.863856) (xy 205.631485 -23.838355) (xy 205.684269 -23.820348) (xy 205.739112 -23.810218)
			(xy 205.794846 -23.808181) (xy 205.850283 -23.814281) (xy 205.90424 -23.828387) (xy 205.955569 -23.850199)
			(xy 206.003175 -23.879253) (xy 206.046043 -23.914928) (xy 206.08326 -23.956465) (xy 206.114033 -24.002978)
			(xy 206.137705 -24.053475) (xy 206.153773 -24.106882) (xy 206.161893 -24.162058) (xy 206.162402 -24.189944)
			(xy 207.921858 -24.189944) (xy 207.925929 -24.134322) (xy 207.938055 -24.079885) (xy 207.957978 -24.027794)
			(xy 207.985274 -23.979159) (xy 208.01936 -23.935016) (xy 208.059509 -23.896307) (xy 208.104867 -23.863856)
			(xy 208.154467 -23.838355) (xy 208.207251 -23.820348) (xy 208.262094 -23.810218) (xy 208.317828 -23.808181)
			(xy 208.373265 -23.814281) (xy 208.427222 -23.828387) (xy 208.478551 -23.850199) (xy 208.526157 -23.879253)
			(xy 208.569025 -23.914928) (xy 208.606242 -23.956465) (xy 208.637015 -24.002978) (xy 208.660687 -24.053475)
			(xy 208.676755 -24.106882) (xy 208.684875 -24.162058) (xy 208.685384 -24.189944) (xy 208.684875 -24.21783)
			(xy 208.676755 -24.273006) (xy 208.660687 -24.326413) (xy 208.637015 -24.37691) (xy 208.606242 -24.423423)
			(xy 208.569025 -24.46496) (xy 208.526157 -24.500635) (xy 208.478551 -24.529689) (xy 208.427222 -24.551501)
			(xy 208.373265 -24.565607) (xy 208.317828 -24.571707) (xy 208.262094 -24.56967) (xy 208.207251 -24.55954)
			(xy 208.154467 -24.541533) (xy 208.104867 -24.516032) (xy 208.059509 -24.483581) (xy 208.01936 -24.444872)
			(xy 207.985274 -24.400729) (xy 207.957978 -24.352094) (xy 207.938055 -24.300003) (xy 207.925929 -24.245566)
			(xy 207.921858 -24.189944) (xy 206.162402 -24.189944) (xy 206.161893 -24.21783) (xy 206.153773 -24.273006)
			(xy 206.137705 -24.326413) (xy 206.114033 -24.37691) (xy 206.08326 -24.423423) (xy 206.046043 -24.46496)
			(xy 206.003175 -24.500635) (xy 205.955569 -24.529689) (xy 205.90424 -24.551501) (xy 205.850283 -24.565607)
			(xy 205.794846 -24.571707) (xy 205.739112 -24.56967) (xy 205.684269 -24.55954) (xy 205.631485 -24.541533)
			(xy 205.581885 -24.516032) (xy 205.536527 -24.483581) (xy 205.496378 -24.444872) (xy 205.462292 -24.400729)
			(xy 205.434996 -24.352094) (xy 205.415073 -24.300003) (xy 205.402947 -24.245566) (xy 205.398876 -24.189944)
			(xy 202.313224 -24.189944) (xy 202.305673 -24.241256) (xy 202.289605 -24.294663) (xy 202.265933 -24.34516)
			(xy 202.23516 -24.391673) (xy 202.197943 -24.43321) (xy 202.155075 -24.468885) (xy 202.107469 -24.497939)
			(xy 202.05614 -24.519751) (xy 202.002183 -24.533857) (xy 201.946746 -24.539957) (xy 201.891012 -24.53792)
			(xy 201.836169 -24.52779) (xy 201.783385 -24.509783) (xy 201.733785 -24.484282) (xy 201.688427 -24.451831)
			(xy 201.648278 -24.413122) (xy 201.614192 -24.368979) (xy 201.586896 -24.320344) (xy 201.566973 -24.268253)
			(xy 201.554847 -24.213816) (xy 201.550776 -24.158194) (xy 196.887838 -24.158194) (xy 196.857218 -24.204475)
			(xy 196.820001 -24.246012) (xy 196.777133 -24.281687) (xy 196.729527 -24.310741) (xy 196.678198 -24.332553)
			(xy 196.624241 -24.346659) (xy 196.568804 -24.352759) (xy 196.51307 -24.350722) (xy 196.458227 -24.340592)
			(xy 196.405443 -24.322585) (xy 196.355843 -24.297084) (xy 196.310485 -24.264633) (xy 196.270336 -24.225924)
			(xy 196.23625 -24.181781) (xy 196.208954 -24.133146) (xy 196.189031 -24.081055) (xy 196.176905 -24.026618)
			(xy 196.172834 -23.970996) (xy 195.943536 -23.970996) (xy 195.943457 -23.975243) (xy 195.935044 -24.031369)
			(xy 195.918412 -24.085631) (xy 195.893929 -24.136831) (xy 195.862135 -24.183842) (xy 195.823729 -24.225627)
			(xy 195.77956 -24.261265) (xy 195.730601 -24.289969) (xy 195.677931 -24.311107) (xy 195.622711 -24.324213)
			(xy 195.594478 -24.327104) (xy 195.593462 -24.327104) (xy 195.584295 -24.328475) (xy 195.567751 -24.336801)
			(xy 195.561204 -24.34336) (xy 195.514468 -24.393906) (xy 195.508282 -24.401165) (xy 195.501361 -24.41892)
			(xy 195.501006 -24.42845) (xy 195.501006 -24.807418) (xy 202.720192 -24.807418) (xy 202.724263 -24.751796)
			(xy 202.736389 -24.697359) (xy 202.756312 -24.645268) (xy 202.783608 -24.596633) (xy 202.817694 -24.55249)
			(xy 202.857843 -24.513781) (xy 202.903201 -24.48133) (xy 202.952801 -24.455829) (xy 203.005585 -24.437822)
			(xy 203.060428 -24.427692) (xy 203.116162 -24.425655) (xy 203.171599 -24.431755) (xy 203.225556 -24.445861)
			(xy 203.276885 -24.467673) (xy 203.324491 -24.496727) (xy 203.367359 -24.532402) (xy 203.404576 -24.573939)
			(xy 203.435349 -24.620452) (xy 203.459021 -24.670949) (xy 203.475089 -24.724356) (xy 203.480136 -24.75865)
			(xy 214.96858 -24.75865) (xy 214.972651 -24.703028) (xy 214.984777 -24.648591) (xy 215.0047 -24.5965)
			(xy 215.031996 -24.547865) (xy 215.066082 -24.503722) (xy 215.106231 -24.465013) (xy 215.151589 -24.432562)
			(xy 215.201189 -24.407061) (xy 215.253973 -24.389054) (xy 215.308816 -24.378924) (xy 215.36455 -24.376887)
			(xy 215.419987 -24.382987) (xy 215.473944 -24.397093) (xy 215.525273 -24.418905) (xy 215.572879 -24.447959)
			(xy 215.615747 -24.483634) (xy 215.652964 -24.525171) (xy 215.683737 -24.571684) (xy 215.707409 -24.622181)
			(xy 215.723477 -24.675588) (xy 215.731597 -24.730764) (xy 215.732106 -24.75865) (xy 215.731597 -24.786536)
			(xy 215.723477 -24.841712) (xy 215.707409 -24.895119) (xy 215.683737 -24.945616) (xy 215.652964 -24.992129)
			(xy 215.615747 -25.033666) (xy 215.572879 -25.069341) (xy 215.525273 -25.098395) (xy 215.473944 -25.120207)
			(xy 215.419987 -25.134313) (xy 215.36455 -25.140413) (xy 215.308816 -25.138376) (xy 215.253973 -25.128246)
			(xy 215.201189 -25.110239) (xy 215.151589 -25.084738) (xy 215.106231 -25.052287) (xy 215.066082 -25.013578)
			(xy 215.031996 -24.969435) (xy 215.0047 -24.9208) (xy 214.984777 -24.868709) (xy 214.972651 -24.814272)
			(xy 214.96858 -24.75865) (xy 203.480136 -24.75865) (xy 203.483209 -24.779532) (xy 203.483718 -24.807418)
			(xy 203.483209 -24.835304) (xy 203.475089 -24.89048) (xy 203.459021 -24.943887) (xy 203.435349 -24.994384)
			(xy 203.404576 -25.040897) (xy 203.367359 -25.082434) (xy 203.324491 -25.118109) (xy 203.276885 -25.147163)
			(xy 203.225556 -25.168975) (xy 203.171599 -25.183081) (xy 203.116162 -25.189181) (xy 203.060428 -25.187144)
			(xy 203.005585 -25.177014) (xy 202.952801 -25.159007) (xy 202.903201 -25.133506) (xy 202.857843 -25.101055)
			(xy 202.817694 -25.062346) (xy 202.783608 -25.018203) (xy 202.756312 -24.969568) (xy 202.736389 -24.917477)
			(xy 202.724263 -24.86304) (xy 202.720192 -24.807418) (xy 195.501006 -24.807418) (xy 195.501006 -25.390094)
			(xy 207.909668 -25.390094) (xy 207.910154 -25.362843) (xy 207.91791 -25.308895) (xy 207.933265 -25.2566)
			(xy 207.955907 -25.207023) (xy 207.985373 -25.161173) (xy 208.021064 -25.119982) (xy 208.062255 -25.084291)
			(xy 208.108105 -25.054825) (xy 208.157682 -25.032183) (xy 208.209977 -25.016828) (xy 208.263925 -25.009072)
			(xy 208.318427 -25.009072) (xy 208.372375 -25.016828) (xy 208.42467 -25.032183) (xy 208.474247 -25.054825)
			(xy 208.520097 -25.084291) (xy 208.561288 -25.119982) (xy 208.596979 -25.161173) (xy 208.626445 -25.207023)
			(xy 208.649087 -25.2566) (xy 208.664442 -25.308895) (xy 208.672198 -25.362843) (xy 208.672684 -25.390094)
			(xy 208.6721 -25.419113) (xy 208.663311 -25.476482) (xy 208.645934 -25.531858) (xy 208.620371 -25.583964)
			(xy 208.587212 -25.631596) (xy 208.54722 -25.673658) (xy 208.524602 -25.691846) (xy 208.514057 -25.700615)
			(xy 208.497614 -25.72255) (xy 208.487608 -25.748071) (xy 208.484761 -25.775336) (xy 208.489278 -25.802374)
			(xy 208.500834 -25.827232) (xy 208.518594 -25.848114) (xy 208.529682 -25.856184) (xy 208.551317 -25.871512)
			(xy 208.590574 -25.907147) (xy 208.624518 -25.947877) (xy 208.652493 -25.992916) (xy 208.67396 -26.041395)
			(xy 208.688506 -26.09238) (xy 208.69585 -26.144888) (xy 208.696306 -26.171398) (xy 208.69582 -26.198649)
			(xy 208.688064 -26.252597) (xy 208.672709 -26.304892) (xy 208.650067 -26.354469) (xy 208.620601 -26.400319)
			(xy 208.58491 -26.44151) (xy 208.543719 -26.477201) (xy 208.497869 -26.506667) (xy 208.448292 -26.529309)
			(xy 208.395997 -26.544664) (xy 208.342049 -26.55242) (xy 208.287547 -26.55242) (xy 208.233599 -26.544664)
			(xy 208.181304 -26.529309) (xy 208.131727 -26.506667) (xy 208.085877 -26.477201) (xy 208.044686 -26.44151)
			(xy 208.008995 -26.400319) (xy 207.979529 -26.354469) (xy 207.956887 -26.304892) (xy 207.941532 -26.252597)
			(xy 207.933776 -26.198649) (xy 207.93329 -26.171398) (xy 207.93384 -26.142377) (xy 207.942632 -26.085005)
			(xy 207.960014 -26.029627) (xy 207.985583 -25.977521) (xy 208.01875 -25.92989) (xy 208.058749 -25.887832)
			(xy 208.081372 -25.869646) (xy 208.091929 -25.860888) (xy 208.108376 -25.838952) (xy 208.118384 -25.813428)
			(xy 208.121231 -25.786159) (xy 208.116711 -25.759118) (xy 208.10515 -25.734258) (xy 208.087384 -25.713376)
			(xy 208.076292 -25.705308) (xy 208.054648 -25.689993) (xy 208.015391 -25.654355) (xy 207.981449 -25.613622)
			(xy 207.953476 -25.568582) (xy 207.93201 -25.520101) (xy 207.917466 -25.469114) (xy 207.910123 -25.416604)
			(xy 207.909668 -25.390094) (xy 195.501006 -25.390094) (xy 195.501006 -25.971246) (xy 196.059804 -25.971246)
			(xy 196.063875 -25.915624) (xy 196.076001 -25.861187) (xy 196.095924 -25.809096) (xy 196.12322 -25.760461)
			(xy 196.157306 -25.716318) (xy 196.197455 -25.677609) (xy 196.242813 -25.645158) (xy 196.292413 -25.619657)
			(xy 196.345197 -25.60165) (xy 196.40004 -25.59152) (xy 196.455774 -25.589483) (xy 196.511211 -25.595583)
			(xy 196.565168 -25.609689) (xy 196.616497 -25.631501) (xy 196.664103 -25.660555) (xy 196.706971 -25.69623)
			(xy 196.744188 -25.737767) (xy 196.774961 -25.78428) (xy 196.798633 -25.834777) (xy 196.814701 -25.888184)
			(xy 196.822821 -25.94336) (xy 196.82333 -25.971246) (xy 197.075804 -25.971246) (xy 197.079875 -25.915624)
			(xy 197.092001 -25.861187) (xy 197.111924 -25.809096) (xy 197.13922 -25.760461) (xy 197.173306 -25.716318)
			(xy 197.213455 -25.677609) (xy 197.258813 -25.645158) (xy 197.308413 -25.619657) (xy 197.361197 -25.60165)
			(xy 197.41604 -25.59152) (xy 197.471774 -25.589483) (xy 197.527211 -25.595583) (xy 197.581168 -25.609689)
			(xy 197.632497 -25.631501) (xy 197.680103 -25.660555) (xy 197.722971 -25.69623) (xy 197.760188 -25.737767)
			(xy 197.790961 -25.78428) (xy 197.814633 -25.834777) (xy 197.830701 -25.888184) (xy 197.838821 -25.94336)
			(xy 197.83933 -25.971246) (xy 198.091804 -25.971246) (xy 198.095875 -25.915624) (xy 198.108001 -25.861187)
			(xy 198.127924 -25.809096) (xy 198.15522 -25.760461) (xy 198.189306 -25.716318) (xy 198.229455 -25.677609)
			(xy 198.274813 -25.645158) (xy 198.324413 -25.619657) (xy 198.377197 -25.60165) (xy 198.43204 -25.59152)
			(xy 198.487774 -25.589483) (xy 198.543211 -25.595583) (xy 198.597168 -25.609689) (xy 198.648497 -25.631501)
			(xy 198.696103 -25.660555) (xy 198.738971 -25.69623) (xy 198.776188 -25.737767) (xy 198.806961 -25.78428)
			(xy 198.830633 -25.834777) (xy 198.846701 -25.888184) (xy 198.854821 -25.94336) (xy 198.85533 -25.971246)
			(xy 198.854821 -25.999132) (xy 198.849729 -26.03373) (xy 199.3679 -26.03373) (xy 199.371971 -25.978108)
			(xy 199.384097 -25.923671) (xy 199.40402 -25.87158) (xy 199.431316 -25.822945) (xy 199.465402 -25.778802)
			(xy 199.505551 -25.740093) (xy 199.550909 -25.707642) (xy 199.600509 -25.682141) (xy 199.653293 -25.664134)
			(xy 199.708136 -25.654004) (xy 199.76387 -25.651967) (xy 199.819307 -25.658067) (xy 199.873264 -25.672173)
			(xy 199.924593 -25.693985) (xy 199.972199 -25.723039) (xy 200.015067 -25.758714) (xy 200.052284 -25.800251)
			(xy 200.083057 -25.846764) (xy 200.106729 -25.897261) (xy 200.122797 -25.950668) (xy 200.130917 -26.005844)
			(xy 200.131426 -26.03373) (xy 200.130917 -26.061616) (xy 200.122797 -26.116792) (xy 200.106729 -26.170199)
			(xy 200.083057 -26.220696) (xy 200.052823 -26.266394) (xy 202.620626 -26.266394) (xy 202.62105 -26.239139)
			(xy 202.628809 -26.185185) (xy 202.644167 -26.132885) (xy 202.666813 -26.083302) (xy 202.696285 -26.037448)
			(xy 202.731982 -25.996254) (xy 202.77318 -25.960561) (xy 202.819037 -25.931094) (xy 202.868622 -25.908453)
			(xy 202.920924 -25.8931) (xy 202.974879 -25.885347) (xy 203.002134 -25.884886) (xy 203.03146 -25.885397)
			(xy 203.089419 -25.894385) (xy 203.145317 -25.912143) (xy 203.197837 -25.938253) (xy 203.222098 -25.954736)
			(xy 203.232512 -25.961848) (xy 203.256896 -25.96515) (xy 203.359258 -25.927304) (xy 203.376022 -25.908762)
			(xy 203.37907 -25.89657) (xy 203.386383 -25.869475) (xy 203.407946 -25.817661) (xy 203.436869 -25.769566)
			(xy 203.472529 -25.726229) (xy 203.514155 -25.688587) (xy 203.560848 -25.657451) (xy 203.6116 -25.633496)
			(xy 203.665315 -25.617236) (xy 203.720833 -25.609025) (xy 203.748894 -25.608534) (xy 203.77615 -25.608913)
			(xy 203.830108 -25.61667) (xy 203.882412 -25.632027) (xy 203.931999 -25.654672) (xy 203.977857 -25.684143)
			(xy 204.019055 -25.71984) (xy 204.054754 -25.761038) (xy 204.084226 -25.806896) (xy 204.106871 -25.856482)
			(xy 204.122229 -25.908786) (xy 204.129987 -25.962744) (xy 204.129987 -25.990042) (xy 205.398876 -25.990042)
			(xy 205.402947 -25.93442) (xy 205.415073 -25.879983) (xy 205.434996 -25.827892) (xy 205.462292 -25.779257)
			(xy 205.496378 -25.735114) (xy 205.536527 -25.696405) (xy 205.581885 -25.663954) (xy 205.631485 -25.638453)
			(xy 205.684269 -25.620446) (xy 205.739112 -25.610316) (xy 205.794846 -25.608279) (xy 205.850283 -25.614379)
			(xy 205.90424 -25.628485) (xy 205.955569 -25.650297) (xy 206.003175 -25.679351) (xy 206.046043 -25.715026)
			(xy 206.08326 -25.756563) (xy 206.114033 -25.803076) (xy 206.137705 -25.853573) (xy 206.153773 -25.90698)
			(xy 206.161893 -25.962156) (xy 206.162402 -25.990042) (xy 206.161893 -26.017928) (xy 206.153773 -26.073104)
			(xy 206.137705 -26.126511) (xy 206.114033 -26.177008) (xy 206.08326 -26.223521) (xy 206.046043 -26.265058)
			(xy 206.003175 -26.300733) (xy 205.955569 -26.329787) (xy 205.90424 -26.351599) (xy 205.850283 -26.365705)
			(xy 205.794846 -26.371805) (xy 205.739112 -26.369768) (xy 205.684269 -26.359638) (xy 205.631485 -26.341631)
			(xy 205.581885 -26.31613) (xy 205.536527 -26.283679) (xy 205.496378 -26.24497) (xy 205.462292 -26.200827)
			(xy 205.434996 -26.152192) (xy 205.415073 -26.100101) (xy 205.402947 -26.045664) (xy 205.398876 -25.990042)
			(xy 204.129987 -25.990042) (xy 204.129987 -26.017256) (xy 204.122229 -26.071214) (xy 204.106871 -26.123518)
			(xy 204.084226 -26.173104) (xy 204.054754 -26.218962) (xy 204.019055 -26.26016) (xy 203.977857 -26.295857)
			(xy 203.931999 -26.325328) (xy 203.882412 -26.347973) (xy 203.830108 -26.36333) (xy 203.77615 -26.371087)
			(xy 203.748894 -26.37155) (xy 203.719569 -26.371018) (xy 203.661611 -26.362036) (xy 203.605713 -26.344283)
			(xy 203.553192 -26.31818) (xy 203.52893 -26.3017) (xy 203.518516 -26.294588) (xy 203.494132 -26.291286)
			(xy 203.39177 -26.329132) (xy 203.375006 -26.347674) (xy 203.371958 -26.359866) (xy 203.365174 -26.384898)
			(xy 203.345758 -26.432988) (xy 203.320002 -26.478002) (xy 203.28838 -26.519109) (xy 203.251478 -26.555549)
			(xy 203.230988 -26.571448) (xy 203.220828 -26.579322) (xy 203.21016 -26.601928) (xy 203.215748 -26.711656)
			(xy 203.228702 -26.733246) (xy 203.239624 -26.73985) (xy 203.263366 -26.754746) (xy 203.3066 -26.790414)
			(xy 203.344151 -26.832024) (xy 203.375209 -26.878679) (xy 203.399108 -26.929377) (xy 203.415333 -26.983025)
			(xy 203.423533 -27.03847) (xy 203.424028 -27.066494) (xy 203.423542 -27.093745) (xy 203.415786 -27.147693)
			(xy 203.400431 -27.199988) (xy 203.377789 -27.249565) (xy 203.348323 -27.295415) (xy 203.312632 -27.336606)
			(xy 203.271441 -27.372297) (xy 203.225591 -27.401763) (xy 203.176014 -27.424405) (xy 203.123719 -27.43976)
			(xy 203.069771 -27.447516) (xy 203.015269 -27.447516) (xy 202.961321 -27.43976) (xy 202.909026 -27.424405)
			(xy 202.859449 -27.401763) (xy 202.813599 -27.372297) (xy 202.772408 -27.336606) (xy 202.736717 -27.295415)
			(xy 202.707251 -27.249565) (xy 202.684609 -27.199988) (xy 202.669254 -27.147693) (xy 202.661498 -27.093745)
			(xy 202.661012 -27.066494) (xy 202.66155 -27.037006) (xy 202.670647 -26.978734) (xy 202.688608 -26.922559)
			(xy 202.715004 -26.869818) (xy 202.749205 -26.821771) (xy 202.790397 -26.779562) (xy 202.813666 -26.76144)
			(xy 202.823826 -26.753566) (xy 202.834494 -26.73096) (xy 202.828906 -26.621232) (xy 202.815952 -26.599642)
			(xy 202.80503 -26.593038) (xy 202.781295 -26.578131) (xy 202.738058 -26.542467) (xy 202.700505 -26.50086)
			(xy 202.669445 -26.454206) (xy 202.645545 -26.40351) (xy 202.62932 -26.349862) (xy 202.62112 -26.294418)
			(xy 202.620626 -26.266394) (xy 200.052823 -26.266394) (xy 200.052284 -26.267209) (xy 200.015067 -26.308746)
			(xy 199.972199 -26.344421) (xy 199.924593 -26.373475) (xy 199.873264 -26.395287) (xy 199.819307 -26.409393)
			(xy 199.76387 -26.415493) (xy 199.708136 -26.413456) (xy 199.653293 -26.403326) (xy 199.600509 -26.385319)
			(xy 199.550909 -26.359818) (xy 199.505551 -26.327367) (xy 199.465402 -26.288658) (xy 199.431316 -26.244515)
			(xy 199.40402 -26.19588) (xy 199.384097 -26.143789) (xy 199.371971 -26.089352) (xy 199.3679 -26.03373)
			(xy 198.849729 -26.03373) (xy 198.846701 -26.054308) (xy 198.830633 -26.107715) (xy 198.806961 -26.158212)
			(xy 198.776188 -26.204725) (xy 198.738971 -26.246262) (xy 198.696103 -26.281937) (xy 198.648497 -26.310991)
			(xy 198.597168 -26.332803) (xy 198.543211 -26.346909) (xy 198.487774 -26.353009) (xy 198.43204 -26.350972)
			(xy 198.377197 -26.340842) (xy 198.324413 -26.322835) (xy 198.274813 -26.297334) (xy 198.229455 -26.264883)
			(xy 198.189306 -26.226174) (xy 198.15522 -26.182031) (xy 198.127924 -26.133396) (xy 198.108001 -26.081305)
			(xy 198.095875 -26.026868) (xy 198.091804 -25.971246) (xy 197.83933 -25.971246) (xy 197.838821 -25.999132)
			(xy 197.830701 -26.054308) (xy 197.814633 -26.107715) (xy 197.790961 -26.158212) (xy 197.760188 -26.204725)
			(xy 197.722971 -26.246262) (xy 197.680103 -26.281937) (xy 197.632497 -26.310991) (xy 197.581168 -26.332803)
			(xy 197.527211 -26.346909) (xy 197.471774 -26.353009) (xy 197.41604 -26.350972) (xy 197.361197 -26.340842)
			(xy 197.308413 -26.322835) (xy 197.258813 -26.297334) (xy 197.213455 -26.264883) (xy 197.173306 -26.226174)
			(xy 197.13922 -26.182031) (xy 197.111924 -26.133396) (xy 197.092001 -26.081305) (xy 197.079875 -26.026868)
			(xy 197.075804 -25.971246) (xy 196.82333 -25.971246) (xy 196.822821 -25.999132) (xy 196.814701 -26.054308)
			(xy 196.798633 -26.107715) (xy 196.774961 -26.158212) (xy 196.744188 -26.204725) (xy 196.706971 -26.246262)
			(xy 196.664103 -26.281937) (xy 196.616497 -26.310991) (xy 196.565168 -26.332803) (xy 196.511211 -26.346909)
			(xy 196.455774 -26.353009) (xy 196.40004 -26.350972) (xy 196.345197 -26.340842) (xy 196.292413 -26.322835)
			(xy 196.242813 -26.297334) (xy 196.197455 -26.264883) (xy 196.157306 -26.226174) (xy 196.12322 -26.182031)
			(xy 196.095924 -26.133396) (xy 196.076001 -26.081305) (xy 196.063875 -26.026868) (xy 196.059804 -25.971246)
			(xy 195.501006 -25.971246) (xy 195.501006 -27.654758) (xy 195.501365 -27.664322) (xy 195.508298 -27.682144)
			(xy 195.521288 -27.696178) (xy 195.529708 -27.700732) (xy 195.529962 -27.700732) (xy 195.556765 -27.714212)
			(xy 195.606172 -27.748241) (xy 195.615347 -27.756956) (xy 198.859043 -27.756956) (xy 198.859043 -27.702444)
			(xy 198.866801 -27.648488) (xy 198.88216 -27.596185) (xy 198.904806 -27.546601) (xy 198.934279 -27.500745)
			(xy 198.969978 -27.459549) (xy 199.011177 -27.423855) (xy 199.057036 -27.394387) (xy 199.106623 -27.371746)
			(xy 199.158927 -27.356393) (xy 199.212884 -27.34864) (xy 199.24014 -27.34818) (xy 199.254225 -27.34828)
			(xy 199.282321 -27.350315) (xy 199.296274 -27.352244) (xy 199.30999 -27.354276) (xy 199.335898 -27.343862)
			(xy 199.406256 -27.249882) (xy 199.409304 -27.221942) (xy 199.403462 -27.209242) (xy 199.39242 -27.184112)
			(xy 199.376817 -27.131489) (xy 199.36891 -27.077174) (xy 199.36841 -27.04973) (xy 199.368896 -27.022479)
			(xy 199.376652 -26.968531) (xy 199.392007 -26.916236) (xy 199.414649 -26.866659) (xy 199.444115 -26.820809)
			(xy 199.479806 -26.779618) (xy 199.520997 -26.743927) (xy 199.566847 -26.714461) (xy 199.616424 -26.691819)
			(xy 199.668719 -26.676464) (xy 199.722667 -26.668708) (xy 199.777169 -26.668708) (xy 199.831117 -26.676464)
			(xy 199.883412 -26.691819) (xy 199.932989 -26.714461) (xy 199.978839 -26.743927) (xy 200.02003 -26.779618)
			(xy 200.055721 -26.820809) (xy 200.085187 -26.866659) (xy 200.107829 -26.916236) (xy 200.123184 -26.968531)
			(xy 200.13094 -27.022479) (xy 200.131426 -27.04973) (xy 200.130802 -27.081146) (xy 200.120541 -27.143132)
			(xy 200.100267 -27.202602) (xy 200.08596 -27.230578) (xy 200.080626 -27.24023) (xy 200.079102 -27.262074)
			(xy 200.113392 -27.354022) (xy 200.128632 -27.369516) (xy 200.138792 -27.37358) (xy 200.165434 -27.38435)
			(xy 200.215402 -27.412727) (xy 200.260545 -27.448283) (xy 200.299841 -27.490211) (xy 200.332399 -27.537561)
			(xy 200.357482 -27.589262) (xy 200.374522 -27.644141) (xy 200.383133 -27.700956) (xy 200.383648 -27.729688)
			(xy 200.383111 -27.756937) (xy 200.375357 -27.810881) (xy 200.360005 -27.863172) (xy 200.337368 -27.912747)
			(xy 200.307907 -27.958595) (xy 200.272221 -27.999784) (xy 200.231037 -28.035476) (xy 200.185192 -28.064944)
			(xy 200.135621 -28.087587) (xy 200.083332 -28.102946) (xy 200.029389 -28.110707) (xy 200.00214 -28.111196)
			(xy 199.973224 -28.11065) (xy 199.916054 -28.101927) (xy 199.860856 -28.084675) (xy 199.808894 -28.059288)
			(xy 199.761359 -28.02635) (xy 199.719341 -27.986613) (xy 199.70115 -27.96413) (xy 199.693574 -27.955383)
			(xy 199.672825 -27.945194) (xy 199.661272 -27.944572) (xy 199.581008 -27.944572) (xy 199.569437 -27.945122)
			(xy 199.548665 -27.955329) (xy 199.54113 -27.96413) (xy 199.52293 -27.986605) (xy 199.480911 -28.02634)
			(xy 199.433378 -28.059279) (xy 199.381418 -28.084668) (xy 199.326223 -28.101927) (xy 199.269055 -28.110659)
			(xy 199.24014 -28.111196) (xy 199.212884 -28.11076) (xy 199.158927 -28.103007) (xy 199.106623 -28.087654)
			(xy 199.057036 -28.065013) (xy 199.011177 -28.035545) (xy 198.969978 -27.999851) (xy 198.934279 -27.958655)
			(xy 198.904806 -27.912799) (xy 198.88216 -27.863215) (xy 198.866801 -27.810912) (xy 198.859043 -27.756956)
			(xy 195.615347 -27.756956) (xy 195.649668 -27.789558) (xy 195.668392 -27.813) (xy 195.670678 -27.816048)
			(xy 195.673218 -27.818588) (xy 195.676266 -27.821636) (xy 195.682225 -27.827145) (xy 195.69673 -27.834409)
			(xy 195.704714 -27.83586) (xy 195.71589 -27.837638) (xy 195.783708 -27.847544) (xy 195.803266 -27.842464)
			(xy 195.811394 -27.836114) (xy 195.831444 -27.821289) (xy 195.87466 -27.796414) (xy 195.920748 -27.77738)
			(xy 195.968923 -27.764512) (xy 196.018364 -27.758029) (xy 196.043296 -27.757628) (xy 196.071346 -27.758124)
			(xy 196.126841 -27.766337) (xy 196.180535 -27.782588) (xy 196.231271 -27.806525) (xy 196.277956 -27.837633)
			(xy 196.319582 -27.875242) (xy 196.355253 -27.91854) (xy 196.370194 -27.942286) (xy 196.37375 -27.947874)
			(xy 196.382386 -27.956764) (xy 196.408294 -27.97175) (xy 196.418454 -27.976322) (xy 196.427852 -27.978608)
			(xy 196.433948 -27.978862) (xy 196.487542 -27.978862) (xy 196.493979 -27.978655) (xy 196.506446 -27.975444)
			(xy 196.51218 -27.972512) (xy 196.537834 -27.958288) (xy 196.546978 -27.949398) (xy 196.550534 -27.94381)
			(xy 196.561605 -27.926394) (xy 196.586933 -27.893811) (xy 196.60108 -27.878786) (xy 196.601588 -27.878278)
			(xy 196.602096 -27.87777) (xy 196.620196 -27.859167) (xy 196.660555 -27.82653) (xy 196.704965 -27.799664)
			(xy 196.752605 -27.779064) (xy 196.802598 -27.76511) (xy 196.85402 -27.758059) (xy 196.879972 -27.757628)
			(xy 196.907225 -27.758089) (xy 196.961177 -27.765843) (xy 197.013476 -27.781197) (xy 197.063058 -27.803839)
			(xy 197.108912 -27.833307) (xy 197.150105 -27.869001) (xy 197.185798 -27.910195) (xy 197.215265 -27.956049)
			(xy 197.237905 -28.005631) (xy 197.253258 -28.057931) (xy 197.261011 -28.111883) (xy 197.26148 -28.139136)
			(xy 197.767954 -28.139136) (xy 197.772025 -28.083514) (xy 197.784151 -28.029077) (xy 197.804074 -27.976986)
			(xy 197.83137 -27.928351) (xy 197.865456 -27.884208) (xy 197.905605 -27.845499) (xy 197.950963 -27.813048)
			(xy 198.000563 -27.787547) (xy 198.053347 -27.76954) (xy 198.10819 -27.75941) (xy 198.163924 -27.757373)
			(xy 198.219361 -27.763473) (xy 198.273318 -27.777579) (xy 198.324647 -27.799391) (xy 198.372253 -27.828445)
			(xy 198.415121 -27.86412) (xy 198.452338 -27.905657) (xy 198.483111 -27.95217) (xy 198.506783 -28.002667)
			(xy 198.522851 -28.056074) (xy 198.530971 -28.11125) (xy 198.53148 -28.139136) (xy 198.530971 -28.167022)
			(xy 198.522851 -28.222198) (xy 198.506783 -28.275605) (xy 198.483111 -28.326102) (xy 198.452338 -28.372615)
			(xy 198.415121 -28.414152) (xy 198.372253 -28.449827) (xy 198.324647 -28.478881) (xy 198.273318 -28.500693)
			(xy 198.219361 -28.514799) (xy 198.163924 -28.520899) (xy 198.10819 -28.518862) (xy 198.053347 -28.508732)
			(xy 198.000563 -28.490725) (xy 197.950963 -28.465224) (xy 197.905605 -28.432773) (xy 197.865456 -28.394064)
			(xy 197.83137 -28.349921) (xy 197.804074 -28.301286) (xy 197.784151 -28.249195) (xy 197.772025 -28.194758)
			(xy 197.767954 -28.139136) (xy 197.26148 -28.139136) (xy 197.260944 -28.168435) (xy 197.251985 -28.226343)
			(xy 197.234283 -28.282202) (xy 197.208254 -28.334701) (xy 197.174508 -28.382606) (xy 197.154546 -28.404058)
			(xy 197.153784 -28.40482) (xy 197.152006 -28.406598) (xy 197.133934 -28.42506) (xy 197.093671 -28.457433)
			(xy 197.049406 -28.484072) (xy 197.001948 -28.504488) (xy 196.952168 -28.518308) (xy 196.900978 -28.525279)
			(xy 196.875146 -28.525724) (xy 196.846593 -28.525187) (xy 196.790125 -28.516672) (xy 196.735556 -28.499839)
			(xy 196.684104 -28.475065) (xy 196.636916 -28.442903) (xy 196.595046 -28.404069) (xy 196.559429 -28.359432)
			(xy 196.544692 -28.33497) (xy 196.539913 -28.327476) (xy 196.526309 -28.316058) (xy 196.509629 -28.309957)
			(xy 196.50075 -28.30957) (xy 196.414644 -28.30957) (xy 196.405851 -28.309933) (xy 196.389301 -28.315877)
			(xy 196.375744 -28.327079) (xy 196.370956 -28.334462) (xy 196.360104 -28.352116) (xy 196.335159 -28.385211)
			(xy 196.321172 -28.400502) (xy 196.32041 -28.401264) (xy 196.319394 -28.402534) (xy 196.318632 -28.403296)
			(xy 196.318378 -28.40355) (xy 196.300248 -28.422463) (xy 196.259706 -28.455646) (xy 196.215008 -28.482975)
			(xy 196.166993 -28.503936) (xy 196.116563 -28.518136) (xy 196.064665 -28.525308) (xy 196.03847 -28.525724)
			(xy 196.009313 -28.525169) (xy 195.951679 -28.516293) (xy 195.896066 -28.498752) (xy 195.843768 -28.472955)
			(xy 195.796005 -28.439501) (xy 195.753886 -28.39917) (xy 195.735702 -28.376372) (xy 195.733416 -28.373324)
			(xy 195.730876 -28.370784) (xy 195.727828 -28.367736) (xy 195.721867 -28.36223) (xy 195.707362 -28.354972)
			(xy 195.69938 -28.353512) (xy 195.629276 -28.343098) (xy 195.607686 -28.339796) (xy 195.579492 -28.361132)
			(xy 195.574666 -28.364434) (xy 195.566538 -28.373324) (xy 195.552314 -28.398978) (xy 195.549352 -28.404701)
			(xy 195.546132 -28.417174) (xy 195.545964 -28.423616) (xy 195.545964 -28.428696) (xy 195.546148 -28.435136)
			(xy 195.549353 -28.447612) (xy 195.552314 -28.453334) (xy 195.556632 -28.460954) (xy 195.559819 -28.466304)
			(xy 195.56829 -28.475424) (xy 195.573396 -28.478988) (xy 195.573904 -28.479242) (xy 195.574158 -28.479242)
			(xy 195.597128 -28.494339) (xy 195.638888 -28.530081) (xy 195.675095 -28.571438) (xy 195.705002 -28.617557)
			(xy 195.72799 -28.667486) (xy 195.743585 -28.720194) (xy 195.751466 -28.774593) (xy 195.751958 -28.802076)
			(xy 195.751442 -28.83078) (xy 195.742845 -28.887542) (xy 195.725841 -28.942374) (xy 195.700815 -28.994041)
			(xy 195.668331 -29.041375) (xy 195.649088 -29.06268) (xy 195.64858 -29.063188) (xy 195.647564 -29.064204)
			(xy 195.646548 -29.065474) (xy 195.64604 -29.065982) (xy 195.629356 -29.083504) (xy 195.592311 -29.114626)
			(xy 195.551633 -29.140822) (xy 195.529962 -29.15158) (xy 195.5165 -29.15793) (xy 195.501006 -29.182568)
			(xy 195.501006 -29.222446) (xy 195.501446 -29.232121) (xy 195.508614 -29.250098) (xy 195.521891 -29.264178)
			(xy 195.53047 -29.268674) (xy 195.554915 -29.280478) (xy 195.600482 -29.30998) (xy 195.641403 -29.345647)
			(xy 195.67685 -29.386759) (xy 195.706106 -29.432484) (xy 195.728579 -29.481897) (xy 195.743815 -29.533998)
			(xy 195.751505 -29.587734) (xy 195.751958 -29.614876) (xy 195.751743 -29.635807) (xy 195.747283 -29.67743)
			(xy 195.743068 -29.697934) (xy 195.736816 -29.723787) (xy 195.718124 -29.773584) (xy 195.692709 -29.820308)
			(xy 195.661061 -29.863058) (xy 195.642738 -29.882338) (xy 195.642484 -29.882592) (xy 195.632569 -29.892729)
			(xy 195.611466 -29.911672) (xy 195.60032 -29.920438) (xy 195.595494 -29.924248) (xy 195.588128 -29.933392)
			(xy 195.585334 -29.93898) (xy 195.583077 -29.944155) (xy 195.580649 -29.955179) (xy 195.580508 -29.960824)
			(xy 195.580508 -30.02026) (xy 195.580689 -30.026064) (xy 195.583372 -30.037358) (xy 195.585842 -30.042612)
			(xy 195.59778 -30.066996) (xy 195.604638 -30.075632) (xy 195.608956 -30.078934) (xy 195.630864 -30.097164)
			(xy 195.669547 -30.139017) (xy 195.701574 -30.186159) (xy 195.726232 -30.23754) (xy 195.742974 -30.292018)
			(xy 195.751425 -30.34838) (xy 195.751958 -30.376876) (xy 195.751442 -30.40558) (xy 195.742845 -30.462342)
			(xy 195.725841 -30.517174) (xy 195.700815 -30.568841) (xy 195.668331 -30.616175) (xy 195.649088 -30.63748)
			(xy 195.64858 -30.637988) (xy 195.647564 -30.639004) (xy 195.646548 -30.640274) (xy 195.64604 -30.640782)
			(xy 195.629356 -30.658304) (xy 195.592311 -30.689426) (xy 195.551633 -30.715622) (xy 195.529962 -30.72638)
			(xy 195.5165 -30.73273) (xy 195.501006 -30.757368) (xy 195.501006 -31.159958) (xy 195.525136 -31.188406)
			(xy 195.543424 -31.191454) (xy 195.570562 -31.196471) (xy 195.623123 -31.213292) (xy 195.672712 -31.237509)
			(xy 195.718294 -31.268619) (xy 195.758919 -31.305971) (xy 195.793739 -31.348786) (xy 195.822027 -31.396171)
			(xy 195.843193 -31.447138) (xy 195.856795 -31.500622) (xy 195.86255 -31.555507) (xy 195.860337 -31.61065)
			(xy 195.850203 -31.664898) (xy 195.832359 -31.71712) (xy 195.831259 -31.719266) (xy 196.385432 -31.719266)
			(xy 196.389503 -31.663644) (xy 196.401629 -31.609207) (xy 196.421552 -31.557116) (xy 196.448848 -31.508481)
			(xy 196.482934 -31.464338) (xy 196.523083 -31.425629) (xy 196.568441 -31.393178) (xy 196.618041 -31.367677)
			(xy 196.670825 -31.34967) (xy 196.725668 -31.33954) (xy 196.781402 -31.337503) (xy 196.836839 -31.343603)
			(xy 196.890796 -31.357709) (xy 196.942125 -31.379521) (xy 196.989731 -31.408575) (xy 197.032599 -31.44425)
			(xy 197.069816 -31.485787) (xy 197.100589 -31.5323) (xy 197.124261 -31.582797) (xy 197.140329 -31.636204)
			(xy 197.144479 -31.664402) (xy 197.66102 -31.664402) (xy 197.665091 -31.60878) (xy 197.677217 -31.554343)
			(xy 197.69714 -31.502252) (xy 197.724436 -31.453617) (xy 197.758522 -31.409474) (xy 197.798671 -31.370765)
			(xy 197.844029 -31.338314) (xy 197.893629 -31.312813) (xy 197.946413 -31.294806) (xy 198.001256 -31.284676)
			(xy 198.05699 -31.282639) (xy 198.112427 -31.288739) (xy 198.166384 -31.302845) (xy 198.217713 -31.324657)
			(xy 198.265319 -31.353711) (xy 198.308187 -31.389386) (xy 198.345404 -31.430923) (xy 198.376177 -31.477436)
			(xy 198.399849 -31.527933) (xy 198.415917 -31.58134) (xy 198.424037 -31.636516) (xy 198.424546 -31.664402)
			(xy 198.424037 -31.692288) (xy 198.415917 -31.747464) (xy 198.406977 -31.777178) (xy 198.926194 -31.777178)
			(xy 198.930265 -31.721556) (xy 198.942391 -31.667119) (xy 198.962314 -31.615028) (xy 198.98961 -31.566393)
			(xy 199.023696 -31.52225) (xy 199.063845 -31.483541) (xy 199.109203 -31.45109) (xy 199.158803 -31.425589)
			(xy 199.211587 -31.407582) (xy 199.26643 -31.397452) (xy 199.322164 -31.395415) (xy 199.377601 -31.401515)
			(xy 199.431558 -31.415621) (xy 199.482887 -31.437433) (xy 199.530493 -31.466487) (xy 199.573361 -31.502162)
			(xy 199.610578 -31.543699) (xy 199.641351 -31.590212) (xy 199.665023 -31.640709) (xy 199.681091 -31.694116)
			(xy 199.689211 -31.749292) (xy 199.68972 -31.777178) (xy 199.689211 -31.805064) (xy 199.681091 -31.86024)
			(xy 199.665023 -31.913647) (xy 199.641351 -31.964144) (xy 199.610578 -32.010657) (xy 199.573361 -32.052194)
			(xy 199.530493 -32.087869) (xy 199.482887 -32.116923) (xy 199.431558 -32.138735) (xy 199.377601 -32.152841)
			(xy 199.322164 -32.158941) (xy 199.26643 -32.156904) (xy 199.211587 -32.146774) (xy 199.158803 -32.128767)
			(xy 199.109203 -32.103266) (xy 199.063845 -32.070815) (xy 199.023696 -32.032106) (xy 198.98961 -31.987963)
			(xy 198.962314 -31.939328) (xy 198.942391 -31.887237) (xy 198.930265 -31.8328) (xy 198.926194 -31.777178)
			(xy 198.406977 -31.777178) (xy 198.399849 -31.800871) (xy 198.376177 -31.851368) (xy 198.345404 -31.897881)
			(xy 198.308187 -31.939418) (xy 198.265319 -31.975093) (xy 198.217713 -32.004147) (xy 198.166384 -32.025959)
			(xy 198.112427 -32.040065) (xy 198.05699 -32.046165) (xy 198.001256 -32.044128) (xy 197.946413 -32.033998)
			(xy 197.893629 -32.015991) (xy 197.844029 -31.99049) (xy 197.798671 -31.958039) (xy 197.758522 -31.91933)
			(xy 197.724436 -31.875187) (xy 197.69714 -31.826552) (xy 197.677217 -31.774461) (xy 197.665091 -31.720024)
			(xy 197.66102 -31.664402) (xy 197.144479 -31.664402) (xy 197.148449 -31.69138) (xy 197.148958 -31.719266)
			(xy 197.148449 -31.747152) (xy 197.140329 -31.802328) (xy 197.124261 -31.855735) (xy 197.100589 -31.906232)
			(xy 197.069816 -31.952745) (xy 197.032599 -31.994282) (xy 196.989731 -32.029957) (xy 196.942125 -32.059011)
			(xy 196.890796 -32.080823) (xy 196.836839 -32.094929) (xy 196.781402 -32.101029) (xy 196.725668 -32.098992)
			(xy 196.670825 -32.088862) (xy 196.618041 -32.070855) (xy 196.568441 -32.045354) (xy 196.523083 -32.012903)
			(xy 196.482934 -31.974194) (xy 196.448848 -31.930051) (xy 196.421552 -31.881416) (xy 196.401629 -31.829325)
			(xy 196.389503 -31.774888) (xy 196.385432 -31.719266) (xy 195.831259 -31.719266) (xy 195.807177 -31.766226)
			(xy 195.775183 -31.811193) (xy 195.75653 -31.831534) (xy 195.756022 -31.832042) (xy 195.755514 -31.832804)
			(xy 195.734096 -31.854964) (xy 195.685418 -31.892756) (xy 195.631299 -31.922235) (xy 195.573147 -31.942635)
			(xy 195.542916 -31.948628) (xy 195.524628 -31.95193) (xy 195.501006 -31.97987) (xy 195.501006 -33.512506)
			(xy 195.501487 -33.522403) (xy 195.508993 -33.54072) (xy 195.522855 -33.554852) (xy 195.53174 -33.559242)
			(xy 195.631562 -33.602168) (xy 195.66128 -33.596834) (xy 195.672456 -33.586166) (xy 195.681399 -33.577764)
			(xy 195.700208 -33.562002) (xy 195.710048 -33.55467) (xy 195.717668 -33.549082) (xy 195.727574 -33.534096)
			(xy 195.736972 -33.492948) (xy 195.744592 -33.46069) (xy 195.745499 -33.45624) (xy 195.74588 -33.447167)
			(xy 195.745354 -33.442656) (xy 195.744338 -33.43402) (xy 195.74002 -33.425384) (xy 195.739766 -33.424876)
			(xy 195.726106 -33.397429) (xy 195.706756 -33.339259) (xy 195.696955 -33.278744) (xy 195.696332 -33.248092)
			(xy 195.696818 -33.220841) (xy 195.704574 -33.166893) (xy 195.719929 -33.114598) (xy 195.742571 -33.065021)
			(xy 195.772037 -33.019171) (xy 195.807728 -32.97798) (xy 195.848919 -32.942289) (xy 195.894769 -32.912823)
			(xy 195.944346 -32.890181) (xy 195.996641 -32.874826) (xy 196.050589 -32.86707) (xy 196.105091 -32.86707)
			(xy 196.159039 -32.874826) (xy 196.211334 -32.890181) (xy 196.260911 -32.912823) (xy 196.306761 -32.942289)
			(xy 196.347952 -32.97798) (xy 196.383643 -33.019171) (xy 196.413109 -33.065021) (xy 196.435751 -33.114598)
			(xy 196.451106 -33.166893) (xy 196.458862 -33.220841) (xy 196.459348 -33.248092) (xy 196.458769 -33.27796)
			(xy 196.449456 -33.336964) (xy 196.431057 -33.393795) (xy 196.404022 -33.447063) (xy 196.369012 -33.495463)
			(xy 196.326883 -33.537812) (xy 196.303138 -33.55594) (xy 196.295518 -33.561528) (xy 196.285612 -33.576514)
			(xy 196.272658 -33.63214) (xy 196.272658 -33.632648) (xy 196.268594 -33.650428) (xy 196.266925 -33.659192)
			(xy 196.269147 -33.676883) (xy 196.272912 -33.684972) (xy 196.273166 -33.685226) (xy 196.273166 -33.68548)
			(xy 196.280452 -33.699609) (xy 196.292918 -33.728857) (xy 196.298058 -33.7439) (xy 196.298058 -33.744154)
			(xy 196.298312 -33.744662) (xy 196.301481 -33.753178) (xy 196.312808 -33.767369) (xy 196.32041 -33.772348)
			(xy 196.385688 -33.81121) (xy 196.393816 -33.812734) (xy 196.416377 -33.807503) (xy 196.462353 -33.801902)
			(xy 196.48551 -33.801558) (xy 196.512762 -33.802044) (xy 196.56671 -33.809802) (xy 196.619006 -33.825158)
			(xy 196.668584 -33.847799) (xy 196.683978 -33.857692) (xy 197.590154 -33.857692) (xy 197.594225 -33.80207)
			(xy 197.606351 -33.747633) (xy 197.626274 -33.695542) (xy 197.65357 -33.646907) (xy 197.687656 -33.602764)
			(xy 197.727805 -33.564055) (xy 197.773163 -33.531604) (xy 197.822763 -33.506103) (xy 197.875547 -33.488096)
			(xy 197.93039 -33.477966) (xy 197.986124 -33.475929) (xy 198.041561 -33.482029) (xy 198.095518 -33.496135)
			(xy 198.146847 -33.517947) (xy 198.194453 -33.547001) (xy 198.237321 -33.582676) (xy 198.274538 -33.624213)
			(xy 198.305311 -33.670726) (xy 198.328983 -33.721223) (xy 198.345051 -33.77463) (xy 198.353171 -33.829806)
			(xy 198.35368 -33.857692) (xy 198.353171 -33.885578) (xy 198.345051 -33.940754) (xy 198.328983 -33.994161)
			(xy 198.305311 -34.044658) (xy 198.274538 -34.091171) (xy 198.237321 -34.132708) (xy 198.194453 -34.168383)
			(xy 198.146847 -34.197437) (xy 198.095518 -34.219249) (xy 198.041561 -34.233355) (xy 197.986124 -34.239455)
			(xy 197.93039 -34.237418) (xy 197.875547 -34.227288) (xy 197.822763 -34.209281) (xy 197.773163 -34.18378)
			(xy 197.727805 -34.151329) (xy 197.687656 -34.11262) (xy 197.65357 -34.068477) (xy 197.626274 -34.019842)
			(xy 197.606351 -33.967751) (xy 197.594225 -33.913314) (xy 197.590154 -33.857692) (xy 196.683978 -33.857692)
			(xy 196.714435 -33.877265) (xy 196.755627 -33.912956) (xy 196.791321 -33.954145) (xy 196.82079 -33.999995)
			(xy 196.843434 -34.049572) (xy 196.858793 -34.101866) (xy 196.866554 -34.155814) (xy 196.867018 -34.183066)
			(xy 196.866479 -34.212363) (xy 196.857515 -34.270268) (xy 196.839807 -34.326123) (xy 196.813772 -34.378616)
			(xy 196.780021 -34.426514) (xy 196.760084 -34.447988) (xy 196.759322 -34.44875) (xy 196.757544 -34.450528)
			(xy 196.739474 -34.468995) (xy 196.699215 -34.501378) (xy 196.654951 -34.528026) (xy 196.607493 -34.548451)
			(xy 196.557711 -34.562279) (xy 196.506517 -34.569255) (xy 196.480684 -34.569654) (xy 196.454075 -34.569198)
			(xy 196.401372 -34.561814) (xy 196.350207 -34.547178) (xy 196.301572 -34.525573) (xy 196.256412 -34.49742)
			(xy 196.215602 -34.463264) (xy 196.179934 -34.423768) (xy 196.150101 -34.379698) (xy 196.126682 -34.331911)
			(xy 196.117972 -34.306764) (xy 196.117718 -34.306256) (xy 196.114547 -34.297742) (xy 196.103214 -34.283559)
			(xy 196.09562 -34.27857) (xy 196.030342 -34.239708) (xy 196.012562 -34.236406) (xy 196.003418 -34.238184)
			(xy 195.986607 -34.241026) (xy 195.952648 -34.244076) (xy 195.9356 -34.24428) (xy 195.935346 -34.24428)
			(xy 195.906336 -34.243736) (xy 195.848983 -34.234953) (xy 195.793619 -34.217598) (xy 195.741516 -34.192069)
			(xy 195.693873 -34.158953) (xy 195.672456 -34.139378) (xy 195.66128 -34.12871) (xy 195.631562 -34.123376)
			(xy 195.53174 -34.166302) (xy 195.522817 -34.170637) (xy 195.508929 -34.184775) (xy 195.501452 -34.203128)
			(xy 195.501006 -34.213038) (xy 195.501006 -35.264852) (xy 198.002396 -35.264852) (xy 198.006467 -35.20923)
			(xy 198.018593 -35.154793) (xy 198.038516 -35.102702) (xy 198.065812 -35.054067) (xy 198.099898 -35.009924)
			(xy 198.140047 -34.971215) (xy 198.185405 -34.938764) (xy 198.235005 -34.913263) (xy 198.287789 -34.895256)
			(xy 198.342632 -34.885126) (xy 198.398366 -34.883089) (xy 198.453803 -34.889189) (xy 198.50776 -34.903295)
			(xy 198.559089 -34.925107) (xy 198.606695 -34.954161) (xy 198.649563 -34.989836) (xy 198.674397 -35.017553)
			(xy 200.319856 -35.017553) (xy 200.319856 -34.963047) (xy 200.327613 -34.909097) (xy 200.342968 -34.8568)
			(xy 200.36561 -34.80722) (xy 200.395078 -34.761367) (xy 200.430771 -34.720175) (xy 200.471963 -34.684481)
			(xy 200.517815 -34.655013) (xy 200.567394 -34.63237) (xy 200.619691 -34.617014) (xy 200.673641 -34.609256)
			(xy 200.700894 -34.60877) (xy 200.718006 -34.608957) (xy 200.752093 -34.612012) (xy 200.768966 -34.614866)
			(xy 200.78023 -34.616294) (xy 200.802116 -34.610343) (xy 200.81113 -34.603436) (xy 200.835514 -34.582354)
			(xy 200.84391 -34.574435) (xy 200.853027 -34.553257) (xy 200.85304 -34.541714) (xy 200.852532 -34.52241)
			(xy 200.852532 -33.65881) (xy 200.85304 -33.638744) (xy 200.852868 -33.627235) (xy 200.843766 -33.606129)
			(xy 200.835514 -33.598104) (xy 200.81113 -33.577022) (xy 200.802125 -33.570098) (xy 200.780233 -33.564154)
			(xy 200.768966 -33.565592) (xy 200.752096 -33.568468) (xy 200.718007 -33.571517) (xy 200.700894 -33.571688)
			(xy 200.673642 -33.571242) (xy 200.619692 -33.563484) (xy 200.567395 -33.548128) (xy 200.517816 -33.525485)
			(xy 200.471964 -33.496017) (xy 200.430772 -33.460324) (xy 200.395079 -33.419131) (xy 200.365612 -33.373279)
			(xy 200.34297 -33.323699) (xy 200.327615 -33.271402) (xy 200.319858 -33.217452) (xy 200.319858 -33.162948)
			(xy 200.327615 -33.108998) (xy 200.34297 -33.056701) (xy 200.365612 -33.007121) (xy 200.395079 -32.961269)
			(xy 200.430772 -32.920076) (xy 200.471964 -32.884383) (xy 200.517816 -32.854915) (xy 200.567395 -32.832272)
			(xy 200.619692 -32.816916) (xy 200.673642 -32.809158) (xy 200.700894 -32.808672) (xy 200.727902 -32.809125)
			(xy 200.78138 -32.816731) (xy 200.833251 -32.831805) (xy 200.882475 -32.854046) (xy 200.92807 -32.883009)
			(xy 200.969123 -32.918115) (xy 201.004812 -32.958662) (xy 201.034425 -33.003838) (xy 201.057367 -33.052739)
			(xy 201.073182 -33.104389) (xy 201.07783 -33.130998) (xy 201.079354 -33.141666) (xy 201.090784 -33.159446)
			(xy 201.171048 -33.212786) (xy 201.191622 -33.216596) (xy 201.20229 -33.214056) (xy 201.228921 -33.207921)
			(xy 201.283169 -33.201303) (xy 201.310494 -33.200848) (xy 201.337818 -33.201311) (xy 201.392066 -33.207927)
			(xy 201.418698 -33.214056) (xy 201.429366 -33.216596) (xy 201.44994 -33.212786) (xy 201.530204 -33.159446)
			(xy 201.541634 -33.141666) (xy 201.543158 -33.130998) (xy 201.547769 -33.104384) (xy 201.563603 -33.052743)
			(xy 201.58656 -33.00385) (xy 201.616182 -32.958683) (xy 201.651877 -32.918144) (xy 201.692931 -32.883043)
			(xy 201.738525 -32.854082) (xy 201.787746 -32.831838) (xy 201.839613 -32.816757) (xy 201.893087 -32.809141)
			(xy 201.920094 -32.808672) (xy 201.947465 -32.809124) (xy 202.001645 -32.816943) (xy 202.054149 -32.832434)
			(xy 202.103896 -32.855279) (xy 202.149862 -32.885008) (xy 202.170792 -32.902652) (xy 202.177904 -32.908748)
			(xy 202.194922 -32.915098) (xy 202.280266 -32.915098) (xy 202.297284 -32.908748) (xy 202.304396 -32.902652)
			(xy 202.325325 -32.885009) (xy 202.371298 -32.855296) (xy 202.421046 -32.83246) (xy 202.473548 -32.81697)
			(xy 202.527725 -32.809144) (xy 202.555094 -32.808672) (xy 202.572206 -32.808859) (xy 202.606293 -32.811914)
			(xy 202.623166 -32.814768) (xy 202.63443 -32.816195) (xy 202.656316 -32.810245) (xy 202.66533 -32.803338)
			(xy 202.689714 -32.782256) (xy 202.698109 -32.774337) (xy 202.707227 -32.753158) (xy 202.70724 -32.741616)
			(xy 202.706732 -32.722312) (xy 202.706732 -31.858712) (xy 202.70724 -31.838646) (xy 202.707067 -31.827137)
			(xy 202.697965 -31.806031) (xy 202.689714 -31.798006) (xy 202.66533 -31.776924) (xy 202.656324 -31.77)
			(xy 202.634433 -31.764056) (xy 202.623166 -31.765494) (xy 202.606296 -31.76837) (xy 202.572207 -31.771419)
			(xy 202.555094 -31.77159) (xy 202.527724 -31.77113) (xy 202.473544 -31.763311) (xy 202.421041 -31.747821)
			(xy 202.371294 -31.724978) (xy 202.325327 -31.695252) (xy 202.304396 -31.67761) (xy 202.297284 -31.671514)
			(xy 202.28052 -31.665164) (xy 202.194922 -31.665164) (xy 202.177904 -31.671514) (xy 202.171046 -31.677864)
			(xy 202.150095 -31.695521) (xy 202.104079 -31.725262) (xy 202.054279 -31.748109) (xy 202.001722 -31.763592)
			(xy 201.94749 -31.771392) (xy 201.920094 -31.771844) (xy 201.893116 -31.77138) (xy 201.839697 -31.763797)
			(xy 201.787881 -31.748758) (xy 201.738704 -31.72656) (xy 201.693148 -31.697649) (xy 201.652126 -31.662603)
			(xy 201.616456 -31.622121) (xy 201.586851 -31.577014) (xy 201.563904 -31.528182) (xy 201.548073 -31.476602)
			(xy 201.543412 -31.450026) (xy 201.541634 -31.439358) (xy 201.530204 -31.421832) (xy 201.44994 -31.368238)
			(xy 201.429366 -31.364682) (xy 201.418952 -31.367222) (xy 201.392251 -31.373301) (xy 201.337875 -31.379791)
			(xy 201.310494 -31.380176) (xy 201.283112 -31.379799) (xy 201.228736 -31.373305) (xy 201.202036 -31.367222)
			(xy 201.191622 -31.364682) (xy 201.171048 -31.368238) (xy 201.090784 -31.421832) (xy 201.079354 -31.439358)
			(xy 201.077576 -31.450026) (xy 201.072879 -31.476591) (xy 201.057024 -31.528153) (xy 201.034063 -31.576967)
			(xy 201.004453 -31.622059) (xy 200.968786 -31.66253) (xy 200.927773 -31.697572) (xy 200.882231 -31.726486)
			(xy 200.833071 -31.748696) (xy 200.781271 -31.763757) (xy 200.727866 -31.771371) (xy 200.700894 -31.771844)
			(xy 200.673646 -31.771285) (xy 200.619704 -31.763529) (xy 200.567415 -31.748175) (xy 200.517843 -31.725535)
			(xy 200.471998 -31.696072) (xy 200.430812 -31.660384) (xy 200.395125 -31.619198) (xy 200.365662 -31.573352)
			(xy 200.343023 -31.52378) (xy 200.32767 -31.47149) (xy 200.319914 -31.417548) (xy 200.319914 -31.363052)
			(xy 200.32767 -31.30911) (xy 200.343023 -31.25682) (xy 200.365662 -31.207248) (xy 200.395125 -31.161402)
			(xy 200.430812 -31.120216) (xy 200.471998 -31.084528) (xy 200.517843 -31.055065) (xy 200.567415 -31.032425)
			(xy 200.619704 -31.017071) (xy 200.673646 -31.009315) (xy 200.700894 -31.008828) (xy 200.718006 -31.009015)
			(xy 200.752093 -31.01207) (xy 200.768966 -31.014924) (xy 200.78023 -31.016362) (xy 200.802118 -31.010406)
			(xy 200.81113 -31.003494) (xy 200.835514 -30.982412) (xy 200.843882 -30.974469) (xy 200.853015 -30.953309)
			(xy 200.85304 -30.941772) (xy 200.852532 -30.922468) (xy 200.852532 -30.058868) (xy 200.85304 -30.038802)
			(xy 200.852834 -30.027296) (xy 200.843756 -30.00619) (xy 200.835514 -29.998162) (xy 200.81113 -29.97708)
			(xy 200.802127 -29.970152) (xy 200.780234 -29.964212) (xy 200.768966 -29.96565) (xy 200.752096 -29.968526)
			(xy 200.718007 -29.971575) (xy 200.700894 -29.971746) (xy 200.673646 -29.971183) (xy 200.619704 -29.963427)
			(xy 200.567415 -29.948073) (xy 200.517844 -29.925434) (xy 200.471999 -29.89597) (xy 200.430813 -29.860282)
			(xy 200.395126 -29.819096) (xy 200.365663 -29.773251) (xy 200.343025 -29.723679) (xy 200.327672 -29.67139)
			(xy 200.319916 -29.617448) (xy 200.319916 -29.562952) (xy 200.327672 -29.50901) (xy 200.343025 -29.456721)
			(xy 200.365663 -29.407149) (xy 200.395126 -29.361304) (xy 200.430813 -29.320118) (xy 200.471999 -29.28443)
			(xy 200.517844 -29.254966) (xy 200.567415 -29.232327) (xy 200.619704 -29.216973) (xy 200.673646 -29.209217)
			(xy 200.700894 -29.20873) (xy 200.727901 -29.209218) (xy 200.781376 -29.216823) (xy 200.833243 -29.231895)
			(xy 200.882466 -29.254133) (xy 200.928059 -29.283093) (xy 200.969111 -29.318194) (xy 201.004801 -29.358736)
			(xy 201.034415 -29.403907) (xy 201.057361 -29.452804) (xy 201.073179 -29.504449) (xy 201.07783 -29.531056)
			(xy 201.079354 -29.541724) (xy 201.090784 -29.559504) (xy 201.171048 -29.612844) (xy 201.191622 -29.616654)
			(xy 201.20229 -29.614114) (xy 201.22893 -29.608056) (xy 201.283177 -29.601559) (xy 201.310494 -29.60116)
			(xy 201.337812 -29.601542) (xy 201.392061 -29.608039) (xy 201.418698 -29.614114) (xy 201.429366 -29.616654)
			(xy 201.44994 -29.612844) (xy 201.530204 -29.559504) (xy 201.541634 -29.541724) (xy 201.543158 -29.531056)
			(xy 201.547813 -29.50445) (xy 201.563639 -29.452809) (xy 201.58659 -29.403916) (xy 201.616206 -29.358748)
			(xy 201.651895 -29.318208) (xy 201.692945 -29.283105) (xy 201.738535 -29.254142) (xy 201.787753 -29.231898)
			(xy 201.839616 -29.216816) (xy 201.893088 -29.209199) (xy 201.920094 -29.20873) (xy 201.947464 -29.209192)
			(xy 202.001644 -29.21701) (xy 202.054147 -29.232499) (xy 202.103894 -29.255342) (xy 202.149861 -29.285068)
			(xy 202.170792 -29.30271) (xy 202.177904 -29.308806) (xy 202.194922 -29.315156) (xy 202.280266 -29.315156)
			(xy 202.297284 -29.308806) (xy 202.304396 -29.30271) (xy 202.32532 -29.285061) (xy 202.371295 -29.25535)
			(xy 202.421044 -29.232516) (xy 202.473547 -29.217027) (xy 202.527724 -29.209202) (xy 202.555094 -29.20873)
			(xy 202.572206 -29.208917) (xy 202.606293 -29.211972) (xy 202.623166 -29.214826) (xy 202.63443 -29.216263)
			(xy 202.656318 -29.210308) (xy 202.66533 -29.203396) (xy 202.689714 -29.182314) (xy 202.698081 -29.17437)
			(xy 202.707215 -29.153211) (xy 202.70724 -29.141674) (xy 202.706732 -29.12237) (xy 202.706732 -28.25877)
			(xy 202.70724 -28.238704) (xy 202.707033 -28.227198) (xy 202.697955 -28.206092) (xy 202.689714 -28.198064)
			(xy 202.66533 -28.176982) (xy 202.656327 -28.170054) (xy 202.634434 -28.164114) (xy 202.623166 -28.165552)
			(xy 202.606296 -28.168428) (xy 202.572207 -28.171477) (xy 202.555094 -28.171648) (xy 202.527846 -28.171081)
			(xy 202.473905 -28.163325) (xy 202.421616 -28.147971) (xy 202.372045 -28.125332) (xy 202.3262 -28.095869)
			(xy 202.285015 -28.060181) (xy 202.249328 -28.018995) (xy 202.219865 -27.97315) (xy 202.197227 -27.923578)
			(xy 202.181874 -27.87129) (xy 202.174118 -27.817348) (xy 202.174118 -27.762852) (xy 202.181874 -27.70891)
			(xy 202.197227 -27.656622) (xy 202.219865 -27.60705) (xy 202.249328 -27.561205) (xy 202.285015 -27.520019)
			(xy 202.3262 -27.484331) (xy 202.372045 -27.454868) (xy 202.421616 -27.432229) (xy 202.473905 -27.416875)
			(xy 202.527846 -27.409119) (xy 202.555094 -27.408632) (xy 202.582101 -27.409119) (xy 202.635576 -27.416723)
			(xy 202.687443 -27.431796) (xy 202.736666 -27.454034) (xy 202.78226 -27.482994) (xy 202.823312 -27.518095)
			(xy 202.859002 -27.558637) (xy 202.888616 -27.603809) (xy 202.911561 -27.652706) (xy 202.927379 -27.704351)
			(xy 202.93203 -27.730958) (xy 202.933554 -27.741626) (xy 202.944984 -27.759406) (xy 203.025248 -27.812746)
			(xy 203.045822 -27.816556) (xy 203.05649 -27.814016) (xy 203.083121 -27.807881) (xy 203.137369 -27.801263)
			(xy 203.164694 -27.800808) (xy 203.186872 -27.80111) (xy 203.231018 -27.805431) (xy 203.252832 -27.809444)
			(xy 203.263246 -27.811476) (xy 203.283058 -27.807412) (xy 203.36002 -27.754072) (xy 203.370942 -27.737054)
			(xy 203.37272 -27.72664) (xy 203.377649 -27.700308) (xy 203.393863 -27.649252) (xy 203.41706 -27.600965)
			(xy 203.446785 -27.556399) (xy 203.482452 -27.51643) (xy 203.523361 -27.481844) (xy 203.568705 -27.453322)
			(xy 203.617595 -27.431424) (xy 203.669067 -27.416581) (xy 203.722109 -27.409086) (xy 203.748894 -27.408632)
			(xy 203.77615 -27.409015) (xy 203.830107 -27.416772) (xy 203.882411 -27.432129) (xy 203.931998 -27.454773)
			(xy 203.977856 -27.484244) (xy 204.019054 -27.519942) (xy 204.054752 -27.561139) (xy 204.084224 -27.606997)
			(xy 204.106869 -27.656583) (xy 204.122227 -27.708887) (xy 204.129985 -27.762844) (xy 204.129985 -27.817356)
			(xy 204.122227 -27.871313) (xy 204.106869 -27.923617) (xy 204.084224 -27.973203) (xy 204.054752 -28.019061)
			(xy 204.019054 -28.060258) (xy 203.977856 -28.095956) (xy 203.931998 -28.125427) (xy 203.882411 -28.148071)
			(xy 203.830107 -28.163428) (xy 203.77615 -28.171185) (xy 203.748894 -28.171648) (xy 203.737372 -28.171552)
			(xy 203.714369 -28.170155) (xy 203.70292 -28.168854) (xy 203.692006 -28.168101) (xy 203.671208 -28.174823)
			(xy 203.662788 -28.181808) (xy 203.638912 -28.203398) (xy 203.63105 -28.211242) (xy 203.62237 -28.231663)
			(xy 203.622148 -28.242768) (xy 203.622656 -28.25877) (xy 203.622656 -29.12237) (xy 203.622402 -29.137356)
			(xy 203.622547 -29.14844) (xy 203.631104 -29.168859) (xy 203.638912 -29.176726) (xy 203.662788 -29.198316)
			(xy 203.671215 -29.205289) (xy 203.692007 -29.212006) (xy 203.70292 -29.21127) (xy 203.714368 -29.209959)
			(xy 203.737371 -29.208561) (xy 203.748894 -29.208476) (xy 203.776146 -29.208971) (xy 203.830095 -29.216727)
			(xy 203.882392 -29.232082) (xy 203.93197 -29.254723) (xy 203.977822 -29.28419) (xy 204.019014 -29.319882)
			(xy 204.054707 -29.361073) (xy 204.084174 -29.406924) (xy 204.106816 -29.456503) (xy 204.122172 -29.508799)
			(xy 204.129929 -29.562748) (xy 204.129929 -29.617252) (xy 204.122172 -29.671201) (xy 204.106816 -29.723497)
			(xy 204.084174 -29.773076) (xy 204.054707 -29.818927) (xy 204.019014 -29.860118) (xy 203.977822 -29.89581)
			(xy 203.93197 -29.925277) (xy 203.882392 -29.947918) (xy 203.830095 -29.963273) (xy 203.776146 -29.971029)
			(xy 203.748894 -29.971492) (xy 203.722147 -29.971028) (xy 203.669179 -29.963533) (xy 203.617775 -29.94872)
			(xy 203.568942 -29.926878) (xy 203.523635 -29.898435) (xy 203.482741 -29.863947) (xy 203.44706 -29.824089)
			(xy 203.41729 -29.779642) (xy 203.394016 -29.731475) (xy 203.37769 -29.680532) (xy 203.37272 -29.654246)
			(xy 203.370942 -29.643832) (xy 203.360274 -29.626814) (xy 203.283058 -29.573728) (xy 203.263246 -29.569664)
			(xy 203.253086 -29.571696) (xy 203.231212 -29.57574) (xy 203.186937 -29.580068) (xy 203.164694 -29.580332)
			(xy 203.137306 -29.579893) (xy 203.08293 -29.573269) (xy 203.056236 -29.567124) (xy 203.045822 -29.564584)
			(xy 203.025248 -29.56814) (xy 202.944984 -29.621734) (xy 202.933554 -29.63926) (xy 202.931776 -29.649928)
			(xy 202.92708 -29.676493) (xy 202.911225 -29.728055) (xy 202.888264 -29.776869) (xy 202.858654 -29.821962)
			(xy 202.822987 -29.862432) (xy 202.781973 -29.897474) (xy 202.736432 -29.926388) (xy 202.687271 -29.948598)
			(xy 202.635471 -29.963659) (xy 202.582066 -29.971273) (xy 202.555094 -29.971746) (xy 202.527723 -29.971297)
			(xy 202.473543 -29.963477) (xy 202.421039 -29.947985) (xy 202.371292 -29.925139) (xy 202.325327 -29.89541)
			(xy 202.304396 -29.877766) (xy 202.297284 -29.87167) (xy 202.280266 -29.86532) (xy 202.194922 -29.86532)
			(xy 202.177904 -29.87167) (xy 202.170792 -29.877766) (xy 202.149869 -29.895417) (xy 202.103895 -29.925128)
			(xy 202.054145 -29.947962) (xy 202.001642 -29.963451) (xy 201.947464 -29.971275) (xy 201.920094 -29.971746)
			(xy 201.902982 -29.971561) (xy 201.868895 -29.968504) (xy 201.852022 -29.96565) (xy 201.840755 -29.964272)
			(xy 201.818874 -29.970188) (xy 201.809858 -29.97708) (xy 201.785474 -29.998162) (xy 201.777068 -30.006072)
			(xy 201.767957 -30.027258) (xy 201.767948 -30.038802) (xy 201.768456 -30.058868) (xy 201.768456 -30.922468)
			(xy 201.767948 -30.941772) (xy 201.768114 -30.953281) (xy 201.777221 -30.974388) (xy 201.785474 -30.982412)
			(xy 201.809858 -31.003494) (xy 201.818867 -31.010413) (xy 201.840755 -31.016359) (xy 201.852022 -31.014924)
			(xy 201.868892 -31.012049) (xy 201.902981 -31.009) (xy 201.920094 -31.008828) (xy 201.947464 -31.009291)
			(xy 202.001644 -31.017108) (xy 202.054147 -31.032598) (xy 202.103894 -31.05544) (xy 202.149861 -31.085166)
			(xy 202.170792 -31.102808) (xy 202.177904 -31.108904) (xy 202.194668 -31.115254) (xy 202.280266 -31.115254)
			(xy 202.297284 -31.108904) (xy 202.304142 -31.102554) (xy 202.3251 -31.084906) (xy 202.371114 -31.055163)
			(xy 202.420912 -31.032314) (xy 202.473468 -31.016829) (xy 202.527699 -31.009027) (xy 202.555094 -31.008574)
			(xy 202.582102 -31.009025) (xy 202.635581 -31.016631) (xy 202.687451 -31.031705) (xy 202.736676 -31.053947)
			(xy 202.782271 -31.08291) (xy 202.823323 -31.118016) (xy 202.859013 -31.158563) (xy 202.888625 -31.203739)
			(xy 202.911568 -31.252641) (xy 202.927382 -31.304291) (xy 202.93203 -31.3309) (xy 202.933554 -31.341568)
			(xy 202.944984 -31.359348) (xy 203.025248 -31.412688) (xy 203.045822 -31.416498) (xy 203.05649 -31.413958)
			(xy 203.08313 -31.4079) (xy 203.137377 -31.401404) (xy 203.164694 -31.401004) (xy 203.186867 -31.401234)
			(xy 203.231013 -31.405431) (xy 203.252832 -31.409386) (xy 203.263246 -31.411418) (xy 203.283058 -31.407354)
			(xy 203.36002 -31.354014) (xy 203.370942 -31.336996) (xy 203.37272 -31.326582) (xy 203.377605 -31.300242)
			(xy 203.393826 -31.249185) (xy 203.417031 -31.200899) (xy 203.446761 -31.156334) (xy 203.482434 -31.116366)
			(xy 203.523347 -31.081782) (xy 203.568696 -31.053261) (xy 203.617588 -31.031364) (xy 203.669063 -31.016522)
			(xy 203.722108 -31.009027) (xy 203.748894 -31.008574) (xy 203.776146 -31.009073) (xy 203.830095 -31.016829)
			(xy 203.882391 -31.032184) (xy 203.93197 -31.054825) (xy 203.977821 -31.084291) (xy 204.019013 -31.119983)
			(xy 204.054705 -31.161174) (xy 204.084172 -31.207025) (xy 204.106814 -31.256603) (xy 204.12217 -31.308899)
			(xy 204.129927 -31.362848) (xy 204.129927 -31.417352) (xy 204.12217 -31.471301) (xy 204.106814 -31.523597)
			(xy 204.084172 -31.573175) (xy 204.054705 -31.619026) (xy 204.019013 -31.660217) (xy 203.977821 -31.695909)
			(xy 203.93197 -31.725375) (xy 203.882391 -31.748016) (xy 203.830095 -31.763371) (xy 203.776146 -31.771127)
			(xy 203.748894 -31.77159) (xy 203.737372 -31.771491) (xy 203.714369 -31.770095) (xy 203.70292 -31.768796)
			(xy 203.692006 -31.768033) (xy 203.671207 -31.77476) (xy 203.662788 -31.78175) (xy 203.638912 -31.80334)
			(xy 203.631077 -31.811207) (xy 203.622381 -31.83161) (xy 203.622148 -31.84271) (xy 203.622656 -31.858712)
			(xy 203.622656 -32.722312) (xy 203.622148 -32.737552) (xy 203.622315 -32.748666) (xy 203.631021 -32.769092)
			(xy 203.638912 -32.776922) (xy 203.662788 -32.798512) (xy 203.671215 -32.805485) (xy 203.692007 -32.812202)
			(xy 203.70292 -32.811466) (xy 203.714368 -32.810155) (xy 203.737371 -32.808757) (xy 203.748894 -32.808672)
			(xy 203.776146 -32.809175) (xy 203.830094 -32.816931) (xy 203.88239 -32.832285) (xy 203.931969 -32.854926)
			(xy 203.97782 -32.884393) (xy 204.019011 -32.920084) (xy 204.054704 -32.961275) (xy 204.084171 -33.007126)
			(xy 204.106812 -33.056704) (xy 204.122168 -33.109) (xy 204.129925 -33.162948) (xy 204.129925 -33.217452)
			(xy 204.122168 -33.2714) (xy 204.106812 -33.323696) (xy 204.084171 -33.373274) (xy 204.054704 -33.419125)
			(xy 204.019011 -33.460316) (xy 203.97782 -33.496007) (xy 203.931969 -33.525474) (xy 203.88239 -33.548115)
			(xy 203.830094 -33.563469) (xy 203.776146 -33.571225) (xy 203.748894 -33.571688) (xy 203.722126 -33.571322)
			(xy 203.669115 -33.56385) (xy 203.617668 -33.54904) (xy 203.568798 -33.527181) (xy 203.523465 -33.498705)
			(xy 203.482558 -33.46417) (xy 203.446881 -33.424254) (xy 203.417136 -33.379743) (xy 203.393906 -33.331509)
			(xy 203.377649 -33.280502) (xy 203.37272 -33.254188) (xy 203.370942 -33.243774) (xy 203.360274 -33.226756)
			(xy 203.283058 -33.17367) (xy 203.263246 -33.169606) (xy 203.253086 -33.171638) (xy 203.231206 -33.175615)
			(xy 203.186931 -33.179817) (xy 203.164694 -33.18002) (xy 203.137312 -33.179644) (xy 203.082936 -33.17315)
			(xy 203.056236 -33.167066) (xy 203.045822 -33.164526) (xy 203.025248 -33.168082) (xy 202.944984 -33.221676)
			(xy 202.933554 -33.239202) (xy 202.931776 -33.24987) (xy 202.927036 -33.276427) (xy 202.911189 -33.327989)
			(xy 202.888234 -33.376803) (xy 202.85863 -33.421897) (xy 202.822968 -33.462369) (xy 202.781959 -33.497412)
			(xy 202.736422 -33.526328) (xy 202.687264 -33.548538) (xy 202.635467 -33.563601) (xy 202.582065 -33.571215)
			(xy 202.555094 -33.571688) (xy 202.527724 -33.571228) (xy 202.473544 -33.563409) (xy 202.421041 -33.547919)
			(xy 202.371294 -33.525076) (xy 202.325327 -33.49535) (xy 202.304396 -33.477708) (xy 202.297284 -33.471612)
			(xy 202.280266 -33.465262) (xy 202.194922 -33.465262) (xy 202.177904 -33.471612) (xy 202.170792 -33.477708)
			(xy 202.149875 -33.495366) (xy 202.103898 -33.525074) (xy 202.054146 -33.547907) (xy 202.001643 -33.563393)
			(xy 201.947464 -33.571217) (xy 201.920094 -33.571688) (xy 201.902982 -33.571502) (xy 201.868895 -33.568446)
			(xy 201.852022 -33.565592) (xy 201.840755 -33.564205) (xy 201.818873 -33.570125) (xy 201.809858 -33.577022)
			(xy 201.785474 -33.598104) (xy 201.777096 -33.606038) (xy 201.767969 -33.627205) (xy 201.767948 -33.638744)
			(xy 201.768456 -33.65881) (xy 201.768456 -34.52241) (xy 201.767948 -34.541714) (xy 201.768148 -34.55322)
			(xy 201.777231 -34.574326) (xy 201.785474 -34.582354) (xy 201.809858 -34.603436) (xy 201.818871 -34.61035)
			(xy 201.840756 -34.616301) (xy 201.852022 -34.614866) (xy 201.868892 -34.611991) (xy 201.902981 -34.608942)
			(xy 201.920094 -34.60877) (xy 201.947344 -34.609283) (xy 202.00129 -34.617038) (xy 202.053583 -34.632392)
			(xy 202.103158 -34.655031) (xy 202.149008 -34.684494) (xy 202.190197 -34.720183) (xy 202.225889 -34.76137)
			(xy 202.255356 -34.807217) (xy 202.277999 -34.856791) (xy 202.293356 -34.909083) (xy 202.301115 -34.963028)
			(xy 202.301597 -34.990024) (xy 203.366876 -34.990024) (xy 203.370947 -34.934402) (xy 203.383073 -34.879965)
			(xy 203.402996 -34.827874) (xy 203.430292 -34.779239) (xy 203.464378 -34.735096) (xy 203.504527 -34.696387)
			(xy 203.549885 -34.663936) (xy 203.599485 -34.638435) (xy 203.652269 -34.620428) (xy 203.707112 -34.610298)
			(xy 203.762846 -34.608261) (xy 203.818283 -34.614361) (xy 203.87224 -34.628467) (xy 203.923569 -34.650279)
			(xy 203.971175 -34.679333) (xy 204.014043 -34.715008) (xy 204.05126 -34.756545) (xy 204.082033 -34.803058)
			(xy 204.105705 -34.853555) (xy 204.121773 -34.906962) (xy 204.129893 -34.962138) (xy 204.130402 -34.990024)
			(xy 204.129893 -35.01791) (xy 204.121773 -35.073086) (xy 204.105705 -35.126493) (xy 204.082033 -35.17699)
			(xy 204.05126 -35.223503) (xy 204.014043 -35.26504) (xy 203.971175 -35.300715) (xy 203.923569 -35.329769)
			(xy 203.87224 -35.351581) (xy 203.818283 -35.365687) (xy 203.762846 -35.371787) (xy 203.707112 -35.36975)
			(xy 203.652269 -35.35962) (xy 203.599485 -35.341613) (xy 203.549885 -35.316112) (xy 203.504527 -35.283661)
			(xy 203.464378 -35.244952) (xy 203.430292 -35.200809) (xy 203.402996 -35.152174) (xy 203.383073 -35.100083)
			(xy 203.370947 -35.045646) (xy 203.366876 -34.990024) (xy 202.301597 -34.990024) (xy 202.301602 -34.990278)
			(xy 202.301113 -35.017049) (xy 202.293603 -35.070061) (xy 202.278756 -35.121504) (xy 202.256864 -35.170365)
			(xy 202.228356 -35.215687) (xy 202.193793 -35.256578) (xy 202.153852 -35.292236) (xy 202.109319 -35.32196)
			(xy 202.061068 -35.345167) (xy 202.010046 -35.361401) (xy 201.957256 -35.370343) (xy 201.930508 -35.371532)
			(xy 201.918062 -35.37204) (xy 201.89698 -35.38347) (xy 201.836528 -35.471862) (xy 201.83348 -35.495484)
			(xy 201.837544 -35.507168) (xy 201.847863 -35.538161) (xy 201.858974 -35.602526) (xy 201.859642 -35.635184)
			(xy 201.859156 -35.662435) (xy 201.8514 -35.716383) (xy 201.836045 -35.768678) (xy 201.813403 -35.818255)
			(xy 201.783937 -35.864105) (xy 201.748246 -35.905296) (xy 201.707055 -35.940987) (xy 201.661205 -35.970453)
			(xy 201.611628 -35.993095) (xy 201.559333 -36.00845) (xy 201.505385 -36.016206) (xy 201.450883 -36.016206)
			(xy 201.396935 -36.00845) (xy 201.34464 -35.993095) (xy 201.295063 -35.970453) (xy 201.249213 -35.940987)
			(xy 201.208022 -35.905296) (xy 201.172331 -35.864105) (xy 201.142865 -35.818255) (xy 201.120223 -35.768678)
			(xy 201.104868 -35.716383) (xy 201.097112 -35.662435) (xy 201.096626 -35.635184) (xy 201.097053 -35.608411)
			(xy 201.104568 -35.555395) (xy 201.119421 -35.50395) (xy 201.14132 -35.455086) (xy 201.169834 -35.409763)
			(xy 201.204404 -35.368872) (xy 201.244351 -35.333214) (xy 201.28889 -35.303491) (xy 201.337147 -35.280286)
			(xy 201.388174 -35.264055) (xy 201.440969 -35.255117) (xy 201.46772 -35.25393) (xy 201.480166 -35.253422)
			(xy 201.501248 -35.241992) (xy 201.5617 -35.1536) (xy 201.564748 -35.129978) (xy 201.560684 -35.118294)
			(xy 201.554982 -35.101592) (xy 201.546333 -35.067373) (xy 201.543412 -35.049968) (xy 201.541634 -35.0393)
			(xy 201.530204 -35.021774) (xy 201.44994 -34.96818) (xy 201.429366 -34.964624) (xy 201.418952 -34.967164)
			(xy 201.392257 -34.973303) (xy 201.337882 -34.979925) (xy 201.310494 -34.980372) (xy 201.283106 -34.979932)
			(xy 201.22873 -34.973308) (xy 201.202036 -34.967164) (xy 201.191622 -34.964624) (xy 201.171048 -34.96818)
			(xy 201.090784 -35.021774) (xy 201.079354 -35.0393) (xy 201.077576 -35.049968) (xy 201.072911 -35.076539)
			(xy 201.05705 -35.128101) (xy 201.034084 -35.176915) (xy 201.00447 -35.222006) (xy 200.968799 -35.262476)
			(xy 200.927783 -35.297517) (xy 200.882238 -35.32643) (xy 200.833075 -35.348639) (xy 200.781274 -35.3637)
			(xy 200.727867 -35.371313) (xy 200.700894 -35.371786) (xy 200.673641 -35.371344) (xy 200.619691 -35.363586)
			(xy 200.567394 -35.34823) (xy 200.517815 -35.325587) (xy 200.471963 -35.296119) (xy 200.430771 -35.260425)
			(xy 200.395078 -35.219233) (xy 200.36561 -35.17338) (xy 200.342968 -35.1238) (xy 200.327613 -35.071503)
			(xy 200.319856 -35.017553) (xy 198.674397 -35.017553) (xy 198.68678 -35.031373) (xy 198.717553 -35.077886)
			(xy 198.741225 -35.128383) (xy 198.757293 -35.18179) (xy 198.765413 -35.236966) (xy 198.765922 -35.264852)
			(xy 198.765413 -35.292738) (xy 198.757293 -35.347914) (xy 198.741225 -35.401321) (xy 198.717553 -35.451818)
			(xy 198.68678 -35.498331) (xy 198.649563 -35.539868) (xy 198.606695 -35.575543) (xy 198.559089 -35.604597)
			(xy 198.50776 -35.626409) (xy 198.453803 -35.640515) (xy 198.398366 -35.646615) (xy 198.342632 -35.644578)
			(xy 198.287789 -35.634448) (xy 198.235005 -35.616441) (xy 198.185405 -35.59094) (xy 198.140047 -35.558489)
			(xy 198.099898 -35.51978) (xy 198.065812 -35.475637) (xy 198.038516 -35.427002) (xy 198.018593 -35.374911)
			(xy 198.006467 -35.320474) (xy 198.002396 -35.264852) (xy 195.501006 -35.264852) (xy 195.501006 -37.087048)
			(xy 199.300846 -37.087048) (xy 199.301311 -37.060444) (xy 199.308687 -37.007751) (xy 199.323317 -36.956595)
			(xy 199.344917 -36.907969) (xy 199.373066 -36.862819) (xy 199.407219 -36.822019) (xy 199.446712 -36.786364)
			(xy 199.468486 -36.771072) (xy 199.47841 -36.763541) (xy 199.490138 -36.741598) (xy 199.490838 -36.729162)
			(xy 199.490838 -36.644834) (xy 199.490166 -36.632384) (xy 199.478457 -36.610408) (xy 199.468486 -36.602924)
			(xy 199.446728 -36.587612) (xy 199.407247 -36.55195) (xy 199.373101 -36.51115) (xy 199.344953 -36.466003)
			(xy 199.323349 -36.417384) (xy 199.308707 -36.366236) (xy 199.30131 -36.313549) (xy 199.300846 -36.286948)
			(xy 199.3014 -36.259698) (xy 199.309149 -36.205753) (xy 199.324497 -36.15346) (xy 199.34713 -36.103883)
			(xy 199.376589 -36.058032) (xy 199.412273 -36.01684) (xy 199.453456 -35.981145) (xy 199.4993 -35.951675)
			(xy 199.548872 -35.92903) (xy 199.601161 -35.913669) (xy 199.655105 -35.905907) (xy 199.682354 -35.90544)
			(xy 199.686926 -35.90544) (xy 199.696578 -35.905694) (xy 199.713342 -35.899344) (xy 199.778874 -35.843464)
			(xy 199.78751 -35.827462) (xy 199.78878 -35.818064) (xy 199.79313 -35.791134) (xy 199.80844 -35.738778)
			(xy 199.831051 -35.689137) (xy 199.860502 -35.643222) (xy 199.896192 -35.60197) (xy 199.937394 -35.566222)
			(xy 199.983268 -35.536707) (xy 200.032878 -35.514026) (xy 200.085212 -35.498643) (xy 200.139204 -35.49087)
			(xy 200.166478 -35.490404) (xy 200.193733 -35.490841) (xy 200.247688 -35.498596) (xy 200.29999 -35.513951)
			(xy 200.349575 -35.536593) (xy 200.395432 -35.566061) (xy 200.436629 -35.601756) (xy 200.472326 -35.64295)
			(xy 200.501797 -35.688806) (xy 200.524442 -35.738389) (xy 200.539799 -35.790691) (xy 200.547557 -35.844645)
			(xy 200.547557 -35.899155) (xy 200.539799 -35.953109) (xy 200.524442 -36.005411) (xy 200.501797 -36.054994)
			(xy 200.472326 -36.10085) (xy 200.436629 -36.142044) (xy 200.395432 -36.177739) (xy 200.349575 -36.207207)
			(xy 200.29999 -36.229849) (xy 200.247688 -36.245204) (xy 200.193733 -36.252959) (xy 200.166478 -36.25342)
			(xy 200.161906 -36.25342) (xy 200.152254 -36.253166) (xy 200.13549 -36.259516) (xy 200.069958 -36.315396)
			(xy 200.061322 -36.331398) (xy 200.060052 -36.340796) (xy 200.055854 -36.366999) (xy 200.04117 -36.417994)
			(xy 200.019557 -36.466459) (xy 199.991433 -36.51146) (xy 199.988006 -36.515548) (xy 201.11415 -36.515548)
			(xy 201.118221 -36.459926) (xy 201.130347 -36.405489) (xy 201.15027 -36.353398) (xy 201.177566 -36.304763)
			(xy 201.211652 -36.26062) (xy 201.251801 -36.221911) (xy 201.297159 -36.18946) (xy 201.346759 -36.163959)
			(xy 201.399543 -36.145952) (xy 201.454386 -36.135822) (xy 201.51012 -36.133785) (xy 201.565557 -36.139885)
			(xy 201.619514 -36.153991) (xy 201.670843 -36.175803) (xy 201.718449 -36.204857) (xy 201.761317 -36.240532)
			(xy 201.798534 -36.282069) (xy 201.829307 -36.328582) (xy 201.852979 -36.379079) (xy 201.869047 -36.432486)
			(xy 201.877167 -36.487662) (xy 201.877676 -36.515548) (xy 201.877167 -36.543434) (xy 201.869047 -36.59861)
			(xy 201.852979 -36.652017) (xy 201.829307 -36.702514) (xy 201.798534 -36.749027) (xy 201.761317 -36.790564)
			(xy 201.718449 -36.826239) (xy 201.670843 -36.855293) (xy 201.619514 -36.877105) (xy 201.565557 -36.891211)
			(xy 201.51012 -36.897311) (xy 201.454386 -36.895274) (xy 201.399543 -36.885144) (xy 201.346759 -36.867137)
			(xy 201.297159 -36.841636) (xy 201.251801 -36.809185) (xy 201.211652 -36.770476) (xy 201.177566 -36.726333)
			(xy 201.15027 -36.677698) (xy 201.130347 -36.625607) (xy 201.118221 -36.57117) (xy 201.11415 -36.515548)
			(xy 199.988006 -36.515548) (xy 199.957341 -36.552127) (xy 199.91794 -36.587675) (xy 199.896222 -36.602924)
			(xy 199.886301 -36.610458) (xy 199.874571 -36.632399) (xy 199.87387 -36.644834) (xy 199.87387 -36.729162)
			(xy 199.874541 -36.741612) (xy 199.886251 -36.763588) (xy 199.896222 -36.771072) (xy 199.91798 -36.786385)
			(xy 199.957461 -36.822047) (xy 199.991606 -36.862846) (xy 200.019754 -36.907993) (xy 200.041358 -36.956612)
			(xy 200.056001 -37.00776) (xy 200.063397 -37.060447) (xy 200.063862 -37.087048) (xy 200.063262 -37.118808)
			(xy 200.052774 -37.181454) (xy 200.032032 -37.241489) (xy 200.01738 -37.269674) (xy 200.012046 -37.27958)
			(xy 200.010522 -37.301678) (xy 200.046336 -37.394896) (xy 200.062338 -37.41039) (xy 200.073006 -37.4142)
			(xy 200.09754 -37.423263) (xy 200.14407 -37.447146) (xy 200.186902 -37.477163) (xy 200.22523 -37.51275)
			(xy 200.258338 -37.553239) (xy 200.285604 -37.597871) (xy 200.306516 -37.64581) (xy 200.320684 -37.696157)
			(xy 200.32784 -37.747967) (xy 200.328276 -37.774118) (xy 200.32779 -37.801369) (xy 200.320034 -37.855317)
			(xy 200.304679 -37.907612) (xy 200.282037 -37.957189) (xy 200.252571 -38.003039) (xy 200.21688 -38.04423)
			(xy 200.175689 -38.079921) (xy 200.129839 -38.109387) (xy 200.080262 -38.132029) (xy 200.027967 -38.147384)
			(xy 199.974019 -38.15514) (xy 199.919517 -38.15514) (xy 199.865569 -38.147384) (xy 199.813274 -38.132029)
			(xy 199.763697 -38.109387) (xy 199.717847 -38.079921) (xy 199.676656 -38.04423) (xy 199.640965 -38.003039)
			(xy 199.611499 -37.957189) (xy 199.588857 -37.907612) (xy 199.573502 -37.855317) (xy 199.565746 -37.801369)
			(xy 199.56526 -37.774118) (xy 199.565844 -37.742358) (xy 199.576338 -37.679711) (xy 199.597087 -37.619676)
			(xy 199.611742 -37.591492) (xy 199.617076 -37.581586) (xy 199.6186 -37.559488) (xy 199.582786 -37.46627)
			(xy 199.566784 -37.450776) (xy 199.556116 -37.446966) (xy 199.531575 -37.43792) (xy 199.485043 -37.414035)
			(xy 199.442211 -37.384018) (xy 199.403881 -37.34843) (xy 199.370773 -37.307938) (xy 199.343508 -37.263303)
			(xy 199.322598 -37.215361) (xy 199.308433 -37.165012) (xy 199.30128 -37.1132) (xy 199.300846 -37.087048)
			(xy 195.501006 -37.087048) (xy 195.501006 -38.315138) (xy 200.518012 -38.315138) (xy 200.522083 -38.259516)
			(xy 200.534209 -38.205079) (xy 200.554132 -38.152988) (xy 200.581428 -38.104353) (xy 200.615514 -38.06021)
			(xy 200.655663 -38.021501) (xy 200.701021 -37.98905) (xy 200.750621 -37.963549) (xy 200.803405 -37.945542)
			(xy 200.858248 -37.935412) (xy 200.913982 -37.933375) (xy 200.969419 -37.939475) (xy 201.023376 -37.953581)
			(xy 201.074705 -37.975393) (xy 201.122311 -38.004447) (xy 201.165179 -38.040122) (xy 201.202396 -38.081659)
			(xy 201.233169 -38.128172) (xy 201.256841 -38.178669) (xy 201.272909 -38.232076) (xy 201.281029 -38.287252)
			(xy 201.281538 -38.315138) (xy 201.281029 -38.343024) (xy 201.272909 -38.3982) (xy 201.256841 -38.451607)
			(xy 201.233169 -38.502104) (xy 201.202396 -38.548617) (xy 201.165179 -38.590154) (xy 201.122311 -38.625829)
			(xy 201.074705 -38.654883) (xy 201.023376 -38.676695) (xy 200.969419 -38.690801) (xy 200.913982 -38.696901)
			(xy 200.858248 -38.694864) (xy 200.803405 -38.684734) (xy 200.750621 -38.666727) (xy 200.701021 -38.641226)
			(xy 200.655663 -38.608775) (xy 200.615514 -38.570066) (xy 200.581428 -38.525923) (xy 200.554132 -38.477288)
			(xy 200.534209 -38.425197) (xy 200.522083 -38.37076) (xy 200.518012 -38.315138) (xy 195.501006 -38.315138)
			(xy 195.501006 -42.4307) (xy 195.501296 -42.438369) (xy 195.505939 -42.452988) (xy 195.51015 -42.459402)
			(xy 195.51015 -42.459656) (xy 195.514993 -42.4662) (xy 195.527949 -42.476043) (xy 195.53555 -42.47896)
			(xy 195.535804 -42.47896) (xy 195.561265 -42.487946) (xy 195.609565 -42.512077) (xy 195.653983 -42.542774)
			(xy 195.693633 -42.579422) (xy 195.727723 -42.621292) (xy 195.755574 -42.667547) (xy 195.77663 -42.717265)
			(xy 195.790471 -42.769453) (xy 195.794122 -42.796206) (xy 195.794884 -42.80408) (xy 195.796662 -42.840656)
			(xy 195.796662 -42.847768) (xy 195.795635 -42.876442) (xy 195.786034 -42.933008) (xy 195.768066 -42.987497)
			(xy 195.742138 -43.038679) (xy 195.708834 -43.0854) (xy 195.68922 -43.10634) (xy 195.688458 -43.107102)
			(xy 195.687188 -43.108372) (xy 195.666167 -43.129698) (xy 195.618691 -43.166185) (xy 195.566098 -43.194807)
			(xy 195.53809 -43.2054) (xy 195.535296 -43.206416) (xy 195.5292 -43.209464) (xy 195.520966 -43.21405)
			(xy 195.508279 -43.227963) (xy 195.501463 -43.245516) (xy 195.501006 -43.25493) (xy 195.501006 -43.4467)
			(xy 195.501296 -43.454369) (xy 195.505939 -43.468988) (xy 195.51015 -43.475402) (xy 195.51015 -43.475656)
			(xy 195.514993 -43.4822) (xy 195.527949 -43.492043) (xy 195.53555 -43.49496) (xy 195.535804 -43.49496)
			(xy 195.561265 -43.503946) (xy 195.609565 -43.528077) (xy 195.653983 -43.558774) (xy 195.693633 -43.595422)
			(xy 195.727723 -43.637292) (xy 195.755574 -43.683547) (xy 195.77663 -43.733265) (xy 195.790471 -43.785453)
			(xy 195.794122 -43.812206) (xy 195.794884 -43.82008) (xy 195.796662 -43.856656) (xy 195.796662 -43.863768)
			(xy 195.795635 -43.892442) (xy 195.786034 -43.949008) (xy 195.768066 -44.003497) (xy 195.742138 -44.054679)
			(xy 195.708834 -44.1014) (xy 195.68922 -44.12234) (xy 195.688458 -44.123102) (xy 195.687188 -44.124372)
			(xy 195.666167 -44.145698) (xy 195.618691 -44.182185) (xy 195.566098 -44.210807) (xy 195.53809 -44.2214)
			(xy 195.535296 -44.222416) (xy 195.5292 -44.225464) (xy 195.520966 -44.23005) (xy 195.508279 -44.243963)
			(xy 195.501463 -44.261516) (xy 195.501006 -44.27093) (xy 195.501006 -44.4627) (xy 195.501296 -44.470369)
			(xy 195.505939 -44.484988) (xy 195.51015 -44.491402) (xy 195.51015 -44.491656) (xy 195.514993 -44.4982)
			(xy 195.527949 -44.508043) (xy 195.53555 -44.51096) (xy 195.535804 -44.51096) (xy 195.561265 -44.519946)
			(xy 195.609565 -44.544077) (xy 195.653983 -44.574774) (xy 195.693633 -44.611422) (xy 195.727723 -44.653292)
			(xy 195.755574 -44.699547) (xy 195.77663 -44.749265) (xy 195.790471 -44.801453) (xy 195.794122 -44.828206)
			(xy 195.794884 -44.83608) (xy 195.796662 -44.872656) (xy 195.796662 -44.879768) (xy 195.795635 -44.908442)
			(xy 195.786034 -44.965008) (xy 195.768066 -45.019497) (xy 195.742138 -45.070679) (xy 195.708834 -45.1174)
			(xy 195.68922 -45.13834) (xy 195.688458 -45.139102) (xy 195.687188 -45.140372) (xy 195.666167 -45.161698)
			(xy 195.618691 -45.198185) (xy 195.566098 -45.226807) (xy 195.53809 -45.2374) (xy 195.535296 -45.238416)
			(xy 195.5292 -45.241464) (xy 195.520966 -45.24605) (xy 195.508279 -45.259963) (xy 195.501463 -45.277516)
			(xy 195.501006 -45.28693) (xy 195.501006 -45.4787) (xy 195.501296 -45.486369) (xy 195.505939 -45.500988)
			(xy 195.51015 -45.507402) (xy 195.51015 -45.507656) (xy 195.514993 -45.5142) (xy 195.527949 -45.524043)
			(xy 195.53555 -45.52696) (xy 195.535804 -45.52696) (xy 195.561265 -45.535946) (xy 195.609565 -45.560077)
			(xy 195.653983 -45.590774) (xy 195.693633 -45.627422) (xy 195.727723 -45.669292) (xy 195.755574 -45.715547)
			(xy 195.77663 -45.765265) (xy 195.790471 -45.817453) (xy 195.794122 -45.844206) (xy 195.794884 -45.85208)
			(xy 195.796662 -45.888656) (xy 195.796662 -45.895768) (xy 195.795635 -45.924442) (xy 195.786034 -45.981008)
			(xy 195.768066 -46.035497) (xy 195.742138 -46.086679) (xy 195.708834 -46.1334) (xy 195.68922 -46.15434)
			(xy 195.688458 -46.155102) (xy 195.687188 -46.156372) (xy 195.666167 -46.177698) (xy 195.618691 -46.214185)
			(xy 195.566098 -46.242807) (xy 195.53809 -46.2534) (xy 195.535296 -46.254416) (xy 195.5292 -46.257464)
			(xy 195.520966 -46.26205) (xy 195.508279 -46.275963) (xy 195.501463 -46.293516) (xy 195.501006 -46.30293)
			(xy 195.501006 -47.040546) (xy 195.522088 -47.067724) (xy 195.539106 -47.072296) (xy 195.566059 -47.079733)
			(xy 195.617593 -47.101418) (xy 195.665405 -47.1304) (xy 195.708471 -47.166057) (xy 195.745864 -47.207623)
			(xy 195.776783 -47.254207) (xy 195.800564 -47.304808) (xy 195.816697 -47.358341) (xy 195.824835 -47.413656)
			(xy 195.825364 -47.441612) (xy 195.825285 -47.45435) (xy 195.823631 -47.479771) (xy 195.822062 -47.492412)
			(xy 195.821808 -47.494952) (xy 195.817027 -47.524513) (xy 195.799467 -47.58176) (xy 195.773179 -47.63556)
			(xy 195.738811 -47.684595) (xy 195.71843 -47.706534) (xy 195.717922 -47.707042) (xy 195.716144 -47.709074)
			(xy 195.697867 -47.727722) (xy 195.657101 -47.760351) (xy 195.612264 -47.787111) (xy 195.564195 -47.807502)
			(xy 195.539106 -47.814738) (xy 195.538598 -47.814992) (xy 195.537328 -47.8155) (xy 195.52704 -47.81908)
			(xy 195.510603 -47.833343) (xy 195.501553 -47.853134) (xy 195.501006 -47.864014) (xy 195.501006 -48.5267)
			(xy 195.501296 -48.534369) (xy 195.505939 -48.548988) (xy 195.51015 -48.555402) (xy 195.51015 -48.555656)
			(xy 195.514993 -48.5622) (xy 195.527949 -48.572043) (xy 195.53555 -48.57496) (xy 195.535804 -48.57496)
			(xy 195.561265 -48.583946) (xy 195.609565 -48.608077) (xy 195.653983 -48.638774) (xy 195.693633 -48.675422)
			(xy 195.727723 -48.717292) (xy 195.755574 -48.763547) (xy 195.77663 -48.813265) (xy 195.790471 -48.865453)
			(xy 195.794122 -48.892206) (xy 195.794884 -48.90008) (xy 195.796662 -48.936656) (xy 195.796662 -48.943768)
			(xy 195.795635 -48.972442) (xy 195.786034 -49.029008) (xy 195.768066 -49.083497) (xy 195.742138 -49.134679)
			(xy 195.708834 -49.1814) (xy 195.68922 -49.20234) (xy 195.688458 -49.203102) (xy 195.687188 -49.204372)
			(xy 195.666167 -49.225698) (xy 195.618691 -49.262185) (xy 195.566098 -49.290807) (xy 195.53809 -49.3014)
			(xy 195.535296 -49.302416) (xy 195.5292 -49.305464) (xy 195.520966 -49.31005) (xy 195.508279 -49.323963)
			(xy 195.501463 -49.341516) (xy 195.501006 -49.35093) (xy 195.501006 -49.53381) (xy 195.501266 -49.541454)
			(xy 195.505791 -49.556058) (xy 195.509896 -49.562512) (xy 195.528438 -49.589944) (xy 195.540376 -49.599088)
			(xy 195.547302 -49.601954) (xy 196.390959 -49.601954) (xy 196.390959 -49.547446) (xy 196.398717 -49.493494)
			(xy 196.414074 -49.441195) (xy 196.436718 -49.391614) (xy 196.466187 -49.34576) (xy 196.501883 -49.304568)
			(xy 196.543078 -49.268874) (xy 196.588933 -49.239407) (xy 196.638516 -49.216766) (xy 196.690816 -49.201412)
			(xy 196.744768 -49.193658) (xy 196.772022 -49.193196) (xy 196.799393 -49.19365) (xy 196.853572 -49.201471)
			(xy 196.906075 -49.216963) (xy 196.955822 -49.239807) (xy 197.001789 -49.269534) (xy 197.02272 -49.287176)
			(xy 197.029832 -49.293272) (xy 197.04685 -49.299622) (xy 197.132194 -49.299622) (xy 197.149212 -49.293272)
			(xy 197.156324 -49.287176) (xy 197.177257 -49.269535) (xy 197.223225 -49.239811) (xy 197.272971 -49.216965)
			(xy 197.325473 -49.201469) (xy 197.379651 -49.19364) (xy 197.434393 -49.19364) (xy 197.488571 -49.201469)
			(xy 197.541073 -49.216965) (xy 197.590819 -49.239811) (xy 197.636787 -49.269535) (xy 197.65772 -49.287176)
			(xy 197.664832 -49.293272) (xy 197.68185 -49.299622) (xy 197.767194 -49.299622) (xy 197.784212 -49.293272)
			(xy 197.791324 -49.287176) (xy 197.812271 -49.269555) (xy 197.85824 -49.239842) (xy 197.907984 -49.217002)
			(xy 197.960481 -49.201507) (xy 198.014654 -49.193673) (xy 198.042022 -49.193196) (xy 198.068338 -49.193656)
			(xy 198.120471 -49.200875) (xy 198.171119 -49.215187) (xy 198.219321 -49.23632) (xy 198.264164 -49.263874)
			(xy 198.304796 -49.297326) (xy 198.322946 -49.316386) (xy 198.33045 -49.323808) (xy 198.349743 -49.332321)
			(xy 198.360284 -49.332896) (xy 198.43496 -49.332896) (xy 198.445509 -49.33236) (xy 198.464804 -49.32383)
			(xy 198.472298 -49.316386) (xy 198.490431 -49.297305) (xy 198.531052 -49.263828) (xy 198.575893 -49.236258)
			(xy 198.624101 -49.21512) (xy 198.674758 -49.200815) (xy 198.726902 -49.193617) (xy 198.753222 -49.193196)
			(xy 198.780473 -49.193675) (xy 198.834418 -49.201434) (xy 198.886711 -49.216792) (xy 198.936286 -49.239434)
			(xy 198.982134 -49.268901) (xy 199.023322 -49.304593) (xy 199.059012 -49.345783) (xy 199.088476 -49.391633)
			(xy 199.111116 -49.44121) (xy 199.12647 -49.493503) (xy 199.134226 -49.547449) (xy 199.134226 -49.601951)
			(xy 199.12647 -49.655897) (xy 199.111116 -49.70819) (xy 199.088476 -49.757767) (xy 199.059012 -49.803617)
			(xy 199.023322 -49.844807) (xy 198.982134 -49.880499) (xy 198.936286 -49.909966) (xy 198.886711 -49.932608)
			(xy 198.834418 -49.947966) (xy 198.780473 -49.955725) (xy 198.753222 -49.956212) (xy 198.726905 -49.955787)
			(xy 198.67477 -49.948561) (xy 198.624121 -49.934242) (xy 198.57592 -49.913102) (xy 198.531078 -49.885542)
			(xy 198.490447 -49.852084) (xy 198.472298 -49.833022) (xy 198.464776 -49.825621) (xy 198.445496 -49.817095)
			(xy 198.43496 -49.816512) (xy 198.360284 -49.816512) (xy 198.349731 -49.817015) (xy 198.330436 -49.825568)
			(xy 198.322946 -49.833022) (xy 198.304822 -49.852113) (xy 198.264201 -49.885593) (xy 198.219359 -49.913164)
			(xy 198.171149 -49.934301) (xy 198.120489 -49.948602) (xy 198.068342 -49.955795) (xy 198.042022 -49.956212)
			(xy 198.014652 -49.95573) (xy 197.960474 -49.947916) (xy 197.907971 -49.93243) (xy 197.858224 -49.909592)
			(xy 197.812256 -49.879871) (xy 197.791324 -49.862232) (xy 197.784212 -49.856136) (xy 197.767194 -49.849786)
			(xy 197.68185 -49.849786) (xy 197.664832 -49.856136) (xy 197.65772 -49.862232) (xy 197.636787 -49.879873)
			(xy 197.590819 -49.909597) (xy 197.541073 -49.932443) (xy 197.488571 -49.947939) (xy 197.434393 -49.955768)
			(xy 197.379651 -49.955768) (xy 197.325473 -49.947939) (xy 197.272971 -49.932443) (xy 197.223225 -49.909597)
			(xy 197.177257 -49.879873) (xy 197.156324 -49.862232) (xy 197.149212 -49.856136) (xy 197.132194 -49.849786)
			(xy 197.04685 -49.849786) (xy 197.029832 -49.856136) (xy 197.02272 -49.862232) (xy 197.001795 -49.87988)
			(xy 196.95582 -49.90959) (xy 196.906071 -49.932423) (xy 196.853568 -49.947912) (xy 196.799392 -49.955739)
			(xy 196.772022 -49.956212) (xy 196.744768 -49.955742) (xy 196.690816 -49.947988) (xy 196.638516 -49.932634)
			(xy 196.588933 -49.909993) (xy 196.543078 -49.880526) (xy 196.501883 -49.844832) (xy 196.466187 -49.80364)
			(xy 196.436718 -49.757786) (xy 196.414074 -49.708205) (xy 196.398717 -49.655906) (xy 196.390959 -49.601954)
			(xy 195.547302 -49.601954) (xy 195.547742 -49.602136) (xy 195.573035 -49.612404) (xy 195.620633 -49.639129)
			(xy 195.663936 -49.672365) (xy 195.70206 -49.711433) (xy 195.734226 -49.755537) (xy 195.759776 -49.803776)
			(xy 195.778191 -49.855163) (xy 195.789092 -49.908651) (xy 195.792259 -49.963147) (xy 195.787625 -50.017537)
			(xy 195.775286 -50.070712) (xy 195.755494 -50.121585) (xy 195.728653 -50.169117) (xy 195.69531 -50.212338)
			(xy 195.656148 -50.250366) (xy 195.611965 -50.282423) (xy 195.563664 -50.307855) (xy 195.53809 -50.3174)
			(xy 195.535296 -50.318416) (xy 195.5292 -50.321464) (xy 195.520966 -50.32605) (xy 195.508279 -50.339963)
			(xy 195.501463 -50.357516) (xy 195.501006 -50.36693) (xy 195.501006 -50.62347) (xy 195.520564 -50.65014)
			(xy 195.53682 -50.65522) (xy 195.562901 -50.66385) (xy 195.612461 -50.687547) (xy 195.658114 -50.718103)
			(xy 195.698915 -50.754886) (xy 195.734024 -50.797138) (xy 195.762714 -50.843986) (xy 195.784393 -50.894461)
			(xy 195.798614 -50.947523) (xy 195.80225 -50.974752) (xy 195.80352 -50.985928) (xy 195.805044 -51.019456)
			(xy 195.80449 -51.048682) (xy 195.795583 -51.106451) (xy 195.777972 -51.162187) (xy 195.752068 -51.214585)
			(xy 195.718477 -51.262421) (xy 195.698618 -51.28387) (xy 195.69811 -51.284378) (xy 195.695062 -51.287426)
			(xy 195.672802 -51.309948) (xy 195.622197 -51.348009) (xy 195.565991 -51.37717) (xy 195.536058 -51.387502)
			(xy 195.528438 -51.390042) (xy 195.515484 -51.399186) (xy 195.510912 -51.40579) (xy 195.506355 -51.412431)
			(xy 195.501303 -51.427714) (xy 195.501006 -51.435762) (xy 195.501006 -51.63947) (xy 195.520564 -51.66614)
			(xy 195.53682 -51.67122) (xy 195.562901 -51.67985) (xy 195.582138 -51.689048) (xy 196.3555 -51.689048)
			(xy 196.3555 -51.634552) (xy 196.363255 -51.580611) (xy 196.378607 -51.528322) (xy 196.401245 -51.47875)
			(xy 196.430706 -51.432905) (xy 196.466391 -51.391718) (xy 196.507574 -51.356028) (xy 196.553417 -51.326563)
			(xy 196.602987 -51.303921) (xy 196.655274 -51.288563) (xy 196.709214 -51.280803) (xy 196.736462 -51.280314)
			(xy 196.763832 -51.280799) (xy 196.81801 -51.288612) (xy 196.870513 -51.304096) (xy 196.92026 -51.326934)
			(xy 196.966228 -51.356655) (xy 196.98716 -51.374294) (xy 196.994272 -51.38039) (xy 197.01129 -51.38674)
			(xy 197.096634 -51.38674) (xy 197.113652 -51.38039) (xy 197.120764 -51.374294) (xy 197.141698 -51.356657)
			(xy 197.18767 -51.326945) (xy 197.237417 -51.304109) (xy 197.289918 -51.288617) (xy 197.344093 -51.280788)
			(xy 197.371462 -51.280314) (xy 197.389805 -51.280548) (xy 197.426318 -51.28411) (xy 197.44436 -51.287426)
			(xy 197.455282 -51.289458) (xy 197.475856 -51.284632) (xy 197.553834 -51.225704) (xy 197.564248 -51.206908)
			(xy 197.56501 -51.195986) (xy 197.567912 -51.167703) (xy 197.580948 -51.112366) (xy 197.602043 -51.059573)
			(xy 197.63073 -51.010489) (xy 197.666376 -50.9662) (xy 197.68693 -50.946558) (xy 197.694342 -50.939045)
			(xy 197.702863 -50.919759) (xy 197.70344 -50.90922) (xy 197.70344 -50.834544) (xy 197.702889 -50.823997)
			(xy 197.694368 -50.804702) (xy 197.68693 -50.797206) (xy 197.667859 -50.779062) (xy 197.634379 -50.738445)
			(xy 197.606807 -50.693606) (xy 197.585667 -50.6454) (xy 197.571361 -50.594744) (xy 197.564161 -50.542601)
			(xy 197.56374 -50.516282) (xy 197.564226 -50.489031) (xy 197.571982 -50.435083) (xy 197.587337 -50.382788)
			(xy 197.609979 -50.333211) (xy 197.639445 -50.287361) (xy 197.675136 -50.24617) (xy 197.716327 -50.210479)
			(xy 197.762177 -50.181013) (xy 197.811754 -50.158371) (xy 197.864049 -50.143016) (xy 197.917997 -50.13526)
			(xy 197.972499 -50.13526) (xy 198.026447 -50.143016) (xy 198.078742 -50.158371) (xy 198.128319 -50.181013)
			(xy 198.174169 -50.210479) (xy 198.21536 -50.24617) (xy 198.251051 -50.287361) (xy 198.280517 -50.333211)
			(xy 198.303159 -50.382788) (xy 198.318514 -50.435083) (xy 198.32627 -50.489031) (xy 198.326756 -50.516282)
			(xy 198.326351 -50.5426) (xy 198.319123 -50.594737) (xy 198.304802 -50.645386) (xy 198.283658 -50.693588)
			(xy 198.256094 -50.738429) (xy 198.222631 -50.779058) (xy 198.203566 -50.797206) (xy 198.196169 -50.804732)
			(xy 198.18764 -50.824008) (xy 198.187056 -50.834544) (xy 198.187056 -50.90922) (xy 198.187628 -50.919764)
			(xy 198.196134 -50.939059) (xy 198.203566 -50.946558) (xy 198.222619 -50.96472) (xy 198.2561 -51.005334)
			(xy 198.283675 -51.050168) (xy 198.304819 -51.098371) (xy 198.319128 -51.149024) (xy 198.326332 -51.201164)
			(xy 198.326756 -51.227482) (xy 198.326205 -51.254731) (xy 198.318452 -51.308673) (xy 198.303102 -51.360964)
			(xy 198.280466 -51.410538) (xy 198.251007 -51.456386) (xy 198.215322 -51.497575) (xy 198.174139 -51.533267)
			(xy 198.128296 -51.562735) (xy 198.078726 -51.585379) (xy 198.026438 -51.600738) (xy 197.972497 -51.6085)
			(xy 197.945248 -51.60899) (xy 197.926905 -51.608754) (xy 197.890392 -51.605193) (xy 197.87235 -51.601878)
			(xy 197.861428 -51.599846) (xy 197.840854 -51.604672) (xy 197.762876 -51.6636) (xy 197.752462 -51.682396)
			(xy 197.7517 -51.693318) (xy 197.748761 -51.72157) (xy 197.73573 -51.776852) (xy 197.714649 -51.829591)
			(xy 197.685982 -51.878623) (xy 197.650363 -51.922862) (xy 197.608579 -51.961333) (xy 197.561553 -51.993184)
			(xy 197.510326 -52.017712) (xy 197.456028 -52.034374) (xy 197.39986 -52.042804) (xy 197.371462 -52.04333)
			(xy 197.344092 -52.042845) (xy 197.289913 -52.035034) (xy 197.23741 -52.01955) (xy 197.187662 -51.996713)
			(xy 197.141696 -51.96699) (xy 197.120764 -51.94935) (xy 197.113652 -51.943254) (xy 197.096634 -51.936904)
			(xy 197.01129 -51.936904) (xy 196.994272 -51.943254) (xy 196.98716 -51.94935) (xy 196.96621 -51.966967)
			(xy 196.920243 -51.996684) (xy 196.8705 -52.019525) (xy 196.818003 -52.035021) (xy 196.76383 -52.042854)
			(xy 196.736462 -52.04333) (xy 196.709214 -52.042797) (xy 196.655274 -52.035037) (xy 196.602987 -52.019679)
			(xy 196.553417 -51.997037) (xy 196.507574 -51.967572) (xy 196.466391 -51.931882) (xy 196.430706 -51.890695)
			(xy 196.401245 -51.84485) (xy 196.378607 -51.795278) (xy 196.363255 -51.742989) (xy 196.3555 -51.689048)
			(xy 195.582138 -51.689048) (xy 195.612461 -51.703547) (xy 195.658114 -51.734103) (xy 195.698915 -51.770886)
			(xy 195.734024 -51.813138) (xy 195.762714 -51.859986) (xy 195.784393 -51.910461) (xy 195.798614 -51.963523)
			(xy 195.80225 -51.990752) (xy 195.80352 -52.001928) (xy 195.805044 -52.035456) (xy 195.80449 -52.064682)
			(xy 195.795583 -52.122451) (xy 195.777972 -52.178187) (xy 195.752068 -52.230585) (xy 195.718477 -52.278421)
			(xy 195.698618 -52.29987) (xy 195.69811 -52.300378) (xy 195.695062 -52.303426) (xy 195.672802 -52.325948)
			(xy 195.622197 -52.364009) (xy 195.565991 -52.39317) (xy 195.536058 -52.403502) (xy 195.528438 -52.406042)
			(xy 195.515484 -52.415186) (xy 195.510912 -52.42179) (xy 195.506355 -52.428431) (xy 195.501303 -52.443714)
			(xy 195.501006 -52.451762) (xy 195.501006 -52.564157) (xy 197.927107 -52.564157) (xy 197.927107 -52.509643)
			(xy 197.934865 -52.455684) (xy 197.950224 -52.403378) (xy 197.97287 -52.353791) (xy 198.002343 -52.307931)
			(xy 198.038043 -52.266733) (xy 198.079243 -52.231035) (xy 198.125103 -52.201564) (xy 198.174692 -52.178919)
			(xy 198.226998 -52.163562) (xy 198.280957 -52.155806) (xy 198.308214 -52.155344) (xy 198.335585 -52.155791)
			(xy 198.389765 -52.163612) (xy 198.442269 -52.179105) (xy 198.492016 -52.201951) (xy 198.537981 -52.23168)
			(xy 198.558912 -52.249324) (xy 198.566024 -52.25542) (xy 198.583042 -52.26177) (xy 198.668386 -52.26177)
			(xy 198.685404 -52.25542) (xy 198.692516 -52.249324) (xy 198.713472 -52.231715) (xy 198.759438 -52.201997)
			(xy 198.809179 -52.179155) (xy 198.861675 -52.163657) (xy 198.915846 -52.155822) (xy 198.943214 -52.155344)
			(xy 198.970461 -52.155927) (xy 199.024401 -52.163684) (xy 199.076687 -52.179039) (xy 199.126256 -52.201678)
			(xy 199.172099 -52.231141) (xy 199.213282 -52.266828) (xy 199.248968 -52.308012) (xy 199.278429 -52.353856)
			(xy 199.301066 -52.403426) (xy 199.316419 -52.455713) (xy 199.324174 -52.509653) (xy 199.324174 -52.564147)
			(xy 199.316419 -52.618087) (xy 199.301066 -52.670374) (xy 199.278429 -52.719944) (xy 199.248968 -52.765788)
			(xy 199.213282 -52.806972) (xy 199.172099 -52.842659) (xy 199.126256 -52.872122) (xy 199.076687 -52.894761)
			(xy 199.024401 -52.910116) (xy 198.970461 -52.917873) (xy 198.943214 -52.91836) (xy 198.915844 -52.917895)
			(xy 198.861664 -52.910079) (xy 198.809161 -52.89459) (xy 198.759414 -52.871748) (xy 198.713447 -52.842022)
			(xy 198.692516 -52.82438) (xy 198.685404 -52.818284) (xy 198.668386 -52.811934) (xy 198.583042 -52.811934)
			(xy 198.566024 -52.818284) (xy 198.558912 -52.82438) (xy 198.537984 -52.842024) (xy 198.49201 -52.871736)
			(xy 198.442262 -52.894571) (xy 198.38976 -52.910061) (xy 198.335583 -52.917887) (xy 198.308214 -52.91836)
			(xy 198.280957 -52.917994) (xy 198.226998 -52.910238) (xy 198.174692 -52.894881) (xy 198.125103 -52.872236)
			(xy 198.079243 -52.842765) (xy 198.038043 -52.807067) (xy 198.002343 -52.765869) (xy 197.97287 -52.720009)
			(xy 197.950224 -52.670422) (xy 197.934865 -52.618116) (xy 197.927107 -52.564157) (xy 195.501006 -52.564157)
			(xy 195.501006 -52.65547) (xy 195.520564 -52.68214) (xy 195.53682 -52.68722) (xy 195.562901 -52.69585)
			(xy 195.612461 -52.719547) (xy 195.658114 -52.750103) (xy 195.698915 -52.786886) (xy 195.734024 -52.829138)
			(xy 195.762714 -52.875986) (xy 195.784393 -52.926461) (xy 195.798614 -52.979523) (xy 195.80225 -53.006752)
			(xy 195.80352 -53.017928) (xy 195.805044 -53.051456) (xy 195.80449 -53.080682) (xy 195.795583 -53.138451)
			(xy 195.777972 -53.194187) (xy 195.752068 -53.246585) (xy 195.718477 -53.294421) (xy 195.698618 -53.31587)
			(xy 195.69811 -53.316378) (xy 195.695062 -53.319426) (xy 195.672802 -53.341948) (xy 195.622197 -53.380009)
			(xy 195.565991 -53.40917) (xy 195.536058 -53.419502) (xy 195.528438 -53.422042) (xy 195.515484 -53.431186)
			(xy 195.510912 -53.43779) (xy 195.506355 -53.444431) (xy 195.501303 -53.459714) (xy 195.501006 -53.467762)
			(xy 195.501006 -53.67147) (xy 195.520564 -53.69814) (xy 195.53682 -53.70322) (xy 195.562901 -53.71185)
			(xy 195.612461 -53.735547) (xy 195.658114 -53.766103) (xy 195.698915 -53.802886) (xy 195.734024 -53.845138)
			(xy 195.762714 -53.891986) (xy 195.784393 -53.942461) (xy 195.798614 -53.995523) (xy 195.80225 -54.022752)
			(xy 195.80352 -54.033928) (xy 195.805044 -54.067456) (xy 195.80449 -54.096682) (xy 195.795583 -54.154451)
			(xy 195.777972 -54.210187) (xy 195.763774 -54.238906) (xy 202.486004 -54.238906) (xy 202.490075 -54.183284)
			(xy 202.502201 -54.128847) (xy 202.522124 -54.076756) (xy 202.54942 -54.028121) (xy 202.583506 -53.983978)
			(xy 202.623655 -53.945269) (xy 202.669013 -53.912818) (xy 202.718613 -53.887317) (xy 202.771397 -53.86931)
			(xy 202.82624 -53.85918) (xy 202.881974 -53.857143) (xy 202.937411 -53.863243) (xy 202.991368 -53.877349)
			(xy 203.042697 -53.899161) (xy 203.090303 -53.928215) (xy 203.133171 -53.96389) (xy 203.170388 -54.005427)
			(xy 203.201161 -54.05194) (xy 203.224833 -54.102437) (xy 203.240901 -54.155844) (xy 203.249021 -54.21102)
			(xy 203.24953 -54.238906) (xy 203.249021 -54.266792) (xy 203.240901 -54.321968) (xy 203.224833 -54.375375)
			(xy 203.201161 -54.425872) (xy 203.170388 -54.472385) (xy 203.133171 -54.513922) (xy 203.090303 -54.549597)
			(xy 203.042697 -54.578651) (xy 202.991368 -54.600463) (xy 202.937411 -54.614569) (xy 202.881974 -54.620669)
			(xy 202.82624 -54.618632) (xy 202.771397 -54.608502) (xy 202.718613 -54.590495) (xy 202.669013 -54.564994)
			(xy 202.623655 -54.532543) (xy 202.583506 -54.493834) (xy 202.54942 -54.449691) (xy 202.522124 -54.401056)
			(xy 202.502201 -54.348965) (xy 202.490075 -54.294528) (xy 202.486004 -54.238906) (xy 195.763774 -54.238906)
			(xy 195.752068 -54.262585) (xy 195.718477 -54.310421) (xy 195.698618 -54.33187) (xy 195.69811 -54.332378)
			(xy 195.695062 -54.335426) (xy 195.672802 -54.357948) (xy 195.622197 -54.396009) (xy 195.565991 -54.42517)
			(xy 195.536058 -54.435502) (xy 195.528438 -54.438042) (xy 195.515484 -54.447186) (xy 195.510912 -54.45379)
			(xy 195.506355 -54.460431) (xy 195.501303 -54.475714) (xy 195.501006 -54.483762) (xy 195.501006 -54.68747)
			(xy 195.520564 -54.71414) (xy 195.53682 -54.71922) (xy 195.562901 -54.72785) (xy 195.612461 -54.751547)
			(xy 195.658114 -54.782103) (xy 195.698915 -54.818886) (xy 195.734024 -54.861138) (xy 195.762714 -54.907986)
			(xy 195.784393 -54.958461) (xy 195.792592 -54.989055) (xy 198.001045 -54.989055) (xy 198.001045 -54.934545)
			(xy 198.008803 -54.88059) (xy 198.024161 -54.828289) (xy 198.046806 -54.778705) (xy 198.076277 -54.73285)
			(xy 198.111975 -54.691655) (xy 198.153172 -54.655961) (xy 198.19903 -54.626492) (xy 198.248615 -54.603851)
			(xy 198.300918 -54.588497) (xy 198.354873 -54.580743) (xy 198.382128 -54.580282) (xy 198.41022 -54.580755)
			(xy 198.465799 -54.588986) (xy 198.519568 -54.605281) (xy 198.570366 -54.629287) (xy 198.617092 -54.660485)
			(xy 198.658737 -54.6982) (xy 198.694398 -54.741616) (xy 198.70928 -54.765448) (xy 198.714614 -54.774592)
			(xy 198.731632 -54.786784) (xy 198.82485 -54.80685) (xy 198.845424 -54.802786) (xy 198.85406 -54.79669)
			(xy 198.878132 -54.780704) (xy 198.930061 -54.755358) (xy 198.985216 -54.738129) (xy 199.042338 -54.729409)
			(xy 199.07123 -54.728872) (xy 199.098481 -54.72935) (xy 199.152428 -54.73711) (xy 199.204722 -54.752468)
			(xy 199.254298 -54.775111) (xy 199.300147 -54.804579) (xy 199.341336 -54.840271) (xy 199.377027 -54.881461)
			(xy 199.406494 -54.927311) (xy 199.429136 -54.976888) (xy 199.444492 -55.029182) (xy 199.452251 -55.083129)
			(xy 199.452738 -55.11038) (xy 199.452275 -55.137751) (xy 199.444459 -55.19193) (xy 199.42897 -55.244434)
			(xy 199.406127 -55.294181) (xy 199.3764 -55.340147) (xy 199.358758 -55.361078) (xy 199.352662 -55.36819)
			(xy 199.346312 -55.385208) (xy 199.346312 -55.470552) (xy 199.352662 -55.48757) (xy 199.358758 -55.494682)
			(xy 199.37638 -55.51563) (xy 199.406106 -55.561595) (xy 199.428954 -55.611339) (xy 199.444452 -55.663838)
			(xy 199.452283 -55.718015) (xy 199.452285 -55.772755) (xy 199.444459 -55.826932) (xy 199.428965 -55.879433)
			(xy 199.406121 -55.929179) (xy 199.376398 -55.975146) (xy 199.358758 -55.996078) (xy 199.352662 -56.00319)
			(xy 199.346312 -56.020208) (xy 199.346312 -56.105552) (xy 199.352662 -56.12257) (xy 199.358758 -56.129682)
			(xy 199.376396 -56.150615) (xy 199.406109 -56.196587) (xy 199.428946 -56.246334) (xy 199.444437 -56.298835)
			(xy 199.452265 -56.353011) (xy 199.452738 -56.38038) (xy 199.452252 -56.407631) (xy 199.444496 -56.461579)
			(xy 199.429141 -56.513874) (xy 199.406499 -56.563451) (xy 199.377033 -56.609301) (xy 199.341342 -56.650492)
			(xy 199.300151 -56.686183) (xy 199.254301 -56.715649) (xy 199.204724 -56.738291) (xy 199.152429 -56.753646)
			(xy 199.098481 -56.761402) (xy 199.043979 -56.761402) (xy 198.990031 -56.753646) (xy 198.937736 -56.738291)
			(xy 198.888159 -56.715649) (xy 198.842309 -56.686183) (xy 198.801118 -56.650492) (xy 198.765427 -56.609301)
			(xy 198.735961 -56.563451) (xy 198.713319 -56.513874) (xy 198.697964 -56.461579) (xy 198.690208 -56.407631)
			(xy 198.689722 -56.38038) (xy 198.690171 -56.353009) (xy 198.697992 -56.298829) (xy 198.713485 -56.246326)
			(xy 198.736331 -56.196579) (xy 198.766059 -56.150613) (xy 198.783702 -56.129682) (xy 198.789798 -56.12257)
			(xy 198.796148 -56.105552) (xy 198.796148 -56.020208) (xy 198.789798 -56.00319) (xy 198.783702 -55.996078)
			(xy 198.766043 -55.975161) (xy 198.736321 -55.92919) (xy 198.713478 -55.879441) (xy 198.697984 -55.826936)
			(xy 198.690158 -55.772756) (xy 198.69016 -55.718014) (xy 198.697991 -55.663834) (xy 198.713489 -55.611331)
			(xy 198.736335 -55.561584) (xy 198.766061 -55.515615) (xy 198.783702 -55.494682) (xy 198.789798 -55.48757)
			(xy 198.796148 -55.470552) (xy 198.796148 -55.385208) (xy 198.789798 -55.36819) (xy 198.783702 -55.361078)
			(xy 198.77275 -55.348283) (xy 198.75291 -55.321063) (xy 198.744078 -55.306722) (xy 198.738744 -55.297578)
			(xy 198.721726 -55.285386) (xy 198.628508 -55.26532) (xy 198.607934 -55.269384) (xy 198.599298 -55.27548)
			(xy 198.575235 -55.291481) (xy 198.523303 -55.316824) (xy 198.468145 -55.334049) (xy 198.411021 -55.342764)
			(xy 198.382128 -55.343298) (xy 198.354873 -55.342857) (xy 198.300918 -55.335103) (xy 198.248615 -55.319749)
			(xy 198.19903 -55.297108) (xy 198.153172 -55.267639) (xy 198.111975 -55.231945) (xy 198.076277 -55.19075)
			(xy 198.046806 -55.144895) (xy 198.024161 -55.095311) (xy 198.008803 -55.04301) (xy 198.001045 -54.989055)
			(xy 195.792592 -54.989055) (xy 195.798614 -55.011523) (xy 195.80225 -55.038752) (xy 195.80352 -55.049928)
			(xy 195.805044 -55.083456) (xy 195.80449 -55.112682) (xy 195.795583 -55.170451) (xy 195.777972 -55.226187)
			(xy 195.752068 -55.278585) (xy 195.718477 -55.326421) (xy 195.698618 -55.34787) (xy 195.69811 -55.348378)
			(xy 195.695062 -55.351426) (xy 195.672802 -55.373948) (xy 195.622197 -55.412009) (xy 195.605147 -55.420855)
			(xy 196.324645 -55.420855) (xy 196.324645 -55.366345) (xy 196.332403 -55.31239) (xy 196.347761 -55.260089)
			(xy 196.370406 -55.210505) (xy 196.399877 -55.16465) (xy 196.435575 -55.123455) (xy 196.476772 -55.087761)
			(xy 196.52263 -55.058292) (xy 196.572215 -55.035651) (xy 196.624518 -55.020297) (xy 196.678473 -55.012543)
			(xy 196.705728 -55.012082) (xy 196.732044 -55.012542) (xy 196.784177 -55.019762) (xy 196.834825 -55.034074)
			(xy 196.883027 -55.055207) (xy 196.927869 -55.082761) (xy 196.968501 -55.116213) (xy 196.986652 -55.135272)
			(xy 196.994156 -55.142695) (xy 197.013449 -55.151208) (xy 197.02399 -55.151782) (xy 197.098666 -55.151782)
			(xy 197.109216 -55.151253) (xy 197.128512 -55.142719) (xy 197.136004 -55.135272) (xy 197.154151 -55.116204)
			(xy 197.194767 -55.082723) (xy 197.239604 -55.055149) (xy 197.28781 -55.034008) (xy 197.338466 -55.019701)
			(xy 197.390609 -55.012503) (xy 197.416928 -55.012082) (xy 197.444177 -55.01259) (xy 197.49812 -55.02035)
			(xy 197.55041 -55.035707) (xy 197.599983 -55.058349) (xy 197.645828 -55.087815) (xy 197.687014 -55.123506)
			(xy 197.722702 -55.164694) (xy 197.752164 -55.210542) (xy 197.774803 -55.260116) (xy 197.790156 -55.312407)
			(xy 197.797912 -55.366351) (xy 197.797912 -55.420849) (xy 197.790156 -55.474793) (xy 197.774803 -55.527084)
			(xy 197.752164 -55.576658) (xy 197.722702 -55.622506) (xy 197.687014 -55.663694) (xy 197.645828 -55.699385)
			(xy 197.599983 -55.728851) (xy 197.55041 -55.751493) (xy 197.49812 -55.76685) (xy 197.444177 -55.77461)
			(xy 197.416928 -55.775098) (xy 197.390611 -55.774673) (xy 197.338476 -55.767448) (xy 197.287827 -55.753129)
			(xy 197.239625 -55.731989) (xy 197.194784 -55.704429) (xy 197.154153 -55.67097) (xy 197.136004 -55.651908)
			(xy 197.128482 -55.644507) (xy 197.109202 -55.635982) (xy 197.098666 -55.635398) (xy 197.02399 -55.635398)
			(xy 197.013438 -55.635909) (xy 196.994143 -55.644457) (xy 196.986652 -55.651908) (xy 196.968542 -55.671012)
			(xy 196.927916 -55.704488) (xy 196.883071 -55.732055) (xy 196.834858 -55.753189) (xy 196.784196 -55.767488)
			(xy 196.732049 -55.774681) (xy 196.705728 -55.775098) (xy 196.678473 -55.774657) (xy 196.624518 -55.766903)
			(xy 196.572215 -55.751549) (xy 196.52263 -55.728908) (xy 196.476772 -55.699439) (xy 196.435575 -55.663745)
			(xy 196.399877 -55.62255) (xy 196.370406 -55.576695) (xy 196.347761 -55.527111) (xy 196.332403 -55.47481)
			(xy 196.324645 -55.420855) (xy 195.605147 -55.420855) (xy 195.565991 -55.44117) (xy 195.536058 -55.451502)
			(xy 195.528438 -55.454042) (xy 195.515484 -55.463186) (xy 195.510912 -55.46979) (xy 195.506355 -55.476431)
			(xy 195.501303 -55.491714) (xy 195.501006 -55.499762) (xy 195.501006 -55.95747) (xy 195.520564 -55.98414)
			(xy 195.53682 -55.98922) (xy 195.562901 -55.99785) (xy 195.612461 -56.021547) (xy 195.658114 -56.052103)
			(xy 195.698915 -56.088886) (xy 195.734024 -56.131138) (xy 195.762714 -56.177986) (xy 195.784393 -56.228461)
			(xy 195.798614 -56.281523) (xy 195.80225 -56.308752) (xy 195.80352 -56.319928) (xy 195.805044 -56.353456)
			(xy 195.80449 -56.382682) (xy 195.795583 -56.440451) (xy 195.777972 -56.496187) (xy 195.752068 -56.548585)
			(xy 195.718477 -56.596421) (xy 195.698618 -56.61787) (xy 195.69811 -56.618378) (xy 195.695062 -56.621426)
			(xy 195.672802 -56.643948) (xy 195.622197 -56.682009) (xy 195.565991 -56.71117) (xy 195.536058 -56.721502)
			(xy 195.528438 -56.724042) (xy 195.515484 -56.733186) (xy 195.510912 -56.73979) (xy 195.506355 -56.746431)
			(xy 195.501303 -56.761714) (xy 195.501006 -56.769762) (xy 195.501006 -57.48528) (xy 198.705976 -57.48528)
			(xy 198.710047 -57.429658) (xy 198.722173 -57.375221) (xy 198.742096 -57.32313) (xy 198.769392 -57.274495)
			(xy 198.803478 -57.230352) (xy 198.843627 -57.191643) (xy 198.888985 -57.159192) (xy 198.938585 -57.133691)
			(xy 198.991369 -57.115684) (xy 199.046212 -57.105554) (xy 199.101946 -57.103517) (xy 199.157383 -57.109617)
			(xy 199.21134 -57.123723) (xy 199.262669 -57.145535) (xy 199.310275 -57.174589) (xy 199.353143 -57.210264)
			(xy 199.39036 -57.251801) (xy 199.421133 -57.298314) (xy 199.444805 -57.348811) (xy 199.460873 -57.402218)
			(xy 199.468993 -57.457394) (xy 199.469502 -57.48528) (xy 199.468993 -57.513166) (xy 199.460873 -57.568342)
			(xy 199.444805 -57.621749) (xy 199.421133 -57.672246) (xy 199.39036 -57.718759) (xy 199.353143 -57.760296)
			(xy 199.310275 -57.795971) (xy 199.262669 -57.825025) (xy 199.21134 -57.846837) (xy 199.157383 -57.860943)
			(xy 199.101946 -57.867043) (xy 199.046212 -57.865006) (xy 198.991369 -57.854876) (xy 198.938585 -57.836869)
			(xy 198.888985 -57.811368) (xy 198.843627 -57.778917) (xy 198.803478 -57.740208) (xy 198.769392 -57.696065)
			(xy 198.742096 -57.64743) (xy 198.722173 -57.595339) (xy 198.710047 -57.540902) (xy 198.705976 -57.48528)
			(xy 195.501006 -57.48528) (xy 195.501006 -58.076084) (xy 199.45807 -58.076084) (xy 199.462141 -58.020462)
			(xy 199.474267 -57.966025) (xy 199.49419 -57.913934) (xy 199.521486 -57.865299) (xy 199.555572 -57.821156)
			(xy 199.595721 -57.782447) (xy 199.641079 -57.749996) (xy 199.690679 -57.724495) (xy 199.743463 -57.706488)
			(xy 199.798306 -57.696358) (xy 199.85404 -57.694321) (xy 199.909477 -57.700421) (xy 199.963434 -57.714527)
			(xy 200.014763 -57.736339) (xy 200.062369 -57.765393) (xy 200.105237 -57.801068) (xy 200.142454 -57.842605)
			(xy 200.15879 -57.867296) (xy 201.7428 -57.867296) (xy 201.746873 -57.811637) (xy 201.759008 -57.757164)
			(xy 201.778944 -57.705038) (xy 201.806258 -57.65637) (xy 201.840366 -57.612198) (xy 201.880543 -57.573463)
			(xy 201.925931 -57.540991) (xy 201.975563 -57.515473) (xy 202.028383 -57.497454) (xy 202.083262 -57.487317)
			(xy 202.139033 -57.485279) (xy 202.194507 -57.491382) (xy 202.2485 -57.505498) (xy 202.299863 -57.527325)
			(xy 202.347501 -57.556398) (xy 202.390397 -57.592097) (xy 202.427639 -57.633661) (xy 202.458433 -57.680205)
			(xy 202.482121 -57.730736) (xy 202.498199 -57.784178) (xy 202.506325 -57.839392) (xy 202.506834 -57.867296)
			(xy 202.506325 -57.8952) (xy 202.498199 -57.950414) (xy 202.482121 -58.003856) (xy 202.458433 -58.054387)
			(xy 202.427639 -58.100931) (xy 202.390397 -58.142495) (xy 202.347501 -58.178194) (xy 202.299863 -58.207267)
			(xy 202.2485 -58.229094) (xy 202.194507 -58.24321) (xy 202.139033 -58.249313) (xy 202.083262 -58.247275)
			(xy 202.028383 -58.237138) (xy 201.975563 -58.219119) (xy 201.925931 -58.193601) (xy 201.880543 -58.161129)
			(xy 201.840366 -58.122394) (xy 201.806258 -58.078222) (xy 201.778944 -58.029554) (xy 201.759008 -57.977428)
			(xy 201.746873 -57.922955) (xy 201.7428 -57.867296) (xy 200.15879 -57.867296) (xy 200.173227 -57.889118)
			(xy 200.196899 -57.939615) (xy 200.212967 -57.993022) (xy 200.221087 -58.048198) (xy 200.221596 -58.076084)
			(xy 200.221087 -58.10397) (xy 200.212967 -58.159146) (xy 200.196899 -58.212553) (xy 200.173227 -58.26305)
			(xy 200.142454 -58.309563) (xy 200.105237 -58.3511) (xy 200.062369 -58.386775) (xy 200.014763 -58.415829)
			(xy 199.963434 -58.437641) (xy 199.909477 -58.451747) (xy 199.85404 -58.457847) (xy 199.798306 -58.45581)
			(xy 199.743463 -58.44568) (xy 199.690679 -58.427673) (xy 199.641079 -58.402172) (xy 199.595721 -58.369721)
			(xy 199.555572 -58.331012) (xy 199.521486 -58.286869) (xy 199.49419 -58.238234) (xy 199.474267 -58.186143)
			(xy 199.462141 -58.131706) (xy 199.45807 -58.076084) (xy 195.501006 -58.076084) (xy 195.501006 -58.561224)
			(xy 200.662284 -58.561224) (xy 200.666355 -58.505602) (xy 200.678481 -58.451165) (xy 200.698404 -58.399074)
			(xy 200.7257 -58.350439) (xy 200.759786 -58.306296) (xy 200.799935 -58.267587) (xy 200.845293 -58.235136)
			(xy 200.894893 -58.209635) (xy 200.947677 -58.191628) (xy 201.00252 -58.181498) (xy 201.058254 -58.179461)
			(xy 201.113691 -58.185561) (xy 201.167648 -58.199667) (xy 201.218977 -58.221479) (xy 201.266583 -58.250533)
			(xy 201.309451 -58.286208) (xy 201.346668 -58.327745) (xy 201.377441 -58.374258) (xy 201.401113 -58.424755)
			(xy 201.408623 -58.449718) (xy 202.908914 -58.449718) (xy 202.912985 -58.394096) (xy 202.925111 -58.339659)
			(xy 202.945034 -58.287568) (xy 202.97233 -58.238933) (xy 203.006416 -58.19479) (xy 203.046565 -58.156081)
			(xy 203.091923 -58.12363) (xy 203.141523 -58.098129) (xy 203.194307 -58.080122) (xy 203.24915 -58.069992)
			(xy 203.304884 -58.067955) (xy 203.360321 -58.074055) (xy 203.414278 -58.088161) (xy 203.465607 -58.109973)
			(xy 203.513213 -58.139027) (xy 203.556081 -58.174702) (xy 203.593298 -58.216239) (xy 203.624071 -58.262752)
			(xy 203.647743 -58.313249) (xy 203.663811 -58.366656) (xy 203.671931 -58.421832) (xy 203.67244 -58.449718)
			(xy 203.671931 -58.477604) (xy 203.663811 -58.53278) (xy 203.647743 -58.586187) (xy 203.624071 -58.636684)
			(xy 203.593298 -58.683197) (xy 203.556081 -58.724734) (xy 203.513213 -58.760409) (xy 203.465607 -58.789463)
			(xy 203.414278 -58.811275) (xy 203.360321 -58.825381) (xy 203.304884 -58.831481) (xy 203.24915 -58.829444)
			(xy 203.194307 -58.819314) (xy 203.141523 -58.801307) (xy 203.091923 -58.775806) (xy 203.046565 -58.743355)
			(xy 203.006416 -58.704646) (xy 202.97233 -58.660503) (xy 202.945034 -58.611868) (xy 202.925111 -58.559777)
			(xy 202.912985 -58.50534) (xy 202.908914 -58.449718) (xy 201.408623 -58.449718) (xy 201.417181 -58.478162)
			(xy 201.425301 -58.533338) (xy 201.42581 -58.561224) (xy 201.425301 -58.58911) (xy 201.417181 -58.644286)
			(xy 201.401113 -58.697693) (xy 201.377441 -58.74819) (xy 201.346668 -58.794703) (xy 201.309451 -58.83624)
			(xy 201.266583 -58.871915) (xy 201.218977 -58.900969) (xy 201.167648 -58.922781) (xy 201.113691 -58.936887)
			(xy 201.058254 -58.942987) (xy 201.00252 -58.94095) (xy 200.947677 -58.93082) (xy 200.894893 -58.912813)
			(xy 200.845293 -58.887312) (xy 200.799935 -58.854861) (xy 200.759786 -58.816152) (xy 200.7257 -58.772009)
			(xy 200.698404 -58.723374) (xy 200.678481 -58.671283) (xy 200.666355 -58.616846) (xy 200.662284 -58.561224)
			(xy 195.501006 -58.561224) (xy 195.501006 -59.974734) (xy 199.187054 -59.974734) (xy 199.187462 -59.947906)
			(xy 199.194983 -59.894779) (xy 199.209869 -59.843229) (xy 199.231826 -59.794271) (xy 199.260421 -59.748869)
			(xy 199.295091 -59.707918) (xy 199.335154 -59.672225) (xy 199.357234 -59.65698) (xy 199.368799 -59.648762)
			(xy 199.387201 -59.627181) (xy 199.398953 -59.601369) (xy 199.403146 -59.573319) (xy 199.399459 -59.545199)
			(xy 199.388174 -59.519179) (xy 199.370164 -59.49727) (xy 199.358758 -59.488832) (xy 199.337297 -59.473485)
			(xy 199.298386 -59.437856) (xy 199.264754 -59.397206) (xy 199.237044 -59.35231) (xy 199.215784 -59.304024)
			(xy 199.20138 -59.253269) (xy 199.194106 -59.201014) (xy 199.193658 -59.174634) (xy 199.194144 -59.147383)
			(xy 199.2019 -59.093435) (xy 199.217255 -59.04114) (xy 199.239897 -58.991563) (xy 199.269363 -58.945713)
			(xy 199.305054 -58.904522) (xy 199.346245 -58.868831) (xy 199.392095 -58.839365) (xy 199.441672 -58.816723)
			(xy 199.493967 -58.801368) (xy 199.547915 -58.793612) (xy 199.602417 -58.793612) (xy 199.656365 -58.801368)
			(xy 199.70866 -58.816723) (xy 199.758237 -58.839365) (xy 199.804087 -58.868831) (xy 199.845278 -58.904522)
			(xy 199.880969 -58.945713) (xy 199.910435 -58.991563) (xy 199.933077 -59.04114) (xy 199.948432 -59.093435)
			(xy 199.956188 -59.147383) (xy 199.956674 -59.174634) (xy 199.95623 -59.201461) (xy 199.948713 -59.254585)
			(xy 199.933833 -59.306134) (xy 199.911882 -59.355091) (xy 199.883292 -59.400494) (xy 199.848628 -59.441446)
			(xy 199.808572 -59.477141) (xy 199.786494 -59.492388) (xy 199.774957 -59.500645) (xy 199.756551 -59.522215)
			(xy 199.744795 -59.548019) (xy 199.740596 -59.576063) (xy 199.744279 -59.604179) (xy 199.755559 -59.630194)
			(xy 199.773566 -59.6521) (xy 199.78497 -59.660536) (xy 199.806469 -59.675832) (xy 199.845378 -59.71147)
			(xy 199.879006 -59.75213) (xy 199.906711 -59.797035) (xy 199.927964 -59.845329) (xy 199.942361 -59.896091)
			(xy 199.949626 -59.948352) (xy 199.95007 -59.974734) (xy 199.949584 -60.001985) (xy 199.941828 -60.055933)
			(xy 199.926473 -60.108228) (xy 199.903831 -60.157805) (xy 199.874365 -60.203655) (xy 199.838674 -60.244846)
			(xy 199.797483 -60.280537) (xy 199.751633 -60.310003) (xy 199.702056 -60.332645) (xy 199.649761 -60.348)
			(xy 199.595813 -60.355756) (xy 199.541311 -60.355756) (xy 199.487363 -60.348) (xy 199.435068 -60.332645)
			(xy 199.385491 -60.310003) (xy 199.339641 -60.280537) (xy 199.29845 -60.244846) (xy 199.262759 -60.203655)
			(xy 199.233293 -60.157805) (xy 199.210651 -60.108228) (xy 199.195296 -60.055933) (xy 199.18754 -60.001985)
			(xy 199.187054 -59.974734) (xy 195.501006 -59.974734) (xy 195.501006 -60.601606) (xy 198.43318 -60.601606)
			(xy 198.437251 -60.545984) (xy 198.449377 -60.491547) (xy 198.4693 -60.439456) (xy 198.496596 -60.390821)
			(xy 198.530682 -60.346678) (xy 198.570831 -60.307969) (xy 198.616189 -60.275518) (xy 198.665789 -60.250017)
			(xy 198.718573 -60.23201) (xy 198.773416 -60.22188) (xy 198.82915 -60.219843) (xy 198.884587 -60.225943)
			(xy 198.938544 -60.240049) (xy 198.989873 -60.261861) (xy 199.037479 -60.290915) (xy 199.080347 -60.32659)
			(xy 199.117564 -60.368127) (xy 199.148337 -60.41464) (xy 199.172009 -60.465137) (xy 199.188077 -60.518544)
			(xy 199.196197 -60.57372) (xy 199.196706 -60.601606) (xy 199.196242 -60.627006) (xy 200.821288 -60.627006)
			(xy 200.825359 -60.571384) (xy 200.837485 -60.516947) (xy 200.857408 -60.464856) (xy 200.884704 -60.416221)
			(xy 200.91879 -60.372078) (xy 200.958939 -60.333369) (xy 201.004297 -60.300918) (xy 201.053897 -60.275417)
			(xy 201.106681 -60.25741) (xy 201.161524 -60.24728) (xy 201.217258 -60.245243) (xy 201.272695 -60.251343)
			(xy 201.326652 -60.265449) (xy 201.377981 -60.287261) (xy 201.425587 -60.316315) (xy 201.468455 -60.35199)
			(xy 201.505672 -60.393527) (xy 201.536445 -60.44004) (xy 201.560117 -60.490537) (xy 201.576185 -60.543944)
			(xy 201.584305 -60.59912) (xy 201.584814 -60.627006) (xy 201.584698 -60.633356) (xy 202.912978 -60.633356)
			(xy 202.917049 -60.577734) (xy 202.929175 -60.523297) (xy 202.949098 -60.471206) (xy 202.976394 -60.422571)
			(xy 203.01048 -60.378428) (xy 203.050629 -60.339719) (xy 203.095987 -60.307268) (xy 203.145587 -60.281767)
			(xy 203.198371 -60.26376) (xy 203.253214 -60.25363) (xy 203.308948 -60.251593) (xy 203.364385 -60.257693)
			(xy 203.418342 -60.271799) (xy 203.469671 -60.293611) (xy 203.517277 -60.322665) (xy 203.560145 -60.35834)
			(xy 203.597362 -60.399877) (xy 203.628135 -60.44639) (xy 203.651807 -60.496887) (xy 203.667875 -60.550294)
			(xy 203.675995 -60.60547) (xy 203.676504 -60.633356) (xy 203.675995 -60.661242) (xy 203.667875 -60.716418)
			(xy 203.651807 -60.769825) (xy 203.628135 -60.820322) (xy 203.597362 -60.866835) (xy 203.560145 -60.908372)
			(xy 203.517277 -60.944047) (xy 203.469671 -60.973101) (xy 203.418342 -60.994913) (xy 203.364385 -61.009019)
			(xy 203.308948 -61.015119) (xy 203.253214 -61.013082) (xy 203.198371 -61.002952) (xy 203.145587 -60.984945)
			(xy 203.095987 -60.959444) (xy 203.050629 -60.926993) (xy 203.01048 -60.888284) (xy 202.976394 -60.844141)
			(xy 202.949098 -60.795506) (xy 202.929175 -60.743415) (xy 202.917049 -60.688978) (xy 202.912978 -60.633356)
			(xy 201.584698 -60.633356) (xy 201.584305 -60.654892) (xy 201.576185 -60.710068) (xy 201.560117 -60.763475)
			(xy 201.536445 -60.813972) (xy 201.505672 -60.860485) (xy 201.468455 -60.902022) (xy 201.425587 -60.937697)
			(xy 201.377981 -60.966751) (xy 201.326652 -60.988563) (xy 201.272695 -61.002669) (xy 201.217258 -61.008769)
			(xy 201.161524 -61.006732) (xy 201.106681 -60.996602) (xy 201.053897 -60.978595) (xy 201.004297 -60.953094)
			(xy 200.958939 -60.920643) (xy 200.91879 -60.881934) (xy 200.884704 -60.837791) (xy 200.857408 -60.789156)
			(xy 200.837485 -60.737065) (xy 200.825359 -60.682628) (xy 200.821288 -60.627006) (xy 199.196242 -60.627006)
			(xy 199.196197 -60.629492) (xy 199.188077 -60.684668) (xy 199.172009 -60.738075) (xy 199.148337 -60.788572)
			(xy 199.117564 -60.835085) (xy 199.080347 -60.876622) (xy 199.037479 -60.912297) (xy 198.989873 -60.941351)
			(xy 198.938544 -60.963163) (xy 198.884587 -60.977269) (xy 198.82915 -60.983369) (xy 198.773416 -60.981332)
			(xy 198.718573 -60.971202) (xy 198.665789 -60.953195) (xy 198.616189 -60.927694) (xy 198.570831 -60.895243)
			(xy 198.530682 -60.856534) (xy 198.496596 -60.812391) (xy 198.4693 -60.763756) (xy 198.449377 -60.711665)
			(xy 198.437251 -60.657228) (xy 198.43318 -60.601606) (xy 195.501006 -60.601606) (xy 195.501006 -61.333126)
			(xy 195.501434 -61.343194) (xy 195.509156 -61.361791) (xy 195.515992 -61.369194) (xy 195.714874 -61.568076)
			(xy 195.73494 -61.575696) (xy 195.745862 -61.575188) (xy 195.761864 -61.57468) (xy 198.2851 -61.57468)
			(xy 198.319898 -61.576712) (xy 198.322946 -61.576966) (xy 199.12584 -61.576966)
		)
		(stroke
			(width 0)
			(type solid)
		)
		(fill yes)
		(layer "In9.Cu")
		(net "P3V3_SSD7")
	)
	(gr_poly
		(pts
			(xy 83.06689 -61.571632) (xy 84.203794 -61.571632) (xy 84.213577 -61.571177) (xy 84.23172 -61.563849)
			(xy 84.2391 -61.557408) (xy 84.257896 -61.539374) (xy 84.29117 -61.50737) (xy 84.294107 -61.504199)
			(xy 84.298953 -61.497044) (xy 84.300822 -61.493146) (xy 84.304632 -61.48451) (xy 84.30514 -61.474096)
			(xy 84.306559 -61.447503) (xy 84.315855 -61.395066) (xy 84.332354 -61.344432) (xy 84.355735 -61.296585)
			(xy 84.385542 -61.252455) (xy 84.421198 -61.212899) (xy 84.462009 -61.178686) (xy 84.507181 -61.150482)
			(xy 84.555837 -61.128835) (xy 84.607031 -61.114165) (xy 84.659767 -61.106757) (xy 84.686394 -61.106304)
			(xy 84.686648 -61.106304) (xy 84.713249 -61.106769) (xy 84.765935 -61.114168) (xy 84.817082 -61.128816)
			(xy 84.865697 -61.150429) (xy 84.910838 -61.178587) (xy 84.951628 -61.212745) (xy 84.987276 -61.252239)
			(xy 85.01709 -61.296303) (xy 85.040493 -61.344082) (xy 85.05703 -61.39465) (xy 85.066379 -61.447025)
			(xy 85.067902 -61.473588) (xy 85.067902 -61.473842) (xy 85.06841 -61.484256) (xy 85.07222 -61.492892)
			(xy 85.0741 -61.496782) (xy 85.078954 -61.503929) (xy 85.081872 -61.507116) (xy 85.126322 -61.549788)
			(xy 85.134196 -61.557408) (xy 85.141543 -61.563901) (xy 85.159706 -61.57124) (xy 85.169502 -61.571632)
			(xy 88.759284 -61.571632) (xy 88.769274 -61.571098) (xy 88.787713 -61.563393) (xy 88.795098 -61.556646)
			(xy 89.423494 -60.92825) (xy 89.428943 -60.921768) (xy 89.435565 -60.906192) (xy 89.436448 -60.89777)
			(xy 89.436448 -41.240202) (xy 89.436702 -41.232328) (xy 89.436702 -38.89629) (xy 89.434924 -38.883082)
			(xy 89.433085 -38.87724) (xy 89.427045 -38.866588) (xy 89.422986 -38.862) (xy 89.389619 -38.832398)
			(xy 89.328032 -38.767864) (xy 89.272833 -38.697788) (xy 89.248234 -38.660578) (xy 89.224244 -38.622522)
			(xy 89.182825 -38.542658) (xy 89.149234 -38.459198) (xy 89.123779 -38.372908) (xy 89.106693 -38.284579)
			(xy 89.098133 -38.195021) (xy 89.097612 -38.150038) (xy 89.098145 -38.105057) (xy 89.106745 -38.015508)
			(xy 89.123851 -37.927188) (xy 89.149308 -37.840904) (xy 89.182882 -37.757443) (xy 89.224268 -37.677566)
			(xy 89.248234 -37.639498) (xy 89.272833 -37.602288) (xy 89.328033 -37.532213) (xy 89.389621 -37.46768)
			(xy 89.422986 -37.438076) (xy 89.427069 -37.433507) (xy 89.433102 -37.422845) (xy 89.434924 -37.416994)
			(xy 89.436702 -37.403786) (xy 89.436702 -31.790132) (xy 89.433146 -31.781242) (xy 89.424845 -31.759031)
			(xy 89.413189 -31.713068) (xy 89.407334 -31.666013) (xy 89.406984 -31.642304) (xy 89.407347 -31.618596)
			(xy 89.413219 -31.571546) (xy 89.424861 -31.525582) (xy 89.433146 -31.503366) (xy 89.436702 -31.494476)
			(xy 89.436702 -31.233364) (xy 89.436824 -31.22841) (xy 89.438749 -31.218692) (xy 89.440512 -31.21406)
			(xy 89.445592 -31.201868) (xy 89.447362 -31.197239) (xy 89.449274 -31.187518) (xy 89.449402 -31.182564)
			(xy 89.449402 -29.84881) (xy 89.449094 -29.840616) (xy 89.443915 -29.825068) (xy 89.439242 -29.81833)
			(xy 89.423333 -29.796245) (xy 89.397269 -29.748464) (xy 89.378265 -29.697462) (xy 89.366706 -29.644276)
			(xy 89.362828 -29.589987) (xy 89.36671 -29.535698) (xy 89.378272 -29.482513) (xy 89.39728 -29.431512)
			(xy 89.423347 -29.383733) (xy 89.439242 -29.361638) (xy 89.443905 -29.354896) (xy 89.449074 -29.33935)
			(xy 89.449402 -29.331158) (xy 89.449402 -28.107894) (xy 89.449445 -28.104224) (xy 89.45046 -28.096955)
			(xy 89.451434 -28.093416) (xy 89.452824 -28.088463) (xy 89.453844 -28.078227) (xy 89.453466 -28.073096)
			(xy 89.450164 -28.044902) (xy 89.44921 -28.038173) (xy 89.444194 -28.025549) (xy 89.440258 -28.02001)
			(xy 89.422148 -27.995021) (xy 89.393389 -27.940419) (xy 89.373788 -27.881903) (xy 89.363855 -27.820996)
			(xy 89.363296 -27.79014) (xy 89.363757 -27.762885) (xy 89.371509 -27.70893) (xy 89.386862 -27.656628)
			(xy 89.409502 -27.607043) (xy 89.438969 -27.561185) (xy 89.474663 -27.519988) (xy 89.515856 -27.48429)
			(xy 89.561711 -27.454819) (xy 89.611294 -27.432174) (xy 89.663595 -27.416817) (xy 89.717549 -27.409059)
			(xy 89.744804 -27.408632) (xy 89.770352 -27.409041) (xy 89.82099 -27.415857) (xy 89.870267 -27.429366)
			(xy 89.917302 -27.449327) (xy 89.961254 -27.475384) (xy 89.981532 -27.490928) (xy 89.989036 -27.496433)
			(xy 90.00674 -27.502119) (xy 90.025304 -27.501071) (xy 90.042256 -27.493429) (xy 90.049096 -27.487118)
			(xy 90.193622 -27.342592) (xy 90.201022 -27.33575) (xy 90.21962 -27.328025) (xy 90.22969 -27.327606)
			(xy 90.419936 -27.327606) (xy 90.427556 -27.327352) (xy 94.47276 -27.327352) (xy 94.482783 -27.326939)
			(xy 94.501305 -27.319274) (xy 94.515479 -27.305099) (xy 94.52314 -27.286575) (xy 94.52356 -27.276552)
			(xy 94.52356 -26.479246) (xy 94.52378 -26.457136) (xy 94.527977 -26.413115) (xy 94.531942 -26.391362)
			(xy 94.531942 -26.3906) (xy 94.532704 -26.387552) (xy 94.532704 -26.387044) (xy 94.533939 -26.379822)
			(xy 94.532655 -26.365232) (xy 94.530164 -26.358342) (xy 94.52737 -26.351484) (xy 94.518226 -26.340054)
			(xy 94.515178 -26.338022) (xy 94.507812 -26.332688) (xy 94.497078 -26.326051) (xy 94.47204 -26.323129)
			(xy 94.46006 -26.3271) (xy 94.455996 -26.329132) (xy 94.454726 -26.32964) (xy 94.427693 -26.342857)
			(xy 94.370498 -26.361542) (xy 94.311075 -26.371001) (xy 94.28099 -26.37155) (xy 94.280736 -26.37155)
			(xy 94.253478 -26.37109) (xy 94.199518 -26.363336) (xy 94.14721 -26.347981) (xy 94.097619 -26.325338)
			(xy 94.051757 -26.295868) (xy 94.010555 -26.26017) (xy 93.974854 -26.218972) (xy 93.945379 -26.173112)
			(xy 93.922731 -26.123524) (xy 93.907372 -26.071218) (xy 93.899613 -26.017258) (xy 93.899613 -25.962742)
			(xy 93.907372 -25.908782) (xy 93.922731 -25.856476) (xy 93.945379 -25.806888) (xy 93.974854 -25.761028)
			(xy 94.010555 -25.71983) (xy 94.051757 -25.684132) (xy 94.097619 -25.654662) (xy 94.14721 -25.632019)
			(xy 94.199518 -25.616664) (xy 94.253478 -25.60891) (xy 94.280736 -25.608534) (xy 94.28099 -25.608534)
			(xy 94.308242 -25.608997) (xy 94.362192 -25.616753) (xy 94.414489 -25.632108) (xy 94.464067 -25.654751)
			(xy 94.509919 -25.684219) (xy 94.551109 -25.719914) (xy 94.5868 -25.761107) (xy 94.616265 -25.806961)
			(xy 94.627722 -25.832054) (xy 96.187766 -25.832054) (xy 96.191837 -25.776432) (xy 96.203963 -25.721995)
			(xy 96.223886 -25.669904) (xy 96.251182 -25.621269) (xy 96.285268 -25.577126) (xy 96.325417 -25.538417)
			(xy 96.370775 -25.505966) (xy 96.420375 -25.480465) (xy 96.473159 -25.462458) (xy 96.528002 -25.452328)
			(xy 96.583736 -25.450291) (xy 96.639173 -25.456391) (xy 96.69313 -25.470497) (xy 96.744459 -25.492309)
			(xy 96.792065 -25.521363) (xy 96.834933 -25.557038) (xy 96.836467 -25.55875) (xy 100.642166 -25.55875)
			(xy 100.642652 -25.531499) (xy 100.650408 -25.477551) (xy 100.665763 -25.425256) (xy 100.688405 -25.375679)
			(xy 100.717871 -25.329829) (xy 100.753562 -25.288638) (xy 100.794753 -25.252947) (xy 100.840603 -25.223481)
			(xy 100.89018 -25.200839) (xy 100.942475 -25.185484) (xy 100.996423 -25.177728) (xy 101.050925 -25.177728)
			(xy 101.104873 -25.185484) (xy 101.157168 -25.200839) (xy 101.206745 -25.223481) (xy 101.252595 -25.252947)
			(xy 101.293786 -25.288638) (xy 101.329477 -25.329829) (xy 101.358943 -25.375679) (xy 101.381585 -25.425256)
			(xy 101.39694 -25.477551) (xy 101.404696 -25.531499) (xy 101.405182 -25.55875) (xy 101.404617 -25.589012)
			(xy 101.395066 -25.648778) (xy 101.376196 -25.706285) (xy 101.34848 -25.76009) (xy 101.331014 -25.78481)
			(xy 101.322707 -25.79694) (xy 101.31275 -25.82459) (xy 101.311081 -25.85393) (xy 101.317837 -25.88253)
			(xy 101.332458 -25.908022) (xy 101.353734 -25.928293) (xy 101.379903 -25.941666) (xy 101.39426 -25.94483)
			(xy 101.420162 -25.95013) (xy 101.470285 -25.966954) (xy 101.517603 -25.99054) (xy 101.561211 -26.020434)
			(xy 101.600271 -26.056066) (xy 101.634036 -26.096751) (xy 101.661858 -26.141709) (xy 101.683204 -26.190079)
			(xy 101.697664 -26.240934) (xy 101.704962 -26.293299) (xy 101.70541 -26.319734) (xy 102.841804 -26.319734)
			(xy 102.845875 -26.264112) (xy 102.858001 -26.209675) (xy 102.877924 -26.157584) (xy 102.90522 -26.108949)
			(xy 102.939306 -26.064806) (xy 102.979455 -26.026097) (xy 103.024813 -25.993646) (xy 103.074413 -25.968145)
			(xy 103.127197 -25.950138) (xy 103.18204 -25.940008) (xy 103.237774 -25.937971) (xy 103.293211 -25.944071)
			(xy 103.347168 -25.958177) (xy 103.398497 -25.979989) (xy 103.446103 -26.009043) (xy 103.488971 -26.044718)
			(xy 103.526188 -26.086255) (xy 103.556961 -26.132768) (xy 103.580633 -26.183265) (xy 103.596701 -26.236672)
			(xy 103.604821 -26.291848) (xy 103.60533 -26.319734) (xy 103.604821 -26.34762) (xy 103.596701 -26.402796)
			(xy 103.580633 -26.456203) (xy 103.556961 -26.5067) (xy 103.526188 -26.553213) (xy 103.488971 -26.59475)
			(xy 103.446103 -26.630425) (xy 103.398497 -26.659479) (xy 103.347168 -26.681291) (xy 103.293211 -26.695397)
			(xy 103.237774 -26.701497) (xy 103.18204 -26.69946) (xy 103.127197 -26.68933) (xy 103.074413 -26.671323)
			(xy 103.024813 -26.645822) (xy 102.979455 -26.613371) (xy 102.939306 -26.574662) (xy 102.90522 -26.530519)
			(xy 102.877924 -26.481884) (xy 102.858001 -26.429793) (xy 102.845875 -26.375356) (xy 102.841804 -26.319734)
			(xy 101.70541 -26.319734) (xy 101.704924 -26.346985) (xy 101.697168 -26.400933) (xy 101.681813 -26.453228)
			(xy 101.659171 -26.502805) (xy 101.629705 -26.548655) (xy 101.594014 -26.589846) (xy 101.552823 -26.625537)
			(xy 101.506973 -26.655003) (xy 101.457396 -26.677645) (xy 101.405101 -26.693) (xy 101.351153 -26.700756)
			(xy 101.296651 -26.700756) (xy 101.242703 -26.693) (xy 101.190408 -26.677645) (xy 101.140831 -26.655003)
			(xy 101.094981 -26.625537) (xy 101.05379 -26.589846) (xy 101.018099 -26.548655) (xy 100.988633 -26.502805)
			(xy 100.965991 -26.453228) (xy 100.950636 -26.400933) (xy 100.94288 -26.346985) (xy 100.942394 -26.319734)
			(xy 100.942955 -26.289472) (xy 100.952508 -26.229706) (xy 100.97138 -26.172199) (xy 100.999096 -26.118394)
			(xy 101.016562 -26.093674) (xy 101.024904 -26.081565) (xy 101.034862 -26.053908) (xy 101.03653 -26.024561)
			(xy 101.029769 -25.995954) (xy 101.015141 -25.970458) (xy 100.993856 -25.950185) (xy 100.967678 -25.936815)
			(xy 100.953316 -25.933654) (xy 100.927422 -25.928313) (xy 100.877298 -25.911498) (xy 100.829978 -25.88792)
			(xy 100.786369 -25.858032) (xy 100.747306 -25.822405) (xy 100.713539 -25.781724) (xy 100.685716 -25.736769)
			(xy 100.66437 -25.688401) (xy 100.64991 -25.637548) (xy 100.642613 -25.585185) (xy 100.642166 -25.55875)
			(xy 96.836467 -25.55875) (xy 96.87215 -25.598575) (xy 96.902923 -25.645088) (xy 96.926595 -25.695585)
			(xy 96.942663 -25.748992) (xy 96.950783 -25.804168) (xy 96.951292 -25.832054) (xy 96.950783 -25.85994)
			(xy 96.942663 -25.915116) (xy 96.926595 -25.968523) (xy 96.902923 -26.01902) (xy 96.87215 -26.065533)
			(xy 96.834933 -26.10707) (xy 96.792065 -26.142745) (xy 96.744459 -26.171799) (xy 96.69313 -26.193611)
			(xy 96.639173 -26.207717) (xy 96.583736 -26.213817) (xy 96.528002 -26.21178) (xy 96.473159 -26.20165)
			(xy 96.420375 -26.183643) (xy 96.370775 -26.158142) (xy 96.325417 -26.125691) (xy 96.285268 -26.086982)
			(xy 96.251182 -26.042839) (xy 96.223886 -25.994204) (xy 96.203963 -25.942113) (xy 96.191837 -25.887676)
			(xy 96.187766 -25.832054) (xy 94.627722 -25.832054) (xy 94.638903 -25.856541) (xy 94.654254 -25.908839)
			(xy 94.662006 -25.96279) (xy 94.662498 -25.990042) (xy 94.662365 -26.001822) (xy 94.660839 -26.025333)
			(xy 94.65945 -26.037032) (xy 94.65945 -26.038048) (xy 94.658859 -26.047089) (xy 94.663313 -26.06464)
			(xy 94.673569 -26.079562) (xy 94.680786 -26.085038) (xy 94.685358 -26.088086) (xy 94.691455 -26.092081)
			(xy 94.705264 -26.096734) (xy 94.712536 -26.09723) (xy 94.719902 -26.097484) (xy 94.734126 -26.093674)
			(xy 94.74073 -26.08961) (xy 94.767963 -26.073434) (xy 94.825933 -26.047907) (xy 94.886865 -26.030598)
			(xy 94.949598 -26.021838) (xy 94.981268 -26.021284) (xy 95.011227 -26.021771) (xy 95.070632 -26.029585)
			(xy 95.12851 -26.045084) (xy 95.183871 -26.068003) (xy 95.235768 -26.097949) (xy 95.283313 -26.134411)
			(xy 95.325695 -26.176765) (xy 95.362187 -26.224288) (xy 95.392167 -26.276165) (xy 95.415121 -26.331511)
			(xy 95.423006 -26.360882) (xy 98.105466 -26.360882) (xy 98.109537 -26.30526) (xy 98.121663 -26.250823)
			(xy 98.141586 -26.198732) (xy 98.168882 -26.150097) (xy 98.202968 -26.105954) (xy 98.243117 -26.067245)
			(xy 98.288475 -26.034794) (xy 98.338075 -26.009293) (xy 98.390859 -25.991286) (xy 98.445702 -25.981156)
			(xy 98.501436 -25.979119) (xy 98.556873 -25.985219) (xy 98.61083 -25.999325) (xy 98.662159 -26.021137)
			(xy 98.709765 -26.050191) (xy 98.752633 -26.085866) (xy 98.78985 -26.127403) (xy 98.820623 -26.173916)
			(xy 98.844295 -26.224413) (xy 98.860363 -26.27782) (xy 98.868483 -26.332996) (xy 98.868992 -26.360882)
			(xy 98.868483 -26.388768) (xy 98.860363 -26.443944) (xy 98.844295 -26.497351) (xy 98.820623 -26.547848)
			(xy 98.78985 -26.594361) (xy 98.752633 -26.635898) (xy 98.709765 -26.671573) (xy 98.662159 -26.700627)
			(xy 98.61083 -26.722439) (xy 98.556873 -26.736545) (xy 98.501436 -26.742645) (xy 98.445702 -26.740608)
			(xy 98.390859 -26.730478) (xy 98.338075 -26.712471) (xy 98.288475 -26.68697) (xy 98.243117 -26.654519)
			(xy 98.202968 -26.61581) (xy 98.168882 -26.571667) (xy 98.141586 -26.523032) (xy 98.121663 -26.470941)
			(xy 98.109537 -26.416504) (xy 98.105466 -26.360882) (xy 95.423006 -26.360882) (xy 95.430657 -26.389379)
			(xy 95.438509 -26.44878) (xy 95.438976 -26.478738) (xy 95.438976 -27.276552) (xy 95.439387 -27.286581)
			(xy 95.447048 -27.305119) (xy 95.461221 -27.319312) (xy 95.479747 -27.326999) (xy 95.489776 -27.327352)
			(xy 104.695752 -27.327352) (xy 104.705404 -27.326336) (xy 104.712644 -27.324701) (xy 104.7258 -27.317847)
			(xy 104.731312 -27.312874) (xy 105.09631 -26.947876) (xy 105.101293 -26.942447) (xy 105.108143 -26.929408)
			(xy 105.109772 -26.922222) (xy 105.109772 -26.921714) (xy 105.110788 -26.912316) (xy 105.110788 -19.906234)
			(xy 105.110708 -19.902491) (xy 105.10956 -19.895093) (xy 105.108502 -19.891502) (xy 105.070351 -19.791002)
			(xy 105.001299 -19.587399) (xy 104.940627 -19.381145) (xy 104.888437 -19.172583) (xy 104.844815 -18.962061)
			(xy 104.809835 -18.749933) (xy 104.783555 -18.536552) (xy 104.76602 -18.322275) (xy 104.757258 -18.107461)
			(xy 104.756712 -17.999964) (xy 104.757247 -17.892467) (xy 104.766015 -17.677653) (xy 104.783555 -17.463377)
			(xy 104.809838 -17.249996) (xy 104.84482 -17.037868) (xy 104.888443 -16.827347) (xy 104.940633 -16.618785)
			(xy 105.001304 -16.41253) (xy 105.070354 -16.208927) (xy 105.108502 -16.108426) (xy 105.109536 -16.10483)
			(xy 105.110679 -16.097435) (xy 105.110788 -16.093694) (xy 105.110788 -8.698738) (xy 105.110435 -8.689719)
			(xy 105.104196 -8.672796) (xy 105.098596 -8.665718) (xy 105.092754 -8.65886) (xy 105.078022 -8.650478)
			(xy 105.06837 -8.6487) (xy 105.040642 -8.643525) (xy 104.987002 -8.626088) (xy 104.936514 -8.600942)
			(xy 104.890279 -8.568637) (xy 104.849304 -8.529875) (xy 104.814484 -8.485503) (xy 104.786577 -8.436488)
			(xy 104.766191 -8.383897) (xy 104.753771 -8.328878) (xy 104.749588 -8.27263) (xy 104.753733 -8.216379)
			(xy 104.766116 -8.161351) (xy 104.786465 -8.108747) (xy 104.814339 -8.059712) (xy 104.84913 -8.015316)
			(xy 104.890078 -7.976527) (xy 104.936291 -7.94419) (xy 104.986762 -7.91901) (xy 105.04039 -7.901537)
			(xy 105.068116 -7.896352) (xy 105.06837 -7.896352) (xy 105.07218 -7.895844) (xy 105.079862 -7.893634)
			(xy 105.093443 -7.885221) (xy 105.09885 -7.879334) (xy 105.104438 -7.872476) (xy 105.107486 -7.864094)
			(xy 105.109006 -7.859806) (xy 105.110666 -7.850862) (xy 105.110788 -7.846314) (xy 105.110788 -7.39267)
			(xy 105.110426 -7.384633) (xy 105.10538 -7.369368) (xy 105.100882 -7.362698) (xy 105.09631 -7.356348)
			(xy 105.083864 -7.347204) (xy 105.075482 -7.34441) (xy 105.048771 -7.335234) (xy 104.998186 -7.310122)
			(xy 104.951854 -7.277827) (xy 104.91079 -7.239055) (xy 104.87589 -7.194653) (xy 104.847917 -7.145591)
			(xy 104.827482 -7.092941) (xy 104.815031 -7.037855) (xy 104.810838 -6.981535) (xy 104.814992 -6.925211)
			(xy 104.827404 -6.870116) (xy 104.847802 -6.817452) (xy 104.87574 -6.768371) (xy 104.910609 -6.723944)
			(xy 104.951646 -6.685143) (xy 104.997954 -6.652815) (xy 105.048522 -6.627667) (xy 105.075228 -6.618478)
			(xy 105.075736 -6.618478) (xy 105.07599 -6.618224) (xy 105.083442 -6.615513) (xy 105.096259 -6.606189)
			(xy 105.101136 -6.599936) (xy 105.105962 -6.593586) (xy 105.108502 -6.585712) (xy 105.109568 -6.581992)
			(xy 105.110713 -6.574341) (xy 105.110788 -6.570472) (xy 105.110788 -6.340856) (xy 105.110621 -6.334846)
			(xy 105.107798 -6.323164) (xy 105.1052 -6.317742) (xy 105.103364 -6.314265) (xy 105.098776 -6.307881)
			(xy 105.096056 -6.305042) (xy 104.779826 -5.988812) (xy 104.77268 -5.982311) (xy 104.75492 -5.97475)
			(xy 104.745282 -5.97408) (xy 104.72293 -5.974842) (xy 104.722422 -5.974842) (xy 104.664256 -5.977128)
			(xy 104.660388 -5.977627) (xy 104.652858 -5.979662) (xy 104.64927 -5.981192) (xy 104.637586 -5.98678)
			(xy 104.630982 -5.9944) (xy 104.630728 -5.994654) (xy 104.612526 -6.015291) (xy 104.571203 -6.051627)
			(xy 104.525085 -6.081643) (xy 104.475129 -6.104716) (xy 104.422375 -6.120364) (xy 104.367919 -6.128264)
			(xy 104.340406 -6.128766) (xy 104.313154 -6.128303) (xy 104.259205 -6.120547) (xy 104.206908 -6.105191)
			(xy 104.15733 -6.082548) (xy 104.111479 -6.053079) (xy 104.070289 -6.017385) (xy 104.034599 -5.976192)
			(xy 104.005135 -5.930338) (xy 103.982497 -5.880758) (xy 103.967146 -5.82846) (xy 103.959394 -5.77451)
			(xy 103.958898 -5.747258) (xy 103.958898 -5.747004) (xy 103.959334 -5.720988) (xy 103.966403 -5.669438)
			(xy 103.980423 -5.619331) (xy 104.001134 -5.571598) (xy 104.01427 -5.549138) (xy 104.017064 -5.544566)
			(xy 104.019229 -5.539628) (xy 104.021657 -5.529125) (xy 104.02189 -5.523738) (xy 104.022144 -5.510276)
			(xy 103.993696 -5.459476) (xy 103.993696 -5.458968) (xy 103.971852 -5.420614) (xy 103.967136 -5.412964)
			(xy 103.953472 -5.401306) (xy 103.936635 -5.395051) (xy 103.927656 -5.394706) (xy 97.58045 -5.394706)
			(xy 97.57444 -5.394873) (xy 97.562758 -5.397697) (xy 97.557336 -5.400294) (xy 97.55386 -5.40213)
			(xy 97.547475 -5.406719) (xy 97.544636 -5.409438) (xy 97.28073 -5.673344) (xy 97.278026 -5.676197)
			(xy 97.273439 -5.682578) (xy 97.271586 -5.686044) (xy 97.269004 -5.691471) (xy 97.266181 -5.703151)
			(xy 97.265998 -5.709158) (xy 97.265998 -6.931152) (xy 98.157284 -6.931152) (xy 98.157784 -6.90259)
			(xy 98.166287 -6.846104) (xy 98.183124 -6.791519) (xy 98.20792 -6.740059) (xy 98.240118 -6.692875)
			(xy 98.278997 -6.651025) (xy 98.323687 -6.615447) (xy 98.373186 -6.586936) (xy 98.3996 -6.57606)
			(xy 98.413368 -6.570063) (xy 98.436942 -6.551491) (xy 98.454094 -6.526864) (xy 98.463338 -6.498311)
			(xy 98.463876 -6.468305) (xy 98.45566 -6.43944) (xy 98.439402 -6.414214) (xy 98.428302 -6.404102)
			(xy 98.407663 -6.385874) (xy 98.37133 -6.3445) (xy 98.341314 -6.298336) (xy 98.31824 -6.248341) (xy 98.302585 -6.19555)
			(xy 98.294673 -6.141058) (xy 98.29419 -6.113526) (xy 98.294676 -6.086275) (xy 98.302432 -6.032327)
			(xy 98.317787 -5.980032) (xy 98.340429 -5.930455) (xy 98.369895 -5.884605) (xy 98.405586 -5.843414)
			(xy 98.446777 -5.807723) (xy 98.492627 -5.778257) (xy 98.542204 -5.755615) (xy 98.594499 -5.74026)
			(xy 98.648447 -5.732504) (xy 98.702949 -5.732504) (xy 98.756897 -5.74026) (xy 98.809192 -5.755615)
			(xy 98.858769 -5.778257) (xy 98.904619 -5.807723) (xy 98.94581 -5.843414) (xy 98.981501 -5.884605)
			(xy 99.010967 -5.930455) (xy 99.033609 -5.980032) (xy 99.048964 -6.032327) (xy 99.05672 -6.086275)
			(xy 99.057206 -6.113526) (xy 99.056716 -6.142087) (xy 99.048204 -6.198571) (xy 99.031361 -6.253153)
			(xy 99.006562 -6.304611) (xy 98.974363 -6.351793) (xy 98.935485 -6.393643) (xy 98.890798 -6.429223)
			(xy 98.841303 -6.457739) (xy 98.81489 -6.468618) (xy 98.801138 -6.474645) (xy 98.777568 -6.493213)
			(xy 98.760419 -6.517835) (xy 98.751174 -6.54638) (xy 98.750633 -6.57638) (xy 98.758842 -6.60524)
			(xy 98.775092 -6.630464) (xy 98.786188 -6.640576) (xy 98.806814 -6.658818) (xy 98.843149 -6.700189)
			(xy 98.873166 -6.746349) (xy 98.896243 -6.796342) (xy 98.911901 -6.849131) (xy 98.919815 -6.903621)
			(xy 98.9203 -6.931152) (xy 98.919814 -6.958403) (xy 98.912058 -7.012351) (xy 98.896703 -7.064646)
			(xy 98.874061 -7.114223) (xy 98.844595 -7.160073) (xy 98.808904 -7.201264) (xy 98.767713 -7.236955)
			(xy 98.721863 -7.266421) (xy 98.672286 -7.289063) (xy 98.619991 -7.304418) (xy 98.566043 -7.312174)
			(xy 98.511541 -7.312174) (xy 98.457593 -7.304418) (xy 98.405298 -7.289063) (xy 98.355721 -7.266421)
			(xy 98.309871 -7.236955) (xy 98.26868 -7.201264) (xy 98.232989 -7.160073) (xy 98.203523 -7.114223)
			(xy 98.180881 -7.064646) (xy 98.165526 -7.012351) (xy 98.15777 -6.958403) (xy 98.157284 -6.931152)
			(xy 97.265998 -6.931152) (xy 97.265998 -7.302246) (xy 97.266955 -7.311544) (xy 97.274784 -7.328504)
			(xy 97.281238 -7.335266) (xy 97.299272 -7.351268) (xy 97.29978 -7.351268) (xy 97.341944 -7.387844)
			(xy 97.346189 -7.391256) (xy 97.355796 -7.39638) (xy 97.360994 -7.398004) (xy 97.363026 -7.398512)
			(xy 97.371408 -7.401052) (xy 97.38233 -7.399528) (xy 97.396031 -7.397632) (xy 97.423617 -7.395597)
			(xy 97.437448 -7.395464) (xy 97.464699 -7.395953) (xy 97.518645 -7.403716) (xy 97.570938 -7.419076)
			(xy 97.620513 -7.441722) (xy 97.666361 -7.471191) (xy 97.707548 -7.506886) (xy 97.743237 -7.548078)
			(xy 97.772701 -7.593929) (xy 97.795341 -7.643507) (xy 97.810694 -7.695801) (xy 97.81845 -7.749749)
			(xy 97.81845 -7.804251) (xy 97.810694 -7.858199) (xy 97.795341 -7.910493) (xy 97.792519 -7.916672)
			(xy 98.32543 -7.916672) (xy 98.329501 -7.86105) (xy 98.341627 -7.806613) (xy 98.36155 -7.754522)
			(xy 98.388846 -7.705887) (xy 98.422932 -7.661744) (xy 98.463081 -7.623035) (xy 98.508439 -7.590584)
			(xy 98.558039 -7.565083) (xy 98.610823 -7.547076) (xy 98.665666 -7.536946) (xy 98.7214 -7.534909)
			(xy 98.776837 -7.541009) (xy 98.830794 -7.555115) (xy 98.882123 -7.576927) (xy 98.929729 -7.605981)
			(xy 98.972597 -7.641656) (xy 99.009814 -7.683193) (xy 99.040587 -7.729706) (xy 99.064259 -7.780203)
			(xy 99.080327 -7.83361) (xy 99.088447 -7.888786) (xy 99.088956 -7.916672) (xy 99.088447 -7.944558)
			(xy 99.080327 -7.999734) (xy 99.064259 -8.053141) (xy 99.040587 -8.103638) (xy 99.009814 -8.150151)
			(xy 98.972597 -8.191688) (xy 98.929729 -8.227363) (xy 98.882123 -8.256417) (xy 98.830794 -8.278229)
			(xy 98.776837 -8.292335) (xy 98.7214 -8.298435) (xy 98.665666 -8.296398) (xy 98.610823 -8.286268)
			(xy 98.558039 -8.268261) (xy 98.508439 -8.24276) (xy 98.463081 -8.210309) (xy 98.422932 -8.1716)
			(xy 98.388846 -8.127457) (xy 98.36155 -8.078822) (xy 98.341627 -8.026731) (xy 98.329501 -7.972294)
			(xy 98.32543 -7.916672) (xy 97.792519 -7.916672) (xy 97.772701 -7.960071) (xy 97.743237 -8.005922)
			(xy 97.707548 -8.047114) (xy 97.666361 -8.082809) (xy 97.620513 -8.112278) (xy 97.570938 -8.134924)
			(xy 97.518646 -8.150284) (xy 97.464699 -8.158047) (xy 97.437448 -8.15848) (xy 97.423618 -8.158332)
			(xy 97.396033 -8.156295) (xy 97.38233 -8.154416) (xy 97.371408 -8.152892) (xy 97.363026 -8.155432)
			(xy 97.360994 -8.15594) (xy 97.355784 -8.157537) (xy 97.346166 -8.162655) (xy 97.341944 -8.1661)
			(xy 97.29978 -8.202676) (xy 97.299272 -8.202676) (xy 97.281238 -8.218678) (xy 97.274878 -8.225502)
			(xy 97.267081 -8.242432) (xy 97.265998 -8.251698) (xy 97.265998 -11.543792) (xy 101.399338 -11.543792)
			(xy 101.403409 -11.48817) (xy 101.415535 -11.433733) (xy 101.435458 -11.381642) (xy 101.462754 -11.333007)
			(xy 101.49684 -11.288864) (xy 101.536989 -11.250155) (xy 101.582347 -11.217704) (xy 101.631947 -11.192203)
			(xy 101.684731 -11.174196) (xy 101.739574 -11.164066) (xy 101.795308 -11.162029) (xy 101.850745 -11.168129)
			(xy 101.904702 -11.182235) (xy 101.956031 -11.204047) (xy 102.003637 -11.233101) (xy 102.046505 -11.268776)
			(xy 102.083722 -11.310313) (xy 102.114495 -11.356826) (xy 102.138167 -11.407323) (xy 102.154235 -11.46073)
			(xy 102.162355 -11.515906) (xy 102.162864 -11.543792) (xy 102.408226 -11.543792) (xy 102.412297 -11.48817)
			(xy 102.424423 -11.433733) (xy 102.444346 -11.381642) (xy 102.471642 -11.333007) (xy 102.505728 -11.288864)
			(xy 102.545877 -11.250155) (xy 102.591235 -11.217704) (xy 102.640835 -11.192203) (xy 102.693619 -11.174196)
			(xy 102.748462 -11.164066) (xy 102.804196 -11.162029) (xy 102.859633 -11.168129) (xy 102.91359 -11.182235)
			(xy 102.964919 -11.204047) (xy 103.012525 -11.233101) (xy 103.055393 -11.268776) (xy 103.09261 -11.310313)
			(xy 103.123383 -11.356826) (xy 103.147055 -11.407323) (xy 103.163123 -11.46073) (xy 103.171243 -11.515906)
			(xy 103.171752 -11.543792) (xy 103.171243 -11.571678) (xy 103.163123 -11.626854) (xy 103.147055 -11.680261)
			(xy 103.123383 -11.730758) (xy 103.09261 -11.777271) (xy 103.055393 -11.818808) (xy 103.012525 -11.854483)
			(xy 102.964919 -11.883537) (xy 102.91359 -11.905349) (xy 102.859633 -11.919455) (xy 102.804196 -11.925555)
			(xy 102.748462 -11.923518) (xy 102.693619 -11.913388) (xy 102.640835 -11.895381) (xy 102.591235 -11.86988)
			(xy 102.545877 -11.837429) (xy 102.505728 -11.79872) (xy 102.471642 -11.754577) (xy 102.444346 -11.705942)
			(xy 102.424423 -11.653851) (xy 102.412297 -11.599414) (xy 102.408226 -11.543792) (xy 102.162864 -11.543792)
			(xy 102.162355 -11.571678) (xy 102.154235 -11.626854) (xy 102.138167 -11.680261) (xy 102.114495 -11.730758)
			(xy 102.083722 -11.777271) (xy 102.046505 -11.818808) (xy 102.003637 -11.854483) (xy 101.956031 -11.883537)
			(xy 101.904702 -11.905349) (xy 101.850745 -11.919455) (xy 101.795308 -11.925555) (xy 101.739574 -11.923518)
			(xy 101.684731 -11.913388) (xy 101.631947 -11.895381) (xy 101.582347 -11.86988) (xy 101.536989 -11.837429)
			(xy 101.49684 -11.79872) (xy 101.462754 -11.754577) (xy 101.435458 -11.705942) (xy 101.415535 -11.653851)
			(xy 101.403409 -11.599414) (xy 101.399338 -11.543792) (xy 97.265998 -11.543792) (xy 97.265998 -13.579094)
			(xy 97.266506 -13.586206) (xy 97.268117 -13.59486) (xy 97.276327 -13.610417) (xy 97.289286 -13.622313)
			(xy 97.29724 -13.626084) (xy 97.360225 -13.647695) (xy 97.483641 -13.697739) (xy 97.603695 -13.755381)
			(xy 97.719921 -13.820398) (xy 97.831867 -13.892536) (xy 97.939096 -13.971515) (xy 98.041192 -14.057026)
			(xy 98.137756 -14.148738) (xy 98.228414 -14.246293) (xy 98.312811 -14.349311) (xy 98.390621 -14.457392)
			(xy 98.461538 -14.570115) (xy 98.525289 -14.68704) (xy 98.581624 -14.807714) (xy 98.630325 -14.931665)
			(xy 98.671201 -15.058412) (xy 98.704094 -15.187462) (xy 98.728876 -15.318311) (xy 98.745449 -15.450452)
			(xy 98.75375 -15.583368) (xy 98.754184 -15.649956) (xy 98.753678 -15.715692) (xy 98.745585 -15.846913)
			(xy 98.729428 -15.977388) (xy 98.705271 -16.106621) (xy 98.673203 -16.234121) (xy 98.633347 -16.359405)
			(xy 98.585854 -16.481999) (xy 98.530905 -16.601436) (xy 98.468706 -16.717263) (xy 98.399496 -16.829042)
			(xy 98.323535 -16.936349) (xy 98.241113 -17.038775) (xy 98.152541 -17.135934) (xy 98.058156 -17.227455)
			(xy 97.958317 -17.312993) (xy 97.8534 -17.392222) (xy 97.743806 -17.464842) (xy 97.629948 -17.530577)
			(xy 97.51226 -17.589179) (xy 97.391188 -17.640425) (xy 97.26719 -17.68412) (xy 97.140738 -17.720099)
			(xy 97.01231 -17.748225) (xy 96.882395 -17.768391) (xy 96.751485 -17.780522) (xy 96.620076 -17.784571)
			(xy 96.488667 -17.780522) (xy 96.357757 -17.768391) (xy 96.227842 -17.748225) (xy 96.099414 -17.720099)
			(xy 95.972962 -17.68412) (xy 95.848964 -17.640425) (xy 95.727892 -17.589179) (xy 95.610204 -17.530577)
			(xy 95.496346 -17.464842) (xy 95.386752 -17.392222) (xy 95.281835 -17.312993) (xy 95.181996 -17.227455)
			(xy 95.087611 -17.135934) (xy 94.999039 -17.038775) (xy 94.916617 -16.936349) (xy 94.840656 -16.829042)
			(xy 94.771446 -16.717263) (xy 94.709247 -16.601436) (xy 94.654298 -16.481999) (xy 94.606805 -16.359405)
			(xy 94.566949 -16.234121) (xy 94.534881 -16.106621) (xy 94.510724 -15.977388) (xy 94.494567 -15.846913)
			(xy 94.486474 -15.715692) (xy 94.485968 -15.649956) (xy 94.486526 -15.581216) (xy 94.495394 -15.444022)
			(xy 94.513072 -15.307683) (xy 94.539486 -15.172765) (xy 94.574526 -15.039825) (xy 94.618048 -14.909416)
			(xy 94.643448 -14.845538) (xy 94.643448 -14.845284) (xy 94.645634 -14.839514) (xy 94.647432 -14.82731)
			(xy 94.647004 -14.821154) (xy 94.645734 -14.808708) (xy 94.591378 -14.727936) (xy 94.583896 -14.717962)
			(xy 94.561919 -14.706246) (xy 94.549468 -14.705584) (xy 92.73413 -14.705584) (xy 92.725494 -14.706346)
			(xy 92.721453 -14.707133) (xy 92.713671 -14.709817) (xy 92.71 -14.71168) (xy 92.71 -14.711934) (xy 92.703613 -14.715666)
			(xy 92.69316 -14.726122) (xy 92.689426 -14.732508) (xy 92.669614 -14.77137) (xy 92.669614 -14.771878)
			(xy 92.647262 -14.816074) (xy 92.64473 -14.821962) (xy 92.642405 -14.834563) (xy 92.64269 -14.840966)
			(xy 92.643452 -14.848586) (xy 92.64396 -14.85011) (xy 92.669977 -14.885251) (xy 92.716121 -14.959525)
			(xy 92.755191 -15.037753) (xy 92.786852 -15.119261) (xy 92.810832 -15.203349) (xy 92.826925 -15.289297)
			(xy 92.834993 -15.376365) (xy 92.835476 -15.420086) (xy 92.834902 -15.467818) (xy 92.825317 -15.5628)
			(xy 92.806192 -15.656329) (xy 92.777725 -15.747449) (xy 92.740204 -15.835231) (xy 92.71762 -15.877286)
			(xy 92.717112 -15.883636) (xy 92.717112 -15.895574) (xy 92.743528 -15.944596) (xy 92.763848 -15.982188)
			(xy 92.77223 -15.993364) (xy 92.780866 -16.00073) (xy 92.790772 -16.00708) (xy 92.803726 -16.00835)
			(xy 92.847547 -16.012893) (xy 92.934176 -16.028964) (xy 93.018982 -16.052858) (xy 93.101258 -16.084378)
			(xy 93.180321 -16.123262) (xy 93.255513 -16.169185) (xy 93.32621 -16.221767) (xy 93.391823 -16.280569)
			(xy 93.451808 -16.345104) (xy 93.505664 -16.414834) (xy 93.552946 -16.48918) (xy 93.593258 -16.567524)
			(xy 93.626267 -16.649214) (xy 93.651698 -16.733572) (xy 93.669339 -16.819895) (xy 93.679043 -16.907466)
			(xy 93.680731 -16.995557) (xy 93.674387 -17.083435) (xy 93.660066 -17.17037) (xy 93.637885 -17.25564)
			(xy 93.608029 -17.338534) (xy 93.570747 -17.418365) (xy 93.548962 -17.456658) (xy 93.526279 -17.49458)
			(xy 93.474981 -17.566538) (xy 93.417323 -17.633509) (xy 93.353788 -17.694932) (xy 93.284908 -17.750294)
			(xy 93.211258 -17.799132) (xy 93.133455 -17.841038) (xy 93.052148 -17.875661) (xy 92.968019 -17.902711)
			(xy 92.88177 -17.921963) (xy 92.794123 -17.933255) (xy 92.705811 -17.936492) (xy 92.617573 -17.931649)
			(xy 92.530146 -17.918765) (xy 92.444262 -17.897947) (xy 92.360638 -17.869371) (xy 92.279975 -17.833275)
			(xy 92.202946 -17.789962) (xy 92.130197 -17.739792) (xy 92.062335 -17.683186) (xy 91.999928 -17.620617)
			(xy 91.943498 -17.552609) (xy 91.893517 -17.47973) (xy 91.850402 -17.40259) (xy 91.814515 -17.321833)
			(xy 91.786156 -17.238136) (xy 91.765561 -17.152198) (xy 91.752903 -17.064738) (xy 91.748288 -16.976487)
			(xy 91.751754 -16.888184) (xy 91.763273 -16.800567) (xy 91.782748 -16.714368) (xy 91.810016 -16.630309)
			(xy 91.844849 -16.549093) (xy 91.86545 -16.51) (xy 91.867736 -16.505682) (xy 91.869765 -16.500656)
			(xy 91.871826 -16.490019) (xy 91.8718 -16.4846) (xy 91.871546 -16.4719) (xy 91.841066 -16.420592)
			(xy 91.819984 -16.385032) (xy 91.81973 -16.384778) (xy 91.819222 -16.383762) (xy 91.814674 -16.377112)
			(xy 91.802238 -16.366882) (xy 91.794838 -16.363696) (xy 90.037666 -16.363696) (xy 89.994065 -16.363191)
			(xy 89.907235 -16.355142) (xy 89.821518 -16.339116) (xy 89.737645 -16.315249) (xy 89.656332 -16.283745)
			(xy 89.578273 -16.244873) (xy 89.504133 -16.198965) (xy 89.434545 -16.146412) (xy 89.370104 -16.087663)
			(xy 89.311357 -16.023218) (xy 89.258808 -15.953627) (xy 89.212903 -15.879485) (xy 89.174035 -15.801424)
			(xy 89.142536 -15.72011) (xy 89.118673 -15.636236) (xy 89.102651 -15.550518) (xy 89.094607 -15.463687)
			(xy 89.094056 -15.420086) (xy 89.094056 -15.419578) (xy 89.09458 -15.375805) (xy 89.102741 -15.28864)
			(xy 89.118936 -15.202605) (xy 89.143024 -15.118438) (xy 89.174801 -15.036863) (xy 89.213992 -14.958579)
			(xy 89.260261 -14.884258) (xy 89.286334 -14.849094) (xy 89.286588 -14.848078) (xy 89.287096 -14.840966)
			(xy 89.287436 -14.834008) (xy 89.284719 -14.82035) (xy 89.281762 -14.814042) (xy 89.26576 -14.782546)
			(xy 89.26576 -14.782038) (xy 89.239344 -14.73073) (xy 89.236109 -14.725575) (xy 89.227637 -14.716843)
			(xy 89.22258 -14.713458) (xy 89.218516 -14.711426) (xy 89.213045 -14.708752) (xy 89.201234 -14.705797)
			(xy 89.195148 -14.705584) (xy 79.874618 -14.705584) (xy 79.868609 -14.705755) (xy 79.85693 -14.708584)
			(xy 79.851504 -14.711172) (xy 79.848028 -14.71301) (xy 79.841646 -14.717599) (xy 79.838804 -14.720316)
			(xy 79.637382 -14.921738) (xy 79.631244 -14.928462) (xy 79.623747 -14.94504) (xy 79.622495 -14.963191)
			(xy 79.624682 -14.97203) (xy 79.654146 -15.054834) (xy 79.656686 -15.0622) (xy 79.659314 -15.068602)
			(xy 79.667422 -15.079809) (xy 79.672688 -15.084298) (xy 79.678276 -15.088616) (xy 79.691484 -15.09395)
			(xy 79.699104 -15.094712) (xy 79.726946 -15.098049) (xy 79.781299 -15.11184) (xy 79.833047 -15.133438)
			(xy 79.881077 -15.162378) (xy 79.924353 -15.198035) (xy 79.961946 -15.239643) (xy 79.993043 -15.286305)
			(xy 80.016976 -15.337015) (xy 80.033229 -15.390683) (xy 80.041453 -15.446151) (xy 80.042004 -15.474188)
			(xy 80.041541 -15.501441) (xy 80.033786 -15.555393) (xy 80.018431 -15.607692) (xy 79.995789 -15.657274)
			(xy 79.966321 -15.703128) (xy 79.930628 -15.744322) (xy 79.889434 -15.780016) (xy 79.843581 -15.809485)
			(xy 79.794 -15.832128) (xy 79.741701 -15.847484) (xy 79.687749 -15.855241) (xy 79.660496 -15.855696)
			(xy 79.659988 -15.855696) (xy 79.632544 -15.855203) (xy 79.578229 -15.847301) (xy 79.551784 -15.839948)
			(xy 79.541878 -15.8369) (xy 79.539846 -15.836392) (xy 79.528416 -15.838424) (xy 79.523345 -15.839446)
			(xy 79.513741 -15.843285) (xy 79.509366 -15.846044) (xy 79.504286 -15.8496) (xy 79.441548 -15.896082)
			(xy 79.434944 -15.901924) (xy 79.429966 -15.907549) (xy 79.423266 -15.920984) (xy 79.421736 -15.92834)
			(xy 79.420974 -15.936976) (xy 79.420974 -20.72005) (xy 83.18552 -20.72005) (xy 83.18949 -20.589916)
			(xy 83.201386 -20.460266) (xy 83.221165 -20.331583) (xy 83.248751 -20.204344) (xy 83.284044 -20.079025)
			(xy 83.32691 -19.956089) (xy 83.377192 -19.835996) (xy 83.434701 -19.719192) (xy 83.499225 -19.60611)
			(xy 83.570522 -19.497173) (xy 83.648327 -19.392785) (xy 83.732352 -19.293334) (xy 83.822284 -19.199191)
			(xy 83.917788 -19.110706) (xy 84.018508 -19.028207) (xy 84.12407 -18.952002) (xy 84.234082 -18.882375)
			(xy 84.348134 -18.819584) (xy 84.465802 -18.763862) (xy 84.586648 -18.715418) (xy 84.710223 -18.674431)
			(xy 84.836066 -18.641054) (xy 84.963711 -18.615411) (xy 85.092681 -18.597597) (xy 85.222497 -18.587679)
			(xy 85.352676 -18.585694) (xy 85.482735 -18.591648) (xy 85.612188 -18.605521) (xy 85.740555 -18.627259)
			(xy 85.867358 -18.656783) (xy 85.992125 -18.693982) (xy 86.114392 -18.738718) (xy 86.233705 -18.790826)
			(xy 86.349618 -18.850109) (xy 86.461703 -18.91635) (xy 86.56954 -18.9893) (xy 86.672729 -19.068688)
			(xy 86.770887 -19.15422) (xy 86.863648 -19.245577) (xy 86.950667 -19.342419) (xy 87.03162 -19.444386)
			(xy 87.106206 -19.551098) (xy 87.174147 -19.662159) (xy 87.235192 -19.777155) (xy 87.289113 -19.895659)
			(xy 87.335708 -20.01723) (xy 87.374806 -20.141415) (xy 87.40626 -20.267753) (xy 87.429954 -20.395774)
			(xy 87.445798 -20.525) (xy 87.453736 -20.654953) (xy 87.454232 -20.72005) (xy 87.453736 -20.785147)
			(xy 87.445798 -20.9151) (xy 87.429954 -21.044326) (xy 87.40626 -21.172347) (xy 87.374806 -21.298685)
			(xy 87.335708 -21.42287) (xy 87.289113 -21.544441) (xy 87.235192 -21.662945) (xy 87.195171 -21.738336)
			(xy 89.416636 -21.738336) (xy 89.417138 -21.709596) (xy 89.425768 -21.652769) (xy 89.442825 -21.597879)
			(xy 89.46792 -21.546167) (xy 89.500488 -21.498805) (xy 89.51976 -21.477478) (xy 89.526364 -21.47062)
			(xy 89.533476 -21.452586) (xy 89.533476 -21.363686) (xy 89.526364 -21.345652) (xy 89.51976 -21.338794)
			(xy 89.500523 -21.317437) (xy 89.467954 -21.270081) (xy 89.442858 -21.218374) (xy 89.425803 -21.163488)
			(xy 89.417177 -21.106664) (xy 89.417173 -21.049189) (xy 89.425792 -20.992364) (xy 89.442839 -20.937475)
			(xy 89.467927 -20.885765) (xy 89.50049 -20.838404) (xy 89.51976 -20.817078) (xy 89.526364 -20.81022)
			(xy 89.533476 -20.792186) (xy 89.533476 -20.703286) (xy 89.526364 -20.685252) (xy 89.51976 -20.678394)
			(xy 89.500523 -20.657037) (xy 89.467954 -20.609681) (xy 89.442858 -20.557974) (xy 89.425803 -20.503088)
			(xy 89.417177 -20.446264) (xy 89.417173 -20.388789) (xy 89.425792 -20.331964) (xy 89.442839 -20.277075)
			(xy 89.467927 -20.225365) (xy 89.50049 -20.178004) (xy 89.51976 -20.156678) (xy 89.526364 -20.14982)
			(xy 89.533476 -20.131786) (xy 89.533476 -20.042886) (xy 89.526364 -20.024852) (xy 89.51976 -20.017994)
			(xy 89.500523 -19.996637) (xy 89.467954 -19.949281) (xy 89.442858 -19.897574) (xy 89.425803 -19.842688)
			(xy 89.417177 -19.785864) (xy 89.417173 -19.728389) (xy 89.425792 -19.671564) (xy 89.442839 -19.616675)
			(xy 89.467927 -19.564965) (xy 89.50049 -19.517604) (xy 89.51976 -19.496278) (xy 89.526364 -19.48942)
			(xy 89.533476 -19.471386) (xy 89.533476 -19.382486) (xy 89.526364 -19.364452) (xy 89.51976 -19.357594)
			(xy 89.50051 -19.336249) (xy 89.46794 -19.288892) (xy 89.442843 -19.237185) (xy 89.425788 -19.182298)
			(xy 89.41716 -19.125474) (xy 89.416636 -19.096736) (xy 89.417122 -19.069485) (xy 89.424878 -19.015537)
			(xy 89.440233 -18.963242) (xy 89.462875 -18.913665) (xy 89.492341 -18.867815) (xy 89.528032 -18.826624)
			(xy 89.569223 -18.790933) (xy 89.615073 -18.761467) (xy 89.66465 -18.738825) (xy 89.716945 -18.72347)
			(xy 89.770893 -18.715714) (xy 89.825395 -18.715714) (xy 89.879343 -18.72347) (xy 89.931638 -18.738825)
			(xy 89.981215 -18.761467) (xy 90.027065 -18.790933) (xy 90.068256 -18.826624) (xy 90.103947 -18.867815)
			(xy 90.133413 -18.913665) (xy 90.156055 -18.963242) (xy 90.17141 -19.015537) (xy 90.179166 -19.069485)
			(xy 90.179652 -19.096736) (xy 90.179136 -19.125475) (xy 90.17051 -19.182302) (xy 90.153457 -19.237192)
			(xy 90.128364 -19.288904) (xy 90.095799 -19.336267) (xy 90.076528 -19.357594) (xy 90.069924 -19.364452)
			(xy 90.062812 -19.382486) (xy 90.062812 -19.471386) (xy 90.069924 -19.48942) (xy 90.076528 -19.496278)
			(xy 90.095832 -19.517575) (xy 90.128392 -19.564944) (xy 90.153478 -19.616661) (xy 90.170523 -19.671556)
			(xy 90.179141 -19.728386) (xy 90.179137 -19.785866) (xy 90.170511 -19.842695) (xy 90.153459 -19.897588)
			(xy 90.128365 -19.949301) (xy 90.095799 -19.996666) (xy 90.076528 -20.017994) (xy 90.069924 -20.024852)
			(xy 90.062812 -20.042886) (xy 90.062812 -20.131786) (xy 90.069924 -20.14982) (xy 90.076528 -20.156678)
			(xy 90.095832 -20.177975) (xy 90.128392 -20.225344) (xy 90.153478 -20.277061) (xy 90.170523 -20.331956)
			(xy 90.179141 -20.388786) (xy 90.179137 -20.446266) (xy 90.170511 -20.503095) (xy 90.153459 -20.557988)
			(xy 90.128365 -20.609701) (xy 90.095799 -20.657066) (xy 90.076528 -20.678394) (xy 90.069924 -20.685252)
			(xy 90.062812 -20.703286) (xy 90.062812 -20.792186) (xy 90.069924 -20.81022) (xy 90.076528 -20.817078)
			(xy 90.095832 -20.838375) (xy 90.128392 -20.885744) (xy 90.153478 -20.937461) (xy 90.170523 -20.992356)
			(xy 90.179141 -21.049186) (xy 90.179137 -21.106666) (xy 90.170511 -21.163495) (xy 90.153459 -21.218388)
			(xy 90.128365 -21.270101) (xy 90.095799 -21.317466) (xy 90.076528 -21.338794) (xy 90.069924 -21.345652)
			(xy 90.062812 -21.363686) (xy 90.062812 -21.452586) (xy 90.069924 -21.47062) (xy 90.076528 -21.477478)
			(xy 90.09581 -21.498795) (xy 90.128376 -21.546159) (xy 90.153467 -21.597873) (xy 90.166246 -21.639022)
			(xy 94.073726 -21.639022) (xy 94.074283 -21.610285) (xy 94.0829 -21.55346) (xy 94.099944 -21.49857)
			(xy 94.125027 -21.446858) (xy 94.157584 -21.399493) (xy 94.17685 -21.378164) (xy 94.183454 -21.371306)
			(xy 94.190566 -21.353272) (xy 94.190566 -21.264372) (xy 94.183454 -21.246338) (xy 94.17685 -21.23948)
			(xy 94.1576 -21.218135) (xy 94.125032 -21.170776) (xy 94.099937 -21.119068) (xy 94.082884 -21.064179)
			(xy 94.074259 -21.007354) (xy 94.074257 -20.949878) (xy 94.082877 -20.893052) (xy 94.099925 -20.838162)
			(xy 94.125016 -20.786451) (xy 94.15758 -20.73909) (xy 94.17685 -20.717764) (xy 94.183454 -20.710906)
			(xy 94.190566 -20.692872) (xy 94.190566 -20.603972) (xy 94.183454 -20.585938) (xy 94.17685 -20.57908)
			(xy 94.1576 -20.557735) (xy 94.125032 -20.510376) (xy 94.099937 -20.458668) (xy 94.082884 -20.403779)
			(xy 94.074259 -20.346954) (xy 94.074257 -20.289478) (xy 94.082877 -20.232652) (xy 94.099925 -20.177762)
			(xy 94.125016 -20.126051) (xy 94.15758 -20.07869) (xy 94.17685 -20.057364) (xy 94.183454 -20.050506)
			(xy 94.190566 -20.032472) (xy 94.190566 -19.943572) (xy 94.183454 -19.925538) (xy 94.17685 -19.91868)
			(xy 94.1576 -19.897335) (xy 94.125032 -19.849976) (xy 94.099937 -19.798268) (xy 94.082884 -19.743379)
			(xy 94.074259 -19.686554) (xy 94.074257 -19.629078) (xy 94.082877 -19.572252) (xy 94.099925 -19.517362)
			(xy 94.125016 -19.465651) (xy 94.15758 -19.41829) (xy 94.17685 -19.396964) (xy 94.183454 -19.390106)
			(xy 94.190566 -19.372072) (xy 94.190566 -19.283172) (xy 94.183454 -19.265138) (xy 94.17685 -19.25828)
			(xy 94.157592 -19.236942) (xy 94.125023 -19.189583) (xy 94.099928 -19.137874) (xy 94.082875 -19.082986)
			(xy 94.074249 -19.02616) (xy 94.073726 -18.997422) (xy 94.074212 -18.970171) (xy 94.081968 -18.916223)
			(xy 94.097323 -18.863928) (xy 94.119965 -18.814351) (xy 94.149431 -18.768501) (xy 94.185122 -18.72731)
			(xy 94.226313 -18.691619) (xy 94.272163 -18.662153) (xy 94.32174 -18.639511) (xy 94.374035 -18.624156)
			(xy 94.427983 -18.6164) (xy 94.482485 -18.6164) (xy 94.536433 -18.624156) (xy 94.588728 -18.639511)
			(xy 94.638305 -18.662153) (xy 94.684155 -18.691619) (xy 94.725346 -18.72731) (xy 94.761037 -18.768501)
			(xy 94.790503 -18.814351) (xy 94.813145 -18.863928) (xy 94.8285 -18.916223) (xy 94.836256 -18.970171)
			(xy 94.836742 -18.997422) (xy 94.83622 -19.026161) (xy 94.827596 -19.082988) (xy 94.810544 -19.137878)
			(xy 94.785453 -19.18959) (xy 94.752888 -19.236953) (xy 94.733618 -19.25828) (xy 94.727014 -19.265138)
			(xy 94.719902 -19.283172) (xy 94.719902 -19.33956) (xy 99.578158 -19.33956) (xy 99.582229 -19.283938)
			(xy 99.594355 -19.229501) (xy 99.614278 -19.17741) (xy 99.641574 -19.128775) (xy 99.67566 -19.084632)
			(xy 99.715809 -19.045923) (xy 99.761167 -19.013472) (xy 99.810767 -18.987971) (xy 99.863551 -18.969964)
			(xy 99.918394 -18.959834) (xy 99.974128 -18.957797) (xy 100.029565 -18.963897) (xy 100.083522 -18.978003)
			(xy 100.134851 -18.999815) (xy 100.182457 -19.028869) (xy 100.225325 -19.064544) (xy 100.262542 -19.106081)
			(xy 100.293315 -19.152594) (xy 100.316987 -19.203091) (xy 100.333055 -19.256498) (xy 100.341175 -19.311674)
			(xy 100.341684 -19.33956) (xy 100.341175 -19.367446) (xy 100.333055 -19.422622) (xy 100.316987 -19.476029)
			(xy 100.293315 -19.526526) (xy 100.262542 -19.573039) (xy 100.225325 -19.614576) (xy 100.182457 -19.650251)
			(xy 100.134851 -19.679305) (xy 100.083522 -19.701117) (xy 100.029565 -19.715223) (xy 99.974128 -19.721323)
			(xy 99.918394 -19.719286) (xy 99.863551 -19.709156) (xy 99.810767 -19.691149) (xy 99.761167 -19.665648)
			(xy 99.715809 -19.633197) (xy 99.67566 -19.594488) (xy 99.641574 -19.550345) (xy 99.614278 -19.50171)
			(xy 99.594355 -19.449619) (xy 99.582229 -19.395182) (xy 99.578158 -19.33956) (xy 94.719902 -19.33956)
			(xy 94.719902 -19.372072) (xy 94.727014 -19.390106) (xy 94.733618 -19.396964) (xy 94.752909 -19.418273)
			(xy 94.78547 -19.46564) (xy 94.810557 -19.517355) (xy 94.827604 -19.572248) (xy 94.836223 -19.629077)
			(xy 94.836221 -19.686555) (xy 94.827597 -19.743384) (xy 94.810545 -19.798275) (xy 94.785454 -19.849988)
			(xy 94.752889 -19.897352) (xy 94.733618 -19.91868) (xy 94.727014 -19.925538) (xy 94.719902 -19.943572)
			(xy 94.719902 -20.032472) (xy 94.727014 -20.050506) (xy 94.733618 -20.057364) (xy 94.752909 -20.078673)
			(xy 94.78547 -20.12604) (xy 94.810557 -20.177755) (xy 94.827604 -20.232648) (xy 94.836223 -20.289477)
			(xy 94.836221 -20.346955) (xy 94.834915 -20.35556) (xy 99.578158 -20.35556) (xy 99.582229 -20.299938)
			(xy 99.594355 -20.245501) (xy 99.614278 -20.19341) (xy 99.641574 -20.144775) (xy 99.67566 -20.100632)
			(xy 99.715809 -20.061923) (xy 99.761167 -20.029472) (xy 99.810767 -20.003971) (xy 99.863551 -19.985964)
			(xy 99.918394 -19.975834) (xy 99.974128 -19.973797) (xy 100.029565 -19.979897) (xy 100.083522 -19.994003)
			(xy 100.134851 -20.015815) (xy 100.182457 -20.044869) (xy 100.225325 -20.080544) (xy 100.262542 -20.122081)
			(xy 100.293315 -20.168594) (xy 100.316987 -20.219091) (xy 100.333055 -20.272498) (xy 100.341175 -20.327674)
			(xy 100.341684 -20.35556) (xy 100.341175 -20.383446) (xy 100.333055 -20.438622) (xy 100.316987 -20.492029)
			(xy 100.293315 -20.542526) (xy 100.262542 -20.589039) (xy 100.225325 -20.630576) (xy 100.182457 -20.666251)
			(xy 100.134851 -20.695305) (xy 100.083522 -20.717117) (xy 100.029565 -20.731223) (xy 99.974128 -20.737323)
			(xy 99.918394 -20.735286) (xy 99.863551 -20.725156) (xy 99.810767 -20.707149) (xy 99.761167 -20.681648)
			(xy 99.715809 -20.649197) (xy 99.67566 -20.610488) (xy 99.641574 -20.566345) (xy 99.614278 -20.51771)
			(xy 99.594355 -20.465619) (xy 99.582229 -20.411182) (xy 99.578158 -20.35556) (xy 94.834915 -20.35556)
			(xy 94.827597 -20.403784) (xy 94.810545 -20.458675) (xy 94.785454 -20.510388) (xy 94.752889 -20.557752)
			(xy 94.733618 -20.57908) (xy 94.727014 -20.585938) (xy 94.719902 -20.603972) (xy 94.719902 -20.692872)
			(xy 94.727014 -20.710906) (xy 94.733618 -20.717764) (xy 94.752909 -20.739073) (xy 94.78547 -20.78644)
			(xy 94.810557 -20.838155) (xy 94.827604 -20.893048) (xy 94.836223 -20.949877) (xy 94.836221 -21.007355)
			(xy 94.827597 -21.064184) (xy 94.810545 -21.119075) (xy 94.785454 -21.170788) (xy 94.752889 -21.218152)
			(xy 94.733618 -21.23948) (xy 94.727014 -21.246338) (xy 94.719902 -21.264372) (xy 94.719902 -21.353272)
			(xy 94.727014 -21.371306) (xy 94.727259 -21.37156) (xy 99.578158 -21.37156) (xy 99.582229 -21.315938)
			(xy 99.594355 -21.261501) (xy 99.614278 -21.20941) (xy 99.641574 -21.160775) (xy 99.67566 -21.116632)
			(xy 99.715809 -21.077923) (xy 99.761167 -21.045472) (xy 99.810767 -21.019971) (xy 99.863551 -21.001964)
			(xy 99.918394 -20.991834) (xy 99.974128 -20.989797) (xy 100.029565 -20.995897) (xy 100.083522 -21.010003)
			(xy 100.134851 -21.031815) (xy 100.182457 -21.060869) (xy 100.225325 -21.096544) (xy 100.262542 -21.138081)
			(xy 100.293315 -21.184594) (xy 100.316987 -21.235091) (xy 100.333055 -21.288498) (xy 100.341175 -21.343674)
			(xy 100.341684 -21.37156) (xy 100.341175 -21.399446) (xy 100.333055 -21.454622) (xy 100.316987 -21.508029)
			(xy 100.293315 -21.558526) (xy 100.262542 -21.605039) (xy 100.225325 -21.646576) (xy 100.182457 -21.682251)
			(xy 100.134851 -21.711305) (xy 100.083522 -21.733117) (xy 100.029565 -21.747223) (xy 99.974128 -21.753323)
			(xy 99.918394 -21.751286) (xy 99.863551 -21.741156) (xy 99.810767 -21.723149) (xy 99.761167 -21.697648)
			(xy 99.715809 -21.665197) (xy 99.67566 -21.626488) (xy 99.641574 -21.582345) (xy 99.614278 -21.53371)
			(xy 99.594355 -21.481619) (xy 99.582229 -21.427182) (xy 99.578158 -21.37156) (xy 94.727259 -21.37156)
			(xy 94.733618 -21.378164) (xy 94.752892 -21.399489) (xy 94.785459 -21.44685) (xy 94.810552 -21.498563)
			(xy 94.827602 -21.553454) (xy 94.836223 -21.610283) (xy 94.836742 -21.639022) (xy 94.836256 -21.666273)
			(xy 94.8285 -21.720221) (xy 94.813145 -21.772516) (xy 94.790503 -21.822093) (xy 94.761037 -21.867943)
			(xy 94.725346 -21.909134) (xy 94.684155 -21.944825) (xy 94.638305 -21.974291) (xy 94.588728 -21.996933)
			(xy 94.536433 -22.012288) (xy 94.482485 -22.020044) (xy 94.427983 -22.020044) (xy 94.374035 -22.012288)
			(xy 94.32174 -21.996933) (xy 94.272163 -21.974291) (xy 94.226313 -21.944825) (xy 94.185122 -21.909134)
			(xy 94.149431 -21.867943) (xy 94.119965 -21.822093) (xy 94.097323 -21.772516) (xy 94.081968 -21.720221)
			(xy 94.074212 -21.666273) (xy 94.073726 -21.639022) (xy 90.166246 -21.639022) (xy 90.170515 -21.652767)
			(xy 90.179134 -21.709596) (xy 90.179652 -21.738336) (xy 90.179166 -21.765587) (xy 90.17141 -21.819535)
			(xy 90.156055 -21.87183) (xy 90.133413 -21.921407) (xy 90.103947 -21.967257) (xy 90.068256 -22.008448)
			(xy 90.027065 -22.044139) (xy 89.981215 -22.073605) (xy 89.931638 -22.096247) (xy 89.879343 -22.111602)
			(xy 89.825395 -22.119358) (xy 89.770893 -22.119358) (xy 89.716945 -22.111602) (xy 89.66465 -22.096247)
			(xy 89.615073 -22.073605) (xy 89.569223 -22.044139) (xy 89.528032 -22.008448) (xy 89.492341 -21.967257)
			(xy 89.462875 -21.921407) (xy 89.440233 -21.87183) (xy 89.424878 -21.819535) (xy 89.417122 -21.765587)
			(xy 89.416636 -21.738336) (xy 87.195171 -21.738336) (xy 87.174147 -21.777941) (xy 87.106206 -21.889002)
			(xy 87.03162 -21.995714) (xy 86.950667 -22.097681) (xy 86.863648 -22.194523) (xy 86.770887 -22.28588)
			(xy 86.672729 -22.371412) (xy 86.56954 -22.4508) (xy 86.461703 -22.52375) (xy 86.349618 -22.589991)
			(xy 86.233705 -22.649274) (xy 86.114392 -22.701382) (xy 85.992125 -22.746118) (xy 85.867358 -22.783317)
			(xy 85.740555 -22.812841) (xy 85.612188 -22.834579) (xy 85.482735 -22.848452) (xy 85.352676 -22.854406)
			(xy 85.222497 -22.852421) (xy 85.092681 -22.842503) (xy 84.963711 -22.824689) (xy 84.836066 -22.799046)
			(xy 84.710223 -22.765669) (xy 84.586648 -22.724682) (xy 84.465802 -22.676238) (xy 84.348134 -22.620516)
			(xy 84.234082 -22.557725) (xy 84.12407 -22.488098) (xy 84.018508 -22.411893) (xy 83.917788 -22.329394)
			(xy 83.822284 -22.240909) (xy 83.732352 -22.146766) (xy 83.648327 -22.047315) (xy 83.570522 -21.942927)
			(xy 83.499225 -21.83399) (xy 83.434701 -21.720908) (xy 83.377192 -21.604104) (xy 83.32691 -21.484011)
			(xy 83.284044 -21.361075) (xy 83.248751 -21.235756) (xy 83.221165 -21.108517) (xy 83.201386 -20.979834)
			(xy 83.18949 -20.850184) (xy 83.18552 -20.72005) (xy 79.420974 -20.72005) (xy 79.420974 -21.503894)
			(xy 79.421228 -21.507196) (xy 79.421228 -21.508212) (xy 79.422496 -21.518344) (xy 79.431926 -21.536435)
			(xy 79.439516 -21.543264) (xy 79.4623 -21.559845) (xy 79.503189 -21.598616) (xy 79.537931 -21.64298)
			(xy 79.565769 -21.691971) (xy 79.586098 -21.744524) (xy 79.598476 -21.799496) (xy 79.601994 -21.847048)
			(xy 80.072736 -21.847048) (xy 80.076807 -21.791426) (xy 80.088933 -21.736989) (xy 80.108856 -21.684898)
			(xy 80.136152 -21.636263) (xy 80.170238 -21.59212) (xy 80.210387 -21.553411) (xy 80.255745 -21.52096)
			(xy 80.305345 -21.495459) (xy 80.358129 -21.477452) (xy 80.412972 -21.467322) (xy 80.468706 -21.465285)
			(xy 80.524143 -21.471385) (xy 80.5781 -21.485491) (xy 80.629429 -21.507303) (xy 80.677035 -21.536357)
			(xy 80.719903 -21.572032) (xy 80.75712 -21.613569) (xy 80.787893 -21.660082) (xy 80.811565 -21.710579)
			(xy 80.827633 -21.763986) (xy 80.835753 -21.819162) (xy 80.836262 -21.847048) (xy 80.835753 -21.874934)
			(xy 80.827633 -21.93011) (xy 80.811565 -21.983517) (xy 80.787893 -22.034014) (xy 80.75712 -22.080527)
			(xy 80.719903 -22.122064) (xy 80.677035 -22.157739) (xy 80.629429 -22.186793) (xy 80.5781 -22.208605)
			(xy 80.524143 -22.222711) (xy 80.468706 -22.228811) (xy 80.412972 -22.226774) (xy 80.358129 -22.216644)
			(xy 80.305345 -22.198637) (xy 80.255745 -22.173136) (xy 80.210387 -22.140685) (xy 80.170238 -22.101976)
			(xy 80.136152 -22.057833) (xy 80.108856 -22.009198) (xy 80.088933 -21.957107) (xy 80.076807 -21.90267)
			(xy 80.072736 -21.847048) (xy 79.601994 -21.847048) (xy 79.602633 -21.855691) (xy 79.598478 -21.911886)
			(xy 79.586104 -21.966858) (xy 79.565777 -22.019412) (xy 79.537941 -22.068405) (xy 79.503202 -22.112771)
			(xy 79.462314 -22.151543) (xy 79.439516 -22.168104) (xy 79.431932 -22.174942) (xy 79.422478 -22.193023)
			(xy 79.421228 -22.203156) (xy 79.421228 -22.204172) (xy 79.420974 -22.207474) (xy 79.420974 -23.0251)
			(xy 89.362278 -23.0251) (xy 89.366349 -22.969478) (xy 89.378475 -22.915041) (xy 89.398398 -22.86295)
			(xy 89.425694 -22.814315) (xy 89.45978 -22.770172) (xy 89.499929 -22.731463) (xy 89.545287 -22.699012)
			(xy 89.594887 -22.673511) (xy 89.647671 -22.655504) (xy 89.702514 -22.645374) (xy 89.758248 -22.643337)
			(xy 89.813685 -22.649437) (xy 89.867642 -22.663543) (xy 89.918971 -22.685355) (xy 89.966577 -22.714409)
			(xy 90.009445 -22.750084) (xy 90.046662 -22.791621) (xy 90.077435 -22.838134) (xy 90.101107 -22.888631)
			(xy 90.117175 -22.942038) (xy 90.125295 -22.997214) (xy 90.125804 -23.0251) (xy 90.125295 -23.052986)
			(xy 90.117175 -23.108162) (xy 90.101107 -23.161569) (xy 90.077435 -23.212066) (xy 90.046662 -23.258579)
			(xy 90.009445 -23.300116) (xy 89.966577 -23.335791) (xy 89.918971 -23.364845) (xy 89.867642 -23.386657)
			(xy 89.813685 -23.400763) (xy 89.758248 -23.406863) (xy 89.702514 -23.404826) (xy 89.647671 -23.394696)
			(xy 89.594887 -23.376689) (xy 89.545287 -23.351188) (xy 89.499929 -23.318737) (xy 89.45978 -23.280028)
			(xy 89.425694 -23.235885) (xy 89.398398 -23.18725) (xy 89.378475 -23.135159) (xy 89.366349 -23.080722)
			(xy 89.362278 -23.0251) (xy 79.420974 -23.0251) (xy 79.420974 -23.488904) (xy 79.421736 -23.497286)
			(xy 79.424784 -23.513288) (xy 79.425292 -23.514304) (xy 79.427082 -23.518259) (xy 79.431801 -23.525543)
			(xy 79.43469 -23.528782) (xy 79.437738 -23.53183) (xy 79.450438 -23.544784) (xy 79.453637 -23.547876)
			(xy 79.460921 -23.552984) (xy 79.464916 -23.554944) (xy 79.467952 -23.556365) (xy 90.065923 -23.556365)
			(xy 90.073676 -23.502426) (xy 90.089027 -23.450139) (xy 90.111662 -23.400569) (xy 90.14112 -23.354725)
			(xy 90.176803 -23.313539) (xy 90.217984 -23.277851) (xy 90.263824 -23.248386) (xy 90.313391 -23.225745)
			(xy 90.365676 -23.210387) (xy 90.419613 -23.202627) (xy 90.44686 -23.202138) (xy 90.47089 -23.202497)
			(xy 90.518568 -23.208543) (xy 90.565109 -23.220531) (xy 90.587576 -23.229062) (xy 90.600712 -23.233891)
			(xy 90.628545 -23.236784) (xy 90.65612 -23.232023) (xy 90.681371 -23.219964) (xy 90.702407 -23.201511)
			(xy 90.717652 -23.178046) (xy 90.725965 -23.151327) (xy 90.726722 -23.123355) (xy 90.72372 -23.109682)
			(xy 90.718269 -23.086699) (xy 90.712408 -23.039828) (xy 90.712036 -23.01621) (xy 90.712467 -22.988959)
			(xy 90.720222 -22.93501) (xy 90.735576 -22.882715) (xy 90.758215 -22.833136) (xy 90.78768 -22.787284)
			(xy 90.82337 -22.746092) (xy 90.864559 -22.710399) (xy 90.910409 -22.68093) (xy 90.959985 -22.658287)
			(xy 91.01228 -22.642929) (xy 91.066227 -22.635169) (xy 91.12073 -22.635166) (xy 91.174679 -22.64292)
			(xy 91.226975 -22.658272) (xy 91.276554 -22.68091) (xy 91.322407 -22.710373) (xy 91.3636 -22.746062)
			(xy 91.399294 -22.78725) (xy 91.428764 -22.833099) (xy 91.451409 -22.882675) (xy 91.466769 -22.934968)
			(xy 91.47453 -22.988916) (xy 91.474535 -23.043419) (xy 91.466783 -23.097368) (xy 91.451432 -23.149664)
			(xy 91.428796 -23.199244) (xy 91.399334 -23.245097) (xy 91.363646 -23.286292) (xy 91.322459 -23.321988)
			(xy 91.276611 -23.351459) (xy 91.227036 -23.374105) (xy 91.174743 -23.389466) (xy 91.120795 -23.397229)
			(xy 91.093544 -23.397718) (xy 91.069514 -23.397354) (xy 91.021837 -23.39131) (xy 90.975296 -23.379324)
			(xy 90.952828 -23.370794) (xy 90.939675 -23.366021) (xy 90.911853 -23.363131) (xy 90.884289 -23.36789)
			(xy 90.859047 -23.379942) (xy 90.838016 -23.398385) (xy 90.822772 -23.421837) (xy 90.814455 -23.448544)
			(xy 90.813688 -23.476506) (xy 90.816684 -23.490174) (xy 90.822145 -23.513155) (xy 90.828 -23.560028)
			(xy 90.828368 -23.583646) (xy 90.828253 -23.589996) (xy 94.084392 -23.589996) (xy 94.088463 -23.534374)
			(xy 94.100589 -23.479937) (xy 94.120512 -23.427846) (xy 94.147808 -23.379211) (xy 94.181894 -23.335068)
			(xy 94.222043 -23.296359) (xy 94.267401 -23.263908) (xy 94.317001 -23.238407) (xy 94.369785 -23.2204)
			(xy 94.424628 -23.21027) (xy 94.480362 -23.208233) (xy 94.535799 -23.214333) (xy 94.589756 -23.228439)
			(xy 94.641085 -23.250251) (xy 94.688691 -23.279305) (xy 94.731559 -23.31498) (xy 94.768776 -23.356517)
			(xy 94.799549 -23.40303) (xy 94.823221 -23.453527) (xy 94.839289 -23.506934) (xy 94.847409 -23.56211)
			(xy 94.847918 -23.589996) (xy 94.847409 -23.617882) (xy 94.839289 -23.673058) (xy 94.823221 -23.726465)
			(xy 94.799549 -23.776962) (xy 94.768776 -23.823475) (xy 94.731559 -23.865012) (xy 94.713167 -23.880318)
			(xy 95.2406 -23.880318) (xy 95.244671 -23.824696) (xy 95.256797 -23.770259) (xy 95.27672 -23.718168)
			(xy 95.304016 -23.669533) (xy 95.338102 -23.62539) (xy 95.378251 -23.586681) (xy 95.423609 -23.55423)
			(xy 95.473209 -23.528729) (xy 95.525993 -23.510722) (xy 95.580836 -23.500592) (xy 95.63657 -23.498555)
			(xy 95.692007 -23.504655) (xy 95.745964 -23.518761) (xy 95.797293 -23.540573) (xy 95.844899 -23.569627)
			(xy 95.887767 -23.605302) (xy 95.924984 -23.646839) (xy 95.955757 -23.693352) (xy 95.979429 -23.743849)
			(xy 95.995497 -23.797256) (xy 96.003617 -23.852432) (xy 96.004126 -23.880318) (xy 96.2566 -23.880318)
			(xy 96.260671 -23.824696) (xy 96.272797 -23.770259) (xy 96.29272 -23.718168) (xy 96.320016 -23.669533)
			(xy 96.354102 -23.62539) (xy 96.394251 -23.586681) (xy 96.439609 -23.55423) (xy 96.489209 -23.528729)
			(xy 96.541993 -23.510722) (xy 96.596836 -23.500592) (xy 96.65257 -23.498555) (xy 96.708007 -23.504655)
			(xy 96.761964 -23.518761) (xy 96.813293 -23.540573) (xy 96.860899 -23.569627) (xy 96.903767 -23.605302)
			(xy 96.940984 -23.646839) (xy 96.971757 -23.693352) (xy 96.995429 -23.743849) (xy 97.011497 -23.797256)
			(xy 97.019617 -23.852432) (xy 97.020126 -23.880318) (xy 97.2726 -23.880318) (xy 97.276671 -23.824696)
			(xy 97.288797 -23.770259) (xy 97.30872 -23.718168) (xy 97.336016 -23.669533) (xy 97.370102 -23.62539)
			(xy 97.410251 -23.586681) (xy 97.455609 -23.55423) (xy 97.505209 -23.528729) (xy 97.557993 -23.510722)
			(xy 97.612836 -23.500592) (xy 97.66857 -23.498555) (xy 97.724007 -23.504655) (xy 97.777964 -23.518761)
			(xy 97.829293 -23.540573) (xy 97.876899 -23.569627) (xy 97.919767 -23.605302) (xy 97.956984 -23.646839)
			(xy 97.987757 -23.693352) (xy 98.011429 -23.743849) (xy 98.027497 -23.797256) (xy 98.035617 -23.852432)
			(xy 98.036126 -23.880318) (xy 98.290886 -23.880318) (xy 98.294957 -23.824696) (xy 98.307083 -23.770259)
			(xy 98.327006 -23.718168) (xy 98.354302 -23.669533) (xy 98.388388 -23.62539) (xy 98.428537 -23.586681)
			(xy 98.473895 -23.55423) (xy 98.523495 -23.528729) (xy 98.576279 -23.510722) (xy 98.631122 -23.500592)
			(xy 98.686856 -23.498555) (xy 98.742293 -23.504655) (xy 98.79625 -23.518761) (xy 98.847579 -23.540573)
			(xy 98.895185 -23.569627) (xy 98.938053 -23.605302) (xy 98.97527 -23.646839) (xy 99.006043 -23.693352)
			(xy 99.029715 -23.743849) (xy 99.045783 -23.797256) (xy 99.053903 -23.852432) (xy 99.054412 -23.880318)
			(xy 99.053903 -23.908204) (xy 99.045783 -23.96338) (xy 99.029715 -24.016787) (xy 99.006043 -24.067284)
			(xy 98.97527 -24.113797) (xy 98.938053 -24.155334) (xy 98.895185 -24.191009) (xy 98.847579 -24.220063)
			(xy 98.79625 -24.241875) (xy 98.742293 -24.255981) (xy 98.686856 -24.262081) (xy 98.631122 -24.260044)
			(xy 98.576279 -24.249914) (xy 98.523495 -24.231907) (xy 98.473895 -24.206406) (xy 98.428537 -24.173955)
			(xy 98.388388 -24.135246) (xy 98.354302 -24.091103) (xy 98.327006 -24.042468) (xy 98.307083 -23.990377)
			(xy 98.294957 -23.93594) (xy 98.290886 -23.880318) (xy 98.036126 -23.880318) (xy 98.035617 -23.908204)
			(xy 98.027497 -23.96338) (xy 98.011429 -24.016787) (xy 97.987757 -24.067284) (xy 97.956984 -24.113797)
			(xy 97.919767 -24.155334) (xy 97.876899 -24.191009) (xy 97.829293 -24.220063) (xy 97.777964 -24.241875)
			(xy 97.724007 -24.255981) (xy 97.66857 -24.262081) (xy 97.612836 -24.260044) (xy 97.557993 -24.249914)
			(xy 97.505209 -24.231907) (xy 97.455609 -24.206406) (xy 97.410251 -24.173955) (xy 97.370102 -24.135246)
			(xy 97.336016 -24.091103) (xy 97.30872 -24.042468) (xy 97.288797 -23.990377) (xy 97.276671 -23.93594)
			(xy 97.2726 -23.880318) (xy 97.020126 -23.880318) (xy 97.019617 -23.908204) (xy 97.011497 -23.96338)
			(xy 96.995429 -24.016787) (xy 96.971757 -24.067284) (xy 96.940984 -24.113797) (xy 96.903767 -24.155334)
			(xy 96.860899 -24.191009) (xy 96.813293 -24.220063) (xy 96.761964 -24.241875) (xy 96.708007 -24.255981)
			(xy 96.65257 -24.262081) (xy 96.596836 -24.260044) (xy 96.541993 -24.249914) (xy 96.489209 -24.231907)
			(xy 96.439609 -24.206406) (xy 96.394251 -24.173955) (xy 96.354102 -24.135246) (xy 96.320016 -24.091103)
			(xy 96.29272 -24.042468) (xy 96.272797 -23.990377) (xy 96.260671 -23.93594) (xy 96.2566 -23.880318)
			(xy 96.004126 -23.880318) (xy 96.003617 -23.908204) (xy 95.995497 -23.96338) (xy 95.979429 -24.016787)
			(xy 95.955757 -24.067284) (xy 95.924984 -24.113797) (xy 95.887767 -24.155334) (xy 95.844899 -24.191009)
			(xy 95.797293 -24.220063) (xy 95.745964 -24.241875) (xy 95.692007 -24.255981) (xy 95.63657 -24.262081)
			(xy 95.580836 -24.260044) (xy 95.525993 -24.249914) (xy 95.473209 -24.231907) (xy 95.423609 -24.206406)
			(xy 95.378251 -24.173955) (xy 95.338102 -24.135246) (xy 95.304016 -24.091103) (xy 95.27672 -24.042468)
			(xy 95.256797 -23.990377) (xy 95.244671 -23.93594) (xy 95.2406 -23.880318) (xy 94.713167 -23.880318)
			(xy 94.688691 -23.900687) (xy 94.641085 -23.929741) (xy 94.589756 -23.951553) (xy 94.535799 -23.965659)
			(xy 94.480362 -23.971759) (xy 94.424628 -23.969722) (xy 94.369785 -23.959592) (xy 94.317001 -23.941585)
			(xy 94.267401 -23.916084) (xy 94.222043 -23.883633) (xy 94.181894 -23.844924) (xy 94.147808 -23.800781)
			(xy 94.120512 -23.752146) (xy 94.100589 -23.700055) (xy 94.088463 -23.645618) (xy 94.084392 -23.589996)
			(xy 90.828253 -23.589996) (xy 90.827873 -23.610893) (xy 90.820111 -23.66483) (xy 90.804753 -23.717115)
			(xy 90.782111 -23.766681) (xy 90.752645 -23.812521) (xy 90.716956 -23.853701) (xy 90.67577 -23.889383)
			(xy 90.629925 -23.918841) (xy 90.580355 -23.941475) (xy 90.528068 -23.956825) (xy 90.474129 -23.964577)
			(xy 90.419636 -23.964575) (xy 90.365698 -23.956817) (xy 90.313412 -23.941463) (xy 90.263844 -23.918825)
			(xy 90.218002 -23.889363) (xy 90.176819 -23.853677) (xy 90.141134 -23.812493) (xy 90.111672 -23.766651)
			(xy 90.089035 -23.717082) (xy 90.073681 -23.664796) (xy 90.065925 -23.610858) (xy 90.065923 -23.556365)
			(xy 79.467952 -23.556365) (xy 79.488792 -23.56612) (xy 79.497682 -23.566882) (xy 79.525734 -23.569991)
			(xy 79.580551 -23.583421) (xy 79.632791 -23.604781) (xy 79.681313 -23.633605) (xy 79.725059 -23.669264)
			(xy 79.763073 -23.71098) (xy 79.794525 -23.757842) (xy 79.818729 -23.808826) (xy 79.835156 -23.862821)
			(xy 79.843447 -23.918647) (xy 79.843884 -23.946866) (xy 79.843464 -23.970996) (xy 80.072736 -23.970996)
			(xy 80.076807 -23.915374) (xy 80.088933 -23.860937) (xy 80.108856 -23.808846) (xy 80.136152 -23.760211)
			(xy 80.170238 -23.716068) (xy 80.210387 -23.677359) (xy 80.255745 -23.644908) (xy 80.305345 -23.619407)
			(xy 80.358129 -23.6014) (xy 80.412972 -23.59127) (xy 80.468706 -23.589233) (xy 80.524143 -23.595333)
			(xy 80.5781 -23.609439) (xy 80.629429 -23.631251) (xy 80.677035 -23.660305) (xy 80.719903 -23.69598)
			(xy 80.75712 -23.737517) (xy 80.787893 -23.78403) (xy 80.811565 -23.834527) (xy 80.827633 -23.887934)
			(xy 80.835753 -23.94311) (xy 80.836262 -23.970996) (xy 80.835753 -23.998882) (xy 80.827633 -24.054058)
			(xy 80.811565 -24.107465) (xy 80.787893 -24.157962) (xy 80.78774 -24.158194) (xy 85.450678 -24.158194)
			(xy 85.454749 -24.102572) (xy 85.466875 -24.048135) (xy 85.486798 -23.996044) (xy 85.514094 -23.947409)
			(xy 85.54818 -23.903266) (xy 85.588329 -23.864557) (xy 85.633687 -23.832106) (xy 85.683287 -23.806605)
			(xy 85.736071 -23.788598) (xy 85.790914 -23.778468) (xy 85.846648 -23.776431) (xy 85.902085 -23.782531)
			(xy 85.956042 -23.796637) (xy 86.007371 -23.818449) (xy 86.054977 -23.847503) (xy 86.097845 -23.883178)
			(xy 86.135062 -23.924715) (xy 86.165835 -23.971228) (xy 86.189507 -24.021725) (xy 86.205575 -24.075132)
			(xy 86.213695 -24.130308) (xy 86.214204 -24.158194) (xy 86.213695 -24.18608) (xy 86.213126 -24.189944)
			(xy 89.298778 -24.189944) (xy 89.302849 -24.134322) (xy 89.314975 -24.079885) (xy 89.334898 -24.027794)
			(xy 89.362194 -23.979159) (xy 89.39628 -23.935016) (xy 89.436429 -23.896307) (xy 89.481787 -23.863856)
			(xy 89.531387 -23.838355) (xy 89.584171 -23.820348) (xy 89.639014 -23.810218) (xy 89.694748 -23.808181)
			(xy 89.750185 -23.814281) (xy 89.804142 -23.828387) (xy 89.855471 -23.850199) (xy 89.903077 -23.879253)
			(xy 89.945945 -23.914928) (xy 89.983162 -23.956465) (xy 90.013935 -24.002978) (xy 90.037607 -24.053475)
			(xy 90.053675 -24.106882) (xy 90.061795 -24.162058) (xy 90.062304 -24.189944) (xy 91.82176 -24.189944)
			(xy 91.825831 -24.134322) (xy 91.837957 -24.079885) (xy 91.85788 -24.027794) (xy 91.885176 -23.979159)
			(xy 91.919262 -23.935016) (xy 91.959411 -23.896307) (xy 92.004769 -23.863856) (xy 92.054369 -23.838355)
			(xy 92.107153 -23.820348) (xy 92.161996 -23.810218) (xy 92.21773 -23.808181) (xy 92.273167 -23.814281)
			(xy 92.327124 -23.828387) (xy 92.378453 -23.850199) (xy 92.426059 -23.879253) (xy 92.468927 -23.914928)
			(xy 92.506144 -23.956465) (xy 92.536917 -24.002978) (xy 92.560589 -24.053475) (xy 92.576657 -24.106882)
			(xy 92.584777 -24.162058) (xy 92.585286 -24.189944) (xy 92.584777 -24.21783) (xy 92.576657 -24.273006)
			(xy 92.560589 -24.326413) (xy 92.536917 -24.37691) (xy 92.506144 -24.423423) (xy 92.468927 -24.46496)
			(xy 92.426059 -24.500635) (xy 92.378453 -24.529689) (xy 92.327124 -24.551501) (xy 92.273167 -24.565607)
			(xy 92.21773 -24.571707) (xy 92.161996 -24.56967) (xy 92.107153 -24.55954) (xy 92.054369 -24.541533)
			(xy 92.004769 -24.516032) (xy 91.959411 -24.483581) (xy 91.919262 -24.444872) (xy 91.885176 -24.400729)
			(xy 91.85788 -24.352094) (xy 91.837957 -24.300003) (xy 91.825831 -24.245566) (xy 91.82176 -24.189944)
			(xy 90.062304 -24.189944) (xy 90.061795 -24.21783) (xy 90.053675 -24.273006) (xy 90.037607 -24.326413)
			(xy 90.013935 -24.37691) (xy 89.983162 -24.423423) (xy 89.945945 -24.46496) (xy 89.903077 -24.500635)
			(xy 89.855471 -24.529689) (xy 89.804142 -24.551501) (xy 89.750185 -24.565607) (xy 89.694748 -24.571707)
			(xy 89.639014 -24.56967) (xy 89.584171 -24.55954) (xy 89.531387 -24.541533) (xy 89.481787 -24.516032)
			(xy 89.436429 -24.483581) (xy 89.39628 -24.444872) (xy 89.362194 -24.400729) (xy 89.334898 -24.352094)
			(xy 89.314975 -24.300003) (xy 89.302849 -24.245566) (xy 89.298778 -24.189944) (xy 86.213126 -24.189944)
			(xy 86.205575 -24.241256) (xy 86.189507 -24.294663) (xy 86.165835 -24.34516) (xy 86.135062 -24.391673)
			(xy 86.097845 -24.43321) (xy 86.054977 -24.468885) (xy 86.007371 -24.497939) (xy 85.956042 -24.519751)
			(xy 85.902085 -24.533857) (xy 85.846648 -24.539957) (xy 85.790914 -24.53792) (xy 85.736071 -24.52779)
			(xy 85.683287 -24.509783) (xy 85.633687 -24.484282) (xy 85.588329 -24.451831) (xy 85.54818 -24.413122)
			(xy 85.514094 -24.368979) (xy 85.486798 -24.320344) (xy 85.466875 -24.268253) (xy 85.454749 -24.213816)
			(xy 85.450678 -24.158194) (xy 80.78774 -24.158194) (xy 80.75712 -24.204475) (xy 80.719903 -24.246012)
			(xy 80.677035 -24.281687) (xy 80.629429 -24.310741) (xy 80.5781 -24.332553) (xy 80.524143 -24.346659)
			(xy 80.468706 -24.352759) (xy 80.412972 -24.350722) (xy 80.358129 -24.340592) (xy 80.305345 -24.322585)
			(xy 80.255745 -24.297084) (xy 80.210387 -24.264633) (xy 80.170238 -24.225924) (xy 80.136152 -24.181781)
			(xy 80.108856 -24.133146) (xy 80.088933 -24.081055) (xy 80.076807 -24.026618) (xy 80.072736 -23.970996)
			(xy 79.843464 -23.970996) (xy 79.843421 -23.973442) (xy 79.836041 -24.026079) (xy 79.821433 -24.077184)
			(xy 79.799878 -24.12577) (xy 79.771795 -24.170896) (xy 79.737724 -24.211693) (xy 79.698325 -24.24737)
			(xy 79.654359 -24.277239) (xy 79.606676 -24.300722) (xy 79.556197 -24.317365) (xy 79.503898 -24.326848)
			(xy 79.477362 -24.328374) (xy 79.47406 -24.328374) (xy 79.464916 -24.329898) (xy 79.463392 -24.330406)
			(xy 79.457296 -24.332692) (xy 79.45386 -24.334364) (xy 79.447478 -24.338566) (xy 79.444596 -24.341074)
			(xy 79.420466 -24.364696) (xy 79.417164 -24.368506) (xy 79.412214 -24.375228) (xy 79.406521 -24.390909)
			(xy 79.405988 -24.39924) (xy 79.405988 -24.807418) (xy 86.620094 -24.807418) (xy 86.624165 -24.751796)
			(xy 86.636291 -24.697359) (xy 86.656214 -24.645268) (xy 86.68351 -24.596633) (xy 86.717596 -24.55249)
			(xy 86.757745 -24.513781) (xy 86.803103 -24.48133) (xy 86.852703 -24.455829) (xy 86.905487 -24.437822)
			(xy 86.96033 -24.427692) (xy 87.016064 -24.425655) (xy 87.071501 -24.431755) (xy 87.125458 -24.445861)
			(xy 87.176787 -24.467673) (xy 87.224393 -24.496727) (xy 87.267261 -24.532402) (xy 87.304478 -24.573939)
			(xy 87.335251 -24.620452) (xy 87.358923 -24.670949) (xy 87.374991 -24.724356) (xy 87.380038 -24.75865)
			(xy 98.868482 -24.75865) (xy 98.872553 -24.703028) (xy 98.884679 -24.648591) (xy 98.904602 -24.5965)
			(xy 98.931898 -24.547865) (xy 98.965984 -24.503722) (xy 99.006133 -24.465013) (xy 99.051491 -24.432562)
			(xy 99.101091 -24.407061) (xy 99.153875 -24.389054) (xy 99.208718 -24.378924) (xy 99.264452 -24.376887)
			(xy 99.319889 -24.382987) (xy 99.373846 -24.397093) (xy 99.425175 -24.418905) (xy 99.472781 -24.447959)
			(xy 99.515649 -24.483634) (xy 99.552866 -24.525171) (xy 99.583639 -24.571684) (xy 99.607311 -24.622181)
			(xy 99.623379 -24.675588) (xy 99.631499 -24.730764) (xy 99.632008 -24.75865) (xy 99.631499 -24.786536)
			(xy 99.623379 -24.841712) (xy 99.607311 -24.895119) (xy 99.583639 -24.945616) (xy 99.552866 -24.992129)
			(xy 99.515649 -25.033666) (xy 99.472781 -25.069341) (xy 99.425175 -25.098395) (xy 99.373846 -25.120207)
			(xy 99.319889 -25.134313) (xy 99.264452 -25.140413) (xy 99.208718 -25.138376) (xy 99.153875 -25.128246)
			(xy 99.101091 -25.110239) (xy 99.051491 -25.084738) (xy 99.006133 -25.052287) (xy 98.965984 -25.013578)
			(xy 98.931898 -24.969435) (xy 98.904602 -24.9208) (xy 98.884679 -24.868709) (xy 98.872553 -24.814272)
			(xy 98.868482 -24.75865) (xy 87.380038 -24.75865) (xy 87.383111 -24.779532) (xy 87.38362 -24.807418)
			(xy 87.383111 -24.835304) (xy 87.374991 -24.89048) (xy 87.358923 -24.943887) (xy 87.335251 -24.994384)
			(xy 87.304478 -25.040897) (xy 87.267261 -25.082434) (xy 87.224393 -25.118109) (xy 87.176787 -25.147163)
			(xy 87.125458 -25.168975) (xy 87.071501 -25.183081) (xy 87.016064 -25.189181) (xy 86.96033 -25.187144)
			(xy 86.905487 -25.177014) (xy 86.852703 -25.159007) (xy 86.803103 -25.133506) (xy 86.757745 -25.101055)
			(xy 86.717596 -25.062346) (xy 86.68351 -25.018203) (xy 86.656214 -24.969568) (xy 86.636291 -24.917477)
			(xy 86.624165 -24.86304) (xy 86.620094 -24.807418) (xy 79.405988 -24.807418) (xy 79.405988 -25.390094)
			(xy 91.80957 -25.390094) (xy 91.810056 -25.362843) (xy 91.817812 -25.308895) (xy 91.833167 -25.2566)
			(xy 91.855809 -25.207023) (xy 91.885275 -25.161173) (xy 91.920966 -25.119982) (xy 91.962157 -25.084291)
			(xy 92.008007 -25.054825) (xy 92.057584 -25.032183) (xy 92.109879 -25.016828) (xy 92.163827 -25.009072)
			(xy 92.218329 -25.009072) (xy 92.272277 -25.016828) (xy 92.324572 -25.032183) (xy 92.374149 -25.054825)
			(xy 92.419999 -25.084291) (xy 92.46119 -25.119982) (xy 92.496881 -25.161173) (xy 92.526347 -25.207023)
			(xy 92.548989 -25.2566) (xy 92.564344 -25.308895) (xy 92.5721 -25.362843) (xy 92.572586 -25.390094)
			(xy 92.572001 -25.419113) (xy 92.563212 -25.476482) (xy 92.545836 -25.531858) (xy 92.520273 -25.583963)
			(xy 92.487113 -25.631596) (xy 92.447122 -25.673658) (xy 92.424504 -25.691846) (xy 92.413958 -25.700615)
			(xy 92.397516 -25.722549) (xy 92.387509 -25.748071) (xy 92.384662 -25.775336) (xy 92.38918 -25.802374)
			(xy 92.400736 -25.827232) (xy 92.418496 -25.848114) (xy 92.429584 -25.856184) (xy 92.451219 -25.871511)
			(xy 92.490477 -25.907147) (xy 92.52442 -25.947877) (xy 92.552395 -25.992915) (xy 92.573863 -26.041394)
			(xy 92.588408 -26.09238) (xy 92.595752 -26.144888) (xy 92.596208 -26.171398) (xy 92.595722 -26.198649)
			(xy 92.587966 -26.252597) (xy 92.572611 -26.304892) (xy 92.549969 -26.354469) (xy 92.520503 -26.400319)
			(xy 92.484812 -26.44151) (xy 92.443621 -26.477201) (xy 92.397771 -26.506667) (xy 92.348194 -26.529309)
			(xy 92.295899 -26.544664) (xy 92.241951 -26.55242) (xy 92.187449 -26.55242) (xy 92.133501 -26.544664)
			(xy 92.081206 -26.529309) (xy 92.031629 -26.506667) (xy 91.985779 -26.477201) (xy 91.944588 -26.44151)
			(xy 91.908897 -26.400319) (xy 91.879431 -26.354469) (xy 91.856789 -26.304892) (xy 91.841434 -26.252597)
			(xy 91.833678 -26.198649) (xy 91.833192 -26.171398) (xy 91.833741 -26.142377) (xy 91.842534 -26.085005)
			(xy 91.859915 -26.029627) (xy 91.885484 -25.977521) (xy 91.918652 -25.92989) (xy 91.958651 -25.887832)
			(xy 91.981274 -25.869646) (xy 91.991831 -25.860888) (xy 92.008277 -25.838952) (xy 92.018285 -25.813428)
			(xy 92.021132 -25.786159) (xy 92.016612 -25.759118) (xy 92.005051 -25.734258) (xy 91.987285 -25.713376)
			(xy 91.976194 -25.705308) (xy 91.95455 -25.689993) (xy 91.915294 -25.654354) (xy 91.881352 -25.613622)
			(xy 91.853378 -25.568581) (xy 91.831912 -25.520101) (xy 91.817368 -25.469114) (xy 91.810025 -25.416604)
			(xy 91.80957 -25.390094) (xy 79.405988 -25.390094) (xy 79.405988 -25.971246) (xy 79.959706 -25.971246)
			(xy 79.963777 -25.915624) (xy 79.975903 -25.861187) (xy 79.995826 -25.809096) (xy 80.023122 -25.760461)
			(xy 80.057208 -25.716318) (xy 80.097357 -25.677609) (xy 80.142715 -25.645158) (xy 80.192315 -25.619657)
			(xy 80.245099 -25.60165) (xy 80.299942 -25.59152) (xy 80.355676 -25.589483) (xy 80.411113 -25.595583)
			(xy 80.46507 -25.609689) (xy 80.516399 -25.631501) (xy 80.564005 -25.660555) (xy 80.606873 -25.69623)
			(xy 80.64409 -25.737767) (xy 80.674863 -25.78428) (xy 80.698535 -25.834777) (xy 80.714603 -25.888184)
			(xy 80.722723 -25.94336) (xy 80.723232 -25.971246) (xy 80.975706 -25.971246) (xy 80.979777 -25.915624)
			(xy 80.991903 -25.861187) (xy 81.011826 -25.809096) (xy 81.039122 -25.760461) (xy 81.073208 -25.716318)
			(xy 81.113357 -25.677609) (xy 81.158715 -25.645158) (xy 81.208315 -25.619657) (xy 81.261099 -25.60165)
			(xy 81.315942 -25.59152) (xy 81.371676 -25.589483) (xy 81.427113 -25.595583) (xy 81.48107 -25.609689)
			(xy 81.532399 -25.631501) (xy 81.580005 -25.660555) (xy 81.622873 -25.69623) (xy 81.66009 -25.737767)
			(xy 81.690863 -25.78428) (xy 81.714535 -25.834777) (xy 81.730603 -25.888184) (xy 81.738723 -25.94336)
			(xy 81.739232 -25.971246) (xy 81.991706 -25.971246) (xy 81.995777 -25.915624) (xy 82.007903 -25.861187)
			(xy 82.027826 -25.809096) (xy 82.055122 -25.760461) (xy 82.089208 -25.716318) (xy 82.129357 -25.677609)
			(xy 82.174715 -25.645158) (xy 82.224315 -25.619657) (xy 82.277099 -25.60165) (xy 82.331942 -25.59152)
			(xy 82.387676 -25.589483) (xy 82.443113 -25.595583) (xy 82.49707 -25.609689) (xy 82.548399 -25.631501)
			(xy 82.596005 -25.660555) (xy 82.638873 -25.69623) (xy 82.67609 -25.737767) (xy 82.706863 -25.78428)
			(xy 82.730535 -25.834777) (xy 82.746603 -25.888184) (xy 82.754723 -25.94336) (xy 82.755232 -25.971246)
			(xy 82.754723 -25.999132) (xy 82.749631 -26.03373) (xy 83.267802 -26.03373) (xy 83.271873 -25.978108)
			(xy 83.283999 -25.923671) (xy 83.303922 -25.87158) (xy 83.331218 -25.822945) (xy 83.365304 -25.778802)
			(xy 83.405453 -25.740093) (xy 83.450811 -25.707642) (xy 83.500411 -25.682141) (xy 83.553195 -25.664134)
			(xy 83.608038 -25.654004) (xy 83.663772 -25.651967) (xy 83.719209 -25.658067) (xy 83.773166 -25.672173)
			(xy 83.824495 -25.693985) (xy 83.872101 -25.723039) (xy 83.914969 -25.758714) (xy 83.952186 -25.800251)
			(xy 83.982959 -25.846764) (xy 84.006631 -25.897261) (xy 84.022699 -25.950668) (xy 84.030819 -26.005844)
			(xy 84.031328 -26.03373) (xy 84.030819 -26.061616) (xy 84.022699 -26.116792) (xy 84.006631 -26.170199)
			(xy 83.982959 -26.220696) (xy 83.952725 -26.266394) (xy 86.520528 -26.266394) (xy 86.52095 -26.239139)
			(xy 86.528709 -26.185185) (xy 86.544067 -26.132884) (xy 86.566713 -26.083302) (xy 86.596185 -26.037447)
			(xy 86.631883 -25.996253) (xy 86.673081 -25.96056) (xy 86.718939 -25.931093) (xy 86.768524 -25.908453)
			(xy 86.820826 -25.8931) (xy 86.874781 -25.885347) (xy 86.902036 -25.884886) (xy 86.931362 -25.885396)
			(xy 86.989321 -25.894384) (xy 87.045219 -25.912143) (xy 87.097739 -25.938253) (xy 87.122 -25.954736)
			(xy 87.132501 -25.961208) (xy 87.156924 -25.96439) (xy 87.168736 -25.960832) (xy 87.247222 -25.931622)
			(xy 87.258643 -25.926775) (xy 87.275288 -25.908416) (xy 87.278972 -25.89657) (xy 87.286375 -25.869502)
			(xy 87.307929 -25.817693) (xy 87.336843 -25.769602) (xy 87.372492 -25.726268) (xy 87.414107 -25.688624)
			(xy 87.460788 -25.657486) (xy 87.511528 -25.633523) (xy 87.565231 -25.617255) (xy 87.620739 -25.609032)
			(xy 87.648796 -25.608534) (xy 87.676052 -25.608913) (xy 87.730009 -25.61667) (xy 87.782314 -25.632027)
			(xy 87.8319 -25.654672) (xy 87.877758 -25.684143) (xy 87.918956 -25.719841) (xy 87.954654 -25.761038)
			(xy 87.984126 -25.806897) (xy 88.006771 -25.856483) (xy 88.022129 -25.908787) (xy 88.029887 -25.962744)
			(xy 88.029887 -25.990042) (xy 89.298778 -25.990042) (xy 89.302849 -25.93442) (xy 89.314975 -25.879983)
			(xy 89.334898 -25.827892) (xy 89.362194 -25.779257) (xy 89.39628 -25.735114) (xy 89.436429 -25.696405)
			(xy 89.481787 -25.663954) (xy 89.531387 -25.638453) (xy 89.584171 -25.620446) (xy 89.639014 -25.610316)
			(xy 89.694748 -25.608279) (xy 89.750185 -25.614379) (xy 89.804142 -25.628485) (xy 89.855471 -25.650297)
			(xy 89.903077 -25.679351) (xy 89.945945 -25.715026) (xy 89.983162 -25.756563) (xy 90.013935 -25.803076)
			(xy 90.037607 -25.853573) (xy 90.053675 -25.90698) (xy 90.061795 -25.962156) (xy 90.062304 -25.990042)
			(xy 90.061795 -26.017928) (xy 90.053675 -26.073104) (xy 90.037607 -26.126511) (xy 90.013935 -26.177008)
			(xy 89.983162 -26.223521) (xy 89.945945 -26.265058) (xy 89.903077 -26.300733) (xy 89.855471 -26.329787)
			(xy 89.804142 -26.351599) (xy 89.750185 -26.365705) (xy 89.694748 -26.371805) (xy 89.639014 -26.369768)
			(xy 89.584171 -26.359638) (xy 89.531387 -26.341631) (xy 89.481787 -26.31613) (xy 89.436429 -26.283679)
			(xy 89.39628 -26.24497) (xy 89.362194 -26.200827) (xy 89.334898 -26.152192) (xy 89.314975 -26.100101)
			(xy 89.302849 -26.045664) (xy 89.298778 -25.990042) (xy 88.029887 -25.990042) (xy 88.029887 -26.017256)
			(xy 88.022129 -26.071213) (xy 88.006771 -26.123517) (xy 87.984126 -26.173103) (xy 87.954654 -26.218962)
			(xy 87.918956 -26.260159) (xy 87.877758 -26.295857) (xy 87.8319 -26.325328) (xy 87.782314 -26.347973)
			(xy 87.730009 -26.36333) (xy 87.676052 -26.371087) (xy 87.648796 -26.37155) (xy 87.619471 -26.371017)
			(xy 87.561513 -26.362035) (xy 87.505615 -26.344283) (xy 87.453094 -26.31818) (xy 87.428832 -26.3017)
			(xy 87.41832 -26.295249) (xy 87.393906 -26.292053) (xy 87.382096 -26.295604) (xy 87.30361 -26.324814)
			(xy 87.292166 -26.329617) (xy 87.275533 -26.348009) (xy 87.27186 -26.359866) (xy 87.265075 -26.384898)
			(xy 87.24566 -26.432988) (xy 87.219903 -26.478002) (xy 87.188282 -26.519109) (xy 87.151379 -26.555549)
			(xy 87.13089 -26.571448) (xy 87.121221 -26.579427) (xy 87.110572 -26.602091) (xy 87.11057 -26.614628)
			(xy 87.115142 -26.698956) (xy 87.11638 -26.711393) (xy 87.129183 -26.73283) (xy 87.139526 -26.73985)
			(xy 87.163268 -26.754746) (xy 87.206502 -26.790414) (xy 87.244053 -26.832023) (xy 87.275111 -26.878679)
			(xy 87.29901 -26.929377) (xy 87.315235 -26.983025) (xy 87.323435 -27.03847) (xy 87.32393 -27.066494)
			(xy 87.323444 -27.093745) (xy 87.315688 -27.147693) (xy 87.300333 -27.199988) (xy 87.277691 -27.249565)
			(xy 87.248225 -27.295415) (xy 87.212534 -27.336606) (xy 87.171343 -27.372297) (xy 87.125493 -27.401763)
			(xy 87.075916 -27.424405) (xy 87.023621 -27.43976) (xy 86.969673 -27.447516) (xy 86.915171 -27.447516)
			(xy 86.861223 -27.43976) (xy 86.808928 -27.424405) (xy 86.759351 -27.401763) (xy 86.713501 -27.372297)
			(xy 86.67231 -27.336606) (xy 86.636619 -27.295415) (xy 86.607153 -27.249565) (xy 86.584511 -27.199988)
			(xy 86.569156 -27.147693) (xy 86.5614 -27.093745) (xy 86.560914 -27.066494) (xy 86.561452 -27.037006)
			(xy 86.570549 -26.978734) (xy 86.588509 -26.922558) (xy 86.614905 -26.869818) (xy 86.649107 -26.82177)
			(xy 86.690299 -26.779562) (xy 86.713568 -26.76144) (xy 86.723235 -26.753459) (xy 86.733888 -26.730797)
			(xy 86.733888 -26.71826) (xy 86.729316 -26.633932) (xy 86.72806 -26.621499) (xy 86.715268 -26.600063)
			(xy 86.704932 -26.593038) (xy 86.681197 -26.57813) (xy 86.637961 -26.542466) (xy 86.600408 -26.50086)
			(xy 86.569347 -26.454206) (xy 86.545447 -26.40351) (xy 86.529222 -26.349862) (xy 86.521022 -26.294418)
			(xy 86.520528 -26.266394) (xy 83.952725 -26.266394) (xy 83.952186 -26.267209) (xy 83.914969 -26.308746)
			(xy 83.872101 -26.344421) (xy 83.824495 -26.373475) (xy 83.773166 -26.395287) (xy 83.719209 -26.409393)
			(xy 83.663772 -26.415493) (xy 83.608038 -26.413456) (xy 83.553195 -26.403326) (xy 83.500411 -26.385319)
			(xy 83.450811 -26.359818) (xy 83.405453 -26.327367) (xy 83.365304 -26.288658) (xy 83.331218 -26.244515)
			(xy 83.303922 -26.19588) (xy 83.283999 -26.143789) (xy 83.271873 -26.089352) (xy 83.267802 -26.03373)
			(xy 82.749631 -26.03373) (xy 82.746603 -26.054308) (xy 82.730535 -26.107715) (xy 82.706863 -26.158212)
			(xy 82.67609 -26.204725) (xy 82.638873 -26.246262) (xy 82.596005 -26.281937) (xy 82.548399 -26.310991)
			(xy 82.49707 -26.332803) (xy 82.443113 -26.346909) (xy 82.387676 -26.353009) (xy 82.331942 -26.350972)
			(xy 82.277099 -26.340842) (xy 82.224315 -26.322835) (xy 82.174715 -26.297334) (xy 82.129357 -26.264883)
			(xy 82.089208 -26.226174) (xy 82.055122 -26.182031) (xy 82.027826 -26.133396) (xy 82.007903 -26.081305)
			(xy 81.995777 -26.026868) (xy 81.991706 -25.971246) (xy 81.739232 -25.971246) (xy 81.738723 -25.999132)
			(xy 81.730603 -26.054308) (xy 81.714535 -26.107715) (xy 81.690863 -26.158212) (xy 81.66009 -26.204725)
			(xy 81.622873 -26.246262) (xy 81.580005 -26.281937) (xy 81.532399 -26.310991) (xy 81.48107 -26.332803)
			(xy 81.427113 -26.346909) (xy 81.371676 -26.353009) (xy 81.315942 -26.350972) (xy 81.261099 -26.340842)
			(xy 81.208315 -26.322835) (xy 81.158715 -26.297334) (xy 81.113357 -26.264883) (xy 81.073208 -26.226174)
			(xy 81.039122 -26.182031) (xy 81.011826 -26.133396) (xy 80.991903 -26.081305) (xy 80.979777 -26.026868)
			(xy 80.975706 -25.971246) (xy 80.723232 -25.971246) (xy 80.722723 -25.999132) (xy 80.714603 -26.054308)
			(xy 80.698535 -26.107715) (xy 80.674863 -26.158212) (xy 80.64409 -26.204725) (xy 80.606873 -26.246262)
			(xy 80.564005 -26.281937) (xy 80.516399 -26.310991) (xy 80.46507 -26.332803) (xy 80.411113 -26.346909)
			(xy 80.355676 -26.353009) (xy 80.299942 -26.350972) (xy 80.245099 -26.340842) (xy 80.192315 -26.322835)
			(xy 80.142715 -26.297334) (xy 80.097357 -26.264883) (xy 80.057208 -26.226174) (xy 80.023122 -26.182031)
			(xy 79.995826 -26.133396) (xy 79.975903 -26.081305) (xy 79.963777 -26.026868) (xy 79.959706 -25.971246)
			(xy 79.405988 -25.971246) (xy 79.405988 -27.649932) (xy 79.406237 -27.657113) (xy 79.410236 -27.670907)
			(xy 79.413862 -27.67711) (xy 79.417672 -27.682952) (xy 79.428086 -27.69235) (xy 79.434944 -27.695652)
			(xy 79.461747 -27.709131) (xy 79.511155 -27.74316) (xy 79.525678 -27.756956) (xy 82.758943 -27.756956)
			(xy 82.758943 -27.702444) (xy 82.766701 -27.648488) (xy 82.78206 -27.596185) (xy 82.804706 -27.546601)
			(xy 82.834179 -27.500744) (xy 82.869879 -27.459549) (xy 82.911078 -27.423854) (xy 82.956937 -27.394386)
			(xy 83.006524 -27.371745) (xy 83.058829 -27.356392) (xy 83.112786 -27.34864) (xy 83.140042 -27.34818)
			(xy 83.154127 -27.34828) (xy 83.182223 -27.350314) (xy 83.196176 -27.352244) (xy 83.210146 -27.354276)
			(xy 83.2358 -27.343862) (xy 83.29803 -27.261058) (xy 83.303164 -27.253536) (xy 83.308229 -27.236056)
			(xy 83.306848 -27.21791) (xy 83.303364 -27.209496) (xy 83.303364 -27.209242) (xy 83.292322 -27.184112)
			(xy 83.276719 -27.131489) (xy 83.268812 -27.077174) (xy 83.268312 -27.04973) (xy 83.268798 -27.022479)
			(xy 83.276554 -26.968531) (xy 83.291909 -26.916236) (xy 83.314551 -26.866659) (xy 83.344017 -26.820809)
			(xy 83.379708 -26.779618) (xy 83.420899 -26.743927) (xy 83.466749 -26.714461) (xy 83.516326 -26.691819)
			(xy 83.568621 -26.676464) (xy 83.622569 -26.668708) (xy 83.677071 -26.668708) (xy 83.731019 -26.676464)
			(xy 83.783314 -26.691819) (xy 83.832891 -26.714461) (xy 83.878741 -26.743927) (xy 83.919932 -26.779618)
			(xy 83.955623 -26.820809) (xy 83.985089 -26.866659) (xy 84.007731 -26.916236) (xy 84.023086 -26.968531)
			(xy 84.030842 -27.022479) (xy 84.031328 -27.04973) (xy 84.031328 -27.050238) (xy 84.030669 -27.081568)
			(xy 84.02038 -27.143379) (xy 84.000135 -27.20268) (xy 83.985862 -27.230578) (xy 83.980528 -27.24023)
			(xy 83.979004 -27.26182) (xy 84.013294 -27.354276) (xy 84.02828 -27.369516) (xy 84.03844 -27.37358)
			(xy 84.038948 -27.37358) (xy 84.065568 -27.384367) (xy 84.115482 -27.412786) (xy 84.160572 -27.448364)
			(xy 84.19982 -27.490299) (xy 84.232339 -27.537644) (xy 84.257394 -27.589327) (xy 84.274419 -27.644182)
			(xy 84.28303 -27.70097) (xy 84.28355 -27.729688) (xy 84.283011 -27.756937) (xy 84.275257 -27.810881)
			(xy 84.259905 -27.863172) (xy 84.237269 -27.912746) (xy 84.207808 -27.958594) (xy 84.172122 -27.999784)
			(xy 84.130938 -28.035475) (xy 84.085093 -28.064943) (xy 84.035522 -28.087587) (xy 83.983233 -28.102945)
			(xy 83.929291 -28.110707) (xy 83.902042 -28.111196) (xy 83.873126 -28.110649) (xy 83.815956 -28.101926)
			(xy 83.760758 -28.084674) (xy 83.708796 -28.059288) (xy 83.661261 -28.026349) (xy 83.619243 -27.986613)
			(xy 83.601052 -27.96413) (xy 83.593468 -27.955299) (xy 83.572549 -27.945131) (xy 83.56092 -27.944572)
			(xy 83.481164 -27.944572) (xy 83.469527 -27.94508) (xy 83.448617 -27.955288) (xy 83.441032 -27.96413)
			(xy 83.422831 -27.986604) (xy 83.380812 -28.026339) (xy 83.333279 -28.059278) (xy 83.28132 -28.084668)
			(xy 83.226125 -28.101926) (xy 83.168957 -28.110659) (xy 83.140042 -28.111196) (xy 83.112786 -28.11076)
			(xy 83.058829 -28.103008) (xy 83.006524 -28.087655) (xy 82.956937 -28.065014) (xy 82.911078 -28.035546)
			(xy 82.869879 -27.999851) (xy 82.834179 -27.958656) (xy 82.804706 -27.912799) (xy 82.78206 -27.863215)
			(xy 82.766701 -27.810912) (xy 82.758943 -27.756956) (xy 79.525678 -27.756956) (xy 79.554651 -27.784478)
			(xy 79.573374 -27.80792) (xy 79.575152 -27.810206) (xy 79.577184 -27.812492) (xy 79.58582 -27.821128)
			(xy 79.591006 -27.824771) (xy 79.602698 -27.829648) (xy 79.608934 -27.83078) (xy 79.671164 -27.839924)
			(xy 79.671672 -27.839924) (xy 79.679546 -27.841194) (xy 79.684568 -27.841843) (xy 79.69468 -27.841329)
			(xy 79.699612 -27.840178) (xy 79.708756 -27.837892) (xy 79.717138 -27.831796) (xy 79.741859 -27.814333)
			(xy 79.795665 -27.786623) (xy 79.853172 -27.767759) (xy 79.912937 -27.758215) (xy 79.943198 -27.757628)
			(xy 79.951072 -27.757628) (xy 79.979051 -27.758698) (xy 80.034258 -27.768024) (xy 80.08751 -27.78532)
			(xy 80.13766 -27.810214) (xy 80.183634 -27.842172) (xy 80.224441 -27.880507) (xy 80.259207 -27.924396)
			(xy 80.273652 -27.948382) (xy 80.282034 -27.95905) (xy 80.284574 -27.96159) (xy 80.289654 -27.9654)
			(xy 80.292448 -27.966924) (xy 80.298325 -27.970067) (xy 80.311187 -27.973541) (xy 80.317848 -27.973782)
			(xy 80.392016 -27.973782) (xy 80.398621 -27.973568) (xy 80.411371 -27.970107) (xy 80.417162 -27.966924)
			(xy 80.437736 -27.95524) (xy 80.447896 -27.947366) (xy 80.452468 -27.943048) (xy 80.45577 -27.93746)
			(xy 80.470804 -27.914228) (xy 80.506513 -27.871957) (xy 80.547948 -27.835282) (xy 80.594244 -27.804971)
			(xy 80.644429 -27.78166) (xy 80.697453 -27.765836) (xy 80.752207 -27.757832) (xy 80.779874 -27.757374)
			(xy 80.783176 -27.757374) (xy 80.795114 -27.757882) (xy 80.822907 -27.759482) (xy 80.877624 -27.769734)
			(xy 80.93027 -27.78783) (xy 80.979728 -27.813384) (xy 81.024946 -27.845855) (xy 81.064965 -27.884553)
			(xy 81.098935 -27.928657) (xy 81.126134 -27.977229) (xy 81.145986 -28.029238) (xy 81.158068 -28.08358)
			(xy 81.162124 -28.139101) (xy 81.162121 -28.139136) (xy 81.667856 -28.139136) (xy 81.671927 -28.083514)
			(xy 81.684053 -28.029077) (xy 81.703976 -27.976986) (xy 81.731272 -27.928351) (xy 81.765358 -27.884208)
			(xy 81.805507 -27.845499) (xy 81.850865 -27.813048) (xy 81.900465 -27.787547) (xy 81.953249 -27.76954)
			(xy 82.008092 -27.75941) (xy 82.063826 -27.757373) (xy 82.119263 -27.763473) (xy 82.17322 -27.777579)
			(xy 82.224549 -27.799391) (xy 82.272155 -27.828445) (xy 82.315023 -27.86412) (xy 82.35224 -27.905657)
			(xy 82.383013 -27.95217) (xy 82.406685 -28.002667) (xy 82.422753 -28.056074) (xy 82.430873 -28.11125)
			(xy 82.431382 -28.139136) (xy 82.430873 -28.167022) (xy 82.422753 -28.222198) (xy 82.406685 -28.275605)
			(xy 82.383013 -28.326102) (xy 82.35224 -28.372615) (xy 82.315023 -28.414152) (xy 82.272155 -28.449827)
			(xy 82.224549 -28.478881) (xy 82.17322 -28.500693) (xy 82.119263 -28.514799) (xy 82.063826 -28.520899)
			(xy 82.008092 -28.518862) (xy 81.953249 -28.508732) (xy 81.900465 -28.490725) (xy 81.850865 -28.465224)
			(xy 81.805507 -28.432773) (xy 81.765358 -28.394064) (xy 81.731272 -28.349921) (xy 81.703976 -28.301286)
			(xy 81.684053 -28.249195) (xy 81.671927 -28.194758) (xy 81.667856 -28.139136) (xy 81.162121 -28.139136)
			(xy 81.158067 -28.194623) (xy 81.145985 -28.248965) (xy 81.126133 -28.300974) (xy 81.098933 -28.349546)
			(xy 81.064963 -28.393649) (xy 81.024944 -28.432347) (xy 80.979725 -28.464817) (xy 80.930268 -28.490371)
			(xy 80.877621 -28.508466) (xy 80.822904 -28.518718) (xy 80.795114 -28.52039) (xy 80.783176 -28.520898)
			(xy 80.779874 -28.520898) (xy 80.752205 -28.520411) (xy 80.697447 -28.512429) (xy 80.644416 -28.496621)
			(xy 80.594224 -28.473319) (xy 80.547925 -28.443012) (xy 80.506488 -28.406335) (xy 80.470784 -28.364058)
			(xy 80.45577 -28.340812) (xy 80.452468 -28.335224) (xy 80.447896 -28.330906) (xy 80.437736 -28.323032)
			(xy 80.417162 -28.311348) (xy 80.411344 -28.308229) (xy 80.398612 -28.304756) (xy 80.392016 -28.30449)
			(xy 80.315054 -28.30449) (xy 80.302865 -28.305886) (xy 80.281788 -28.318371) (xy 80.274668 -28.328366)
			(xy 80.259994 -28.353005) (xy 80.224412 -28.397977) (xy 80.182502 -28.43712) (xy 80.135208 -28.469552)
			(xy 80.083594 -28.494543) (xy 80.028822 -28.511531) (xy 79.972125 -28.520133) (xy 79.943452 -28.520644)
			(xy 79.943198 -28.520644) (xy 79.913405 -28.520071) (xy 79.854543 -28.510807) (xy 79.797836 -28.492506)
			(xy 79.744664 -28.465612) (xy 79.696319 -28.430778) (xy 79.653977 -28.388853) (xy 79.635858 -28.365196)
			(xy 79.630329 -28.359353) (xy 79.616469 -28.351208) (xy 79.60868 -28.349194) (xy 79.605124 -28.348432)
			(xy 79.534258 -28.338018) (xy 79.524954 -28.336966) (xy 79.506682 -28.341001) (xy 79.498698 -28.345892)
			(xy 79.49692 -28.347162) (xy 79.491332 -28.351226) (xy 79.490316 -28.351734) (xy 79.484474 -28.356052)
			(xy 79.478886 -28.359862) (xy 79.475838 -28.363418) (xy 79.469996 -28.371038) (xy 79.456026 -28.396438)
			(xy 79.4537 -28.4016) (xy 79.451129 -28.412624) (xy 79.450946 -28.418282) (xy 79.450946 -28.42387)
			(xy 79.451123 -28.429531) (xy 79.453677 -28.440561) (xy 79.456026 -28.445714) (xy 79.46898 -28.469082)
			(xy 79.475838 -28.478988) (xy 79.479394 -28.482798) (xy 79.480918 -28.483814) (xy 79.484982 -28.486608)
			(xy 79.491078 -28.490926) (xy 79.491586 -28.491434) (xy 79.512513 -28.506804) (xy 79.550403 -28.542306)
			(xy 79.583115 -28.582628) (xy 79.610042 -28.627023) (xy 79.630685 -28.674666) (xy 79.64466 -28.724672)
			(xy 79.651707 -28.776115) (xy 79.652114 -28.802076) (xy 79.651658 -28.82893) (xy 79.644131 -28.882107)
			(xy 79.629223 -28.933704) (xy 79.607227 -28.9827) (xy 79.578579 -29.028129) (xy 79.543844 -29.069092)
			(xy 79.503709 -29.10478) (xy 79.458966 -29.134488) (xy 79.434944 -29.1465) (xy 79.43469 -29.146754)
			(xy 79.428333 -29.14999) (xy 79.417615 -29.159395) (xy 79.413608 -29.165296) (xy 79.409798 -29.171138)
			(xy 79.407766 -29.17825) (xy 79.405988 -29.191712) (xy 79.405988 -29.224732) (xy 79.406237 -29.231913)
			(xy 79.410236 -29.245707) (xy 79.413862 -29.25191) (xy 79.417672 -29.257752) (xy 79.428086 -29.26715)
			(xy 79.434944 -29.270452) (xy 79.458978 -29.282443) (xy 79.503715 -29.312162) (xy 79.543847 -29.347857)
			(xy 79.578582 -29.388823) (xy 79.607233 -29.434253) (xy 79.629236 -29.483249) (xy 79.644156 -29.534844)
			(xy 79.6517 -29.588021) (xy 79.652114 -29.614876) (xy 79.651582 -29.643794) (xy 79.642858 -29.700967)
			(xy 79.625607 -29.75617) (xy 79.600224 -29.808137) (xy 79.567289 -29.855679) (xy 79.527558 -29.897706)
			(xy 79.505048 -29.915866) (xy 79.497666 -29.922151) (xy 79.487877 -29.938866) (xy 79.485998 -29.948378)
			(xy 79.48549 -29.955236) (xy 79.48549 -30.036516) (xy 79.485998 -30.043374) (xy 79.487865 -30.05289)
			(xy 79.497659 -30.069607) (xy 79.505048 -30.075886) (xy 79.527533 -30.094075) (xy 79.567274 -30.136091)
			(xy 79.600215 -30.183626) (xy 79.625602 -30.235588) (xy 79.642854 -30.290788) (xy 79.651574 -30.34796)
			(xy 79.652114 -30.376876) (xy 79.651658 -30.40373) (xy 79.644131 -30.456907) (xy 79.629223 -30.508504)
			(xy 79.607227 -30.5575) (xy 79.578579 -30.602929) (xy 79.543844 -30.643892) (xy 79.503709 -30.67958)
			(xy 79.458966 -30.709288) (xy 79.434944 -30.7213) (xy 79.43469 -30.721554) (xy 79.428333 -30.72479)
			(xy 79.417615 -30.734195) (xy 79.413608 -30.740096) (xy 79.409798 -30.745938) (xy 79.407766 -30.75305)
			(xy 79.405988 -30.766512) (xy 79.405988 -31.142432) (xy 79.406242 -31.146242) (xy 79.406242 -31.14675)
			(xy 79.40762 -31.157052) (xy 79.417434 -31.17535) (xy 79.433686 -31.188273) (xy 79.44358 -31.191454)
			(xy 79.443834 -31.191454) (xy 79.471498 -31.196587) (xy 79.525027 -31.213911) (xy 79.575434 -31.238905)
			(xy 79.621625 -31.271029) (xy 79.662599 -31.309585) (xy 79.697469 -31.353739) (xy 79.72548 -31.402534)
			(xy 79.746023 -31.454913) (xy 79.758654 -31.50974) (xy 79.7631 -31.565827) (xy 79.759263 -31.621959)
			(xy 79.747227 -31.676919) (xy 79.731147 -31.719266) (xy 80.285334 -31.719266) (xy 80.289405 -31.663644)
			(xy 80.301531 -31.609207) (xy 80.321454 -31.557116) (xy 80.34875 -31.508481) (xy 80.382836 -31.464338)
			(xy 80.422985 -31.425629) (xy 80.468343 -31.393178) (xy 80.517943 -31.367677) (xy 80.570727 -31.34967)
			(xy 80.62557 -31.33954) (xy 80.681304 -31.337503) (xy 80.736741 -31.343603) (xy 80.790698 -31.357709)
			(xy 80.842027 -31.379521) (xy 80.889633 -31.408575) (xy 80.932501 -31.44425) (xy 80.969718 -31.485787)
			(xy 81.000491 -31.5323) (xy 81.024163 -31.582797) (xy 81.040231 -31.636204) (xy 81.044381 -31.664402)
			(xy 81.560922 -31.664402) (xy 81.564993 -31.60878) (xy 81.577119 -31.554343) (xy 81.597042 -31.502252)
			(xy 81.624338 -31.453617) (xy 81.658424 -31.409474) (xy 81.698573 -31.370765) (xy 81.743931 -31.338314)
			(xy 81.793531 -31.312813) (xy 81.846315 -31.294806) (xy 81.901158 -31.284676) (xy 81.956892 -31.282639)
			(xy 82.012329 -31.288739) (xy 82.066286 -31.302845) (xy 82.117615 -31.324657) (xy 82.165221 -31.353711)
			(xy 82.208089 -31.389386) (xy 82.245306 -31.430923) (xy 82.276079 -31.477436) (xy 82.299751 -31.527933)
			(xy 82.315819 -31.58134) (xy 82.323939 -31.636516) (xy 82.324448 -31.664402) (xy 82.323939 -31.692288)
			(xy 82.315819 -31.747464) (xy 82.306879 -31.777178) (xy 82.826096 -31.777178) (xy 82.830167 -31.721556)
			(xy 82.842293 -31.667119) (xy 82.862216 -31.615028) (xy 82.889512 -31.566393) (xy 82.923598 -31.52225)
			(xy 82.963747 -31.483541) (xy 83.009105 -31.45109) (xy 83.058705 -31.425589) (xy 83.111489 -31.407582)
			(xy 83.166332 -31.397452) (xy 83.222066 -31.395415) (xy 83.277503 -31.401515) (xy 83.33146 -31.415621)
			(xy 83.382789 -31.437433) (xy 83.430395 -31.466487) (xy 83.473263 -31.502162) (xy 83.51048 -31.543699)
			(xy 83.541253 -31.590212) (xy 83.564925 -31.640709) (xy 83.580993 -31.694116) (xy 83.589113 -31.749292)
			(xy 83.589622 -31.777178) (xy 83.589113 -31.805064) (xy 83.580993 -31.86024) (xy 83.564925 -31.913647)
			(xy 83.541253 -31.964144) (xy 83.51048 -32.010657) (xy 83.473263 -32.052194) (xy 83.430395 -32.087869)
			(xy 83.382789 -32.116923) (xy 83.33146 -32.138735) (xy 83.277503 -32.152841) (xy 83.222066 -32.158941)
			(xy 83.166332 -32.156904) (xy 83.111489 -32.146774) (xy 83.058705 -32.128767) (xy 83.009105 -32.103266)
			(xy 82.963747 -32.070815) (xy 82.923598 -32.032106) (xy 82.889512 -31.987963) (xy 82.862216 -31.939328)
			(xy 82.842293 -31.887237) (xy 82.830167 -31.8328) (xy 82.826096 -31.777178) (xy 82.306879 -31.777178)
			(xy 82.299751 -31.800871) (xy 82.276079 -31.851368) (xy 82.245306 -31.897881) (xy 82.208089 -31.939418)
			(xy 82.165221 -31.975093) (xy 82.117615 -32.004147) (xy 82.066286 -32.025959) (xy 82.012329 -32.040065)
			(xy 81.956892 -32.046165) (xy 81.901158 -32.044128) (xy 81.846315 -32.033998) (xy 81.793531 -32.015991)
			(xy 81.743931 -31.99049) (xy 81.698573 -31.958039) (xy 81.658424 -31.91933) (xy 81.624338 -31.875187)
			(xy 81.597042 -31.826552) (xy 81.577119 -31.774461) (xy 81.564993 -31.720024) (xy 81.560922 -31.664402)
			(xy 81.044381 -31.664402) (xy 81.048351 -31.69138) (xy 81.04886 -31.719266) (xy 81.048351 -31.747152)
			(xy 81.040231 -31.802328) (xy 81.024163 -31.855735) (xy 81.000491 -31.906232) (xy 80.969718 -31.952745)
			(xy 80.932501 -31.994282) (xy 80.889633 -32.029957) (xy 80.842027 -32.059011) (xy 80.790698 -32.080823)
			(xy 80.736741 -32.094929) (xy 80.681304 -32.101029) (xy 80.62557 -32.098992) (xy 80.570727 -32.088862)
			(xy 80.517943 -32.070855) (xy 80.468343 -32.045354) (xy 80.422985 -32.012903) (xy 80.382836 -31.974194)
			(xy 80.34875 -31.930051) (xy 80.321454 -31.881416) (xy 80.301531 -31.829325) (xy 80.289405 -31.774888)
			(xy 80.285334 -31.719266) (xy 79.731147 -31.719266) (xy 79.727254 -31.729517) (xy 79.699774 -31.778613)
			(xy 79.665385 -31.823143) (xy 79.624831 -31.862142) (xy 79.578992 -31.894765) (xy 79.528859 -31.920305)
			(xy 79.475521 -31.938208) (xy 79.447898 -31.943548) (xy 79.444342 -31.94431) (xy 79.434304 -31.947373)
			(xy 79.41773 -31.960212) (xy 79.407694 -31.978618) (xy 79.406242 -31.989014) (xy 79.406242 -31.989522)
			(xy 79.405988 -31.993332) (xy 79.405988 -33.507426) (xy 79.406247 -33.514837) (xy 79.410516 -33.52903)
			(xy 79.41437 -33.535366) (xy 79.418495 -33.541187) (xy 79.429326 -33.550462) (xy 79.435706 -33.553654)
			(xy 79.479394 -33.572704) (xy 79.479902 -33.572704) (xy 79.522574 -33.590992) (xy 79.529479 -33.593682)
			(xy 79.544196 -33.595354) (xy 79.55153 -33.594294) (xy 79.558642 -33.593024) (xy 79.57185 -33.58642)
			(xy 79.577438 -33.581086) (xy 79.584753 -33.574198) (xy 79.600001 -33.561111) (xy 79.607918 -33.554924)
			(xy 79.614014 -33.550098) (xy 79.615538 -33.549082) (xy 79.619856 -33.542224) (xy 79.622024 -33.538478)
			(xy 79.625216 -33.530435) (xy 79.626206 -33.526222) (xy 79.632556 -33.497266) (xy 79.640938 -33.459166)
			(xy 79.641533 -33.455319) (xy 79.641662 -33.447536) (xy 79.641192 -33.443672) (xy 79.641192 -33.442656)
			(xy 79.639922 -33.434782) (xy 79.637382 -33.429956) (xy 79.635604 -33.426654) (xy 79.62167 -33.399021)
			(xy 79.601955 -33.340362) (xy 79.591978 -33.279288) (xy 79.591408 -33.248346) (xy 79.591408 -33.242504)
			(xy 79.592272 -33.215517) (xy 79.60067 -33.16218) (xy 79.616506 -33.11056) (xy 79.639463 -33.061689)
			(xy 79.669082 -33.016544) (xy 79.704771 -32.976027) (xy 79.745818 -32.940948) (xy 79.791402 -32.912008)
			(xy 79.840611 -32.889786) (xy 79.892462 -32.874725) (xy 79.945919 -32.867127) (xy 79.972916 -32.866584)
			(xy 80.000167 -32.867071) (xy 80.054113 -32.874829) (xy 80.106406 -32.890186) (xy 80.155982 -32.912828)
			(xy 80.201831 -32.942294) (xy 80.24302 -32.977986) (xy 80.278711 -33.019175) (xy 80.308176 -33.065025)
			(xy 80.330817 -33.114601) (xy 80.346173 -33.166895) (xy 80.35393 -33.220841) (xy 80.354424 -33.248092)
			(xy 80.353874 -33.277218) (xy 80.345017 -33.334794) (xy 80.327509 -33.390354) (xy 80.301756 -33.442605)
			(xy 80.268357 -33.490333) (xy 80.22809 -33.532427) (xy 80.205326 -33.550606) (xy 80.197706 -33.556448)
			(xy 80.193134 -33.563814) (xy 80.191258 -33.566984) (xy 80.188325 -33.57374) (xy 80.187292 -33.577276)
			(xy 80.185768 -33.584134) (xy 80.17256 -33.644078) (xy 80.171653 -33.648592) (xy 80.171274 -33.657791)
			(xy 80.171798 -33.662366) (xy 80.173068 -33.670748) (xy 80.177386 -33.678876) (xy 80.184921 -33.693423)
			(xy 80.197764 -33.723564) (xy 80.20304 -33.739074) (xy 80.206088 -33.748218) (xy 80.211676 -33.755076)
			(xy 80.214564 -33.758507) (xy 80.221333 -33.764387) (xy 80.225138 -33.76676) (xy 80.283304 -33.801812)
			(xy 80.29067 -33.80613) (xy 80.30845 -33.809178) (xy 80.317594 -33.807654) (xy 80.333775 -33.804892)
			(xy 80.36646 -33.801837) (xy 80.382872 -33.801558) (xy 80.385158 -33.801558) (xy 80.386174 -33.801558)
			(xy 80.386428 -33.801558) (xy 80.413646 -33.802093) (xy 80.467517 -33.809934) (xy 80.519726 -33.825351)
			(xy 80.569214 -33.848033) (xy 80.584205 -33.857692) (xy 81.490056 -33.857692) (xy 81.494127 -33.80207)
			(xy 81.506253 -33.747633) (xy 81.526176 -33.695542) (xy 81.553472 -33.646907) (xy 81.587558 -33.602764)
			(xy 81.627707 -33.564055) (xy 81.673065 -33.531604) (xy 81.722665 -33.506103) (xy 81.775449 -33.488096)
			(xy 81.830292 -33.477966) (xy 81.886026 -33.475929) (xy 81.941463 -33.482029) (xy 81.99542 -33.496135)
			(xy 82.046749 -33.517947) (xy 82.094355 -33.547001) (xy 82.137223 -33.582676) (xy 82.17444 -33.624213)
			(xy 82.205213 -33.670726) (xy 82.228885 -33.721223) (xy 82.244953 -33.77463) (xy 82.253073 -33.829806)
			(xy 82.253582 -33.857692) (xy 82.253073 -33.885578) (xy 82.244953 -33.940754) (xy 82.228885 -33.994161)
			(xy 82.205213 -34.044658) (xy 82.17444 -34.091171) (xy 82.137223 -34.132708) (xy 82.094355 -34.168383)
			(xy 82.046749 -34.197437) (xy 81.99542 -34.219249) (xy 81.941463 -34.233355) (xy 81.886026 -34.239455)
			(xy 81.830292 -34.237418) (xy 81.775449 -34.227288) (xy 81.722665 -34.209281) (xy 81.673065 -34.18378)
			(xy 81.627707 -34.151329) (xy 81.587558 -34.11262) (xy 81.553472 -34.068477) (xy 81.526176 -34.019842)
			(xy 81.506253 -33.967751) (xy 81.494127 -33.913314) (xy 81.490056 -33.857692) (xy 80.584205 -33.857692)
			(xy 80.614976 -33.877519) (xy 80.656082 -33.91321) (xy 80.691697 -33.954381) (xy 80.7211 -34.000196)
			(xy 80.743692 -34.049725) (xy 80.759014 -34.101962) (xy 80.766757 -34.155847) (xy 80.767174 -34.183066)
			(xy 80.76673 -34.20975) (xy 80.759294 -34.262598) (xy 80.744563 -34.313893) (xy 80.722825 -34.362634)
			(xy 80.694503 -34.407867) (xy 80.660152 -34.448711) (xy 80.620442 -34.484366) (xy 80.576148 -34.514137)
			(xy 80.528137 -34.537442) (xy 80.477346 -34.553825) (xy 80.424766 -34.562968) (xy 80.398112 -34.56432)
			(xy 80.397604 -34.56432) (xy 80.389984 -34.564574) (xy 80.389222 -34.564574) (xy 80.385412 -34.564828)
			(xy 80.358851 -34.56437) (xy 80.306242 -34.557002) (xy 80.255165 -34.542407) (xy 80.206606 -34.520868)
			(xy 80.161504 -34.4928) (xy 80.120733 -34.458746) (xy 80.08508 -34.419366) (xy 80.055235 -34.37542)
			(xy 80.031775 -34.327759) (xy 80.022954 -34.3027) (xy 80.019906 -34.292286) (xy 80.014318 -34.285428)
			(xy 80.011927 -34.282601) (xy 80.006442 -34.277628) (xy 80.003396 -34.275522) (xy 79.94142 -34.238438)
			(xy 79.93783 -34.236501) (xy 79.930172 -34.233689) (xy 79.92618 -34.23285) (xy 79.918052 -34.231326)
			(xy 79.913734 -34.232088) (xy 79.9084 -34.233104) (xy 79.89159 -34.23595) (xy 79.85763 -34.239007)
			(xy 79.840582 -34.2392) (xy 79.840328 -34.2392) (xy 79.811319 -34.238655) (xy 79.753969 -34.229868)
			(xy 79.698608 -34.212507) (xy 79.646511 -34.186973) (xy 79.598875 -34.153852) (xy 79.577438 -34.134298)
			(xy 79.576676 -34.133536) (xy 79.571216 -34.128823) (xy 79.558323 -34.122371) (xy 79.551276 -34.120836)
			(xy 79.544164 -34.119566) (xy 79.536798 -34.120582) (xy 79.533205 -34.12102) (xy 79.526192 -34.122803)
			(xy 79.522828 -34.124138) (xy 79.436722 -34.161222) (xy 79.427839 -34.165536) (xy 79.413997 -34.179593)
			(xy 79.4065 -34.197841) (xy 79.405988 -34.207704) (xy 79.405988 -35.264852) (xy 81.902298 -35.264852)
			(xy 81.906369 -35.20923) (xy 81.918495 -35.154793) (xy 81.938418 -35.102702) (xy 81.965714 -35.054067)
			(xy 81.9998 -35.009924) (xy 82.039949 -34.971215) (xy 82.085307 -34.938764) (xy 82.134907 -34.913263)
			(xy 82.187691 -34.895256) (xy 82.242534 -34.885126) (xy 82.298268 -34.883089) (xy 82.353705 -34.889189)
			(xy 82.407662 -34.903295) (xy 82.458991 -34.925107) (xy 82.506597 -34.954161) (xy 82.549465 -34.989836)
			(xy 82.574299 -35.017553) (xy 84.219756 -35.017553) (xy 84.219756 -34.963047) (xy 84.227513 -34.909097)
			(xy 84.242868 -34.856799) (xy 84.265511 -34.80722) (xy 84.294978 -34.761367) (xy 84.330671 -34.720174)
			(xy 84.371864 -34.684481) (xy 84.417716 -34.655013) (xy 84.467296 -34.63237) (xy 84.519593 -34.617014)
			(xy 84.573543 -34.609256) (xy 84.600796 -34.60877) (xy 84.617908 -34.608957) (xy 84.651995 -34.612012)
			(xy 84.668868 -34.614866) (xy 84.680159 -34.616245) (xy 84.702049 -34.610163) (xy 84.711032 -34.603182)
			(xy 84.735416 -34.5821) (xy 84.743836 -34.574176) (xy 84.753105 -34.553021) (xy 84.753196 -34.54146)
			(xy 84.752688 -34.522664) (xy 84.752688 -33.65881) (xy 84.753196 -33.638744) (xy 84.752971 -33.627301)
			(xy 84.74388 -33.606331) (xy 84.73567 -33.598358) (xy 84.711032 -33.577022) (xy 84.702028 -33.569952)
			(xy 84.679949 -33.563993) (xy 84.668614 -33.565592) (xy 84.651806 -33.568452) (xy 84.617845 -33.571506)
			(xy 84.600796 -33.571688) (xy 84.573544 -33.571242) (xy 84.519593 -33.563485) (xy 84.467296 -33.548128)
			(xy 84.417717 -33.525486) (xy 84.371865 -33.496018) (xy 84.330673 -33.460324) (xy 84.29498 -33.419132)
			(xy 84.265512 -33.373279) (xy 84.24287 -33.3237) (xy 84.227515 -33.271403) (xy 84.219758 -33.217452)
			(xy 84.219758 -33.162948) (xy 84.227515 -33.108997) (xy 84.24287 -33.0567) (xy 84.265512 -33.007121)
			(xy 84.29498 -32.961268) (xy 84.330673 -32.920076) (xy 84.371865 -32.884382) (xy 84.417717 -32.854914)
			(xy 84.467296 -32.832272) (xy 84.519593 -32.816915) (xy 84.573544 -32.809158) (xy 84.600796 -32.808672)
			(xy 84.627804 -32.809123) (xy 84.681282 -32.816729) (xy 84.733153 -32.831804) (xy 84.782378 -32.854045)
			(xy 84.827972 -32.883008) (xy 84.869025 -32.918115) (xy 84.904714 -32.958661) (xy 84.934327 -33.003837)
			(xy 84.957269 -33.052739) (xy 84.973084 -33.104389) (xy 84.977732 -33.130998) (xy 84.979256 -33.141666)
			(xy 84.990686 -33.159446) (xy 85.06206 -33.206944) (xy 85.070982 -33.212306) (xy 85.091452 -33.215972)
			(xy 85.101684 -33.214056) (xy 85.102446 -33.214056) (xy 85.129015 -33.207938) (xy 85.183135 -33.201317)
			(xy 85.210396 -33.200848) (xy 85.23772 -33.201311) (xy 85.291968 -33.207927) (xy 85.3186 -33.214056)
			(xy 85.319108 -33.214056) (xy 85.32934 -33.215896) (xy 85.349785 -33.212237) (xy 85.358732 -33.206944)
			(xy 85.430106 -33.159446) (xy 85.441536 -33.141666) (xy 85.44306 -33.130998) (xy 85.447669 -33.104384)
			(xy 85.463503 -33.052742) (xy 85.486461 -33.00385) (xy 85.516083 -32.958683) (xy 85.551778 -32.918144)
			(xy 85.592832 -32.883043) (xy 85.638426 -32.854081) (xy 85.687648 -32.831838) (xy 85.739514 -32.816757)
			(xy 85.792989 -32.80914) (xy 85.819996 -32.808672) (xy 85.847367 -32.809123) (xy 85.901547 -32.816942)
			(xy 85.954051 -32.832433) (xy 86.003798 -32.855279) (xy 86.049764 -32.885008) (xy 86.070694 -32.902652)
			(xy 86.070948 -32.902906) (xy 86.078045 -32.908478) (xy 86.094954 -32.914733) (xy 86.103968 -32.915098)
			(xy 86.171024 -32.915098) (xy 86.180042 -32.914753) (xy 86.196959 -32.908497) (xy 86.204044 -32.902906)
			(xy 86.204044 -32.902652) (xy 86.204298 -32.902652) (xy 86.225227 -32.885008) (xy 86.2712 -32.855296)
			(xy 86.320948 -32.83246) (xy 86.37345 -32.81697) (xy 86.427626 -32.809144) (xy 86.454996 -32.808672)
			(xy 86.472108 -32.808858) (xy 86.506195 -32.811914) (xy 86.523068 -32.814768) (xy 86.534359 -32.816146)
			(xy 86.556249 -32.810064) (xy 86.565232 -32.803084) (xy 86.589616 -32.782002) (xy 86.598035 -32.774077)
			(xy 86.607305 -32.752923) (xy 86.607396 -32.741362) (xy 86.606888 -32.722566) (xy 86.606888 -31.858712)
			(xy 86.607396 -31.838646) (xy 86.60717 -31.827203) (xy 86.59808 -31.806233) (xy 86.58987 -31.79826)
			(xy 86.565232 -31.776924) (xy 86.556228 -31.769854) (xy 86.534149 -31.763895) (xy 86.522814 -31.765494)
			(xy 86.506006 -31.768354) (xy 86.472045 -31.771408) (xy 86.454996 -31.77159) (xy 86.427626 -31.771129)
			(xy 86.373446 -31.76331) (xy 86.320943 -31.74782) (xy 86.271196 -31.724977) (xy 86.22523 -31.695252)
			(xy 86.204298 -31.67761) (xy 86.19744 -31.671514) (xy 86.180422 -31.665164) (xy 86.095078 -31.665164)
			(xy 86.077806 -31.671768) (xy 86.070948 -31.677864) (xy 86.050016 -31.695504) (xy 86.004047 -31.725224)
			(xy 85.9543 -31.748064) (xy 85.901798 -31.763553) (xy 85.84762 -31.771375) (xy 85.82025 -31.771844)
			(xy 85.819996 -31.771844) (xy 85.793018 -31.771378) (xy 85.739599 -31.763796) (xy 85.687783 -31.748756)
			(xy 85.638606 -31.726559) (xy 85.593051 -31.697649) (xy 85.552028 -31.662602) (xy 85.516358 -31.622121)
			(xy 85.486753 -31.577013) (xy 85.463806 -31.528182) (xy 85.447975 -31.476602) (xy 85.443314 -31.450026)
			(xy 85.441137 -31.439799) (xy 85.429867 -31.422218) (xy 85.42147 -31.41599) (xy 85.350096 -31.368492)
			(xy 85.329014 -31.364682) (xy 85.318854 -31.367222) (xy 85.292153 -31.3733) (xy 85.237777 -31.379791)
			(xy 85.210396 -31.380176) (xy 85.183014 -31.379798) (xy 85.128638 -31.373305) (xy 85.101938 -31.367222)
			(xy 85.091778 -31.364682) (xy 85.070696 -31.368492) (xy 84.990432 -31.421832) (xy 84.979256 -31.439358)
			(xy 84.977478 -31.450026) (xy 84.972779 -31.47659) (xy 84.956924 -31.528152) (xy 84.933963 -31.576966)
			(xy 84.904354 -31.622059) (xy 84.868687 -31.662529) (xy 84.827674 -31.697571) (xy 84.782133 -31.726486)
			(xy 84.732972 -31.748695) (xy 84.681173 -31.763757) (xy 84.627768 -31.771371) (xy 84.600796 -31.771844)
			(xy 84.573548 -31.771286) (xy 84.519605 -31.763529) (xy 84.467316 -31.748175) (xy 84.417744 -31.725536)
			(xy 84.371899 -31.696073) (xy 84.330713 -31.660384) (xy 84.295025 -31.619198) (xy 84.265562 -31.573352)
			(xy 84.242923 -31.52378) (xy 84.22757 -31.471491) (xy 84.219814 -31.417548) (xy 84.219814 -31.363052)
			(xy 84.22757 -31.309109) (xy 84.242923 -31.25682) (xy 84.265562 -31.207248) (xy 84.295025 -31.161402)
			(xy 84.330713 -31.120216) (xy 84.371899 -31.084527) (xy 84.417744 -31.055064) (xy 84.467316 -31.032425)
			(xy 84.519605 -31.017071) (xy 84.573548 -31.009314) (xy 84.600796 -31.008828) (xy 84.617908 -31.009015)
			(xy 84.651995 -31.01207) (xy 84.668868 -31.014924) (xy 84.680159 -31.016313) (xy 84.702051 -31.010225)
			(xy 84.711032 -31.00324) (xy 84.735416 -30.982158) (xy 84.743856 -30.974251) (xy 84.753114 -30.953083)
			(xy 84.753196 -30.941518) (xy 84.752688 -30.922722) (xy 84.752688 -30.058868) (xy 84.753196 -30.038802)
			(xy 84.752996 -30.027357) (xy 84.743887 -30.006387) (xy 84.73567 -29.998416) (xy 84.711032 -29.97708)
			(xy 84.702024 -29.970015) (xy 84.679948 -29.964051) (xy 84.668614 -29.96565) (xy 84.651806 -29.96851)
			(xy 84.617845 -29.971564) (xy 84.600796 -29.971746) (xy 84.573548 -29.971184) (xy 84.519606 -29.963427)
			(xy 84.467317 -29.948073) (xy 84.417745 -29.925434) (xy 84.3719 -29.895971) (xy 84.330714 -29.860283)
			(xy 84.295027 -29.819097) (xy 84.265564 -29.773251) (xy 84.242925 -29.723679) (xy 84.227572 -29.67139)
			(xy 84.219816 -29.617448) (xy 84.219816 -29.562952) (xy 84.227572 -29.50901) (xy 84.242925 -29.456721)
			(xy 84.265564 -29.407149) (xy 84.295027 -29.361303) (xy 84.330714 -29.320117) (xy 84.3719 -29.284429)
			(xy 84.417745 -29.254966) (xy 84.467317 -29.232327) (xy 84.519606 -29.216973) (xy 84.573548 -29.209216)
			(xy 84.600796 -29.20873) (xy 84.627803 -29.209217) (xy 84.681278 -29.216821) (xy 84.733145 -29.231894)
			(xy 84.782368 -29.254132) (xy 84.827961 -29.283092) (xy 84.869013 -29.318194) (xy 84.904703 -29.358736)
			(xy 84.934317 -29.403907) (xy 84.957263 -29.452804) (xy 84.973081 -29.504449) (xy 84.977732 -29.531056)
			(xy 84.979256 -29.541724) (xy 84.990686 -29.559504) (xy 85.06206 -29.607002) (xy 85.070983 -29.612362)
			(xy 85.091452 -29.616031) (xy 85.101684 -29.614114) (xy 85.102446 -29.614114) (xy 85.129021 -29.608057)
			(xy 85.183142 -29.601567) (xy 85.210396 -29.60116) (xy 85.237714 -29.601541) (xy 85.291963 -29.608039)
			(xy 85.3186 -29.614114) (xy 85.319108 -29.614114) (xy 85.329341 -29.615945) (xy 85.349783 -29.61229)
			(xy 85.358732 -29.607002) (xy 85.430106 -29.559504) (xy 85.441536 -29.541724) (xy 85.44306 -29.531056)
			(xy 85.447713 -29.50445) (xy 85.463539 -29.452809) (xy 85.48649 -29.403916) (xy 85.516106 -29.358747)
			(xy 85.551796 -29.318207) (xy 85.592846 -29.283105) (xy 85.638436 -29.254142) (xy 85.687654 -29.231897)
			(xy 85.739518 -29.216816) (xy 85.79299 -29.209198) (xy 85.819996 -29.20873) (xy 85.847366 -29.209191)
			(xy 85.901546 -29.217009) (xy 85.95405 -29.232499) (xy 86.003796 -29.255342) (xy 86.049763 -29.285068)
			(xy 86.070694 -29.30271) (xy 86.070948 -29.302964) (xy 86.07804 -29.308543) (xy 86.094953 -29.314792)
			(xy 86.103968 -29.315156) (xy 86.171024 -29.315156) (xy 86.180043 -29.31482) (xy 86.196961 -29.308559)
			(xy 86.204044 -29.302964) (xy 86.204044 -29.30271) (xy 86.204298 -29.30271) (xy 86.225221 -29.28506)
			(xy 86.271196 -29.255349) (xy 86.320946 -29.232515) (xy 86.373449 -29.217027) (xy 86.427626 -29.209202)
			(xy 86.454996 -29.20873) (xy 86.472108 -29.208917) (xy 86.506195 -29.211972) (xy 86.523068 -29.214826)
			(xy 86.534359 -29.216214) (xy 86.556251 -29.210127) (xy 86.565232 -29.203142) (xy 86.589616 -29.18206)
			(xy 86.598055 -29.174153) (xy 86.607313 -29.152985) (xy 86.607396 -29.14142) (xy 86.606888 -29.122624)
			(xy 86.606888 -28.25877) (xy 86.607396 -28.238704) (xy 86.607194 -28.227259) (xy 86.598087 -28.206289)
			(xy 86.58987 -28.198318) (xy 86.565232 -28.176982) (xy 86.556224 -28.169918) (xy 86.534148 -28.163953)
			(xy 86.522814 -28.165552) (xy 86.506006 -28.168412) (xy 86.472045 -28.171466) (xy 86.454996 -28.171648)
			(xy 86.427748 -28.171082) (xy 86.373806 -28.163325) (xy 86.321518 -28.147972) (xy 86.271946 -28.125333)
			(xy 86.226101 -28.095869) (xy 86.184916 -28.060182) (xy 86.149228 -28.018996) (xy 86.119766 -27.97315)
			(xy 86.097127 -27.923579) (xy 86.081774 -27.87129) (xy 86.074018 -27.817348) (xy 86.074018 -27.762852)
			(xy 86.081774 -27.70891) (xy 86.097127 -27.656621) (xy 86.119766 -27.60705) (xy 86.149228 -27.561204)
			(xy 86.184916 -27.520018) (xy 86.226101 -27.484331) (xy 86.271946 -27.454867) (xy 86.321518 -27.432228)
			(xy 86.373806 -27.416875) (xy 86.427748 -27.409118) (xy 86.454996 -27.408632) (xy 86.482003 -27.409117)
			(xy 86.535478 -27.416722) (xy 86.587346 -27.431794) (xy 86.636568 -27.454033) (xy 86.682162 -27.482993)
			(xy 86.723214 -27.518095) (xy 86.758904 -27.558637) (xy 86.788518 -27.603808) (xy 86.811463 -27.652706)
			(xy 86.827281 -27.704351) (xy 86.831932 -27.730958) (xy 86.833456 -27.741626) (xy 86.844886 -27.759406)
			(xy 86.91626 -27.806904) (xy 86.925183 -27.812265) (xy 86.945652 -27.815933) (xy 86.955884 -27.814016)
			(xy 86.956646 -27.814016) (xy 86.983215 -27.807897) (xy 87.037335 -27.801277) (xy 87.064596 -27.800808)
			(xy 87.086774 -27.80111) (xy 87.13092 -27.805431) (xy 87.152734 -27.809444) (xy 87.162894 -27.811476)
			(xy 87.18296 -27.807412) (xy 87.251286 -27.760168) (xy 87.259455 -27.753962) (xy 87.270462 -27.736669)
			(xy 87.272622 -27.72664) (xy 87.277549 -27.700308) (xy 87.293763 -27.649251) (xy 87.316961 -27.600965)
			(xy 87.346685 -27.556398) (xy 87.382353 -27.516429) (xy 87.423262 -27.481844) (xy 87.468607 -27.453321)
			(xy 87.517496 -27.431423) (xy 87.568969 -27.416581) (xy 87.622011 -27.409086) (xy 87.648796 -27.408632)
			(xy 87.676052 -27.409015) (xy 87.730009 -27.416772) (xy 87.782313 -27.432129) (xy 87.831899 -27.454774)
			(xy 87.877757 -27.484245) (xy 87.918955 -27.519942) (xy 87.954653 -27.56114) (xy 87.984124 -27.606998)
			(xy 88.006769 -27.656583) (xy 88.022127 -27.708887) (xy 88.029885 -27.762844) (xy 88.029885 -27.817356)
			(xy 88.022127 -27.871313) (xy 88.006769 -27.923617) (xy 87.984124 -27.973202) (xy 87.954653 -28.01906)
			(xy 87.918955 -28.060258) (xy 87.877757 -28.095955) (xy 87.831899 -28.125426) (xy 87.782313 -28.148071)
			(xy 87.730009 -28.163428) (xy 87.676052 -28.171185) (xy 87.648796 -28.171648) (xy 87.648034 -28.171648)
			(xy 87.636702 -28.171534) (xy 87.614082 -28.170135) (xy 87.602822 -28.168854) (xy 87.591908 -28.168102)
			(xy 87.57111 -28.174823) (xy 87.56269 -28.181808) (xy 87.53856 -28.203652) (xy 87.53081 -28.211479)
			(xy 87.522258 -28.231755) (xy 87.52205 -28.242768) (xy 87.522304 -28.25877) (xy 87.522304 -29.12237)
			(xy 87.52205 -29.13761) (xy 87.52225 -29.14866) (xy 87.53096 -29.168948) (xy 87.538814 -29.176726)
			(xy 87.56269 -29.198316) (xy 87.571116 -29.20529) (xy 87.591909 -29.212007) (xy 87.602822 -29.21127)
			(xy 87.614081 -29.209981) (xy 87.636702 -29.20858) (xy 87.648034 -29.208476) (xy 87.648796 -29.208476)
			(xy 87.676048 -29.208971) (xy 87.729997 -29.216727) (xy 87.782293 -29.232082) (xy 87.831872 -29.254724)
			(xy 87.877723 -29.28419) (xy 87.918915 -29.319882) (xy 87.954607 -29.361073) (xy 87.984075 -29.406925)
			(xy 88.006716 -29.456503) (xy 88.022072 -29.508799) (xy 88.029829 -29.562748) (xy 88.029829 -29.617252)
			(xy 88.022072 -29.671201) (xy 88.006716 -29.723497) (xy 87.984075 -29.773075) (xy 87.954607 -29.818927)
			(xy 87.918915 -29.860118) (xy 87.877723 -29.89581) (xy 87.831872 -29.925276) (xy 87.782293 -29.947918)
			(xy 87.729997 -29.963273) (xy 87.676048 -29.971029) (xy 87.648796 -29.971492) (xy 87.622049 -29.971026)
			(xy 87.569081 -29.963532) (xy 87.517677 -29.948719) (xy 87.468844 -29.926877) (xy 87.423537 -29.898434)
			(xy 87.382643 -29.863946) (xy 87.346962 -29.824089) (xy 87.317192 -29.779642) (xy 87.293918 -29.731475)
			(xy 87.277593 -29.680532) (xy 87.272622 -29.654246) (xy 87.270844 -29.643832) (xy 87.260176 -29.627068)
			(xy 87.183214 -29.573728) (xy 87.163148 -29.569664) (xy 87.152988 -29.571696) (xy 87.131114 -29.57574)
			(xy 87.086839 -29.580068) (xy 87.064596 -29.580332) (xy 87.037208 -29.579893) (xy 86.982832 -29.573268)
			(xy 86.956138 -29.567124) (xy 86.945978 -29.564584) (xy 86.924896 -29.568394) (xy 86.844632 -29.621734)
			(xy 86.833456 -29.63926) (xy 86.831678 -29.649928) (xy 86.82698 -29.676493) (xy 86.811125 -29.728055)
			(xy 86.788164 -29.776869) (xy 86.758555 -29.821961) (xy 86.722887 -29.862432) (xy 86.681874 -29.897474)
			(xy 86.636333 -29.926388) (xy 86.587172 -29.948597) (xy 86.535373 -29.963659) (xy 86.481968 -29.971273)
			(xy 86.454996 -29.971746) (xy 86.427625 -29.971295) (xy 86.373445 -29.963476) (xy 86.320941 -29.947984)
			(xy 86.271194 -29.925138) (xy 86.225229 -29.89541) (xy 86.204298 -29.877766) (xy 86.204044 -29.877512)
			(xy 86.196948 -29.871939) (xy 86.180039 -29.865684) (xy 86.171024 -29.86532) (xy 86.103968 -29.86532)
			(xy 86.094949 -29.865657) (xy 86.078032 -29.871918) (xy 86.070948 -29.877512) (xy 86.070948 -29.877766)
			(xy 86.070694 -29.877766) (xy 86.049771 -29.895416) (xy 86.003796 -29.925127) (xy 85.954046 -29.947962)
			(xy 85.901544 -29.96345) (xy 85.847366 -29.971274) (xy 85.819996 -29.971746) (xy 85.802948 -29.971542)
			(xy 85.768989 -29.968492) (xy 85.752178 -29.96565) (xy 85.740853 -29.964188) (xy 85.718832 -29.970141)
			(xy 85.70976 -29.97708) (xy 85.685122 -29.998416) (xy 85.676778 -30.006293) (xy 85.667659 -30.027327)
			(xy 85.667596 -30.038802) (xy 85.668104 -30.058868) (xy 85.668104 -30.922722) (xy 85.667596 -30.941518)
			(xy 85.667699 -30.953077) (xy 85.67696 -30.974233) (xy 85.685376 -30.982158) (xy 85.70976 -31.00324)
			(xy 85.718721 -31.010255) (xy 85.740628 -31.016313) (xy 85.751924 -31.014924) (xy 85.768794 -31.012049)
			(xy 85.802883 -31.009) (xy 85.819996 -31.008828) (xy 85.847366 -31.00929) (xy 85.901546 -31.017107)
			(xy 85.954049 -31.032597) (xy 86.003796 -31.05544) (xy 86.049763 -31.085166) (xy 86.070694 -31.102808)
			(xy 86.077552 -31.108904) (xy 86.09457 -31.115254) (xy 86.179914 -31.115254) (xy 86.197186 -31.10865)
			(xy 86.204044 -31.102554) (xy 86.224981 -31.08492) (xy 86.270949 -31.055199) (xy 86.320694 -31.032358)
			(xy 86.373195 -31.016867) (xy 86.427372 -31.009043) (xy 86.454742 -31.008574) (xy 86.454996 -31.008574)
			(xy 86.482004 -31.009024) (xy 86.535483 -31.016629) (xy 86.587353 -31.031704) (xy 86.636578 -31.053945)
			(xy 86.682173 -31.082909) (xy 86.723226 -31.118015) (xy 86.758915 -31.158562) (xy 86.788527 -31.203739)
			(xy 86.81147 -31.252641) (xy 86.827284 -31.304291) (xy 86.831932 -31.3309) (xy 86.833456 -31.341568)
			(xy 86.844886 -31.359348) (xy 86.91626 -31.406846) (xy 86.925182 -31.412208) (xy 86.945652 -31.415874)
			(xy 86.955884 -31.413958) (xy 86.956646 -31.413958) (xy 86.983222 -31.407902) (xy 87.037342 -31.401411)
			(xy 87.064596 -31.401004) (xy 87.086769 -31.401233) (xy 87.130915 -31.405431) (xy 87.152734 -31.409386)
			(xy 87.162894 -31.411418) (xy 87.18296 -31.407354) (xy 87.251286 -31.36011) (xy 87.259476 -31.353927)
			(xy 87.270472 -31.336618) (xy 87.272622 -31.326582) (xy 87.277505 -31.300241) (xy 87.293727 -31.249184)
			(xy 87.316931 -31.200898) (xy 87.346662 -31.156333) (xy 87.382335 -31.116366) (xy 87.423248 -31.081781)
			(xy 87.468597 -31.05326) (xy 87.51749 -31.031363) (xy 87.568965 -31.016522) (xy 87.62201 -31.009027)
			(xy 87.648796 -31.008574) (xy 87.676048 -31.009073) (xy 87.729997 -31.016829) (xy 87.782292 -31.032184)
			(xy 87.831871 -31.054825) (xy 87.877722 -31.084292) (xy 87.918913 -31.119984) (xy 87.954606 -31.161175)
			(xy 87.984073 -31.207026) (xy 88.006714 -31.256604) (xy 88.02207 -31.3089) (xy 88.029827 -31.362848)
			(xy 88.029827 -31.417352) (xy 88.02207 -31.4713) (xy 88.006714 -31.523596) (xy 87.984073 -31.573174)
			(xy 87.954606 -31.619025) (xy 87.918913 -31.660216) (xy 87.877722 -31.695908) (xy 87.831871 -31.725375)
			(xy 87.782292 -31.748016) (xy 87.729997 -31.763371) (xy 87.676048 -31.771127) (xy 87.648796 -31.77159)
			(xy 87.648034 -31.77159) (xy 87.636702 -31.771476) (xy 87.614082 -31.770077) (xy 87.602822 -31.768796)
			(xy 87.591908 -31.768034) (xy 87.571109 -31.77476) (xy 87.56269 -31.78175) (xy 87.53856 -31.803594)
			(xy 87.53079 -31.811404) (xy 87.522249 -31.831693) (xy 87.52205 -31.84271) (xy 87.522304 -31.858712)
			(xy 87.522304 -32.722312) (xy 87.52205 -32.737806) (xy 87.522252 -32.748856) (xy 87.530961 -32.769144)
			(xy 87.538814 -32.776922) (xy 87.56269 -32.798512) (xy 87.571116 -32.805486) (xy 87.591909 -32.812203)
			(xy 87.602822 -32.811466) (xy 87.614081 -32.810177) (xy 87.636702 -32.808776) (xy 87.648034 -32.808672)
			(xy 87.648796 -32.808672) (xy 87.676048 -32.809175) (xy 87.729996 -32.816931) (xy 87.782292 -32.832286)
			(xy 87.83187 -32.854927) (xy 87.877721 -32.884393) (xy 87.918912 -32.920085) (xy 87.954604 -32.961276)
			(xy 87.984071 -33.007127) (xy 88.006713 -33.056705) (xy 88.022068 -33.109) (xy 88.029825 -33.162948)
			(xy 88.029825 -33.217452) (xy 88.022068 -33.2714) (xy 88.006713 -33.323695) (xy 87.984071 -33.373273)
			(xy 87.954604 -33.419124) (xy 87.918912 -33.460315) (xy 87.877721 -33.496007) (xy 87.83187 -33.525473)
			(xy 87.782292 -33.548114) (xy 87.729996 -33.563469) (xy 87.676048 -33.571225) (xy 87.648796 -33.571688)
			(xy 87.622028 -33.571321) (xy 87.569017 -33.563849) (xy 87.517571 -33.549038) (xy 87.468701 -33.52718)
			(xy 87.423367 -33.498704) (xy 87.38246 -33.464169) (xy 87.346783 -33.424254) (xy 87.317038 -33.379742)
			(xy 87.293808 -33.331509) (xy 87.277551 -33.280502) (xy 87.272622 -33.254188) (xy 87.270844 -33.243774)
			(xy 87.260176 -33.22701) (xy 87.183214 -33.17367) (xy 87.163148 -33.169606) (xy 87.152988 -33.171638)
			(xy 87.131108 -33.175615) (xy 87.086833 -33.179817) (xy 87.064596 -33.18002) (xy 87.037214 -33.179644)
			(xy 86.982838 -33.17315) (xy 86.956138 -33.167066) (xy 86.945978 -33.164526) (xy 86.924896 -33.168336)
			(xy 86.844632 -33.221676) (xy 86.833456 -33.239202) (xy 86.831678 -33.24987) (xy 86.826936 -33.276426)
			(xy 86.811089 -33.327988) (xy 86.788134 -33.376803) (xy 86.758531 -33.421896) (xy 86.722869 -33.462368)
			(xy 86.68186 -33.497412) (xy 86.636323 -33.526327) (xy 86.587166 -33.548538) (xy 86.535369 -33.5636)
			(xy 86.481967 -33.571215) (xy 86.454996 -33.571688) (xy 86.427626 -33.571227) (xy 86.373446 -33.563409)
			(xy 86.320943 -33.547918) (xy 86.271196 -33.525075) (xy 86.225229 -33.49535) (xy 86.204298 -33.477708)
			(xy 86.204044 -33.477454) (xy 86.196953 -33.471874) (xy 86.180039 -33.465625) (xy 86.171024 -33.465262)
			(xy 86.103968 -33.465262) (xy 86.094951 -33.465612) (xy 86.078034 -33.471865) (xy 86.070948 -33.477454)
			(xy 86.070948 -33.477708) (xy 86.070694 -33.477708) (xy 86.049776 -33.495365) (xy 86.003799 -33.525074)
			(xy 85.954048 -33.547906) (xy 85.901544 -33.563393) (xy 85.847366 -33.571216) (xy 85.819996 -33.571688)
			(xy 85.802948 -33.571484) (xy 85.768988 -33.568434) (xy 85.752178 -33.565592) (xy 85.740853 -33.56412)
			(xy 85.718831 -33.570079) (xy 85.70976 -33.577022) (xy 85.685122 -33.598358) (xy 85.676806 -33.606259)
			(xy 85.667671 -33.627274) (xy 85.667596 -33.638744) (xy 85.668104 -33.65881) (xy 85.668104 -34.522664)
			(xy 85.667596 -34.54146) (xy 85.667733 -34.553016) (xy 85.67697 -34.574172) (xy 85.685376 -34.5821)
			(xy 85.70976 -34.603182) (xy 85.718726 -34.610191) (xy 85.740628 -34.616255) (xy 85.751924 -34.614866)
			(xy 85.768794 -34.611991) (xy 85.802883 -34.608942) (xy 85.819996 -34.60877) (xy 85.847247 -34.609277)
			(xy 85.901196 -34.617033) (xy 85.953491 -34.632388) (xy 86.003069 -34.655029) (xy 86.04892 -34.684495)
			(xy 86.090111 -34.720187) (xy 86.125803 -34.761377) (xy 86.155269 -34.807228) (xy 86.177911 -34.856805)
			(xy 86.193266 -34.9091) (xy 86.201023 -34.963049) (xy 86.201023 -34.990024) (xy 87.266778 -34.990024)
			(xy 87.270849 -34.934402) (xy 87.282975 -34.879965) (xy 87.302898 -34.827874) (xy 87.330194 -34.779239)
			(xy 87.36428 -34.735096) (xy 87.404429 -34.696387) (xy 87.449787 -34.663936) (xy 87.499387 -34.638435)
			(xy 87.552171 -34.620428) (xy 87.607014 -34.610298) (xy 87.662748 -34.608261) (xy 87.718185 -34.614361)
			(xy 87.772142 -34.628467) (xy 87.823471 -34.650279) (xy 87.871077 -34.679333) (xy 87.913945 -34.715008)
			(xy 87.951162 -34.756545) (xy 87.981935 -34.803058) (xy 88.005607 -34.853555) (xy 88.021675 -34.906962)
			(xy 88.029795 -34.962138) (xy 88.030304 -34.990024) (xy 88.029795 -35.01791) (xy 88.021675 -35.073086)
			(xy 88.005607 -35.126493) (xy 87.981935 -35.17699) (xy 87.951162 -35.223503) (xy 87.913945 -35.26504)
			(xy 87.871077 -35.300715) (xy 87.823471 -35.329769) (xy 87.772142 -35.351581) (xy 87.718185 -35.365687)
			(xy 87.662748 -35.371787) (xy 87.607014 -35.36975) (xy 87.552171 -35.35962) (xy 87.499387 -35.341613)
			(xy 87.449787 -35.316112) (xy 87.404429 -35.283661) (xy 87.36428 -35.244952) (xy 87.330194 -35.200809)
			(xy 87.302898 -35.152174) (xy 87.282975 -35.100083) (xy 87.270849 -35.045646) (xy 87.266778 -34.990024)
			(xy 86.201023 -34.990024) (xy 86.201023 -35.017551) (xy 86.193266 -35.0715) (xy 86.177911 -35.123795)
			(xy 86.155269 -35.173372) (xy 86.125803 -35.219223) (xy 86.090111 -35.260413) (xy 86.04892 -35.296105)
			(xy 86.003069 -35.325571) (xy 85.953491 -35.348212) (xy 85.901196 -35.363567) (xy 85.847247 -35.371323)
			(xy 85.819996 -35.371786) (xy 85.79302 -35.371284) (xy 85.739604 -35.363704) (xy 85.68779 -35.348666)
			(xy 85.638615 -35.326472) (xy 85.593062 -35.297565) (xy 85.55204 -35.262523) (xy 85.516369 -35.222046)
			(xy 85.486763 -35.176944) (xy 85.463813 -35.128117) (xy 85.447978 -35.076542) (xy 85.443314 -35.049968)
			(xy 85.441165 -35.039734) (xy 85.429874 -35.022157) (xy 85.42147 -35.015932) (xy 85.350096 -34.968434)
			(xy 85.329014 -34.964624) (xy 85.318854 -34.967164) (xy 85.292159 -34.973302) (xy 85.237784 -34.979925)
			(xy 85.210396 -34.980372) (xy 85.183008 -34.979932) (xy 85.128632 -34.973308) (xy 85.101938 -34.967164)
			(xy 85.091778 -34.964624) (xy 85.070696 -34.968434) (xy 84.990432 -35.021774) (xy 84.979256 -35.0393)
			(xy 84.977478 -35.049968) (xy 84.972811 -35.076538) (xy 84.95695 -35.1281) (xy 84.933984 -35.176914)
			(xy 84.904371 -35.222006) (xy 84.8687 -35.262475) (xy 84.827684 -35.297516) (xy 84.78214 -35.326429)
			(xy 84.732977 -35.348638) (xy 84.681176 -35.363699) (xy 84.627769 -35.371313) (xy 84.600796 -35.371786)
			(xy 84.573543 -35.371344) (xy 84.519593 -35.363586) (xy 84.467296 -35.34823) (xy 84.417716 -35.325587)
			(xy 84.371864 -35.296119) (xy 84.330671 -35.260426) (xy 84.294978 -35.219233) (xy 84.265511 -35.17338)
			(xy 84.242868 -35.123801) (xy 84.227513 -35.071503) (xy 84.219756 -35.017553) (xy 82.574299 -35.017553)
			(xy 82.586682 -35.031373) (xy 82.617455 -35.077886) (xy 82.641127 -35.128383) (xy 82.657195 -35.18179)
			(xy 82.665315 -35.236966) (xy 82.665824 -35.264852) (xy 82.665315 -35.292738) (xy 82.657195 -35.347914)
			(xy 82.641127 -35.401321) (xy 82.617455 -35.451818) (xy 82.586682 -35.498331) (xy 82.549465 -35.539868)
			(xy 82.506597 -35.575543) (xy 82.458991 -35.604597) (xy 82.407662 -35.626409) (xy 82.353705 -35.640515)
			(xy 82.298268 -35.646615) (xy 82.242534 -35.644578) (xy 82.187691 -35.634448) (xy 82.134907 -35.616441)
			(xy 82.085307 -35.59094) (xy 82.039949 -35.558489) (xy 81.9998 -35.51978) (xy 81.965714 -35.475637)
			(xy 81.938418 -35.427002) (xy 81.918495 -35.374911) (xy 81.906369 -35.320474) (xy 81.902298 -35.264852)
			(xy 79.405988 -35.264852) (xy 79.405988 -37.087048) (xy 83.200748 -37.087048) (xy 83.201212 -37.060444)
			(xy 83.208589 -37.007751) (xy 83.223218 -36.956595) (xy 83.244818 -36.907969) (xy 83.272968 -36.862818)
			(xy 83.307121 -36.822019) (xy 83.346614 -36.786364) (xy 83.368388 -36.771072) (xy 83.378313 -36.763542)
			(xy 83.39004 -36.741598) (xy 83.39074 -36.729162) (xy 83.39074 -36.644834) (xy 83.390068 -36.632384)
			(xy 83.378358 -36.610408) (xy 83.368388 -36.602924) (xy 83.346631 -36.587611) (xy 83.307149 -36.551949)
			(xy 83.273003 -36.51115) (xy 83.244855 -36.466003) (xy 83.223251 -36.417384) (xy 83.208609 -36.366236)
			(xy 83.201212 -36.313549) (xy 83.200748 -36.286948) (xy 83.2013 -36.259698) (xy 83.209049 -36.205753)
			(xy 83.224397 -36.153459) (xy 83.247031 -36.103882) (xy 83.276489 -36.058031) (xy 83.312174 -36.016839)
			(xy 83.353357 -35.981145) (xy 83.399201 -35.951675) (xy 83.448773 -35.929029) (xy 83.501063 -35.913669)
			(xy 83.555006 -35.905906) (xy 83.582256 -35.90544) (xy 83.586828 -35.90544) (xy 83.596037 -35.905167)
			(xy 83.613356 -35.898927) (xy 83.62061 -35.893248) (xy 83.67141 -35.84956) (xy 83.678116 -35.843324)
			(xy 83.686975 -35.827314) (xy 83.688682 -35.818318) (xy 83.688682 -35.818064) (xy 83.69303 -35.791134)
			(xy 83.70834 -35.738778) (xy 83.730951 -35.689136) (xy 83.760402 -35.643221) (xy 83.796093 -35.601969)
			(xy 83.837295 -35.566221) (xy 83.883169 -35.536706) (xy 83.932779 -35.514026) (xy 83.985114 -35.498643)
			(xy 84.039106 -35.49087) (xy 84.06638 -35.490404) (xy 84.093635 -35.490842) (xy 84.14759 -35.498596)
			(xy 84.199891 -35.513951) (xy 84.249476 -35.536593) (xy 84.295333 -35.566062) (xy 84.336529 -35.601757)
			(xy 84.372226 -35.642951) (xy 84.401697 -35.688807) (xy 84.424342 -35.73839) (xy 84.439699 -35.790691)
			(xy 84.447457 -35.844645) (xy 84.447457 -35.899155) (xy 84.439699 -35.953109) (xy 84.424342 -36.00541)
			(xy 84.401697 -36.054993) (xy 84.372226 -36.100849) (xy 84.336529 -36.142043) (xy 84.295333 -36.177738)
			(xy 84.249476 -36.207207) (xy 84.199891 -36.229849) (xy 84.14759 -36.245204) (xy 84.093635 -36.252958)
			(xy 84.06638 -36.25342) (xy 84.061808 -36.25342) (xy 84.052594 -36.253648) (xy 84.035275 -36.259918)
			(xy 84.028026 -36.265612) (xy 83.977226 -36.3093) (xy 83.970488 -36.315506) (xy 83.961649 -36.331538)
			(xy 83.959954 -36.340542) (xy 83.959954 -36.340796) (xy 83.955755 -36.366999) (xy 83.941071 -36.417993)
			(xy 83.919458 -36.466459) (xy 83.891334 -36.51146) (xy 83.887907 -36.515548) (xy 85.014052 -36.515548)
			(xy 85.018123 -36.459926) (xy 85.030249 -36.405489) (xy 85.050172 -36.353398) (xy 85.077468 -36.304763)
			(xy 85.111554 -36.26062) (xy 85.151703 -36.221911) (xy 85.197061 -36.18946) (xy 85.246661 -36.163959)
			(xy 85.299445 -36.145952) (xy 85.354288 -36.135822) (xy 85.410022 -36.133785) (xy 85.465459 -36.139885)
			(xy 85.519416 -36.153991) (xy 85.570745 -36.175803) (xy 85.618351 -36.204857) (xy 85.661219 -36.240532)
			(xy 85.698436 -36.282069) (xy 85.729209 -36.328582) (xy 85.752881 -36.379079) (xy 85.768949 -36.432486)
			(xy 85.777069 -36.487662) (xy 85.777578 -36.515548) (xy 85.777069 -36.543434) (xy 85.768949 -36.59861)
			(xy 85.752881 -36.652017) (xy 85.729209 -36.702514) (xy 85.698436 -36.749027) (xy 85.661219 -36.790564)
			(xy 85.618351 -36.826239) (xy 85.570745 -36.855293) (xy 85.519416 -36.877105) (xy 85.465459 -36.891211)
			(xy 85.410022 -36.897311) (xy 85.354288 -36.895274) (xy 85.299445 -36.885144) (xy 85.246661 -36.867137)
			(xy 85.197061 -36.841636) (xy 85.151703 -36.809185) (xy 85.111554 -36.770476) (xy 85.077468 -36.726333)
			(xy 85.050172 -36.677698) (xy 85.030249 -36.625607) (xy 85.018123 -36.57117) (xy 85.014052 -36.515548)
			(xy 83.887907 -36.515548) (xy 83.857243 -36.552127) (xy 83.817842 -36.587675) (xy 83.796124 -36.602924)
			(xy 83.786203 -36.610459) (xy 83.774473 -36.632399) (xy 83.773772 -36.644834) (xy 83.773772 -36.729162)
			(xy 83.774442 -36.741612) (xy 83.786153 -36.763589) (xy 83.796124 -36.771072) (xy 83.817882 -36.786384)
			(xy 83.857363 -36.822046) (xy 83.891508 -36.862846) (xy 83.919656 -36.907993) (xy 83.94126 -36.956612)
			(xy 83.955903 -37.00776) (xy 83.963299 -37.060447) (xy 83.963764 -37.087048) (xy 83.963764 -37.087302)
			(xy 83.963146 -37.119019) (xy 83.952645 -37.181577) (xy 83.931917 -37.241528) (xy 83.917282 -37.269674)
			(xy 83.911948 -37.27958) (xy 83.910424 -37.301678) (xy 83.942428 -37.384482) (xy 83.946921 -37.394568)
			(xy 83.962709 -37.409972) (xy 83.972908 -37.4142) (xy 83.997443 -37.423261) (xy 84.043973 -37.447146)
			(xy 84.086804 -37.477162) (xy 84.125132 -37.512749) (xy 84.15824 -37.553238) (xy 84.185506 -37.597871)
			(xy 84.206418 -37.64581) (xy 84.220586 -37.696157) (xy 84.227742 -37.747967) (xy 84.228178 -37.774118)
			(xy 84.227692 -37.801369) (xy 84.219936 -37.855317) (xy 84.204581 -37.907612) (xy 84.181939 -37.957189)
			(xy 84.152473 -38.003039) (xy 84.116782 -38.04423) (xy 84.075591 -38.079921) (xy 84.029741 -38.109387)
			(xy 83.980164 -38.132029) (xy 83.927869 -38.147384) (xy 83.873921 -38.15514) (xy 83.819419 -38.15514)
			(xy 83.765471 -38.147384) (xy 83.713176 -38.132029) (xy 83.663599 -38.109387) (xy 83.617749 -38.079921)
			(xy 83.576558 -38.04423) (xy 83.540867 -38.003039) (xy 83.511401 -37.957189) (xy 83.488759 -37.907612)
			(xy 83.473404 -37.855317) (xy 83.465648 -37.801369) (xy 83.465162 -37.774118) (xy 83.465162 -37.773864)
			(xy 83.465763 -37.742146) (xy 83.476271 -37.679588) (xy 83.497006 -37.619637) (xy 83.511644 -37.591492)
			(xy 83.516978 -37.581586) (xy 83.518502 -37.559488) (xy 83.486498 -37.476684) (xy 83.482049 -37.466574)
			(xy 83.46623 -37.451182) (xy 83.456018 -37.446966) (xy 83.431478 -37.437918) (xy 83.384945 -37.414035)
			(xy 83.342113 -37.384017) (xy 83.303783 -37.348429) (xy 83.270676 -37.307938) (xy 83.243411 -37.263303)
			(xy 83.2225 -37.215361) (xy 83.208335 -37.165012) (xy 83.201182 -37.1132) (xy 83.200748 -37.087048)
			(xy 79.405988 -37.087048) (xy 79.405988 -38.315138) (xy 84.417914 -38.315138) (xy 84.421985 -38.259516)
			(xy 84.434111 -38.205079) (xy 84.454034 -38.152988) (xy 84.48133 -38.104353) (xy 84.515416 -38.06021)
			(xy 84.555565 -38.021501) (xy 84.600923 -37.98905) (xy 84.650523 -37.963549) (xy 84.703307 -37.945542)
			(xy 84.75815 -37.935412) (xy 84.813884 -37.933375) (xy 84.869321 -37.939475) (xy 84.923278 -37.953581)
			(xy 84.974607 -37.975393) (xy 85.022213 -38.004447) (xy 85.065081 -38.040122) (xy 85.102298 -38.081659)
			(xy 85.133071 -38.128172) (xy 85.156743 -38.178669) (xy 85.172811 -38.232076) (xy 85.180931 -38.287252)
			(xy 85.18144 -38.315138) (xy 85.180931 -38.343024) (xy 85.172811 -38.3982) (xy 85.156743 -38.451607)
			(xy 85.133071 -38.502104) (xy 85.102298 -38.548617) (xy 85.065081 -38.590154) (xy 85.022213 -38.625829)
			(xy 84.974607 -38.654883) (xy 84.923278 -38.676695) (xy 84.869321 -38.690801) (xy 84.813884 -38.696901)
			(xy 84.75815 -38.694864) (xy 84.703307 -38.684734) (xy 84.650523 -38.666727) (xy 84.600923 -38.641226)
			(xy 84.555565 -38.608775) (xy 84.515416 -38.570066) (xy 84.48133 -38.525923) (xy 84.454034 -38.477288)
			(xy 84.434111 -38.425197) (xy 84.421985 -38.37076) (xy 84.417914 -38.315138) (xy 79.405988 -38.315138)
			(xy 79.405988 -42.41673) (xy 79.406251 -42.424374) (xy 79.410779 -42.438975) (xy 79.414878 -42.445432)
			(xy 79.437992 -42.479214) (xy 79.448152 -42.483278) (xy 79.473702 -42.493278) (xy 79.521866 -42.519555)
			(xy 79.56577 -42.55246) (xy 79.604506 -42.591316) (xy 79.637277 -42.63532) (xy 79.663407 -42.683565)
			(xy 79.682355 -42.735055) (xy 79.693732 -42.788728) (xy 79.697302 -42.843478) (xy 79.692993 -42.898175)
			(xy 79.680893 -42.95169) (xy 79.661251 -43.00292) (xy 79.634473 -43.050807) (xy 79.601111 -43.094365)
			(xy 79.561854 -43.132694) (xy 79.51751 -43.165004) (xy 79.468995 -43.190629) (xy 79.443326 -43.20032)
			(xy 79.43723 -43.20286) (xy 79.42834 -43.207432) (xy 79.418367 -43.214914) (xy 79.406654 -43.236891)
			(xy 79.405988 -43.249342) (xy 79.405988 -43.43273) (xy 79.406251 -43.440374) (xy 79.410779 -43.454975)
			(xy 79.414878 -43.461432) (xy 79.437992 -43.495214) (xy 79.448152 -43.499278) (xy 79.473702 -43.509278)
			(xy 79.521866 -43.535555) (xy 79.56577 -43.56846) (xy 79.604506 -43.607316) (xy 79.637277 -43.65132)
			(xy 79.663407 -43.699565) (xy 79.682355 -43.751055) (xy 79.693732 -43.804728) (xy 79.697302 -43.859478)
			(xy 79.692993 -43.914175) (xy 79.680893 -43.96769) (xy 79.661251 -44.01892) (xy 79.634473 -44.066807)
			(xy 79.601111 -44.110365) (xy 79.561854 -44.148694) (xy 79.51751 -44.181004) (xy 79.468995 -44.206629)
			(xy 79.443326 -44.21632) (xy 79.43723 -44.21886) (xy 79.42834 -44.223432) (xy 79.418367 -44.230914)
			(xy 79.406654 -44.252891) (xy 79.405988 -44.265342) (xy 79.405988 -44.44873) (xy 79.406251 -44.456374)
			(xy 79.410779 -44.470975) (xy 79.414878 -44.477432) (xy 79.437992 -44.511214) (xy 79.448152 -44.515278)
			(xy 79.473702 -44.525278) (xy 79.521866 -44.551555) (xy 79.56577 -44.58446) (xy 79.604506 -44.623316)
			(xy 79.637277 -44.66732) (xy 79.663407 -44.715565) (xy 79.682355 -44.767055) (xy 79.693732 -44.820728)
			(xy 79.697302 -44.875478) (xy 79.692993 -44.930175) (xy 79.680893 -44.98369) (xy 79.661251 -45.03492)
			(xy 79.634473 -45.082807) (xy 79.601111 -45.126365) (xy 79.561854 -45.164694) (xy 79.51751 -45.197004)
			(xy 79.468995 -45.222629) (xy 79.443326 -45.23232) (xy 79.43723 -45.23486) (xy 79.42834 -45.239432)
			(xy 79.418367 -45.246914) (xy 79.406654 -45.268891) (xy 79.405988 -45.281342) (xy 79.405988 -45.46473)
			(xy 79.406251 -45.472374) (xy 79.410779 -45.486975) (xy 79.414878 -45.493432) (xy 79.437992 -45.527214)
			(xy 79.448152 -45.531278) (xy 79.473702 -45.541278) (xy 79.521866 -45.567555) (xy 79.56577 -45.60046)
			(xy 79.604506 -45.639316) (xy 79.637277 -45.68332) (xy 79.663407 -45.731565) (xy 79.682355 -45.783055)
			(xy 79.693732 -45.836728) (xy 79.697302 -45.891478) (xy 79.692993 -45.946175) (xy 79.680893 -45.99969)
			(xy 79.661251 -46.05092) (xy 79.634473 -46.098807) (xy 79.601111 -46.142365) (xy 79.561854 -46.180694)
			(xy 79.51751 -46.213004) (xy 79.468995 -46.238629) (xy 79.443326 -46.24832) (xy 79.43723 -46.25086)
			(xy 79.42834 -46.255432) (xy 79.418367 -46.262914) (xy 79.406654 -46.284891) (xy 79.405988 -46.297342)
			(xy 79.405988 -47.027846) (xy 79.407195 -47.037873) (xy 79.416217 -47.055917) (xy 79.423514 -47.062898)
			(xy 79.44358 -47.068232) (xy 79.470638 -47.075974) (xy 79.522336 -47.098211) (xy 79.570262 -47.127713)
			(xy 79.613401 -47.163854) (xy 79.650842 -47.205872) (xy 79.681791 -47.252875) (xy 79.705594 -47.303871)
			(xy 79.721749 -47.357781) (xy 79.729912 -47.413464) (xy 79.729912 -47.469742) (xy 79.721747 -47.525425)
			(xy 79.705592 -47.579334) (xy 79.681788 -47.63033) (xy 79.650838 -47.677333) (xy 79.613397 -47.71935)
			(xy 79.570257 -47.755491) (xy 79.522331 -47.784992) (xy 79.470632 -47.807228) (xy 79.44358 -47.814992)
			(xy 79.423514 -47.820326) (xy 79.416137 -47.827248) (xy 79.407091 -47.845323) (xy 79.405988 -47.855378)
			(xy 79.405988 -48.51273) (xy 79.406251 -48.520374) (xy 79.410779 -48.534975) (xy 79.414878 -48.541432)
			(xy 79.437992 -48.575214) (xy 79.448152 -48.579278) (xy 79.473702 -48.589278) (xy 79.521866 -48.615555)
			(xy 79.56577 -48.64846) (xy 79.604506 -48.687316) (xy 79.637277 -48.73132) (xy 79.663407 -48.779565)
			(xy 79.682355 -48.831055) (xy 79.693732 -48.884728) (xy 79.697302 -48.939478) (xy 79.692993 -48.994175)
			(xy 79.680893 -49.04769) (xy 79.661251 -49.09892) (xy 79.634473 -49.146807) (xy 79.601111 -49.190365)
			(xy 79.561854 -49.228694) (xy 79.51751 -49.261004) (xy 79.468995 -49.286629) (xy 79.443326 -49.29632)
			(xy 79.43723 -49.29886) (xy 79.42834 -49.303432) (xy 79.418367 -49.310914) (xy 79.406654 -49.332891)
			(xy 79.405988 -49.345342) (xy 79.405988 -49.52873) (xy 79.406251 -49.536374) (xy 79.410779 -49.550975)
			(xy 79.414878 -49.557432) (xy 79.437992 -49.591214) (xy 79.448152 -49.595278) (xy 79.465209 -49.601954)
			(xy 80.290859 -49.601954) (xy 80.290859 -49.547446) (xy 80.298617 -49.493494) (xy 80.313974 -49.441195)
			(xy 80.336618 -49.391613) (xy 80.366088 -49.34576) (xy 80.401784 -49.304567) (xy 80.442979 -49.268874)
			(xy 80.488835 -49.239406) (xy 80.538417 -49.216766) (xy 80.590717 -49.201412) (xy 80.64467 -49.193658)
			(xy 80.671924 -49.193196) (xy 80.699295 -49.193649) (xy 80.753474 -49.20147) (xy 80.805978 -49.216962)
			(xy 80.855724 -49.239807) (xy 80.901691 -49.269534) (xy 80.922622 -49.287176) (xy 80.922876 -49.28743)
			(xy 80.929963 -49.293016) (xy 80.94688 -49.299262) (xy 80.955896 -49.299622) (xy 81.022952 -49.299622)
			(xy 81.031966 -49.299237) (xy 81.048883 -49.293008) (xy 81.055972 -49.28743) (xy 81.055972 -49.287176)
			(xy 81.056226 -49.287176) (xy 81.077159 -49.269535) (xy 81.123127 -49.239811) (xy 81.172873 -49.216965)
			(xy 81.225375 -49.201469) (xy 81.279553 -49.19364) (xy 81.334295 -49.19364) (xy 81.388473 -49.201469)
			(xy 81.440975 -49.216965) (xy 81.490721 -49.239811) (xy 81.536689 -49.269535) (xy 81.557622 -49.287176)
			(xy 81.557876 -49.28743) (xy 81.564963 -49.293016) (xy 81.58188 -49.299262) (xy 81.590896 -49.299622)
			(xy 81.657952 -49.299622) (xy 81.666966 -49.299237) (xy 81.683883 -49.293008) (xy 81.690972 -49.28743)
			(xy 81.690972 -49.287176) (xy 81.691226 -49.287176) (xy 81.712172 -49.269554) (xy 81.758141 -49.239841)
			(xy 81.807885 -49.217002) (xy 81.860383 -49.201507) (xy 81.914556 -49.193673) (xy 81.941924 -49.193196)
			(xy 81.968238 -49.193649) (xy 82.020368 -49.200887) (xy 82.07101 -49.215209) (xy 82.119209 -49.236344)
			(xy 82.164053 -49.263893) (xy 82.204692 -49.297333) (xy 82.222848 -49.316386) (xy 82.230352 -49.323809)
			(xy 82.249645 -49.332321) (xy 82.260186 -49.332896) (xy 82.334862 -49.332896) (xy 82.345411 -49.332361)
			(xy 82.364707 -49.32383) (xy 82.3722 -49.316386) (xy 82.39036 -49.297335) (xy 82.430989 -49.263878)
			(xy 82.475828 -49.236319) (xy 82.524028 -49.215179) (xy 82.574675 -49.200861) (xy 82.626808 -49.193635)
			(xy 82.653124 -49.193196) (xy 82.680374 -49.193675) (xy 82.73432 -49.201435) (xy 82.786613 -49.216792)
			(xy 82.836187 -49.239435) (xy 82.882035 -49.268902) (xy 82.923223 -49.304594) (xy 82.958912 -49.345784)
			(xy 82.988377 -49.391634) (xy 83.011016 -49.44121) (xy 83.02637 -49.493503) (xy 83.034126 -49.54745)
			(xy 83.034126 -49.60195) (xy 83.02637 -49.655897) (xy 83.011016 -49.70819) (xy 82.988377 -49.757766)
			(xy 82.958912 -49.803616) (xy 82.923223 -49.844806) (xy 82.882035 -49.880498) (xy 82.836187 -49.909965)
			(xy 82.786613 -49.932608) (xy 82.73432 -49.947965) (xy 82.680374 -49.955725) (xy 82.653124 -49.956212)
			(xy 82.626811 -49.955725) (xy 82.574683 -49.948493) (xy 82.524041 -49.934178) (xy 82.475842 -49.913049)
			(xy 82.430998 -49.885507) (xy 82.390357 -49.852072) (xy 82.3722 -49.833022) (xy 82.364677 -49.825622)
			(xy 82.345398 -49.817096) (xy 82.334862 -49.816512) (xy 82.260186 -49.816512) (xy 82.249633 -49.817016)
			(xy 82.230338 -49.825568) (xy 82.222848 -49.833022) (xy 82.204715 -49.8521) (xy 82.16408 -49.885554)
			(xy 82.119235 -49.91311) (xy 82.07103 -49.934244) (xy 82.020378 -49.948557) (xy 81.968241 -49.955776)
			(xy 81.941924 -49.956212) (xy 81.914554 -49.955729) (xy 81.860376 -49.947915) (xy 81.807873 -49.932429)
			(xy 81.758126 -49.909592) (xy 81.712158 -49.879871) (xy 81.691226 -49.862232) (xy 81.690972 -49.861978)
			(xy 81.683871 -49.856413) (xy 81.666965 -49.850154) (xy 81.657952 -49.849786) (xy 81.590896 -49.849786)
			(xy 81.581879 -49.850144) (xy 81.564963 -49.856391) (xy 81.557876 -49.861978) (xy 81.557876 -49.862232)
			(xy 81.557622 -49.862232) (xy 81.536689 -49.879873) (xy 81.490721 -49.909597) (xy 81.440975 -49.932443)
			(xy 81.388473 -49.947939) (xy 81.334295 -49.955768) (xy 81.279553 -49.955768) (xy 81.225375 -49.947939)
			(xy 81.172873 -49.932443) (xy 81.123127 -49.909597) (xy 81.077159 -49.879873) (xy 81.056226 -49.862232)
			(xy 81.055972 -49.861978) (xy 81.048871 -49.856413) (xy 81.031965 -49.850154) (xy 81.022952 -49.849786)
			(xy 80.955896 -49.849786) (xy 80.946879 -49.850144) (xy 80.929963 -49.856391) (xy 80.922876 -49.861978)
			(xy 80.922876 -49.862232) (xy 80.922622 -49.862232) (xy 80.901697 -49.879879) (xy 80.855721 -49.909589)
			(xy 80.805972 -49.932423) (xy 80.75347 -49.947912) (xy 80.699294 -49.955739) (xy 80.671924 -49.956212)
			(xy 80.64467 -49.955742) (xy 80.590717 -49.947988) (xy 80.538417 -49.932634) (xy 80.488835 -49.909994)
			(xy 80.442979 -49.880526) (xy 80.401784 -49.844833) (xy 80.366088 -49.80364) (xy 80.336618 -49.757787)
			(xy 80.313974 -49.708205) (xy 80.298617 -49.655906) (xy 80.290859 -49.601954) (xy 79.465209 -49.601954)
			(xy 79.473702 -49.605278) (xy 79.521866 -49.631555) (xy 79.56577 -49.66446) (xy 79.604506 -49.703316)
			(xy 79.637277 -49.74732) (xy 79.663407 -49.795565) (xy 79.682355 -49.847055) (xy 79.693732 -49.900728)
			(xy 79.697302 -49.955478) (xy 79.692993 -50.010175) (xy 79.680893 -50.06369) (xy 79.661251 -50.11492)
			(xy 79.634473 -50.162807) (xy 79.601111 -50.206365) (xy 79.561854 -50.244694) (xy 79.51751 -50.277004)
			(xy 79.468995 -50.302629) (xy 79.443326 -50.31232) (xy 79.43723 -50.31486) (xy 79.42834 -50.319432)
			(xy 79.418367 -50.326914) (xy 79.406654 -50.348891) (xy 79.405988 -50.361342) (xy 79.405988 -50.60823)
			(xy 79.406251 -50.615874) (xy 79.410779 -50.630475) (xy 79.414878 -50.636932) (xy 79.420466 -50.644552)
			(xy 79.433166 -50.65395) (xy 79.44104 -50.65649) (xy 79.467745 -50.66568) (xy 79.518317 -50.690819)
			(xy 79.564632 -50.723137) (xy 79.605678 -50.761928) (xy 79.640558 -50.806345) (xy 79.66851 -50.855418)
			(xy 79.688925 -50.908075) (xy 79.701356 -50.963165) (xy 79.705531 -51.019486) (xy 79.70136 -51.075808)
			(xy 79.688933 -51.130899) (xy 79.668522 -51.183557) (xy 79.640573 -51.232632) (xy 79.605696 -51.277052)
			(xy 79.564653 -51.315846) (xy 79.518341 -51.348167) (xy 79.46777 -51.37331) (xy 79.44104 -51.382422)
			(xy 79.433166 -51.384962) (xy 79.420466 -51.39436) (xy 79.414878 -51.40198) (xy 79.41077 -51.408433)
			(xy 79.406245 -51.423037) (xy 79.405988 -51.430682) (xy 79.405988 -51.62423) (xy 79.406251 -51.631874)
			(xy 79.410779 -51.646475) (xy 79.414878 -51.652932) (xy 79.420466 -51.660552) (xy 79.433166 -51.66995)
			(xy 79.44104 -51.67249) (xy 79.467745 -51.68168) (xy 79.482567 -51.689048) (xy 80.2554 -51.689048)
			(xy 80.2554 -51.634552) (xy 80.263155 -51.580611) (xy 80.278508 -51.528322) (xy 80.301145 -51.47875)
			(xy 80.330606 -51.432904) (xy 80.366292 -51.391717) (xy 80.407475 -51.356028) (xy 80.453318 -51.326562)
			(xy 80.502888 -51.30392) (xy 80.555175 -51.288563) (xy 80.609116 -51.280803) (xy 80.636364 -51.280314)
			(xy 80.663734 -51.280798) (xy 80.717912 -51.288611) (xy 80.770415 -51.304096) (xy 80.820162 -51.326933)
			(xy 80.86613 -51.356654) (xy 80.887062 -51.374294) (xy 80.887316 -51.374548) (xy 80.89439 -51.380153)
			(xy 80.911317 -51.386388) (xy 80.920336 -51.38674) (xy 80.987392 -51.38674) (xy 80.99641 -51.386392)
			(xy 81.013328 -51.38014) (xy 81.020412 -51.374548) (xy 81.020412 -51.374294) (xy 81.020666 -51.374294)
			(xy 81.041599 -51.356656) (xy 81.087572 -51.326945) (xy 81.137319 -51.304108) (xy 81.189819 -51.288617)
			(xy 81.243995 -51.280788) (xy 81.271364 -51.280314) (xy 81.289707 -51.280548) (xy 81.32622 -51.28411)
			(xy 81.344262 -51.287426) (xy 81.354892 -51.289035) (xy 81.375814 -51.284157) (xy 81.384648 -51.278028)
			(xy 81.453736 -51.225704) (xy 81.46415 -51.206908) (xy 81.464912 -51.195986) (xy 81.467813 -51.167703)
			(xy 81.48085 -51.112366) (xy 81.501945 -51.059573) (xy 81.530632 -51.010489) (xy 81.566277 -50.9662)
			(xy 81.586832 -50.946558) (xy 81.594244 -50.939045) (xy 81.602765 -50.919759) (xy 81.603342 -50.90922)
			(xy 81.603342 -50.834544) (xy 81.60279 -50.823997) (xy 81.594269 -50.804703) (xy 81.586832 -50.797206)
			(xy 81.567792 -50.779034) (xy 81.534333 -50.738409) (xy 81.506771 -50.693572) (xy 81.485629 -50.645374)
			(xy 81.471309 -50.594729) (xy 81.464082 -50.542597) (xy 81.463642 -50.516282) (xy 81.464128 -50.489031)
			(xy 81.471884 -50.435083) (xy 81.487239 -50.382788) (xy 81.509881 -50.333211) (xy 81.539347 -50.287361)
			(xy 81.575038 -50.24617) (xy 81.616229 -50.210479) (xy 81.662079 -50.181013) (xy 81.711656 -50.158371)
			(xy 81.763951 -50.143016) (xy 81.817899 -50.13526) (xy 81.872401 -50.13526) (xy 81.926349 -50.143016)
			(xy 81.978644 -50.158371) (xy 82.028221 -50.181013) (xy 82.074071 -50.210479) (xy 82.115262 -50.24617)
			(xy 82.150953 -50.287361) (xy 82.180419 -50.333211) (xy 82.203061 -50.382788) (xy 82.218416 -50.435083)
			(xy 82.226172 -50.489031) (xy 82.226658 -50.516282) (xy 82.226192 -50.542596) (xy 82.218959 -50.594725)
			(xy 82.20464 -50.645369) (xy 82.183508 -50.693568) (xy 82.155961 -50.738411) (xy 82.12252 -50.77905)
			(xy 82.103468 -50.797206) (xy 82.096072 -50.804732) (xy 82.087542 -50.824008) (xy 82.086958 -50.834544)
			(xy 82.086958 -50.90922) (xy 82.087529 -50.919764) (xy 82.096036 -50.93906) (xy 82.103468 -50.946558)
			(xy 82.122539 -50.964699) (xy 82.155996 -51.005331) (xy 82.183553 -51.050174) (xy 82.204689 -51.098378)
			(xy 82.219003 -51.149028) (xy 82.226223 -51.201165) (xy 82.226658 -51.227482) (xy 82.226228 -51.254737)
			(xy 82.218472 -51.308691) (xy 82.203116 -51.360993) (xy 82.180472 -51.410576) (xy 82.151001 -51.456432)
			(xy 82.115303 -51.497626) (xy 82.074106 -51.53332) (xy 82.028248 -51.562787) (xy 81.978663 -51.585427)
			(xy 81.92636 -51.600779) (xy 81.872405 -51.60853) (xy 81.84515 -51.60899) (xy 81.826807 -51.608754)
			(xy 81.790294 -51.605193) (xy 81.772252 -51.601878) (xy 81.76162 -51.600297) (xy 81.740704 -51.605159)
			(xy 81.731866 -51.611276) (xy 81.662778 -51.6636) (xy 81.652364 -51.682396) (xy 81.651602 -51.693318)
			(xy 81.648661 -51.72157) (xy 81.635631 -51.776852) (xy 81.614549 -51.829591) (xy 81.585882 -51.878622)
			(xy 81.550263 -51.922862) (xy 81.50848 -51.961332) (xy 81.461454 -51.993183) (xy 81.410227 -52.017711)
			(xy 81.35593 -52.034374) (xy 81.299762 -52.042803) (xy 81.271364 -52.04333) (xy 81.243992 -52.042902)
			(xy 81.189811 -52.035078) (xy 81.137307 -52.019581) (xy 81.08756 -51.99673) (xy 81.041596 -51.966996)
			(xy 81.020666 -51.94935) (xy 81.020412 -51.949096) (xy 81.013327 -51.943508) (xy 80.996409 -51.937262)
			(xy 80.987392 -51.936904) (xy 80.920336 -51.936904) (xy 80.911321 -51.937277) (xy 80.894404 -51.943513)
			(xy 80.887316 -51.949096) (xy 80.887316 -51.94935) (xy 80.887062 -51.94935) (xy 80.866111 -51.966966)
			(xy 80.820144 -51.996683) (xy 80.770402 -52.019524) (xy 80.717905 -52.03502) (xy 80.663732 -52.042854)
			(xy 80.636364 -52.04333) (xy 80.609116 -52.042797) (xy 80.555175 -52.035037) (xy 80.502888 -52.01968)
			(xy 80.453318 -51.997038) (xy 80.407475 -51.967572) (xy 80.366292 -51.931883) (xy 80.330606 -51.890696)
			(xy 80.301145 -51.84485) (xy 80.278508 -51.795278) (xy 80.263155 -51.742989) (xy 80.2554 -51.689048)
			(xy 79.482567 -51.689048) (xy 79.518317 -51.706819) (xy 79.564632 -51.739137) (xy 79.605678 -51.777928)
			(xy 79.640558 -51.822345) (xy 79.66851 -51.871418) (xy 79.688925 -51.924075) (xy 79.701356 -51.979165)
			(xy 79.705531 -52.035486) (xy 79.70136 -52.091808) (xy 79.688933 -52.146899) (xy 79.668522 -52.199557)
			(xy 79.640573 -52.248632) (xy 79.605696 -52.293052) (xy 79.564653 -52.331846) (xy 79.518341 -52.364167)
			(xy 79.46777 -52.38931) (xy 79.44104 -52.398422) (xy 79.433166 -52.400962) (xy 79.420466 -52.41036)
			(xy 79.414878 -52.41798) (xy 79.41077 -52.424433) (xy 79.406245 -52.439037) (xy 79.405988 -52.446682)
			(xy 79.405988 -52.564157) (xy 81.827007 -52.564157) (xy 81.827007 -52.509643) (xy 81.834765 -52.455684)
			(xy 81.850124 -52.403378) (xy 81.872771 -52.353791) (xy 81.902244 -52.307931) (xy 81.937944 -52.266733)
			(xy 81.979144 -52.231034) (xy 82.025005 -52.201563) (xy 82.074593 -52.178919) (xy 82.126899 -52.163562)
			(xy 82.180859 -52.155806) (xy 82.208116 -52.155344) (xy 82.235487 -52.15579) (xy 82.289667 -52.163611)
			(xy 82.342171 -52.179104) (xy 82.391918 -52.201951) (xy 82.437883 -52.23168) (xy 82.458814 -52.249324)
			(xy 82.459068 -52.249578) (xy 82.466153 -52.255166) (xy 82.483071 -52.26141) (xy 82.492088 -52.26177)
			(xy 82.559144 -52.26177) (xy 82.568159 -52.261393) (xy 82.585076 -52.25516) (xy 82.592164 -52.249578)
			(xy 82.592164 -52.249324) (xy 82.592418 -52.249324) (xy 82.613373 -52.231714) (xy 82.659339 -52.201997)
			(xy 82.709081 -52.179155) (xy 82.761577 -52.163657) (xy 82.815748 -52.155822) (xy 82.843116 -52.155344)
			(xy 82.870363 -52.155927) (xy 82.924302 -52.163685) (xy 82.976588 -52.179039) (xy 83.026157 -52.201678)
			(xy 83.072 -52.231141) (xy 83.113183 -52.266828) (xy 83.148868 -52.308013) (xy 83.178329 -52.353857)
			(xy 83.200966 -52.403427) (xy 83.216319 -52.455713) (xy 83.224074 -52.509653) (xy 83.224074 -52.564147)
			(xy 83.216319 -52.618087) (xy 83.200966 -52.670373) (xy 83.178329 -52.719943) (xy 83.148868 -52.765787)
			(xy 83.113183 -52.806972) (xy 83.072 -52.842659) (xy 83.026157 -52.872122) (xy 82.976588 -52.894761)
			(xy 82.924302 -52.910115) (xy 82.870363 -52.917873) (xy 82.843116 -52.91836) (xy 82.815746 -52.917894)
			(xy 82.761566 -52.910078) (xy 82.709063 -52.894589) (xy 82.659316 -52.871747) (xy 82.613349 -52.842022)
			(xy 82.592418 -52.82438) (xy 82.592164 -52.824126) (xy 82.58507 -52.818551) (xy 82.568159 -52.812299)
			(xy 82.559144 -52.811934) (xy 82.492088 -52.811934) (xy 82.48307 -52.812278) (xy 82.466152 -52.818534)
			(xy 82.459068 -52.824126) (xy 82.459068 -52.82438) (xy 82.458814 -52.82438) (xy 82.437885 -52.842023)
			(xy 82.391912 -52.871735) (xy 82.342163 -52.89457) (xy 82.289662 -52.91006) (xy 82.235485 -52.917887)
			(xy 82.208116 -52.91836) (xy 82.180859 -52.917994) (xy 82.126899 -52.910238) (xy 82.074593 -52.894881)
			(xy 82.025005 -52.872237) (xy 81.979144 -52.842766) (xy 81.937944 -52.807067) (xy 81.902244 -52.765869)
			(xy 81.872771 -52.720009) (xy 81.850124 -52.670422) (xy 81.834765 -52.618116) (xy 81.827007 -52.564157)
			(xy 79.405988 -52.564157) (xy 79.405988 -52.64023) (xy 79.406251 -52.647874) (xy 79.410779 -52.662475)
			(xy 79.414878 -52.668932) (xy 79.420466 -52.676552) (xy 79.433166 -52.68595) (xy 79.44104 -52.68849)
			(xy 79.467745 -52.69768) (xy 79.518317 -52.722819) (xy 79.564632 -52.755137) (xy 79.605678 -52.793928)
			(xy 79.640558 -52.838345) (xy 79.66851 -52.887418) (xy 79.688925 -52.940075) (xy 79.701356 -52.995165)
			(xy 79.705531 -53.051486) (xy 79.70136 -53.107808) (xy 79.688933 -53.162899) (xy 79.668522 -53.215557)
			(xy 79.640573 -53.264632) (xy 79.605696 -53.309052) (xy 79.564653 -53.347846) (xy 79.518341 -53.380167)
			(xy 79.46777 -53.40531) (xy 79.44104 -53.414422) (xy 79.433166 -53.416962) (xy 79.420466 -53.42636)
			(xy 79.414878 -53.43398) (xy 79.41077 -53.440433) (xy 79.406245 -53.455037) (xy 79.405988 -53.462682)
			(xy 79.405988 -53.65623) (xy 79.406251 -53.663874) (xy 79.410779 -53.678475) (xy 79.414878 -53.684932)
			(xy 79.420466 -53.692552) (xy 79.433166 -53.70195) (xy 79.44104 -53.70449) (xy 79.467745 -53.71368)
			(xy 79.518317 -53.738819) (xy 79.564632 -53.771137) (xy 79.605678 -53.809928) (xy 79.640558 -53.854345)
			(xy 79.66851 -53.903418) (xy 79.688925 -53.956075) (xy 79.701356 -54.011165) (xy 79.705531 -54.067486)
			(xy 79.70136 -54.123808) (xy 79.688933 -54.178899) (xy 79.668522 -54.231557) (xy 79.664337 -54.238906)
			(xy 86.385906 -54.238906) (xy 86.389977 -54.183284) (xy 86.402103 -54.128847) (xy 86.422026 -54.076756)
			(xy 86.449322 -54.028121) (xy 86.483408 -53.983978) (xy 86.523557 -53.945269) (xy 86.568915 -53.912818)
			(xy 86.618515 -53.887317) (xy 86.671299 -53.86931) (xy 86.726142 -53.85918) (xy 86.781876 -53.857143)
			(xy 86.837313 -53.863243) (xy 86.89127 -53.877349) (xy 86.942599 -53.899161) (xy 86.990205 -53.928215)
			(xy 87.033073 -53.96389) (xy 87.07029 -54.005427) (xy 87.101063 -54.05194) (xy 87.124735 -54.102437)
			(xy 87.140803 -54.155844) (xy 87.148923 -54.21102) (xy 87.149432 -54.238906) (xy 87.148923 -54.266792)
			(xy 87.140803 -54.321968) (xy 87.124735 -54.375375) (xy 87.101063 -54.425872) (xy 87.07029 -54.472385)
			(xy 87.033073 -54.513922) (xy 86.990205 -54.549597) (xy 86.942599 -54.578651) (xy 86.89127 -54.600463)
			(xy 86.837313 -54.614569) (xy 86.781876 -54.620669) (xy 86.726142 -54.618632) (xy 86.671299 -54.608502)
			(xy 86.618515 -54.590495) (xy 86.568915 -54.564994) (xy 86.523557 -54.532543) (xy 86.483408 -54.493834)
			(xy 86.449322 -54.449691) (xy 86.422026 -54.401056) (xy 86.402103 -54.348965) (xy 86.389977 -54.294528)
			(xy 86.385906 -54.238906) (xy 79.664337 -54.238906) (xy 79.640573 -54.280632) (xy 79.605696 -54.325052)
			(xy 79.564653 -54.363846) (xy 79.518341 -54.396167) (xy 79.46777 -54.42131) (xy 79.44104 -54.430422)
			(xy 79.433166 -54.432962) (xy 79.420466 -54.44236) (xy 79.414878 -54.44998) (xy 79.41077 -54.456433)
			(xy 79.406245 -54.471037) (xy 79.405988 -54.478682) (xy 79.405988 -54.67223) (xy 79.406251 -54.679874)
			(xy 79.410779 -54.694475) (xy 79.414878 -54.700932) (xy 79.420466 -54.708552) (xy 79.433166 -54.71795)
			(xy 79.44104 -54.72049) (xy 79.467745 -54.72968) (xy 79.518317 -54.754819) (xy 79.564632 -54.787137)
			(xy 79.605678 -54.825928) (xy 79.640558 -54.870345) (xy 79.66851 -54.919418) (xy 79.688925 -54.972075)
			(xy 79.692757 -54.989055) (xy 81.900945 -54.989055) (xy 81.900945 -54.934545) (xy 81.908703 -54.88059)
			(xy 81.924061 -54.828288) (xy 81.946706 -54.778705) (xy 81.976178 -54.732849) (xy 82.011876 -54.691654)
			(xy 82.053073 -54.65596) (xy 82.098931 -54.626492) (xy 82.148516 -54.60385) (xy 82.200819 -54.588497)
			(xy 82.254775 -54.580743) (xy 82.28203 -54.580282) (xy 82.310122 -54.580753) (xy 82.365701 -54.588985)
			(xy 82.41947 -54.60528) (xy 82.470268 -54.629286) (xy 82.516994 -54.660485) (xy 82.558639 -54.6982)
			(xy 82.5943 -54.741616) (xy 82.609182 -54.765448) (xy 82.614516 -54.774338) (xy 82.631534 -54.78653)
			(xy 82.724752 -54.80685) (xy 82.745326 -54.802532) (xy 82.753962 -54.79669) (xy 82.778034 -54.780703)
			(xy 82.829963 -54.755357) (xy 82.885118 -54.738128) (xy 82.94224 -54.729409) (xy 82.971132 -54.728872)
			(xy 82.998383 -54.729348) (xy 83.05233 -54.737108) (xy 83.104624 -54.752467) (xy 83.1542 -54.77511)
			(xy 83.200049 -54.804578) (xy 83.241238 -54.84027) (xy 83.27693 -54.88146) (xy 83.306396 -54.927311)
			(xy 83.329038 -54.976887) (xy 83.344394 -55.029182) (xy 83.352153 -55.083129) (xy 83.35264 -55.11038)
			(xy 83.352177 -55.137751) (xy 83.344361 -55.19193) (xy 83.328872 -55.244434) (xy 83.306029 -55.294181)
			(xy 83.276302 -55.340147) (xy 83.25866 -55.361078) (xy 83.258406 -55.361332) (xy 83.252842 -55.368434)
			(xy 83.246582 -55.385339) (xy 83.246214 -55.394352) (xy 83.246214 -55.461408) (xy 83.246564 -55.470426)
			(xy 83.252816 -55.487343) (xy 83.258406 -55.494428) (xy 83.25866 -55.494428) (xy 83.25866 -55.494682)
			(xy 83.276282 -55.51563) (xy 83.306008 -55.561595) (xy 83.328856 -55.611339) (xy 83.344354 -55.663839)
			(xy 83.352185 -55.718015) (xy 83.352187 -55.772755) (xy 83.34436 -55.826932) (xy 83.328866 -55.879433)
			(xy 83.306023 -55.929178) (xy 83.2763 -55.975146) (xy 83.25866 -55.996078) (xy 83.258406 -55.996332)
			(xy 83.252842 -56.003434) (xy 83.246582 -56.020339) (xy 83.246214 -56.029352) (xy 83.246214 -56.096408)
			(xy 83.246564 -56.105426) (xy 83.252816 -56.122343) (xy 83.258406 -56.129428) (xy 83.25866 -56.129428)
			(xy 83.25866 -56.129682) (xy 83.276298 -56.150615) (xy 83.306011 -56.196587) (xy 83.328848 -56.246334)
			(xy 83.344339 -56.298835) (xy 83.352167 -56.353011) (xy 83.35264 -56.38038) (xy 83.352154 -56.407631)
			(xy 83.344398 -56.461579) (xy 83.329043 -56.513874) (xy 83.306401 -56.563451) (xy 83.276935 -56.609301)
			(xy 83.241244 -56.650492) (xy 83.200053 -56.686183) (xy 83.154203 -56.715649) (xy 83.104626 -56.738291)
			(xy 83.052331 -56.753646) (xy 82.998383 -56.761402) (xy 82.943881 -56.761402) (xy 82.889933 -56.753646)
			(xy 82.837638 -56.738291) (xy 82.788061 -56.715649) (xy 82.742211 -56.686183) (xy 82.70102 -56.650492)
			(xy 82.665329 -56.609301) (xy 82.635863 -56.563451) (xy 82.613221 -56.513874) (xy 82.597866 -56.461579)
			(xy 82.59011 -56.407631) (xy 82.589624 -56.38038) (xy 82.590072 -56.353009) (xy 82.597894 -56.298829)
			(xy 82.613387 -56.246325) (xy 82.636232 -56.196579) (xy 82.665961 -56.150613) (xy 82.683604 -56.129682)
			(xy 82.683858 -56.129428) (xy 82.689446 -56.122343) (xy 82.69569 -56.105425) (xy 82.69605 -56.096408)
			(xy 82.69605 -56.029352) (xy 82.695679 -56.020336) (xy 82.689442 -56.003419) (xy 82.683858 -55.996332)
			(xy 82.683604 -55.996332) (xy 82.683604 -55.996078) (xy 82.665945 -55.975161) (xy 82.636222 -55.92919)
			(xy 82.61338 -55.879441) (xy 82.597886 -55.826936) (xy 82.59006 -55.772756) (xy 82.590062 -55.718014)
			(xy 82.597892 -55.663834) (xy 82.61339 -55.611331) (xy 82.636237 -55.561584) (xy 82.665963 -55.515615)
			(xy 82.683604 -55.494682) (xy 82.683858 -55.494428) (xy 82.689446 -55.487343) (xy 82.69569 -55.470425)
			(xy 82.69605 -55.461408) (xy 82.69605 -55.394352) (xy 82.695679 -55.385336) (xy 82.689442 -55.368419)
			(xy 82.683858 -55.361332) (xy 82.683604 -55.360824) (xy 82.672661 -55.348089) (xy 82.652819 -55.320998)
			(xy 82.64398 -55.306722) (xy 82.638646 -55.297832) (xy 82.621628 -55.28564) (xy 82.52841 -55.26532)
			(xy 82.507836 -55.269638) (xy 82.4992 -55.27548) (xy 82.475136 -55.29148) (xy 82.423205 -55.316823)
			(xy 82.368047 -55.334049) (xy 82.310923 -55.342764) (xy 82.28203 -55.343298) (xy 82.254775 -55.342857)
			(xy 82.200819 -55.335103) (xy 82.148516 -55.31975) (xy 82.098931 -55.297108) (xy 82.053073 -55.26764)
			(xy 82.011876 -55.231946) (xy 81.976178 -55.190751) (xy 81.946706 -55.144895) (xy 81.924061 -55.095312)
			(xy 81.908703 -55.04301) (xy 81.900945 -54.989055) (xy 79.692757 -54.989055) (xy 79.701356 -55.027165)
			(xy 79.705531 -55.083486) (xy 79.70136 -55.139808) (xy 79.688933 -55.194899) (xy 79.668522 -55.247557)
			(xy 79.640573 -55.296632) (xy 79.605696 -55.341052) (xy 79.564653 -55.379846) (xy 79.518341 -55.412167)
			(xy 79.500867 -55.420855) (xy 80.224545 -55.420855) (xy 80.224545 -55.366345) (xy 80.232303 -55.31239)
			(xy 80.247661 -55.260088) (xy 80.270306 -55.210505) (xy 80.299778 -55.164649) (xy 80.335476 -55.123454)
			(xy 80.376673 -55.08776) (xy 80.422531 -55.058292) (xy 80.472116 -55.03565) (xy 80.524419 -55.020297)
			(xy 80.578375 -55.012543) (xy 80.60563 -55.012082) (xy 80.631944 -55.012535) (xy 80.684073 -55.019774)
			(xy 80.734716 -55.034096) (xy 80.782915 -55.055231) (xy 80.827758 -55.082779) (xy 80.868397 -55.11622)
			(xy 80.886554 -55.135272) (xy 80.894057 -55.142695) (xy 80.913351 -55.151208) (xy 80.923892 -55.151782)
			(xy 80.998568 -55.151782) (xy 81.009118 -55.151255) (xy 81.028414 -55.142719) (xy 81.035906 -55.135272)
			(xy 81.05406 -55.116215) (xy 81.094691 -55.082759) (xy 81.139532 -55.055201) (xy 81.187733 -55.034063)
			(xy 81.23838 -55.019746) (xy 81.290514 -55.012521) (xy 81.31683 -55.012082) (xy 81.344079 -55.01259)
			(xy 81.398022 -55.02035) (xy 81.450312 -55.035707) (xy 81.499884 -55.05835) (xy 81.545729 -55.087816)
			(xy 81.586915 -55.123506) (xy 81.622602 -55.164695) (xy 81.652065 -55.210542) (xy 81.674703 -55.260116)
			(xy 81.690056 -55.312407) (xy 81.697812 -55.366351) (xy 81.697812 -55.420849) (xy 81.690056 -55.474793)
			(xy 81.674703 -55.527084) (xy 81.652065 -55.576658) (xy 81.622602 -55.622505) (xy 81.586915 -55.663694)
			(xy 81.545729 -55.699384) (xy 81.499884 -55.72885) (xy 81.450312 -55.751493) (xy 81.398022 -55.76685)
			(xy 81.344079 -55.77461) (xy 81.31683 -55.775098) (xy 81.290514 -55.774678) (xy 81.238384 -55.767433)
			(xy 81.18774 -55.753105) (xy 81.139541 -55.731964) (xy 81.094699 -55.704409) (xy 81.054061 -55.670963)
			(xy 81.035906 -55.651908) (xy 81.028383 -55.644508) (xy 81.009104 -55.635983) (xy 80.998568 -55.635398)
			(xy 80.923892 -55.635398) (xy 80.91334 -55.63591) (xy 80.894045 -55.644457) (xy 80.886554 -55.651908)
			(xy 80.868415 -55.67098) (xy 80.827782 -55.704436) (xy 80.782938 -55.731992) (xy 80.734734 -55.753128)
			(xy 80.684084 -55.767441) (xy 80.631947 -55.774662) (xy 80.60563 -55.775098) (xy 80.578375 -55.774657)
			(xy 80.524419 -55.766903) (xy 80.472116 -55.75155) (xy 80.422531 -55.728908) (xy 80.376673 -55.69944)
			(xy 80.335476 -55.663746) (xy 80.299778 -55.622551) (xy 80.270306 -55.576695) (xy 80.247661 -55.527112)
			(xy 80.232303 -55.47481) (xy 80.224545 -55.420855) (xy 79.500867 -55.420855) (xy 79.46777 -55.43731)
			(xy 79.44104 -55.446422) (xy 79.433166 -55.448962) (xy 79.420466 -55.45836) (xy 79.414878 -55.46598)
			(xy 79.41077 -55.472433) (xy 79.406245 -55.487037) (xy 79.405988 -55.494682) (xy 79.405988 -55.94223)
			(xy 79.406251 -55.949874) (xy 79.410779 -55.964475) (xy 79.414878 -55.970932) (xy 79.420466 -55.978552)
			(xy 79.433166 -55.98795) (xy 79.44104 -55.99049) (xy 79.467745 -55.99968) (xy 79.518317 -56.024819)
			(xy 79.564632 -56.057137) (xy 79.605678 -56.095928) (xy 79.640558 -56.140345) (xy 79.66851 -56.189418)
			(xy 79.688925 -56.242075) (xy 79.701356 -56.297165) (xy 79.705531 -56.353486) (xy 79.70136 -56.409808)
			(xy 79.688933 -56.464899) (xy 79.668522 -56.517557) (xy 79.640573 -56.566632) (xy 79.605696 -56.611052)
			(xy 79.564653 -56.649846) (xy 79.518341 -56.682167) (xy 79.46777 -56.70731) (xy 79.44104 -56.716422)
			(xy 79.433166 -56.718962) (xy 79.420466 -56.72836) (xy 79.414878 -56.73598) (xy 79.41077 -56.742433)
			(xy 79.406245 -56.757037) (xy 79.405988 -56.764682) (xy 79.405988 -57.48528) (xy 82.605878 -57.48528)
			(xy 82.609949 -57.429658) (xy 82.622075 -57.375221) (xy 82.641998 -57.32313) (xy 82.669294 -57.274495)
			(xy 82.70338 -57.230352) (xy 82.743529 -57.191643) (xy 82.788887 -57.159192) (xy 82.838487 -57.133691)
			(xy 82.891271 -57.115684) (xy 82.946114 -57.105554) (xy 83.001848 -57.103517) (xy 83.057285 -57.109617)
			(xy 83.111242 -57.123723) (xy 83.162571 -57.145535) (xy 83.210177 -57.174589) (xy 83.253045 -57.210264)
			(xy 83.290262 -57.251801) (xy 83.321035 -57.298314) (xy 83.344707 -57.348811) (xy 83.360775 -57.402218)
			(xy 83.368895 -57.457394) (xy 83.369404 -57.48528) (xy 83.368895 -57.513166) (xy 83.360775 -57.568342)
			(xy 83.344707 -57.621749) (xy 83.321035 -57.672246) (xy 83.290262 -57.718759) (xy 83.253045 -57.760296)
			(xy 83.210177 -57.795971) (xy 83.162571 -57.825025) (xy 83.111242 -57.846837) (xy 83.057285 -57.860943)
			(xy 83.001848 -57.867043) (xy 82.946114 -57.865006) (xy 82.891271 -57.854876) (xy 82.838487 -57.836869)
			(xy 82.788887 -57.811368) (xy 82.743529 -57.778917) (xy 82.70338 -57.740208) (xy 82.669294 -57.696065)
			(xy 82.641998 -57.64743) (xy 82.622075 -57.595339) (xy 82.609949 -57.540902) (xy 82.605878 -57.48528)
			(xy 79.405988 -57.48528) (xy 79.405988 -58.076084) (xy 83.357972 -58.076084) (xy 83.362043 -58.020462)
			(xy 83.374169 -57.966025) (xy 83.394092 -57.913934) (xy 83.421388 -57.865299) (xy 83.455474 -57.821156)
			(xy 83.495623 -57.782447) (xy 83.540981 -57.749996) (xy 83.590581 -57.724495) (xy 83.643365 -57.706488)
			(xy 83.698208 -57.696358) (xy 83.753942 -57.694321) (xy 83.809379 -57.700421) (xy 83.863336 -57.714527)
			(xy 83.914665 -57.736339) (xy 83.962271 -57.765393) (xy 84.005139 -57.801068) (xy 84.042356 -57.842605)
			(xy 84.058692 -57.867296) (xy 85.642702 -57.867296) (xy 85.646775 -57.811637) (xy 85.65891 -57.757164)
			(xy 85.678846 -57.705038) (xy 85.70616 -57.65637) (xy 85.740268 -57.612198) (xy 85.780445 -57.573463)
			(xy 85.825833 -57.540991) (xy 85.875465 -57.515473) (xy 85.928285 -57.497454) (xy 85.983164 -57.487317)
			(xy 86.038935 -57.485279) (xy 86.094409 -57.491382) (xy 86.148402 -57.505498) (xy 86.199765 -57.527325)
			(xy 86.247403 -57.556398) (xy 86.290299 -57.592097) (xy 86.327541 -57.633661) (xy 86.358335 -57.680205)
			(xy 86.382023 -57.730736) (xy 86.398101 -57.784178) (xy 86.406227 -57.839392) (xy 86.406736 -57.867296)
			(xy 86.406227 -57.8952) (xy 86.398101 -57.950414) (xy 86.382023 -58.003856) (xy 86.358335 -58.054387)
			(xy 86.327541 -58.100931) (xy 86.290299 -58.142495) (xy 86.247403 -58.178194) (xy 86.199765 -58.207267)
			(xy 86.148402 -58.229094) (xy 86.094409 -58.24321) (xy 86.038935 -58.249313) (xy 85.983164 -58.247275)
			(xy 85.928285 -58.237138) (xy 85.875465 -58.219119) (xy 85.825833 -58.193601) (xy 85.780445 -58.161129)
			(xy 85.740268 -58.122394) (xy 85.70616 -58.078222) (xy 85.678846 -58.029554) (xy 85.65891 -57.977428)
			(xy 85.646775 -57.922955) (xy 85.642702 -57.867296) (xy 84.058692 -57.867296) (xy 84.073129 -57.889118)
			(xy 84.096801 -57.939615) (xy 84.112869 -57.993022) (xy 84.120989 -58.048198) (xy 84.121498 -58.076084)
			(xy 84.120989 -58.10397) (xy 84.112869 -58.159146) (xy 84.096801 -58.212553) (xy 84.073129 -58.26305)
			(xy 84.042356 -58.309563) (xy 84.005139 -58.3511) (xy 83.962271 -58.386775) (xy 83.914665 -58.415829)
			(xy 83.863336 -58.437641) (xy 83.809379 -58.451747) (xy 83.753942 -58.457847) (xy 83.698208 -58.45581)
			(xy 83.643365 -58.44568) (xy 83.590581 -58.427673) (xy 83.540981 -58.402172) (xy 83.495623 -58.369721)
			(xy 83.455474 -58.331012) (xy 83.421388 -58.286869) (xy 83.394092 -58.238234) (xy 83.374169 -58.186143)
			(xy 83.362043 -58.131706) (xy 83.357972 -58.076084) (xy 79.405988 -58.076084) (xy 79.405988 -58.561224)
			(xy 84.562186 -58.561224) (xy 84.566257 -58.505602) (xy 84.578383 -58.451165) (xy 84.598306 -58.399074)
			(xy 84.625602 -58.350439) (xy 84.659688 -58.306296) (xy 84.699837 -58.267587) (xy 84.745195 -58.235136)
			(xy 84.794795 -58.209635) (xy 84.847579 -58.191628) (xy 84.902422 -58.181498) (xy 84.958156 -58.179461)
			(xy 85.013593 -58.185561) (xy 85.06755 -58.199667) (xy 85.118879 -58.221479) (xy 85.166485 -58.250533)
			(xy 85.209353 -58.286208) (xy 85.24657 -58.327745) (xy 85.277343 -58.374258) (xy 85.301015 -58.424755)
			(xy 85.308525 -58.449718) (xy 86.808816 -58.449718) (xy 86.812887 -58.394096) (xy 86.825013 -58.339659)
			(xy 86.844936 -58.287568) (xy 86.872232 -58.238933) (xy 86.906318 -58.19479) (xy 86.946467 -58.156081)
			(xy 86.991825 -58.12363) (xy 87.041425 -58.098129) (xy 87.094209 -58.080122) (xy 87.149052 -58.069992)
			(xy 87.204786 -58.067955) (xy 87.260223 -58.074055) (xy 87.31418 -58.088161) (xy 87.365509 -58.109973)
			(xy 87.413115 -58.139027) (xy 87.455983 -58.174702) (xy 87.4932 -58.216239) (xy 87.523973 -58.262752)
			(xy 87.547645 -58.313249) (xy 87.563713 -58.366656) (xy 87.571833 -58.421832) (xy 87.572342 -58.449718)
			(xy 87.571833 -58.477604) (xy 87.563713 -58.53278) (xy 87.547645 -58.586187) (xy 87.523973 -58.636684)
			(xy 87.4932 -58.683197) (xy 87.455983 -58.724734) (xy 87.413115 -58.760409) (xy 87.365509 -58.789463)
			(xy 87.31418 -58.811275) (xy 87.260223 -58.825381) (xy 87.204786 -58.831481) (xy 87.149052 -58.829444)
			(xy 87.094209 -58.819314) (xy 87.041425 -58.801307) (xy 86.991825 -58.775806) (xy 86.946467 -58.743355)
			(xy 86.906318 -58.704646) (xy 86.872232 -58.660503) (xy 86.844936 -58.611868) (xy 86.825013 -58.559777)
			(xy 86.812887 -58.50534) (xy 86.808816 -58.449718) (xy 85.308525 -58.449718) (xy 85.317083 -58.478162)
			(xy 85.325203 -58.533338) (xy 85.325712 -58.561224) (xy 85.325203 -58.58911) (xy 85.317083 -58.644286)
			(xy 85.301015 -58.697693) (xy 85.277343 -58.74819) (xy 85.24657 -58.794703) (xy 85.209353 -58.83624)
			(xy 85.166485 -58.871915) (xy 85.118879 -58.900969) (xy 85.06755 -58.922781) (xy 85.013593 -58.936887)
			(xy 84.958156 -58.942987) (xy 84.902422 -58.94095) (xy 84.847579 -58.93082) (xy 84.794795 -58.912813)
			(xy 84.745195 -58.887312) (xy 84.699837 -58.854861) (xy 84.659688 -58.816152) (xy 84.625602 -58.772009)
			(xy 84.598306 -58.723374) (xy 84.578383 -58.671283) (xy 84.566257 -58.616846) (xy 84.562186 -58.561224)
			(xy 79.405988 -58.561224) (xy 79.405988 -59.974734) (xy 83.086956 -59.974734) (xy 83.087407 -59.947908)
			(xy 83.094927 -59.894785) (xy 83.109808 -59.843238) (xy 83.131759 -59.794281) (xy 83.160346 -59.74888)
			(xy 83.195008 -59.707926) (xy 83.23506 -59.672228) (xy 83.257136 -59.65698) (xy 83.268701 -59.648762)
			(xy 83.287102 -59.627181) (xy 83.298854 -59.601369) (xy 83.303048 -59.573319) (xy 83.29936 -59.545199)
			(xy 83.288076 -59.51918) (xy 83.270066 -59.497271) (xy 83.25866 -59.488832) (xy 83.2372 -59.473485)
			(xy 83.198288 -59.437856) (xy 83.164656 -59.397206) (xy 83.136946 -59.352309) (xy 83.115686 -59.304023)
			(xy 83.101282 -59.253269) (xy 83.094008 -59.201013) (xy 83.09356 -59.174634) (xy 83.094046 -59.147383)
			(xy 83.101802 -59.093435) (xy 83.117157 -59.04114) (xy 83.139799 -58.991563) (xy 83.169265 -58.945713)
			(xy 83.204956 -58.904522) (xy 83.246147 -58.868831) (xy 83.291997 -58.839365) (xy 83.341574 -58.816723)
			(xy 83.393869 -58.801368) (xy 83.447817 -58.793612) (xy 83.502319 -58.793612) (xy 83.556267 -58.801368)
			(xy 83.608562 -58.816723) (xy 83.658139 -58.839365) (xy 83.703989 -58.868831) (xy 83.74518 -58.904522)
			(xy 83.780871 -58.945713) (xy 83.810337 -58.991563) (xy 83.832979 -59.04114) (xy 83.848334 -59.093435)
			(xy 83.85609 -59.147383) (xy 83.856576 -59.174634) (xy 83.856131 -59.201461) (xy 83.848614 -59.254585)
			(xy 83.833734 -59.306134) (xy 83.811783 -59.355091) (xy 83.783194 -59.400493) (xy 83.74853 -59.441446)
			(xy 83.708474 -59.477141) (xy 83.686396 -59.492388) (xy 83.674859 -59.500645) (xy 83.656453 -59.522215)
			(xy 83.644696 -59.548019) (xy 83.640497 -59.576063) (xy 83.64418 -59.604179) (xy 83.655461 -59.630194)
			(xy 83.673467 -59.6521) (xy 83.684872 -59.660536) (xy 83.706371 -59.675831) (xy 83.745281 -59.71147)
			(xy 83.778908 -59.752129) (xy 83.806613 -59.797035) (xy 83.827866 -59.845329) (xy 83.842263 -59.896091)
			(xy 83.849528 -59.948352) (xy 83.849972 -59.974734) (xy 83.849486 -60.001985) (xy 83.84173 -60.055933)
			(xy 83.826375 -60.108228) (xy 83.803733 -60.157805) (xy 83.774267 -60.203655) (xy 83.738576 -60.244846)
			(xy 83.697385 -60.280537) (xy 83.651535 -60.310003) (xy 83.601958 -60.332645) (xy 83.549663 -60.348)
			(xy 83.495715 -60.355756) (xy 83.441213 -60.355756) (xy 83.387265 -60.348) (xy 83.33497 -60.332645)
			(xy 83.285393 -60.310003) (xy 83.239543 -60.280537) (xy 83.198352 -60.244846) (xy 83.162661 -60.203655)
			(xy 83.133195 -60.157805) (xy 83.110553 -60.108228) (xy 83.095198 -60.055933) (xy 83.087442 -60.001985)
			(xy 83.086956 -59.974734) (xy 79.405988 -59.974734) (xy 79.405988 -60.601606) (xy 82.333082 -60.601606)
			(xy 82.337153 -60.545984) (xy 82.349279 -60.491547) (xy 82.369202 -60.439456) (xy 82.396498 -60.390821)
			(xy 82.430584 -60.346678) (xy 82.470733 -60.307969) (xy 82.516091 -60.275518) (xy 82.565691 -60.250017)
			(xy 82.618475 -60.23201) (xy 82.673318 -60.22188) (xy 82.729052 -60.219843) (xy 82.784489 -60.225943)
			(xy 82.838446 -60.240049) (xy 82.889775 -60.261861) (xy 82.937381 -60.290915) (xy 82.980249 -60.32659)
			(xy 83.017466 -60.368127) (xy 83.048239 -60.41464) (xy 83.071911 -60.465137) (xy 83.087979 -60.518544)
			(xy 83.096099 -60.57372) (xy 83.096608 -60.601606) (xy 83.096144 -60.627006) (xy 84.72119 -60.627006)
			(xy 84.725261 -60.571384) (xy 84.737387 -60.516947) (xy 84.75731 -60.464856) (xy 84.784606 -60.416221)
			(xy 84.818692 -60.372078) (xy 84.858841 -60.333369) (xy 84.904199 -60.300918) (xy 84.953799 -60.275417)
			(xy 85.006583 -60.25741) (xy 85.061426 -60.24728) (xy 85.11716 -60.245243) (xy 85.172597 -60.251343)
			(xy 85.226554 -60.265449) (xy 85.277883 -60.287261) (xy 85.325489 -60.316315) (xy 85.368357 -60.35199)
			(xy 85.405574 -60.393527) (xy 85.436347 -60.44004) (xy 85.460019 -60.490537) (xy 85.476087 -60.543944)
			(xy 85.484207 -60.59912) (xy 85.484716 -60.627006) (xy 85.4846 -60.633356) (xy 86.81288 -60.633356)
			(xy 86.816951 -60.577734) (xy 86.829077 -60.523297) (xy 86.849 -60.471206) (xy 86.876296 -60.422571)
			(xy 86.910382 -60.378428) (xy 86.950531 -60.339719) (xy 86.995889 -60.307268) (xy 87.045489 -60.281767)
			(xy 87.098273 -60.26376) (xy 87.153116 -60.25363) (xy 87.20885 -60.251593) (xy 87.264287 -60.257693)
			(xy 87.318244 -60.271799) (xy 87.369573 -60.293611) (xy 87.417179 -60.322665) (xy 87.460047 -60.35834)
			(xy 87.497264 -60.399877) (xy 87.528037 -60.44639) (xy 87.551709 -60.496887) (xy 87.567777 -60.550294)
			(xy 87.575897 -60.60547) (xy 87.576406 -60.633356) (xy 87.575897 -60.661242) (xy 87.567777 -60.716418)
			(xy 87.551709 -60.769825) (xy 87.528037 -60.820322) (xy 87.497264 -60.866835) (xy 87.460047 -60.908372)
			(xy 87.417179 -60.944047) (xy 87.369573 -60.973101) (xy 87.318244 -60.994913) (xy 87.264287 -61.009019)
			(xy 87.20885 -61.015119) (xy 87.153116 -61.013082) (xy 87.098273 -61.002952) (xy 87.045489 -60.984945)
			(xy 86.995889 -60.959444) (xy 86.950531 -60.926993) (xy 86.910382 -60.888284) (xy 86.876296 -60.844141)
			(xy 86.849 -60.795506) (xy 86.829077 -60.743415) (xy 86.816951 -60.688978) (xy 86.81288 -60.633356)
			(xy 85.4846 -60.633356) (xy 85.484207 -60.654892) (xy 85.476087 -60.710068) (xy 85.460019 -60.763475)
			(xy 85.436347 -60.813972) (xy 85.405574 -60.860485) (xy 85.368357 -60.902022) (xy 85.325489 -60.937697)
			(xy 85.277883 -60.966751) (xy 85.226554 -60.988563) (xy 85.172597 -61.002669) (xy 85.11716 -61.008769)
			(xy 85.061426 -61.006732) (xy 85.006583 -60.996602) (xy 84.953799 -60.978595) (xy 84.904199 -60.953094)
			(xy 84.858841 -60.920643) (xy 84.818692 -60.881934) (xy 84.784606 -60.837791) (xy 84.75731 -60.789156)
			(xy 84.737387 -60.737065) (xy 84.725261 -60.682628) (xy 84.72119 -60.627006) (xy 83.096144 -60.627006)
			(xy 83.096099 -60.629492) (xy 83.087979 -60.684668) (xy 83.071911 -60.738075) (xy 83.048239 -60.788572)
			(xy 83.017466 -60.835085) (xy 82.980249 -60.876622) (xy 82.937381 -60.912297) (xy 82.889775 -60.941351)
			(xy 82.838446 -60.963163) (xy 82.784489 -60.977269) (xy 82.729052 -60.983369) (xy 82.673318 -60.981332)
			(xy 82.618475 -60.971202) (xy 82.565691 -60.953195) (xy 82.516091 -60.927694) (xy 82.470733 -60.895243)
			(xy 82.430584 -60.856534) (xy 82.396498 -60.812391) (xy 82.369202 -60.763756) (xy 82.349279 -60.711665)
			(xy 82.337153 -60.657228) (xy 82.333082 -60.601606) (xy 79.405988 -60.601606) (xy 79.405988 -61.328046)
			(xy 79.407004 -61.337444) (xy 79.407004 -61.337952) (xy 79.408705 -61.345113) (xy 79.415532 -61.358145)
			(xy 79.420466 -61.363606) (xy 79.61376 -61.5569) (xy 79.621168 -61.56359) (xy 79.639604 -61.571187)
			(xy 79.649574 -61.571632) (xy 82.1817 -61.571632) (xy 82.18932 -61.571886) (xy 83.061048 -61.571886)
		)
		(stroke
			(width 0)
			(type solid)
		)
		(fill yes)
		(layer "In9.Cu")
		(net "P3V3_SSD3")
	)
	(gr_poly
		(pts
			(xy 57.066688 -61.571632) (xy 58.203592 -61.571632) (xy 58.213375 -61.571177) (xy 58.231519 -61.563849)
			(xy 58.238898 -61.557408) (xy 58.255662 -61.541406) (xy 58.290968 -61.50737) (xy 58.29399 -61.504155)
			(xy 58.298968 -61.496871) (xy 58.300874 -61.492892) (xy 58.304938 -61.484002) (xy 58.305192 -61.473588)
			(xy 58.306738 -61.445754) (xy 58.316902 -61.390943) (xy 58.334933 -61.338195) (xy 58.360449 -61.288632)
			(xy 58.392906 -61.24331) (xy 58.431613 -61.203195) (xy 58.475747 -61.169139) (xy 58.524366 -61.141869)
			(xy 58.576437 -61.121964) (xy 58.630849 -61.109849) (xy 58.686446 -61.105782) (xy 58.742043 -61.109849)
			(xy 58.796455 -61.121964) (xy 58.848526 -61.141869) (xy 58.897145 -61.169139) (xy 58.941279 -61.203195)
			(xy 58.979986 -61.24331) (xy 59.012443 -61.288632) (xy 59.037959 -61.338195) (xy 59.05599 -61.390943)
			(xy 59.066154 -61.445754) (xy 59.0677 -61.473588) (xy 59.0677 -61.473842) (xy 59.068208 -61.484256)
			(xy 59.072018 -61.492892) (xy 59.073897 -61.496782) (xy 59.078752 -61.503929) (xy 59.08167 -61.507116)
			(xy 59.12612 -61.549788) (xy 59.133994 -61.557408) (xy 59.141341 -61.563902) (xy 59.159504 -61.571241)
			(xy 59.1693 -61.571632) (xy 62.759336 -61.571632) (xy 62.769321 -61.571089) (xy 62.787747 -61.56337)
			(xy 62.79515 -61.556646) (xy 63.421514 -60.930282) (xy 63.428331 -60.92294) (xy 63.43607 -60.904477)
			(xy 63.4365 -60.894468) (xy 63.4365 -38.896036) (xy 63.43523 -38.88486) (xy 63.433516 -38.878315)
			(xy 63.427221 -38.866345) (xy 63.422784 -38.861238) (xy 63.390988 -38.833104) (xy 63.332049 -38.771984)
			(xy 63.278859 -38.705801) (xy 63.231851 -38.635093) (xy 63.191408 -38.560436) (xy 63.157859 -38.482437)
			(xy 63.131478 -38.401732) (xy 63.112478 -38.318977) (xy 63.101015 -38.234846) (xy 63.097182 -38.150025)
			(xy 63.101011 -38.065203) (xy 63.112469 -37.981072) (xy 63.131464 -37.898316) (xy 63.157842 -37.817609)
			(xy 63.191386 -37.739609) (xy 63.231825 -37.664949) (xy 63.278829 -37.594239) (xy 63.332016 -37.528053)
			(xy 63.390951 -37.466931) (xy 63.422784 -37.438838) (xy 63.427264 -37.43376) (xy 63.433571 -37.421782)
			(xy 63.43523 -37.415216) (xy 63.4365 -37.40404) (xy 63.4365 -31.789624) (xy 63.432944 -31.780734)
			(xy 63.42472 -31.758594) (xy 63.413176 -31.712794) (xy 63.407372 -31.66592) (xy 63.407036 -31.642304)
			(xy 63.407371 -31.618687) (xy 63.413167 -31.571811) (xy 63.424707 -31.52601) (xy 63.432944 -31.503874)
			(xy 63.4365 -31.494984) (xy 63.4365 -31.233364) (xy 63.436622 -31.22841) (xy 63.438547 -31.218692)
			(xy 63.44031 -31.21406) (xy 63.44539 -31.201868) (xy 63.44716 -31.197239) (xy 63.449072 -31.187518)
			(xy 63.4492 -31.182564) (xy 63.4492 -29.848556) (xy 63.448884 -29.840365) (xy 63.443691 -29.824827)
			(xy 63.43904 -29.818076) (xy 63.423169 -29.796008) (xy 63.39717 -29.748271) (xy 63.378215 -29.697327)
			(xy 63.366686 -29.644206) (xy 63.362818 -29.589987) (xy 63.36669 -29.535768) (xy 63.378222 -29.482649)
			(xy 63.397181 -29.431705) (xy 63.423183 -29.383971) (xy 63.43904 -29.361892) (xy 63.443711 -29.355152)
			(xy 63.448896 -29.339606) (xy 63.4492 -29.331412) (xy 63.4492 -28.107894) (xy 63.44923 -28.104161)
			(xy 63.450253 -28.096765) (xy 63.451232 -28.093162) (xy 63.452626 -28.088209) (xy 63.453655 -28.077972)
			(xy 63.453264 -28.072842) (xy 63.449962 -28.044648) (xy 63.449002 -28.037922) (xy 63.443974 -28.025307)
			(xy 63.440056 -28.019756) (xy 63.422005 -27.994778) (xy 63.393348 -27.940223) (xy 63.373818 -27.881776)
			(xy 63.363922 -27.820952) (xy 63.363348 -27.79014) (xy 63.363831 -27.762886) (xy 63.371583 -27.708931)
			(xy 63.386934 -27.656629) (xy 63.409572 -27.607044) (xy 63.439037 -27.561186) (xy 63.474728 -27.519987)
			(xy 63.515918 -27.484287) (xy 63.56177 -27.454812) (xy 63.61135 -27.432163) (xy 63.663649 -27.416801)
			(xy 63.717602 -27.409037) (xy 63.744856 -27.408632) (xy 63.770402 -27.409044) (xy 63.821038 -27.415867)
			(xy 63.870311 -27.429381) (xy 63.917341 -27.449347) (xy 63.961288 -27.475408) (xy 63.981584 -27.490928)
			(xy 63.989086 -27.496342) (xy 64.006714 -27.501909) (xy 64.025171 -27.500868) (xy 64.04206 -27.493353)
			(xy 64.048894 -27.487118) (xy 64.19342 -27.342592) (xy 64.20082 -27.33575) (xy 64.219418 -27.328024)
			(xy 64.229488 -27.327606) (xy 64.419734 -27.327606) (xy 64.427354 -27.327352) (xy 68.472812 -27.327352)
			(xy 68.482828 -27.32693) (xy 68.501333 -27.319256) (xy 68.51549 -27.305082) (xy 68.523141 -27.286569)
			(xy 68.523612 -27.276552) (xy 68.523612 -26.479246) (xy 68.523825 -26.457072) (xy 68.528027 -26.412925)
			(xy 68.531994 -26.391108) (xy 68.531994 -26.3906) (xy 68.532248 -26.389584) (xy 68.532756 -26.387298)
			(xy 68.533264 -26.385266) (xy 68.533939 -26.380054) (xy 68.533434 -26.369558) (xy 68.532248 -26.364438)
			(xy 68.530216 -26.358088) (xy 68.524628 -26.344626) (xy 68.515992 -26.33853) (xy 68.50761 -26.332688)
			(xy 68.501768 -26.329132) (xy 68.491862 -26.326846) (xy 68.468039 -26.341239) (xy 68.417222 -26.363945)
			(xy 68.363732 -26.379333) (xy 68.308618 -26.387102) (xy 68.280788 -26.387552) (xy 68.252389 -26.387068)
			(xy 68.196168 -26.378983) (xy 68.141671 -26.362979) (xy 68.090006 -26.339382) (xy 68.042225 -26.308673)
			(xy 67.9993 -26.271476) (xy 67.962107 -26.228548) (xy 67.931401 -26.180765) (xy 67.907809 -26.129097)
			(xy 67.89181 -26.074599) (xy 67.883729 -26.018377) (xy 67.883732 -25.961579) (xy 67.891819 -25.905358)
			(xy 67.907824 -25.850861) (xy 67.931423 -25.799197) (xy 67.962133 -25.751417) (xy 67.999332 -25.708493)
			(xy 68.04226 -25.671301) (xy 68.090044 -25.640597) (xy 68.141712 -25.617005) (xy 68.196211 -25.601007)
			(xy 68.252433 -25.592929) (xy 68.309231 -25.592933) (xy 68.365451 -25.601021) (xy 68.419948 -25.617028)
			(xy 68.471612 -25.640627) (xy 68.519391 -25.671339) (xy 68.562314 -25.708539) (xy 68.599505 -25.751468)
			(xy 68.630208 -25.799253) (xy 68.645184 -25.832054) (xy 70.187818 -25.832054) (xy 70.191889 -25.776432)
			(xy 70.204015 -25.721995) (xy 70.223938 -25.669904) (xy 70.251234 -25.621269) (xy 70.28532 -25.577126)
			(xy 70.325469 -25.538417) (xy 70.370827 -25.505966) (xy 70.420427 -25.480465) (xy 70.473211 -25.462458)
			(xy 70.528054 -25.452328) (xy 70.583788 -25.450291) (xy 70.639225 -25.456391) (xy 70.693182 -25.470497)
			(xy 70.744511 -25.492309) (xy 70.792117 -25.521363) (xy 70.834985 -25.557038) (xy 70.836519 -25.55875)
			(xy 74.642218 -25.55875) (xy 74.642704 -25.531499) (xy 74.65046 -25.477551) (xy 74.665815 -25.425256)
			(xy 74.688457 -25.375679) (xy 74.717923 -25.329829) (xy 74.753614 -25.288638) (xy 74.794805 -25.252947)
			(xy 74.840655 -25.223481) (xy 74.890232 -25.200839) (xy 74.942527 -25.185484) (xy 74.996475 -25.177728)
			(xy 75.050977 -25.177728) (xy 75.104925 -25.185484) (xy 75.15722 -25.200839) (xy 75.206797 -25.223481)
			(xy 75.252647 -25.252947) (xy 75.293838 -25.288638) (xy 75.329529 -25.329829) (xy 75.358995 -25.375679)
			(xy 75.381637 -25.425256) (xy 75.396992 -25.477551) (xy 75.404748 -25.531499) (xy 75.405234 -25.55875)
			(xy 75.404679 -25.589013) (xy 75.395126 -25.648779) (xy 75.376253 -25.706287) (xy 75.348534 -25.760091)
			(xy 75.331066 -25.78481) (xy 75.322788 -25.796957) (xy 75.312839 -25.8246) (xy 75.311172 -25.853932)
			(xy 75.317925 -25.882524) (xy 75.332539 -25.908011) (xy 75.353804 -25.928282) (xy 75.37996 -25.941661)
			(xy 75.394312 -25.94483) (xy 75.420207 -25.950166) (xy 75.470329 -25.966983) (xy 75.517649 -25.990563)
			(xy 75.561257 -26.020453) (xy 75.600319 -26.05608) (xy 75.634085 -26.096761) (xy 75.661908 -26.141717)
			(xy 75.683255 -26.190084) (xy 75.697716 -26.240937) (xy 75.705014 -26.2933) (xy 75.705462 -26.319734)
			(xy 76.841856 -26.319734) (xy 76.845927 -26.264112) (xy 76.858053 -26.209675) (xy 76.877976 -26.157584)
			(xy 76.905272 -26.108949) (xy 76.939358 -26.064806) (xy 76.979507 -26.026097) (xy 77.024865 -25.993646)
			(xy 77.074465 -25.968145) (xy 77.127249 -25.950138) (xy 77.182092 -25.940008) (xy 77.237826 -25.937971)
			(xy 77.293263 -25.944071) (xy 77.34722 -25.958177) (xy 77.398549 -25.979989) (xy 77.446155 -26.009043)
			(xy 77.489023 -26.044718) (xy 77.52624 -26.086255) (xy 77.557013 -26.132768) (xy 77.580685 -26.183265)
			(xy 77.596753 -26.236672) (xy 77.604873 -26.291848) (xy 77.605382 -26.319734) (xy 77.604873 -26.34762)
			(xy 77.596753 -26.402796) (xy 77.580685 -26.456203) (xy 77.557013 -26.5067) (xy 77.52624 -26.553213)
			(xy 77.489023 -26.59475) (xy 77.446155 -26.630425) (xy 77.398549 -26.659479) (xy 77.34722 -26.681291)
			(xy 77.293263 -26.695397) (xy 77.237826 -26.701497) (xy 77.182092 -26.69946) (xy 77.127249 -26.68933)
			(xy 77.074465 -26.671323) (xy 77.024865 -26.645822) (xy 76.979507 -26.613371) (xy 76.939358 -26.574662)
			(xy 76.905272 -26.530519) (xy 76.877976 -26.481884) (xy 76.858053 -26.429793) (xy 76.845927 -26.375356)
			(xy 76.841856 -26.319734) (xy 75.705462 -26.319734) (xy 75.704976 -26.346985) (xy 75.69722 -26.400933)
			(xy 75.681865 -26.453228) (xy 75.659223 -26.502805) (xy 75.629757 -26.548655) (xy 75.594066 -26.589846)
			(xy 75.552875 -26.625537) (xy 75.507025 -26.655003) (xy 75.457448 -26.677645) (xy 75.405153 -26.693)
			(xy 75.351205 -26.700756) (xy 75.296703 -26.700756) (xy 75.242755 -26.693) (xy 75.19046 -26.677645)
			(xy 75.140883 -26.655003) (xy 75.095033 -26.625537) (xy 75.053842 -26.589846) (xy 75.018151 -26.548655)
			(xy 74.988685 -26.502805) (xy 74.966043 -26.453228) (xy 74.950688 -26.400933) (xy 74.942932 -26.346985)
			(xy 74.942446 -26.319734) (xy 74.942997 -26.289471) (xy 74.952551 -26.229705) (xy 74.971426 -26.172197)
			(xy 74.999146 -26.118393) (xy 75.016614 -26.093674) (xy 75.024924 -26.081547) (xy 75.034874 -26.053897)
			(xy 75.036539 -26.024558) (xy 75.029782 -25.99596) (xy 75.015162 -25.97047) (xy 74.993889 -25.950197)
			(xy 74.967724 -25.936821) (xy 74.953368 -25.933654) (xy 74.927467 -25.928348) (xy 74.877343 -25.911527)
			(xy 74.830023 -25.887944) (xy 74.786415 -25.85805) (xy 74.747353 -25.82242) (xy 74.713588 -25.781735)
			(xy 74.685766 -25.736776) (xy 74.664421 -25.688406) (xy 74.649961 -25.637551) (xy 74.642665 -25.585186)
			(xy 74.642218 -25.55875) (xy 70.836519 -25.55875) (xy 70.872202 -25.598575) (xy 70.902975 -25.645088)
			(xy 70.926647 -25.695585) (xy 70.942715 -25.748992) (xy 70.950835 -25.804168) (xy 70.951344 -25.832054)
			(xy 70.950835 -25.85994) (xy 70.942715 -25.915116) (xy 70.926647 -25.968523) (xy 70.902975 -26.01902)
			(xy 70.872202 -26.065533) (xy 70.834985 -26.10707) (xy 70.792117 -26.142745) (xy 70.744511 -26.171799)
			(xy 70.693182 -26.193611) (xy 70.639225 -26.207717) (xy 70.583788 -26.213817) (xy 70.528054 -26.21178)
			(xy 70.473211 -26.20165) (xy 70.420427 -26.183643) (xy 70.370827 -26.158142) (xy 70.325469 -26.125691)
			(xy 70.28532 -26.086982) (xy 70.251234 -26.042839) (xy 70.223938 -25.994204) (xy 70.204015 -25.942113)
			(xy 70.191889 -25.887676) (xy 70.187818 -25.832054) (xy 68.645184 -25.832054) (xy 68.653798 -25.850921)
			(xy 68.669795 -25.905421) (xy 68.677872 -25.961643) (xy 68.678298 -25.990042) (xy 68.677973 -26.011229)
			(xy 68.673389 -26.053354) (xy 68.669154 -26.074116) (xy 68.671668 -26.077307) (xy 68.677541 -26.082919)
			(xy 68.680838 -26.085292) (xy 68.686426 -26.089102) (xy 68.692423 -26.092773) (xy 68.705825 -26.097014)
			(xy 68.712842 -26.097484) (xy 68.72732 -26.097738) (xy 68.740528 -26.08961) (xy 68.768714 -26.072847)
			(xy 68.828843 -26.046673) (xy 68.89209 -26.029341) (xy 68.957162 -26.021204) (xy 68.989956 -26.021284)
			(xy 68.993258 -26.021538) (xy 69.02269 -26.02277) (xy 69.080891 -26.031862) (xy 69.137446 -26.048344)
			(xy 69.19142 -26.071944) (xy 69.241921 -26.102272) (xy 69.288114 -26.138827) (xy 69.329237 -26.181006)
			(xy 69.364611 -26.22811) (xy 69.39365 -26.279363) (xy 69.415875 -26.333917) (xy 69.422998 -26.360882)
			(xy 72.105518 -26.360882) (xy 72.109589 -26.30526) (xy 72.121715 -26.250823) (xy 72.141638 -26.198732)
			(xy 72.168934 -26.150097) (xy 72.20302 -26.105954) (xy 72.243169 -26.067245) (xy 72.288527 -26.034794)
			(xy 72.338127 -26.009293) (xy 72.390911 -25.991286) (xy 72.445754 -25.981156) (xy 72.501488 -25.979119)
			(xy 72.556925 -25.985219) (xy 72.610882 -25.999325) (xy 72.662211 -26.021137) (xy 72.709817 -26.050191)
			(xy 72.752685 -26.085866) (xy 72.789902 -26.127403) (xy 72.820675 -26.173916) (xy 72.844347 -26.224413)
			(xy 72.860415 -26.27782) (xy 72.868535 -26.332996) (xy 72.869044 -26.360882) (xy 72.868535 -26.388768)
			(xy 72.860415 -26.443944) (xy 72.844347 -26.497351) (xy 72.820675 -26.547848) (xy 72.789902 -26.594361)
			(xy 72.752685 -26.635898) (xy 72.709817 -26.671573) (xy 72.662211 -26.700627) (xy 72.610882 -26.722439)
			(xy 72.556925 -26.736545) (xy 72.501488 -26.742645) (xy 72.445754 -26.740608) (xy 72.390911 -26.730478)
			(xy 72.338127 -26.712471) (xy 72.288527 -26.68697) (xy 72.243169 -26.654519) (xy 72.20302 -26.61581)
			(xy 72.168934 -26.571667) (xy 72.141638 -26.523032) (xy 72.121715 -26.470941) (xy 72.109589 -26.416504)
			(xy 72.105518 -26.360882) (xy 69.422998 -26.360882) (xy 69.43092 -26.390871) (xy 69.438534 -26.449285)
			(xy 69.439028 -26.478738) (xy 69.439028 -27.276552) (xy 69.43944 -27.286578) (xy 69.447102 -27.305106)
			(xy 69.461277 -27.319287) (xy 69.479803 -27.326956) (xy 69.489828 -27.327352) (xy 78.69555 -27.327352)
			(xy 78.705202 -27.326336) (xy 78.712442 -27.324701) (xy 78.725599 -27.317847) (xy 78.73111 -27.312874)
			(xy 79.096108 -26.947876) (xy 79.101091 -26.942447) (xy 79.107942 -26.929408) (xy 79.10957 -26.922222)
			(xy 79.10957 -26.921714) (xy 79.110586 -26.912316) (xy 79.110586 -25.020524) (xy 79.11 -25.009989)
			(xy 79.10147 -24.990714) (xy 79.094076 -24.983186) (xy 79.03845 -24.932386) (xy 79.030246 -24.925682)
			(xy 79.010172 -24.918982) (xy 78.999588 -24.919432) (xy 78.964028 -24.92121) (xy 78.936774 -24.920749)
			(xy 78.88282 -24.912995) (xy 78.830518 -24.897641) (xy 78.780935 -24.875) (xy 78.735078 -24.845533)
			(xy 78.693882 -24.80984) (xy 78.658185 -24.768646) (xy 78.628714 -24.722792) (xy 78.606069 -24.67321)
			(xy 78.590712 -24.62091) (xy 78.582954 -24.566956) (xy 78.58252 -24.539702) (xy 78.582764 -24.52136)
			(xy 78.586327 -24.484848) (xy 78.589632 -24.466804) (xy 78.591339 -24.455194) (xy 78.585248 -24.432559)
			(xy 78.577948 -24.42337) (xy 78.524862 -24.362918) (xy 78.516703 -24.354566) (xy 78.495133 -24.345692)
			(xy 78.48346 -24.3459) (xy 78.45933 -24.346662) (xy 78.432082 -24.346178) (xy 78.378141 -24.338427)
			(xy 78.325852 -24.323078) (xy 78.276279 -24.300444) (xy 78.230432 -24.270985) (xy 78.189244 -24.235302)
			(xy 78.153554 -24.19412) (xy 78.124088 -24.148278) (xy 78.101445 -24.09871) (xy 78.086087 -24.046423)
			(xy 78.078327 -23.992483) (xy 78.078322 -23.937988) (xy 78.086072 -23.884046) (xy 78.10142 -23.831757)
			(xy 78.124054 -23.782184) (xy 78.153512 -23.736337) (xy 78.189194 -23.695148) (xy 78.230376 -23.659457)
			(xy 78.276217 -23.62999) (xy 78.325785 -23.607347) (xy 78.378072 -23.591988) (xy 78.432012 -23.584227)
			(xy 78.486507 -23.584221) (xy 78.540449 -23.591971) (xy 78.592738 -23.607318) (xy 78.642311 -23.629951)
			(xy 78.688159 -23.659408) (xy 78.729348 -23.695091) (xy 78.76504 -23.736271) (xy 78.794507 -23.782112)
			(xy 78.817151 -23.83168) (xy 78.832511 -23.883967) (xy 78.840273 -23.937906) (xy 78.840838 -23.965154)
			(xy 78.840596 -23.983497) (xy 78.837037 -24.020009) (xy 78.833726 -24.038052) (xy 78.832009 -24.049666)
			(xy 78.838082 -24.072316) (xy 78.84541 -24.081486) (xy 78.898496 -24.141938) (xy 78.906656 -24.150291)
			(xy 78.928225 -24.159172) (xy 78.939898 -24.158956) (xy 78.964028 -24.158194) (xy 78.985355 -24.15845)
			(xy 79.027747 -24.163162) (xy 79.04861 -24.167592) (xy 79.054198 -24.168862) (xy 79.059786 -24.168862)
			(xy 79.069806 -24.168444) (xy 79.088321 -24.160775) (xy 79.102489 -24.146601) (xy 79.110149 -24.128083)
			(xy 79.110586 -24.118062) (xy 79.110586 -24.095202) (xy 79.10703 -24.086312) (xy 79.09894 -24.0647)
			(xy 79.087445 -24.020007) (xy 79.081431 -23.974253) (xy 79.080868 -23.951184) (xy 79.080868 -23.947628)
			(xy 79.081177 -23.92375) (xy 79.087008 -23.876354) (xy 79.098694 -23.830052) (xy 79.10703 -23.807674)
			(xy 79.110586 -23.798784) (xy 79.110586 -22.25675) (xy 79.110586 -22.255988) (xy 79.110229 -22.248772)
			(xy 79.105975 -22.234972) (xy 79.102204 -22.22881) (xy 79.101696 -22.228556) (xy 79.101696 -22.228302)
			(xy 79.078836 -22.210014) (xy 79.072232 -22.20722) (xy 79.046673 -22.195902) (xy 78.998897 -22.166884)
			(xy 78.955866 -22.131207) (xy 78.918501 -22.089632) (xy 78.887602 -22.043051) (xy 78.86383 -21.99246)
			(xy 78.847694 -21.938942) (xy 78.839539 -21.883643) (xy 78.83954 -21.827745) (xy 78.847697 -21.772446)
			(xy 78.863835 -21.718928) (xy 78.887608 -21.668338) (xy 78.918509 -21.621758) (xy 78.955875 -21.580185)
			(xy 78.998907 -21.544508) (xy 79.046684 -21.515493) (xy 79.072232 -21.504148) (xy 79.078836 -21.501354)
			(xy 79.101696 -21.483066) (xy 79.101696 -21.482812) (xy 79.102204 -21.482558) (xy 79.105968 -21.476391)
			(xy 79.110233 -21.462595) (xy 79.110586 -21.45538) (xy 79.110586 -15.818866) (xy 79.110078 -15.811754)
			(xy 79.108424 -15.80307) (xy 79.100115 -15.787482) (xy 79.093822 -15.781274) (xy 79.093314 -15.780766)
			(xy 79.035148 -15.729458) (xy 79.031104 -15.726261) (xy 79.02202 -15.72139) (xy 79.017114 -15.719806)
			(xy 79.007462 -15.717012) (xy 78.996286 -15.718282) (xy 78.984149 -15.719787) (xy 78.959747 -15.721439)
			(xy 78.947518 -15.721584) (xy 78.921383 -15.721156) (xy 78.869603 -15.714024) (xy 78.81928 -15.699891)
			(xy 78.771357 -15.679022) (xy 78.726732 -15.651807) (xy 78.686239 -15.618756) (xy 78.668118 -15.599918)
			(xy 78.667864 -15.599664) (xy 78.66401 -15.595647) (xy 78.654915 -15.58923) (xy 78.64983 -15.586964)
			(xy 78.640178 -15.5829) (xy 78.581504 -15.585694) (xy 78.580996 -15.585694) (xy 78.5495 -15.586964)
			(xy 78.544256 -15.587483) (xy 78.534142 -15.590436) (xy 78.529434 -15.592806) (xy 78.520036 -15.597886)
			(xy 78.513178 -15.606776) (xy 78.494997 -15.629537) (xy 78.452898 -15.669798) (xy 78.40517 -15.703192)
			(xy 78.35292 -15.728944) (xy 78.297363 -15.746455) (xy 78.23979 -15.755319) (xy 78.210664 -15.755874)
			(xy 78.183415 -15.755385) (xy 78.129473 -15.747624) (xy 78.077185 -15.732266) (xy 78.027615 -15.709622)
			(xy 77.981771 -15.680154) (xy 77.940588 -15.644462) (xy 77.904904 -15.603273) (xy 77.875444 -15.557424)
			(xy 77.85281 -15.507849) (xy 77.837461 -15.455558) (xy 77.82971 -15.401615) (xy 77.829156 -15.374366)
			(xy 77.829656 -15.346628) (xy 77.837693 -15.291737) (xy 77.853592 -15.238588) (xy 77.87702 -15.188301)
			(xy 77.90748 -15.141936) (xy 77.944333 -15.10047) (xy 77.986802 -15.064776) (xy 78.03399 -15.035607)
			(xy 78.084905 -15.013578) (xy 78.138473 -14.999152) (xy 78.16596 -14.995398) (xy 78.179676 -14.993874)
			(xy 78.210664 -14.992604) (xy 78.236799 -14.993031) (xy 78.288579 -15.000162) (xy 78.338901 -15.014295)
			(xy 78.386822 -15.035167) (xy 78.431446 -15.062385) (xy 78.471935 -15.09544) (xy 78.490064 -15.11427)
			(xy 78.490318 -15.114524) (xy 78.494175 -15.118537) (xy 78.503275 -15.124941) (xy 78.508352 -15.127224)
			(xy 78.518004 -15.131288) (xy 78.576678 -15.128494) (xy 78.577186 -15.128494) (xy 78.608682 -15.127224)
			(xy 78.613927 -15.126707) (xy 78.624042 -15.123756) (xy 78.628748 -15.121382) (xy 78.638146 -15.116302)
			(xy 78.645004 -15.107412) (xy 78.663185 -15.084651) (xy 78.705284 -15.044389) (xy 78.753012 -15.010994)
			(xy 78.805262 -14.98524) (xy 78.860819 -14.967727) (xy 78.918392 -14.958861) (xy 78.947518 -14.958314)
			(xy 78.94828 -14.958314) (xy 78.960315 -14.958405) (xy 78.984336 -14.95993) (xy 78.996286 -14.961362)
			(xy 79.007716 -14.962632) (xy 79.017368 -14.959838) (xy 79.022454 -14.95813) (xy 79.031807 -14.95288)
			(xy 79.03591 -14.949424) (xy 79.042006 -14.94409) (xy 79.079598 -14.91107) (xy 79.080106 -14.910562)
			(xy 79.094584 -14.897608) (xy 79.100172 -14.891512) (xy 79.10195 -14.889226) (xy 79.105524 -14.883516)
			(xy 79.109895 -14.870781) (xy 79.110586 -14.86408) (xy 79.110586 -13.72616) (xy 79.11042 -13.72015)
			(xy 79.107597 -13.708467) (xy 79.104998 -13.703046) (xy 79.103156 -13.699573) (xy 79.09856 -13.693198)
			(xy 79.095854 -13.690346) (xy 78.790038 -13.38453) (xy 78.787188 -13.381823) (xy 78.780812 -13.377226)
			(xy 78.777338 -13.375386) (xy 78.771911 -13.372806) (xy 78.760231 -13.369987) (xy 78.754224 -13.369798)
			(xy 74.047604 -13.369798) (xy 74.041596 -13.369971) (xy 74.029918 -13.372804) (xy 74.02449 -13.375386)
			(xy 74.021015 -13.377225) (xy 74.014635 -13.381817) (xy 74.01179 -13.38453) (xy 73.296018 -14.100302)
			(xy 78.043022 -14.100302) (xy 78.047093 -14.04468) (xy 78.059219 -13.990243) (xy 78.079142 -13.938152)
			(xy 78.106438 -13.889517) (xy 78.140524 -13.845374) (xy 78.180673 -13.806665) (xy 78.226031 -13.774214)
			(xy 78.275631 -13.748713) (xy 78.328415 -13.730706) (xy 78.383258 -13.720576) (xy 78.438992 -13.718539)
			(xy 78.494429 -13.724639) (xy 78.548386 -13.738745) (xy 78.599715 -13.760557) (xy 78.647321 -13.789611)
			(xy 78.690189 -13.825286) (xy 78.727406 -13.866823) (xy 78.758179 -13.913336) (xy 78.781851 -13.963833)
			(xy 78.797919 -14.01724) (xy 78.806039 -14.072416) (xy 78.806548 -14.100302) (xy 78.806039 -14.128188)
			(xy 78.797919 -14.183364) (xy 78.781851 -14.236771) (xy 78.758179 -14.287268) (xy 78.727406 -14.333781)
			(xy 78.690189 -14.375318) (xy 78.647321 -14.410993) (xy 78.599715 -14.440047) (xy 78.548386 -14.461859)
			(xy 78.494429 -14.475965) (xy 78.438992 -14.482065) (xy 78.383258 -14.480028) (xy 78.328415 -14.469898)
			(xy 78.275631 -14.451891) (xy 78.226031 -14.42639) (xy 78.180673 -14.393939) (xy 78.140524 -14.35523)
			(xy 78.106438 -14.311087) (xy 78.079142 -14.262452) (xy 78.059219 -14.210361) (xy 78.047093 -14.155924)
			(xy 78.043022 -14.100302) (xy 73.296018 -14.100302) (xy 72.705722 -14.690598) (xy 72.700511 -14.695512)
			(xy 72.688009 -14.702487) (xy 72.681084 -14.704314) (xy 72.678544 -14.704822) (xy 72.670467 -14.707436)
			(xy 72.656564 -14.717162) (xy 72.651366 -14.723872) (xy 72.600058 -14.800326) (xy 72.597263 -14.805199)
			(xy 72.593664 -14.815837) (xy 72.592946 -14.821408) (xy 72.591676 -14.8336) (xy 72.596502 -14.845284)
			(xy 72.621915 -14.909157) (xy 72.665449 -15.039564) (xy 72.700496 -15.172503) (xy 72.726908 -15.307424)
			(xy 72.744578 -15.443765) (xy 72.753431 -15.580961) (xy 72.753982 -15.649702) (xy 72.753982 -15.649956)
			(xy 72.753476 -15.715692) (xy 72.745383 -15.846913) (xy 72.729226 -15.977388) (xy 72.705069 -16.106621)
			(xy 72.673001 -16.234121) (xy 72.633145 -16.359405) (xy 72.585652 -16.481999) (xy 72.530703 -16.601436)
			(xy 72.468504 -16.717263) (xy 72.399294 -16.829042) (xy 72.323333 -16.936349) (xy 72.240911 -17.038775)
			(xy 72.152339 -17.135934) (xy 72.057954 -17.227455) (xy 71.958115 -17.312993) (xy 71.853198 -17.392222)
			(xy 71.743604 -17.464842) (xy 71.629746 -17.530577) (xy 71.512058 -17.589179) (xy 71.390986 -17.640425)
			(xy 71.266988 -17.68412) (xy 71.140536 -17.720099) (xy 71.012108 -17.748225) (xy 70.882193 -17.768391)
			(xy 70.751283 -17.780522) (xy 70.619874 -17.784571) (xy 70.488465 -17.780522) (xy 70.357555 -17.768391)
			(xy 70.22764 -17.748225) (xy 70.099212 -17.720099) (xy 69.97276 -17.68412) (xy 69.848762 -17.640425)
			(xy 69.72769 -17.589179) (xy 69.610002 -17.530577) (xy 69.496144 -17.464842) (xy 69.38655 -17.392222)
			(xy 69.281633 -17.312993) (xy 69.181794 -17.227455) (xy 69.087409 -17.135934) (xy 68.998837 -17.038775)
			(xy 68.916415 -16.936349) (xy 68.840454 -16.829042) (xy 68.771244 -16.717263) (xy 68.709045 -16.601436)
			(xy 68.654096 -16.481999) (xy 68.606603 -16.359405) (xy 68.566747 -16.234121) (xy 68.534679 -16.106621)
			(xy 68.510522 -15.977388) (xy 68.494365 -15.846913) (xy 68.486272 -15.715692) (xy 68.485766 -15.649956)
			(xy 68.486324 -15.581216) (xy 68.495192 -15.444022) (xy 68.51287 -15.307683) (xy 68.539283 -15.172765)
			(xy 68.574324 -15.039825) (xy 68.617846 -14.909415) (xy 68.643246 -14.845538) (xy 68.643246 -14.845284)
			(xy 68.645432 -14.839514) (xy 68.64723 -14.82731) (xy 68.646802 -14.821154) (xy 68.645532 -14.808708)
			(xy 68.591176 -14.727936) (xy 68.583694 -14.717962) (xy 68.561717 -14.706247) (xy 68.549266 -14.705584)
			(xy 66.733928 -14.705584) (xy 66.725292 -14.706346) (xy 66.721251 -14.707133) (xy 66.713469 -14.709817)
			(xy 66.709798 -14.71168) (xy 66.709798 -14.711934) (xy 66.70329 -14.715825) (xy 66.692699 -14.726668)
			(xy 66.68897 -14.73327) (xy 66.648076 -14.814042) (xy 66.645058 -14.820333) (xy 66.642231 -14.833992)
			(xy 66.642488 -14.840966) (xy 66.64325 -14.848332) (xy 66.647822 -14.861032) (xy 66.65214 -14.866874)
			(xy 66.676618 -14.901315) (xy 66.719987 -14.973839) (xy 66.756671 -15.049962) (xy 66.786375 -15.129071)
			(xy 66.808859 -15.210527) (xy 66.823941 -15.293672) (xy 66.8315 -15.377835) (xy 66.831972 -15.420086)
			(xy 66.831972 -15.42034) (xy 66.831413 -15.466046) (xy 66.822515 -15.557023) (xy 66.804835 -15.646708)
			(xy 66.778541 -15.734256) (xy 66.74388 -15.818842) (xy 66.723006 -15.859506) (xy 66.722752 -15.860014)
			(xy 66.720102 -15.86562) (xy 66.717275 -15.87769) (xy 66.717164 -15.88389) (xy 66.717164 -15.896082)
			(xy 66.763646 -15.982188) (xy 66.764154 -15.98295) (xy 66.772282 -15.993872) (xy 66.780664 -16.00073)
			(xy 66.79057 -16.00708) (xy 66.803524 -16.00835) (xy 66.848018 -16.012961) (xy 66.935958 -16.029382)
			(xy 67.022002 -16.053864) (xy 67.105413 -16.086198) (xy 67.185477 -16.126107) (xy 67.261508 -16.173248)
			(xy 67.332853 -16.227219) (xy 67.398902 -16.287556) (xy 67.459088 -16.353742) (xy 67.512896 -16.42521)
			(xy 67.559864 -16.501347) (xy 67.59959 -16.581502) (xy 67.631734 -16.664987) (xy 67.65602 -16.751087)
			(xy 67.67224 -16.839063) (xy 67.680255 -16.928163) (xy 67.679996 -17.017622) (xy 67.671466 -17.106674)
			(xy 67.654737 -17.194555) (xy 67.629954 -17.280513) (xy 67.597327 -17.36381) (xy 67.557138 -17.443734)
			(xy 67.50973 -17.519598) (xy 67.455509 -17.590754) (xy 67.394941 -17.656591) (xy 67.328545 -17.716544)
			(xy 67.292982 -17.743678) (xy 67.25776 -17.769392) (xy 67.183472 -17.815082) (xy 67.105368 -17.853889)
			(xy 67.024082 -17.885495) (xy 66.940278 -17.909643) (xy 66.854638 -17.926137) (xy 66.767859 -17.934842)
			(xy 66.680649 -17.935687) (xy 66.593719 -17.928665) (xy 66.507775 -17.913835) (xy 66.423518 -17.891315)
			(xy 66.341636 -17.86129) (xy 66.262794 -17.824005) (xy 66.187634 -17.779763) (xy 66.11677 -17.728924)
			(xy 66.050779 -17.671903) (xy 65.990197 -17.609164) (xy 65.93552 -17.541218) (xy 65.887191 -17.46862)
			(xy 65.845604 -17.391959) (xy 65.811099 -17.311861) (xy 65.783957 -17.228978) (xy 65.764398 -17.143986)
			(xy 65.752583 -17.057576) (xy 65.748606 -16.970452) (xy 65.752501 -16.883326) (xy 65.764236 -16.796905)
			(xy 65.783715 -16.711894) (xy 65.81078 -16.628986) (xy 65.845209 -16.548855) (xy 65.865502 -16.510254)
			(xy 65.865502 -16.51) (xy 65.865756 -16.51) (xy 65.867026 -16.50746) (xy 65.869281 -16.502157) (xy 65.871599 -16.49087)
			(xy 65.871598 -16.485108) (xy 65.871344 -16.471646) (xy 65.819782 -16.385032) (xy 65.817581 -16.381493)
			(xy 65.812216 -16.375116) (xy 65.809114 -16.372332) (xy 65.802029 -16.366742) (xy 65.785112 -16.360491)
			(xy 65.776094 -16.36014) (xy 64.037718 -16.36014) (xy 63.994279 -16.359654) (xy 63.907771 -16.35164)
			(xy 63.822372 -16.335677) (xy 63.73881 -16.311903) (xy 63.657798 -16.28052) (xy 63.580027 -16.241795)
			(xy 63.506162 -16.19606) (xy 63.436831 -16.143705) (xy 63.372627 -16.085176) (xy 63.314098 -16.020972)
			(xy 63.261742 -15.951642) (xy 63.216007 -15.877776) (xy 63.177282 -15.800006) (xy 63.145899 -15.718994)
			(xy 63.122124 -15.635432) (xy 63.106161 -15.550033) (xy 63.098146 -15.463525) (xy 63.097664 -15.420086)
			(xy 63.097664 -15.419578) (xy 63.098134 -15.377363) (xy 63.105726 -15.293273) (xy 63.120828 -15.210204)
			(xy 63.143319 -15.128824) (xy 63.173018 -15.049788) (xy 63.209684 -14.973734) (xy 63.253024 -14.901275)
			(xy 63.277496 -14.866874) (xy 63.281814 -14.861032) (xy 63.286386 -14.848332) (xy 63.287148 -14.840966)
			(xy 63.28742 -14.833992) (xy 63.284589 -14.82033) (xy 63.28156 -14.814042) (xy 63.275972 -14.80312)
			(xy 63.238888 -14.729968) (xy 63.235756 -14.725299) (xy 63.227809 -14.717351) (xy 63.22314 -14.71422)
			(xy 63.217298 -14.710918) (xy 63.212032 -14.708478) (xy 63.200746 -14.705782) (xy 63.194946 -14.705584)
			(xy 53.874416 -14.705584) (xy 53.868407 -14.705755) (xy 53.856728 -14.708585) (xy 53.851302 -14.711172)
			(xy 53.847826 -14.71301) (xy 53.841444 -14.717599) (xy 53.838602 -14.720316) (xy 53.636926 -14.921992)
			(xy 53.634132 -14.92504) (xy 53.627608 -14.933648) (xy 53.621808 -14.954433) (xy 53.622956 -14.965172)
			(xy 53.624734 -14.973046) (xy 53.640736 -15.018004) (xy 53.655976 -15.06093) (xy 53.658516 -15.067026)
			(xy 53.661186 -15.072005) (xy 53.668363 -15.080727) (xy 53.67274 -15.084298) (xy 53.678328 -15.088616)
			(xy 53.691536 -15.09395) (xy 53.698902 -15.094712) (xy 53.726763 -15.098028) (xy 53.781155 -15.111786)
			(xy 53.832947 -15.13336) (xy 53.881023 -15.162285) (xy 53.924345 -15.197936) (xy 53.96198 -15.239547)
			(xy 53.993117 -15.286219) (xy 54.017085 -15.336948) (xy 54.033368 -15.390639) (xy 54.041613 -15.446135)
			(xy 54.042056 -15.474188) (xy 54.041578 -15.501337) (xy 54.033882 -15.555088) (xy 54.018644 -15.607204)
			(xy 53.996171 -15.656634) (xy 53.966918 -15.702378) (xy 53.931475 -15.743514) (xy 53.890558 -15.779209)
			(xy 53.844994 -15.808743) (xy 53.795704 -15.831519) (xy 53.743682 -15.847078) (xy 53.68998 -15.855104)
			(xy 53.662834 -15.855696) (xy 53.66004 -15.855696) (xy 53.630665 -15.855138) (xy 53.572618 -15.846081)
			(xy 53.54447 -15.837662) (xy 53.540152 -15.836392) (xy 53.528214 -15.838424) (xy 53.523388 -15.83944)
			(xy 53.519324 -15.84071) (xy 53.50764 -15.846806) (xy 53.490114 -15.860014) (xy 53.441346 -15.896336)
			(xy 53.432159 -15.903897) (xy 53.421418 -15.925096) (xy 53.420772 -15.936976) (xy 53.420772 -18.44421)
			(xy 74.276202 -18.44421) (xy 74.280273 -18.388588) (xy 74.292399 -18.334151) (xy 74.312322 -18.28206)
			(xy 74.339618 -18.233425) (xy 74.373704 -18.189282) (xy 74.413853 -18.150573) (xy 74.459211 -18.118122)
			(xy 74.508811 -18.092621) (xy 74.561595 -18.074614) (xy 74.616438 -18.064484) (xy 74.672172 -18.062447)
			(xy 74.727609 -18.068547) (xy 74.781566 -18.082653) (xy 74.832895 -18.104465) (xy 74.880501 -18.133519)
			(xy 74.923369 -18.169194) (xy 74.960586 -18.210731) (xy 74.991359 -18.257244) (xy 75.015031 -18.307741)
			(xy 75.031099 -18.361148) (xy 75.039219 -18.416324) (xy 75.039728 -18.44421) (xy 75.039219 -18.472096)
			(xy 75.031099 -18.527272) (xy 75.015031 -18.580679) (xy 74.991359 -18.631176) (xy 74.960586 -18.677689)
			(xy 74.923369 -18.719226) (xy 74.880501 -18.754901) (xy 74.832895 -18.783955) (xy 74.781566 -18.805767)
			(xy 74.727609 -18.819873) (xy 74.672172 -18.825973) (xy 74.616438 -18.823936) (xy 74.561595 -18.813806)
			(xy 74.508811 -18.795799) (xy 74.459211 -18.770298) (xy 74.413853 -18.737847) (xy 74.373704 -18.699138)
			(xy 74.339618 -18.654995) (xy 74.312322 -18.60636) (xy 74.292399 -18.554269) (xy 74.280273 -18.499832)
			(xy 74.276202 -18.44421) (xy 53.420772 -18.44421) (xy 53.420772 -20.72005) (xy 57.185318 -20.72005)
			(xy 57.189288 -20.589916) (xy 57.201184 -20.460266) (xy 57.220963 -20.331583) (xy 57.248549 -20.204344)
			(xy 57.283842 -20.079025) (xy 57.326708 -19.956089) (xy 57.37699 -19.835996) (xy 57.434499 -19.719192)
			(xy 57.499023 -19.60611) (xy 57.57032 -19.497173) (xy 57.648125 -19.392785) (xy 57.73215 -19.293334)
			(xy 57.822082 -19.199191) (xy 57.917586 -19.110706) (xy 58.018306 -19.028207) (xy 58.123868 -18.952002)
			(xy 58.23388 -18.882375) (xy 58.347932 -18.819584) (xy 58.4656 -18.763862) (xy 58.586446 -18.715418)
			(xy 58.710021 -18.674431) (xy 58.835864 -18.641054) (xy 58.963509 -18.615411) (xy 59.092479 -18.597597)
			(xy 59.222295 -18.587679) (xy 59.352474 -18.585694) (xy 59.482533 -18.591648) (xy 59.611986 -18.605521)
			(xy 59.740353 -18.627259) (xy 59.867156 -18.656783) (xy 59.991923 -18.693982) (xy 60.11419 -18.738718)
			(xy 60.233503 -18.790826) (xy 60.349416 -18.850109) (xy 60.461501 -18.91635) (xy 60.569338 -18.9893)
			(xy 60.672527 -19.068688) (xy 60.770685 -19.15422) (xy 60.863446 -19.245577) (xy 60.950465 -19.342419)
			(xy 61.031418 -19.444386) (xy 61.106004 -19.551098) (xy 61.173945 -19.662159) (xy 61.23499 -19.777155)
			(xy 61.288911 -19.895659) (xy 61.335506 -20.01723) (xy 61.374604 -20.141415) (xy 61.406058 -20.267753)
			(xy 61.429752 -20.395774) (xy 61.445596 -20.525) (xy 61.453534 -20.654953) (xy 61.45403 -20.72005)
			(xy 61.453534 -20.785147) (xy 61.445596 -20.9151) (xy 61.429752 -21.044326) (xy 61.406058 -21.172347)
			(xy 61.374604 -21.298685) (xy 61.335506 -21.42287) (xy 61.288911 -21.544441) (xy 61.23499 -21.662945)
			(xy 61.194969 -21.738336) (xy 63.416688 -21.738336) (xy 63.417176 -21.709596) (xy 63.425808 -21.652767)
			(xy 63.442866 -21.597876) (xy 63.467966 -21.546165) (xy 63.500538 -21.498804) (xy 63.519812 -21.477478)
			(xy 63.526416 -21.47062) (xy 63.533528 -21.452586) (xy 63.533528 -21.363686) (xy 63.526416 -21.345652)
			(xy 63.519812 -21.338794) (xy 63.500577 -21.317436) (xy 63.468012 -21.270079) (xy 63.442919 -21.218372)
			(xy 63.425867 -21.163486) (xy 63.417241 -21.106663) (xy 63.417238 -21.049189) (xy 63.425855 -20.992365)
			(xy 63.4429 -20.937477) (xy 63.467986 -20.885767) (xy 63.500544 -20.838405) (xy 63.519812 -20.817078)
			(xy 63.526416 -20.81022) (xy 63.533528 -20.792186) (xy 63.533528 -20.703286) (xy 63.526416 -20.685252)
			(xy 63.519812 -20.678394) (xy 63.500577 -20.657036) (xy 63.468012 -20.609679) (xy 63.442919 -20.557972)
			(xy 63.425867 -20.503086) (xy 63.417241 -20.446263) (xy 63.417238 -20.388789) (xy 63.425855 -20.331965)
			(xy 63.4429 -20.277077) (xy 63.467986 -20.225367) (xy 63.500544 -20.178005) (xy 63.519812 -20.156678)
			(xy 63.526416 -20.14982) (xy 63.533528 -20.131786) (xy 63.533528 -20.042886) (xy 63.526416 -20.024852)
			(xy 63.519812 -20.017994) (xy 63.500577 -19.996636) (xy 63.468012 -19.949279) (xy 63.442919 -19.897572)
			(xy 63.425867 -19.842686) (xy 63.417241 -19.785863) (xy 63.417238 -19.728389) (xy 63.425855 -19.671565)
			(xy 63.4429 -19.616677) (xy 63.467986 -19.564967) (xy 63.500544 -19.517605) (xy 63.519812 -19.496278)
			(xy 63.526416 -19.48942) (xy 63.533528 -19.471386) (xy 63.533528 -19.382486) (xy 63.526416 -19.364452)
			(xy 63.519812 -19.357594) (xy 63.500554 -19.336256) (xy 63.467987 -19.288897) (xy 63.442893 -19.237188)
			(xy 63.425839 -19.182299) (xy 63.417212 -19.125474) (xy 63.416688 -19.096736) (xy 63.417174 -19.069485)
			(xy 63.42493 -19.015537) (xy 63.440285 -18.963242) (xy 63.462927 -18.913665) (xy 63.492393 -18.867815)
			(xy 63.528084 -18.826624) (xy 63.569275 -18.790933) (xy 63.615125 -18.761467) (xy 63.664702 -18.738825)
			(xy 63.716997 -18.72347) (xy 63.770945 -18.715714) (xy 63.825447 -18.715714) (xy 63.879395 -18.72347)
			(xy 63.93169 -18.738825) (xy 63.981267 -18.761467) (xy 64.027117 -18.790933) (xy 64.068308 -18.826624)
			(xy 64.103999 -18.867815) (xy 64.133465 -18.913665) (xy 64.156107 -18.963242) (xy 64.171462 -19.015537)
			(xy 64.179218 -19.069485) (xy 64.179704 -19.096736) (xy 64.179201 -19.125476) (xy 64.170573 -19.182304)
			(xy 64.153518 -19.237195) (xy 64.128422 -19.288906) (xy 64.095853 -19.336268) (xy 64.07658 -19.357594)
			(xy 64.069976 -19.364452) (xy 64.062864 -19.382486) (xy 64.062864 -19.471386) (xy 64.069976 -19.48942)
			(xy 64.07658 -19.496278) (xy 64.095886 -19.517574) (xy 64.12845 -19.564942) (xy 64.153539 -19.616659)
			(xy 64.170587 -19.671554) (xy 64.179206 -19.728386) (xy 64.179202 -19.785867) (xy 64.170575 -19.842697)
			(xy 64.15352 -19.89759) (xy 64.128424 -19.949304) (xy 64.095853 -19.996667) (xy 64.07658 -20.017994)
			(xy 64.069976 -20.024852) (xy 64.062864 -20.042886) (xy 64.062864 -20.131786) (xy 64.069976 -20.14982)
			(xy 64.07658 -20.156678) (xy 64.095886 -20.177974) (xy 64.12845 -20.225342) (xy 64.153539 -20.277059)
			(xy 64.170587 -20.331954) (xy 64.179206 -20.388786) (xy 64.179202 -20.446267) (xy 64.170575 -20.503097)
			(xy 64.15352 -20.55799) (xy 64.128424 -20.609704) (xy 64.095853 -20.657067) (xy 64.07658 -20.678394)
			(xy 64.069976 -20.685252) (xy 64.062864 -20.703286) (xy 64.062864 -20.792186) (xy 64.069976 -20.81022)
			(xy 64.07658 -20.817078) (xy 64.095886 -20.838374) (xy 64.12845 -20.885742) (xy 64.153539 -20.937459)
			(xy 64.170587 -20.992354) (xy 64.179206 -21.049186) (xy 64.179202 -21.106667) (xy 64.170575 -21.163497)
			(xy 64.15352 -21.21839) (xy 64.128424 -21.270104) (xy 64.095853 -21.317467) (xy 64.07658 -21.338794)
			(xy 64.069976 -21.345652) (xy 64.062864 -21.363686) (xy 64.062864 -21.452586) (xy 64.069976 -21.47062)
			(xy 64.07658 -21.477478) (xy 64.095871 -21.498788) (xy 64.128434 -21.546155) (xy 64.153522 -21.597871)
			(xy 64.1663 -21.639022) (xy 68.073778 -21.639022) (xy 68.074321 -21.610284) (xy 68.08294 -21.553458)
			(xy 68.099986 -21.498567) (xy 68.125073 -21.446855) (xy 68.157633 -21.399492) (xy 68.176902 -21.378164)
			(xy 68.183506 -21.371306) (xy 68.190618 -21.353272) (xy 68.190618 -21.264372) (xy 68.183506 -21.246338)
			(xy 68.176902 -21.23948) (xy 68.157654 -21.218134) (xy 68.12509 -21.170774) (xy 68.099999 -21.119065)
			(xy 68.082948 -21.064178) (xy 68.074324 -21.007354) (xy 68.074321 -20.949879) (xy 68.082941 -20.893054)
			(xy 68.099987 -20.838165) (xy 68.125074 -20.786454) (xy 68.157634 -20.739091) (xy 68.176902 -20.717764)
			(xy 68.183506 -20.710906) (xy 68.190618 -20.692872) (xy 68.190618 -20.603972) (xy 68.183506 -20.585938)
			(xy 68.176902 -20.57908) (xy 68.157654 -20.557734) (xy 68.12509 -20.510374) (xy 68.099999 -20.458665)
			(xy 68.082948 -20.403778) (xy 68.074324 -20.346954) (xy 68.074321 -20.289479) (xy 68.082941 -20.232654)
			(xy 68.099987 -20.177765) (xy 68.125074 -20.126054) (xy 68.157634 -20.078691) (xy 68.176902 -20.057364)
			(xy 68.183506 -20.050506) (xy 68.190618 -20.032472) (xy 68.190618 -19.943572) (xy 68.183506 -19.925538)
			(xy 68.176902 -19.91868) (xy 68.157654 -19.897334) (xy 68.12509 -19.849974) (xy 68.099999 -19.798265)
			(xy 68.082948 -19.743378) (xy 68.074324 -19.686554) (xy 68.074321 -19.629079) (xy 68.082941 -19.572254)
			(xy 68.099987 -19.517365) (xy 68.125074 -19.465654) (xy 68.157634 -19.418291) (xy 68.176902 -19.396964)
			(xy 68.183506 -19.390106) (xy 68.190618 -19.372072) (xy 68.190618 -19.283172) (xy 68.183506 -19.265138)
			(xy 68.176902 -19.25828) (xy 68.157653 -19.236934) (xy 68.125081 -19.189578) (xy 68.099984 -19.137872)
			(xy 68.082928 -19.082985) (xy 68.074301 -19.02616) (xy 68.073778 -18.997422) (xy 68.074264 -18.970171)
			(xy 68.08202 -18.916223) (xy 68.097375 -18.863928) (xy 68.120017 -18.814351) (xy 68.149483 -18.768501)
			(xy 68.185174 -18.72731) (xy 68.226365 -18.691619) (xy 68.272215 -18.662153) (xy 68.321792 -18.639511)
			(xy 68.374087 -18.624156) (xy 68.428035 -18.6164) (xy 68.482537 -18.6164) (xy 68.536485 -18.624156)
			(xy 68.58878 -18.639511) (xy 68.638357 -18.662153) (xy 68.684207 -18.691619) (xy 68.725398 -18.72731)
			(xy 68.761089 -18.768501) (xy 68.790555 -18.814351) (xy 68.813197 -18.863928) (xy 68.828552 -18.916223)
			(xy 68.836308 -18.970171) (xy 68.836794 -18.997422) (xy 68.836285 -19.026161) (xy 68.827659 -19.08299)
			(xy 68.810606 -19.137881) (xy 68.785511 -19.189592) (xy 68.752942 -19.236954) (xy 68.73367 -19.25828)
			(xy 68.727066 -19.265138) (xy 68.719954 -19.283172) (xy 68.719954 -19.366857) (xy 73.579115 -19.366857)
			(xy 73.579115 -19.312343) (xy 73.586874 -19.258384) (xy 73.602233 -19.206078) (xy 73.62488 -19.156491)
			(xy 73.654353 -19.110632) (xy 73.690054 -19.069434) (xy 73.731254 -19.033736) (xy 73.777116 -19.004266)
			(xy 73.826705 -18.981623) (xy 73.879011 -18.966268) (xy 73.932971 -18.958513) (xy 73.960228 -18.958052)
			(xy 73.987 -18.958506) (xy 74.040015 -18.966008) (xy 74.091461 -18.980845) (xy 74.140329 -19.002728)
			(xy 74.185658 -19.031226) (xy 74.226559 -19.06578) (xy 74.262229 -19.105712) (xy 74.277474 -19.127724)
			(xy 74.277728 -19.127978) (xy 74.28398 -19.136353) (xy 74.301544 -19.147638) (xy 74.311764 -19.149822)
			(xy 74.384916 -19.16176) (xy 74.395366 -19.162874) (xy 74.415695 -19.15765) (xy 74.424286 -19.1516)
			(xy 74.444419 -19.136499) (xy 74.487893 -19.111145) (xy 74.534327 -19.091735) (xy 74.582912 -19.078607)
			(xy 74.632802 -19.07199) (xy 74.657966 -19.07159) (xy 74.65822 -19.07159) (xy 74.68547 -19.072081)
			(xy 74.739415 -19.07984) (xy 74.791708 -19.095197) (xy 74.841282 -19.117839) (xy 74.88713 -19.147306)
			(xy 74.928317 -19.182997) (xy 74.964006 -19.224186) (xy 74.993471 -19.270036) (xy 75.01611 -19.319611)
			(xy 75.031464 -19.371904) (xy 75.03922 -19.42585) (xy 75.03922 -19.48035) (xy 75.031464 -19.534296)
			(xy 75.01611 -19.586589) (xy 74.993471 -19.636164) (xy 74.964006 -19.682014) (xy 74.928317 -19.723203)
			(xy 74.88713 -19.758894) (xy 74.841282 -19.788361) (xy 74.791708 -19.811003) (xy 74.739415 -19.82636)
			(xy 74.68547 -19.834119) (xy 74.65822 -19.834606) (xy 74.631449 -19.834134) (xy 74.578434 -19.826638)
			(xy 74.526987 -19.811805) (xy 74.478119 -19.789925) (xy 74.432789 -19.76143) (xy 74.391888 -19.726877)
			(xy 74.356218 -19.686946) (xy 74.340974 -19.664934) (xy 74.34072 -19.66468) (xy 74.334477 -19.656296)
			(xy 74.316907 -19.645014) (xy 74.306684 -19.642836) (xy 74.233532 -19.630898) (xy 74.223083 -19.629742)
			(xy 74.202749 -19.634992) (xy 74.194162 -19.641058) (xy 74.174042 -19.656177) (xy 74.130564 -19.681529)
			(xy 74.084127 -19.700936) (xy 74.03554 -19.71406) (xy 73.985647 -19.720671) (xy 73.960482 -19.721068)
			(xy 73.960228 -19.721068) (xy 73.932971 -19.720687) (xy 73.879011 -19.712932) (xy 73.826705 -19.697577)
			(xy 73.777116 -19.674934) (xy 73.731254 -19.645464) (xy 73.690054 -19.609766) (xy 73.654353 -19.568568)
			(xy 73.62488 -19.522709) (xy 73.602233 -19.473122) (xy 73.586874 -19.420816) (xy 73.579115 -19.366857)
			(xy 68.719954 -19.366857) (xy 68.719954 -19.372072) (xy 68.727066 -19.390106) (xy 68.73367 -19.396964)
			(xy 68.752963 -19.418272) (xy 68.785528 -19.465637) (xy 68.810619 -19.517352) (xy 68.827667 -19.572246)
			(xy 68.836288 -19.629076) (xy 68.836286 -19.686556) (xy 68.82766 -19.743386) (xy 68.810607 -19.798278)
			(xy 68.785512 -19.849991) (xy 68.752943 -19.897353) (xy 68.73367 -19.91868) (xy 68.727066 -19.925538)
			(xy 68.719954 -19.943572) (xy 68.719954 -20.032472) (xy 68.727066 -20.050506) (xy 68.73367 -20.057364)
			(xy 68.752963 -20.078672) (xy 68.785528 -20.126037) (xy 68.810619 -20.177752) (xy 68.827667 -20.232646)
			(xy 68.836288 -20.289476) (xy 68.836286 -20.346956) (xy 68.83498 -20.35556) (xy 73.57821 -20.35556)
			(xy 73.582281 -20.299938) (xy 73.594407 -20.245501) (xy 73.61433 -20.19341) (xy 73.641626 -20.144775)
			(xy 73.675712 -20.100632) (xy 73.715861 -20.061923) (xy 73.761219 -20.029472) (xy 73.810819 -20.003971)
			(xy 73.863603 -19.985964) (xy 73.918446 -19.975834) (xy 73.97418 -19.973797) (xy 74.029617 -19.979897)
			(xy 74.083574 -19.994003) (xy 74.134903 -20.015815) (xy 74.182509 -20.044869) (xy 74.225377 -20.080544)
			(xy 74.262594 -20.122081) (xy 74.293367 -20.168594) (xy 74.317039 -20.219091) (xy 74.333107 -20.272498)
			(xy 74.341227 -20.327674) (xy 74.341736 -20.35556) (xy 74.341227 -20.383446) (xy 74.333107 -20.438622)
			(xy 74.317039 -20.492029) (xy 74.293367 -20.542526) (xy 74.262594 -20.589039) (xy 74.225377 -20.630576)
			(xy 74.182509 -20.666251) (xy 74.134903 -20.695305) (xy 74.083574 -20.717117) (xy 74.029617 -20.731223)
			(xy 73.97418 -20.737323) (xy 73.918446 -20.735286) (xy 73.863603 -20.725156) (xy 73.810819 -20.707149)
			(xy 73.761219 -20.681648) (xy 73.715861 -20.649197) (xy 73.675712 -20.610488) (xy 73.641626 -20.566345)
			(xy 73.61433 -20.51771) (xy 73.594407 -20.465619) (xy 73.582281 -20.411182) (xy 73.57821 -20.35556)
			(xy 68.83498 -20.35556) (xy 68.82766 -20.403786) (xy 68.810607 -20.458678) (xy 68.785512 -20.510391)
			(xy 68.752943 -20.557753) (xy 68.73367 -20.57908) (xy 68.727066 -20.585938) (xy 68.719954 -20.603972)
			(xy 68.719954 -20.692872) (xy 68.727066 -20.710906) (xy 68.73367 -20.717764) (xy 68.752963 -20.739072)
			(xy 68.785528 -20.786437) (xy 68.810619 -20.838152) (xy 68.827667 -20.893046) (xy 68.836288 -20.949876)
			(xy 68.836286 -21.007356) (xy 68.82766 -21.064186) (xy 68.810607 -21.119078) (xy 68.785512 -21.170791)
			(xy 68.752943 -21.218153) (xy 68.73367 -21.23948) (xy 68.727066 -21.246338) (xy 68.719954 -21.264372)
			(xy 68.719954 -21.353272) (xy 68.727066 -21.371306) (xy 68.727311 -21.37156) (xy 73.57821 -21.37156)
			(xy 73.582281 -21.315938) (xy 73.594407 -21.261501) (xy 73.61433 -21.20941) (xy 73.641626 -21.160775)
			(xy 73.675712 -21.116632) (xy 73.715861 -21.077923) (xy 73.761219 -21.045472) (xy 73.810819 -21.019971)
			(xy 73.863603 -21.001964) (xy 73.918446 -20.991834) (xy 73.97418 -20.989797) (xy 74.029617 -20.995897)
			(xy 74.083574 -21.010003) (xy 74.134903 -21.031815) (xy 74.182509 -21.060869) (xy 74.225377 -21.096544)
			(xy 74.262594 -21.138081) (xy 74.293367 -21.184594) (xy 74.317039 -21.235091) (xy 74.333107 -21.288498)
			(xy 74.341227 -21.343674) (xy 74.341736 -21.37156) (xy 74.341227 -21.399446) (xy 74.333107 -21.454622)
			(xy 74.317039 -21.508029) (xy 74.293367 -21.558526) (xy 74.262594 -21.605039) (xy 74.225377 -21.646576)
			(xy 74.182509 -21.682251) (xy 74.134903 -21.711305) (xy 74.083574 -21.733117) (xy 74.029617 -21.747223)
			(xy 73.97418 -21.753323) (xy 73.918446 -21.751286) (xy 73.863603 -21.741156) (xy 73.810819 -21.723149)
			(xy 73.761219 -21.697648) (xy 73.715861 -21.665197) (xy 73.675712 -21.626488) (xy 73.641626 -21.582345)
			(xy 73.61433 -21.53371) (xy 73.594407 -21.481619) (xy 73.582281 -21.427182) (xy 73.57821 -21.37156)
			(xy 68.727311 -21.37156) (xy 68.73367 -21.378164) (xy 68.752952 -21.399481) (xy 68.785517 -21.446846)
			(xy 68.810607 -21.49856) (xy 68.827655 -21.553453) (xy 68.836275 -21.610282) (xy 68.836794 -21.639022)
			(xy 68.836308 -21.666273) (xy 68.828552 -21.720221) (xy 68.813197 -21.772516) (xy 68.811755 -21.775674)
			(xy 77.935834 -21.775674) (xy 77.939905 -21.720052) (xy 77.952031 -21.665615) (xy 77.971954 -21.613524)
			(xy 77.99925 -21.564889) (xy 78.033336 -21.520746) (xy 78.073485 -21.482037) (xy 78.118843 -21.449586)
			(xy 78.168443 -21.424085) (xy 78.221227 -21.406078) (xy 78.27607 -21.395948) (xy 78.331804 -21.393911)
			(xy 78.387241 -21.400011) (xy 78.441198 -21.414117) (xy 78.492527 -21.435929) (xy 78.540133 -21.464983)
			(xy 78.583001 -21.500658) (xy 78.620218 -21.542195) (xy 78.650991 -21.588708) (xy 78.674663 -21.639205)
			(xy 78.690731 -21.692612) (xy 78.698851 -21.747788) (xy 78.69936 -21.775674) (xy 78.698851 -21.80356)
			(xy 78.690731 -21.858736) (xy 78.674663 -21.912143) (xy 78.650991 -21.96264) (xy 78.620218 -22.009153)
			(xy 78.583001 -22.05069) (xy 78.540133 -22.086365) (xy 78.492527 -22.115419) (xy 78.441198 -22.137231)
			(xy 78.387241 -22.151337) (xy 78.331804 -22.157437) (xy 78.27607 -22.1554) (xy 78.221227 -22.14527)
			(xy 78.168443 -22.127263) (xy 78.118843 -22.101762) (xy 78.073485 -22.069311) (xy 78.033336 -22.030602)
			(xy 77.99925 -21.986459) (xy 77.971954 -21.937824) (xy 77.952031 -21.885733) (xy 77.939905 -21.831296)
			(xy 77.935834 -21.775674) (xy 68.811755 -21.775674) (xy 68.790555 -21.822093) (xy 68.761089 -21.867943)
			(xy 68.725398 -21.909134) (xy 68.684207 -21.944825) (xy 68.638357 -21.974291) (xy 68.58878 -21.996933)
			(xy 68.536485 -22.012288) (xy 68.482537 -22.020044) (xy 68.428035 -22.020044) (xy 68.374087 -22.012288)
			(xy 68.321792 -21.996933) (xy 68.272215 -21.974291) (xy 68.226365 -21.944825) (xy 68.185174 -21.909134)
			(xy 68.149483 -21.867943) (xy 68.120017 -21.822093) (xy 68.097375 -21.772516) (xy 68.08202 -21.720221)
			(xy 68.074264 -21.666273) (xy 68.073778 -21.639022) (xy 64.1663 -21.639022) (xy 64.170568 -21.652765)
			(xy 64.179186 -21.709596) (xy 64.179704 -21.738336) (xy 64.179218 -21.765587) (xy 64.171462 -21.819535)
			(xy 64.156107 -21.87183) (xy 64.133465 -21.921407) (xy 64.103999 -21.967257) (xy 64.068308 -22.008448)
			(xy 64.027117 -22.044139) (xy 63.981267 -22.073605) (xy 63.93169 -22.096247) (xy 63.879395 -22.111602)
			(xy 63.825447 -22.119358) (xy 63.770945 -22.119358) (xy 63.716997 -22.111602) (xy 63.664702 -22.096247)
			(xy 63.615125 -22.073605) (xy 63.569275 -22.044139) (xy 63.528084 -22.008448) (xy 63.492393 -21.967257)
			(xy 63.462927 -21.921407) (xy 63.440285 -21.87183) (xy 63.42493 -21.819535) (xy 63.417174 -21.765587)
			(xy 63.416688 -21.738336) (xy 61.194969 -21.738336) (xy 61.173945 -21.777941) (xy 61.106004 -21.889002)
			(xy 61.031418 -21.995714) (xy 60.950465 -22.097681) (xy 60.863446 -22.194523) (xy 60.770685 -22.28588)
			(xy 60.672527 -22.371412) (xy 60.569338 -22.4508) (xy 60.461501 -22.52375) (xy 60.349416 -22.589991)
			(xy 60.233503 -22.649274) (xy 60.11419 -22.701382) (xy 59.991923 -22.746118) (xy 59.867156 -22.783317)
			(xy 59.740353 -22.812841) (xy 59.611986 -22.834579) (xy 59.482533 -22.848452) (xy 59.352474 -22.854406)
			(xy 59.222295 -22.852421) (xy 59.092479 -22.842503) (xy 58.963509 -22.824689) (xy 58.835864 -22.799046)
			(xy 58.710021 -22.765669) (xy 58.586446 -22.724682) (xy 58.4656 -22.676238) (xy 58.347932 -22.620516)
			(xy 58.23388 -22.557725) (xy 58.123868 -22.488098) (xy 58.018306 -22.411893) (xy 57.917586 -22.329394)
			(xy 57.822082 -22.240909) (xy 57.73215 -22.146766) (xy 57.648125 -22.047315) (xy 57.57032 -21.942927)
			(xy 57.499023 -21.83399) (xy 57.434499 -21.720908) (xy 57.37699 -21.604104) (xy 57.326708 -21.484011)
			(xy 57.283842 -21.361075) (xy 57.248549 -21.235756) (xy 57.220963 -21.108517) (xy 57.201184 -20.979834)
			(xy 57.189288 -20.850184) (xy 57.185318 -20.72005) (xy 53.420772 -20.72005) (xy 53.420772 -21.491448)
			(xy 53.420772 -21.49348) (xy 53.421086 -21.498548) (xy 53.42352 -21.508405) (xy 53.425598 -21.513038)
			(xy 53.436774 -21.534882) (xy 53.43934 -21.539602) (xy 53.446132 -21.547924) (xy 53.450236 -21.551392)
			(xy 53.450744 -21.551646) (xy 53.45684 -21.556218) (xy 53.457348 -21.556726) (xy 53.479488 -21.574915)
			(xy 53.518581 -21.616806) (xy 53.550967 -21.664074) (xy 53.575918 -21.715655) (xy 53.59287 -21.770388)
			(xy 53.601444 -21.827041) (xy 53.601444 -21.847048) (xy 54.072788 -21.847048) (xy 54.076859 -21.791426)
			(xy 54.088985 -21.736989) (xy 54.108908 -21.684898) (xy 54.136204 -21.636263) (xy 54.17029 -21.59212)
			(xy 54.210439 -21.553411) (xy 54.255797 -21.52096) (xy 54.305397 -21.495459) (xy 54.358181 -21.477452)
			(xy 54.413024 -21.467322) (xy 54.468758 -21.465285) (xy 54.524195 -21.471385) (xy 54.578152 -21.485491)
			(xy 54.629481 -21.507303) (xy 54.677087 -21.536357) (xy 54.719955 -21.572032) (xy 54.757172 -21.613569)
			(xy 54.787945 -21.660082) (xy 54.811617 -21.710579) (xy 54.827685 -21.763986) (xy 54.835805 -21.819162)
			(xy 54.836314 -21.847048) (xy 54.835805 -21.874934) (xy 54.827685 -21.93011) (xy 54.811617 -21.983517)
			(xy 54.787945 -22.034014) (xy 54.757172 -22.080527) (xy 54.719955 -22.122064) (xy 54.677087 -22.157739)
			(xy 54.629481 -22.186793) (xy 54.578152 -22.208605) (xy 54.524195 -22.222711) (xy 54.468758 -22.228811)
			(xy 54.413024 -22.226774) (xy 54.358181 -22.216644) (xy 54.305397 -22.198637) (xy 54.255797 -22.173136)
			(xy 54.210439 -22.140685) (xy 54.17029 -22.101976) (xy 54.136204 -22.057833) (xy 54.108908 -22.009198)
			(xy 54.088985 -21.957107) (xy 54.076859 -21.90267) (xy 54.072788 -21.847048) (xy 53.601444 -21.847048)
			(xy 53.601445 -21.884339) (xy 53.592875 -21.940993) (xy 53.575925 -21.995727) (xy 53.550977 -22.047309)
			(xy 53.518594 -22.094579) (xy 53.479503 -22.136471) (xy 53.457348 -22.154642) (xy 53.45684 -22.15515)
			(xy 53.450744 -22.159722) (xy 53.450236 -22.159976) (xy 53.446123 -22.163436) (xy 53.439323 -22.171755)
			(xy 53.436774 -22.176486) (xy 53.425598 -22.19833) (xy 53.423559 -22.202977) (xy 53.421119 -22.212826)
			(xy 53.420772 -22.217888) (xy 53.420772 -23.0251) (xy 63.36233 -23.0251) (xy 63.366401 -22.969478)
			(xy 63.378527 -22.915041) (xy 63.39845 -22.86295) (xy 63.425746 -22.814315) (xy 63.459832 -22.770172)
			(xy 63.499981 -22.731463) (xy 63.545339 -22.699012) (xy 63.594939 -22.673511) (xy 63.647723 -22.655504)
			(xy 63.702566 -22.645374) (xy 63.7583 -22.643337) (xy 63.813737 -22.649437) (xy 63.867694 -22.663543)
			(xy 63.919023 -22.685355) (xy 63.966629 -22.714409) (xy 64.009497 -22.750084) (xy 64.046714 -22.791621)
			(xy 64.077487 -22.838134) (xy 64.101159 -22.888631) (xy 64.117227 -22.942038) (xy 64.125347 -22.997214)
			(xy 64.125856 -23.0251) (xy 64.125347 -23.052986) (xy 64.117227 -23.108162) (xy 64.101159 -23.161569)
			(xy 64.077487 -23.212066) (xy 64.046714 -23.258579) (xy 64.009497 -23.300116) (xy 63.966629 -23.335791)
			(xy 63.919023 -23.364845) (xy 63.867694 -23.386657) (xy 63.813737 -23.400763) (xy 63.7583 -23.406863)
			(xy 63.702566 -23.404826) (xy 63.647723 -23.394696) (xy 63.594939 -23.376689) (xy 63.545339 -23.351188)
			(xy 63.499981 -23.318737) (xy 63.459832 -23.280028) (xy 63.425746 -23.235885) (xy 63.39845 -23.18725)
			(xy 63.378527 -23.135159) (xy 63.366401 -23.080722) (xy 63.36233 -23.0251) (xy 53.420772 -23.0251)
			(xy 53.420772 -23.495762) (xy 53.421148 -23.501954) (xy 53.424481 -23.513898) (xy 53.427376 -23.519384)
			(xy 53.428646 -23.521416) (xy 53.43525 -23.529544) (xy 53.450744 -23.545038) (xy 53.453807 -23.547934)
			(xy 53.460699 -23.552787) (xy 53.46446 -23.55469) (xy 53.488844 -23.56612) (xy 53.497734 -23.566882)
			(xy 53.525783 -23.569995) (xy 53.580594 -23.58343) (xy 53.632828 -23.604794) (xy 53.681344 -23.63362)
			(xy 53.725083 -23.66928) (xy 53.763091 -23.710995) (xy 53.794538 -23.757855) (xy 53.818738 -23.808837)
			(xy 53.835162 -23.862828) (xy 53.843452 -23.918649) (xy 53.843936 -23.946866) (xy 53.843518 -23.970996)
			(xy 54.072788 -23.970996) (xy 54.076859 -23.915374) (xy 54.088985 -23.860937) (xy 54.108908 -23.808846)
			(xy 54.136204 -23.760211) (xy 54.17029 -23.716068) (xy 54.210439 -23.677359) (xy 54.255797 -23.644908)
			(xy 54.305397 -23.619407) (xy 54.358181 -23.6014) (xy 54.413024 -23.59127) (xy 54.468758 -23.589233)
			(xy 54.524195 -23.595333) (xy 54.578152 -23.609439) (xy 54.581411 -23.610824) (xy 64.065922 -23.610824)
			(xy 64.065926 -23.556329) (xy 64.073684 -23.50239) (xy 64.08904 -23.450103) (xy 64.111681 -23.400534)
			(xy 64.141145 -23.354692) (xy 64.176834 -23.313509) (xy 64.21802 -23.277824) (xy 64.263865 -23.248364)
			(xy 64.313436 -23.225728) (xy 64.365724 -23.210377) (xy 64.419665 -23.202623) (xy 64.446912 -23.202138)
			(xy 64.470941 -23.202512) (xy 64.518619 -23.208551) (xy 64.56516 -23.220533) (xy 64.587628 -23.229062)
			(xy 64.600783 -23.233836) (xy 64.628609 -23.236739) (xy 64.65618 -23.231987) (xy 64.681428 -23.219937)
			(xy 64.702463 -23.201491) (xy 64.717708 -23.178032) (xy 64.726019 -23.151318) (xy 64.726775 -23.123351)
			(xy 64.723772 -23.109682) (xy 64.718322 -23.086699) (xy 64.71246 -23.039828) (xy 64.712088 -23.01621)
			(xy 64.712544 -22.988956) (xy 64.7203 -22.935003) (xy 64.735655 -22.882703) (xy 64.758298 -22.833121)
			(xy 64.787766 -22.787265) (xy 64.82346 -22.74607) (xy 64.864653 -22.710375) (xy 64.910507 -22.680905)
			(xy 64.960089 -22.658261) (xy 65.012388 -22.642903) (xy 65.066341 -22.635145) (xy 65.120848 -22.635144)
			(xy 65.174801 -22.642901) (xy 65.227101 -22.658257) (xy 65.276683 -22.6809) (xy 65.322538 -22.710368)
			(xy 65.363733 -22.746063) (xy 65.399428 -22.787257) (xy 65.428897 -22.833111) (xy 65.451541 -22.882693)
			(xy 65.466898 -22.934993) (xy 65.474655 -22.988946) (xy 65.474655 -23.043453) (xy 65.466898 -23.097406)
			(xy 65.451541 -23.149706) (xy 65.428898 -23.199287) (xy 65.399429 -23.245142) (xy 65.363734 -23.286336)
			(xy 65.322539 -23.322031) (xy 65.276685 -23.3515) (xy 65.227103 -23.374143) (xy 65.174803 -23.389499)
			(xy 65.12085 -23.397255) (xy 65.093596 -23.397718) (xy 65.069567 -23.397338) (xy 65.021889 -23.3913)
			(xy 64.975348 -23.379321) (xy 64.95288 -23.370794) (xy 64.939706 -23.366081) (xy 64.911892 -23.36318)
			(xy 64.884332 -23.367929) (xy 64.859093 -23.379972) (xy 64.838064 -23.398407) (xy 64.82282 -23.421853)
			(xy 64.814505 -23.448554) (xy 64.81374 -23.476509) (xy 64.816736 -23.490174) (xy 64.822197 -23.513155)
			(xy 64.828052 -23.560028) (xy 64.82842 -23.583646) (xy 64.828293 -23.589996) (xy 68.084444 -23.589996)
			(xy 68.088515 -23.534374) (xy 68.100641 -23.479937) (xy 68.120564 -23.427846) (xy 68.14786 -23.379211)
			(xy 68.181946 -23.335068) (xy 68.222095 -23.296359) (xy 68.267453 -23.263908) (xy 68.317053 -23.238407)
			(xy 68.369837 -23.2204) (xy 68.42468 -23.21027) (xy 68.480414 -23.208233) (xy 68.535851 -23.214333)
			(xy 68.589808 -23.228439) (xy 68.641137 -23.250251) (xy 68.688743 -23.279305) (xy 68.731611 -23.31498)
			(xy 68.767965 -23.355554) (xy 77.330554 -23.355554) (xy 77.331042 -23.328744) (xy 77.338549 -23.275651)
			(xy 77.353421 -23.224134) (xy 77.375366 -23.17521) (xy 77.40395 -23.129843) (xy 77.43861 -23.08893)
			(xy 77.47866 -23.053278) (xy 77.500734 -23.038054) (xy 77.512273 -23.029765) (xy 77.530671 -23.008134)
			(xy 77.542404 -22.982274) (xy 77.546566 -22.954184) (xy 77.542835 -22.926033) (xy 77.5315 -22.899996)
			(xy 77.513437 -22.878085) (xy 77.502004 -22.869652) (xy 77.480563 -22.854279) (xy 77.441649 -22.818656)
			(xy 77.408014 -22.778011) (xy 77.380301 -22.733119) (xy 77.359038 -22.684837) (xy 77.344631 -22.634085)
			(xy 77.337354 -22.581832) (xy 77.336904 -22.555454) (xy 77.33739 -22.528203) (xy 77.345146 -22.474255)
			(xy 77.360501 -22.42196) (xy 77.383143 -22.372383) (xy 77.412609 -22.326533) (xy 77.4483 -22.285342)
			(xy 77.489491 -22.249651) (xy 77.535341 -22.220185) (xy 77.584918 -22.197543) (xy 77.637213 -22.182188)
			(xy 77.691161 -22.174432) (xy 77.745663 -22.174432) (xy 77.799611 -22.182188) (xy 77.851906 -22.197543)
			(xy 77.901483 -22.220185) (xy 77.947333 -22.249651) (xy 77.988524 -22.285342) (xy 78.024215 -22.326533)
			(xy 78.053681 -22.372383) (xy 78.076323 -22.42196) (xy 78.091678 -22.474255) (xy 78.099434 -22.528203)
			(xy 78.09992 -22.555454) (xy 78.099449 -22.582265) (xy 78.091941 -22.635359) (xy 78.077067 -22.686877)
			(xy 78.055119 -22.735802) (xy 78.026532 -22.781168) (xy 77.991869 -22.82208) (xy 77.951815 -22.857731)
			(xy 77.92974 -22.872954) (xy 77.918187 -22.881229) (xy 77.899776 -22.902859) (xy 77.888034 -22.928723)
			(xy 77.88387 -22.956821) (xy 77.887605 -22.984979) (xy 77.89895 -23.011019) (xy 77.917029 -23.032928)
			(xy 77.92847 -23.041356) (xy 77.949931 -23.056702) (xy 77.988842 -23.092332) (xy 78.022472 -23.132983)
			(xy 78.050182 -23.177879) (xy 78.071441 -23.226165) (xy 78.085846 -23.27692) (xy 78.093121 -23.329175)
			(xy 78.09357 -23.355554) (xy 78.093084 -23.382805) (xy 78.085328 -23.436753) (xy 78.069973 -23.489048)
			(xy 78.047331 -23.538625) (xy 78.017865 -23.584475) (xy 77.982174 -23.625666) (xy 77.940983 -23.661357)
			(xy 77.895133 -23.690823) (xy 77.845556 -23.713465) (xy 77.793261 -23.72882) (xy 77.739313 -23.736576)
			(xy 77.684811 -23.736576) (xy 77.630863 -23.72882) (xy 77.578568 -23.713465) (xy 77.528991 -23.690823)
			(xy 77.483141 -23.661357) (xy 77.44195 -23.625666) (xy 77.406259 -23.584475) (xy 77.376793 -23.538625)
			(xy 77.354151 -23.489048) (xy 77.338796 -23.436753) (xy 77.33104 -23.382805) (xy 77.330554 -23.355554)
			(xy 68.767965 -23.355554) (xy 68.768828 -23.356517) (xy 68.799601 -23.40303) (xy 68.823273 -23.453527)
			(xy 68.839341 -23.506934) (xy 68.847461 -23.56211) (xy 68.84797 -23.589996) (xy 68.847461 -23.617882)
			(xy 68.839341 -23.673058) (xy 68.823273 -23.726465) (xy 68.799601 -23.776962) (xy 68.768828 -23.823475)
			(xy 68.731611 -23.865012) (xy 68.713219 -23.880318) (xy 69.240652 -23.880318) (xy 69.244723 -23.824696)
			(xy 69.256849 -23.770259) (xy 69.276772 -23.718168) (xy 69.304068 -23.669533) (xy 69.338154 -23.62539)
			(xy 69.378303 -23.586681) (xy 69.423661 -23.55423) (xy 69.473261 -23.528729) (xy 69.526045 -23.510722)
			(xy 69.580888 -23.500592) (xy 69.636622 -23.498555) (xy 69.692059 -23.504655) (xy 69.746016 -23.518761)
			(xy 69.797345 -23.540573) (xy 69.844951 -23.569627) (xy 69.887819 -23.605302) (xy 69.925036 -23.646839)
			(xy 69.955809 -23.693352) (xy 69.979481 -23.743849) (xy 69.995549 -23.797256) (xy 70.003669 -23.852432)
			(xy 70.004178 -23.880318) (xy 70.256652 -23.880318) (xy 70.260723 -23.824696) (xy 70.272849 -23.770259)
			(xy 70.292772 -23.718168) (xy 70.320068 -23.669533) (xy 70.354154 -23.62539) (xy 70.394303 -23.586681)
			(xy 70.439661 -23.55423) (xy 70.489261 -23.528729) (xy 70.542045 -23.510722) (xy 70.596888 -23.500592)
			(xy 70.652622 -23.498555) (xy 70.708059 -23.504655) (xy 70.762016 -23.518761) (xy 70.813345 -23.540573)
			(xy 70.860951 -23.569627) (xy 70.903819 -23.605302) (xy 70.941036 -23.646839) (xy 70.971809 -23.693352)
			(xy 70.995481 -23.743849) (xy 71.011549 -23.797256) (xy 71.019669 -23.852432) (xy 71.020178 -23.880318)
			(xy 71.272652 -23.880318) (xy 71.276723 -23.824696) (xy 71.288849 -23.770259) (xy 71.308772 -23.718168)
			(xy 71.336068 -23.669533) (xy 71.370154 -23.62539) (xy 71.410303 -23.586681) (xy 71.455661 -23.55423)
			(xy 71.505261 -23.528729) (xy 71.558045 -23.510722) (xy 71.612888 -23.500592) (xy 71.668622 -23.498555)
			(xy 71.724059 -23.504655) (xy 71.778016 -23.518761) (xy 71.829345 -23.540573) (xy 71.876951 -23.569627)
			(xy 71.919819 -23.605302) (xy 71.957036 -23.646839) (xy 71.987809 -23.693352) (xy 72.011481 -23.743849)
			(xy 72.027549 -23.797256) (xy 72.035669 -23.852432) (xy 72.036178 -23.880318) (xy 72.290938 -23.880318)
			(xy 72.295009 -23.824696) (xy 72.307135 -23.770259) (xy 72.327058 -23.718168) (xy 72.354354 -23.669533)
			(xy 72.38844 -23.62539) (xy 72.428589 -23.586681) (xy 72.473947 -23.55423) (xy 72.523547 -23.528729)
			(xy 72.576331 -23.510722) (xy 72.631174 -23.500592) (xy 72.686908 -23.498555) (xy 72.742345 -23.504655)
			(xy 72.796302 -23.518761) (xy 72.847631 -23.540573) (xy 72.895237 -23.569627) (xy 72.938105 -23.605302)
			(xy 72.975322 -23.646839) (xy 73.006095 -23.693352) (xy 73.029767 -23.743849) (xy 73.045835 -23.797256)
			(xy 73.053955 -23.852432) (xy 73.054464 -23.880318) (xy 73.053955 -23.908204) (xy 73.045835 -23.96338)
			(xy 73.029767 -24.016787) (xy 73.006095 -24.067284) (xy 72.975322 -24.113797) (xy 72.938105 -24.155334)
			(xy 72.895237 -24.191009) (xy 72.847631 -24.220063) (xy 72.796302 -24.241875) (xy 72.742345 -24.255981)
			(xy 72.686908 -24.262081) (xy 72.631174 -24.260044) (xy 72.576331 -24.249914) (xy 72.523547 -24.231907)
			(xy 72.473947 -24.206406) (xy 72.428589 -24.173955) (xy 72.38844 -24.135246) (xy 72.354354 -24.091103)
			(xy 72.327058 -24.042468) (xy 72.307135 -23.990377) (xy 72.295009 -23.93594) (xy 72.290938 -23.880318)
			(xy 72.036178 -23.880318) (xy 72.035669 -23.908204) (xy 72.027549 -23.96338) (xy 72.011481 -24.016787)
			(xy 71.987809 -24.067284) (xy 71.957036 -24.113797) (xy 71.919819 -24.155334) (xy 71.876951 -24.191009)
			(xy 71.829345 -24.220063) (xy 71.778016 -24.241875) (xy 71.724059 -24.255981) (xy 71.668622 -24.262081)
			(xy 71.612888 -24.260044) (xy 71.558045 -24.249914) (xy 71.505261 -24.231907) (xy 71.455661 -24.206406)
			(xy 71.410303 -24.173955) (xy 71.370154 -24.135246) (xy 71.336068 -24.091103) (xy 71.308772 -24.042468)
			(xy 71.288849 -23.990377) (xy 71.276723 -23.93594) (xy 71.272652 -23.880318) (xy 71.020178 -23.880318)
			(xy 71.019669 -23.908204) (xy 71.011549 -23.96338) (xy 70.995481 -24.016787) (xy 70.971809 -24.067284)
			(xy 70.941036 -24.113797) (xy 70.903819 -24.155334) (xy 70.860951 -24.191009) (xy 70.813345 -24.220063)
			(xy 70.762016 -24.241875) (xy 70.708059 -24.255981) (xy 70.652622 -24.262081) (xy 70.596888 -24.260044)
			(xy 70.542045 -24.249914) (xy 70.489261 -24.231907) (xy 70.439661 -24.206406) (xy 70.394303 -24.173955)
			(xy 70.354154 -24.135246) (xy 70.320068 -24.091103) (xy 70.292772 -24.042468) (xy 70.272849 -23.990377)
			(xy 70.260723 -23.93594) (xy 70.256652 -23.880318) (xy 70.004178 -23.880318) (xy 70.003669 -23.908204)
			(xy 69.995549 -23.96338) (xy 69.979481 -24.016787) (xy 69.955809 -24.067284) (xy 69.925036 -24.113797)
			(xy 69.887819 -24.155334) (xy 69.844951 -24.191009) (xy 69.797345 -24.220063) (xy 69.746016 -24.241875)
			(xy 69.692059 -24.255981) (xy 69.636622 -24.262081) (xy 69.580888 -24.260044) (xy 69.526045 -24.249914)
			(xy 69.473261 -24.231907) (xy 69.423661 -24.206406) (xy 69.378303 -24.173955) (xy 69.338154 -24.135246)
			(xy 69.304068 -24.091103) (xy 69.276772 -24.042468) (xy 69.256849 -23.990377) (xy 69.244723 -23.93594)
			(xy 69.240652 -23.880318) (xy 68.713219 -23.880318) (xy 68.688743 -23.900687) (xy 68.641137 -23.929741)
			(xy 68.589808 -23.951553) (xy 68.535851 -23.965659) (xy 68.480414 -23.971759) (xy 68.42468 -23.969722)
			(xy 68.369837 -23.959592) (xy 68.317053 -23.941585) (xy 68.267453 -23.916084) (xy 68.222095 -23.883633)
			(xy 68.181946 -23.844924) (xy 68.14786 -23.800781) (xy 68.120564 -23.752146) (xy 68.100641 -23.700055)
			(xy 68.088515 -23.645618) (xy 68.084444 -23.589996) (xy 64.828293 -23.589996) (xy 64.827873 -23.610893)
			(xy 64.820111 -23.664833) (xy 64.804752 -23.717118) (xy 64.782108 -23.766686) (xy 64.752641 -23.812527)
			(xy 64.71695 -23.853707) (xy 64.675762 -23.88939) (xy 64.629915 -23.918847) (xy 64.580343 -23.94148)
			(xy 64.528054 -23.956828) (xy 64.474113 -23.964578) (xy 64.419618 -23.964573) (xy 64.365678 -23.956813)
			(xy 64.313392 -23.941456) (xy 64.263824 -23.918814) (xy 64.217982 -23.889348) (xy 64.176801 -23.853658)
			(xy 64.141117 -23.812471) (xy 64.111658 -23.766625) (xy 64.089024 -23.717053) (xy 64.073674 -23.664765)
			(xy 64.065922 -23.610824) (xy 54.581411 -23.610824) (xy 54.629481 -23.631251) (xy 54.677087 -23.660305)
			(xy 54.719955 -23.69598) (xy 54.757172 -23.737517) (xy 54.787945 -23.78403) (xy 54.811617 -23.834527)
			(xy 54.827685 -23.887934) (xy 54.835805 -23.94311) (xy 54.836314 -23.970996) (xy 54.835805 -23.998882)
			(xy 54.827685 -24.054058) (xy 54.811617 -24.107465) (xy 54.787945 -24.157962) (xy 54.787792 -24.158194)
			(xy 59.45073 -24.158194) (xy 59.454801 -24.102572) (xy 59.466927 -24.048135) (xy 59.48685 -23.996044)
			(xy 59.514146 -23.947409) (xy 59.548232 -23.903266) (xy 59.588381 -23.864557) (xy 59.633739 -23.832106)
			(xy 59.683339 -23.806605) (xy 59.736123 -23.788598) (xy 59.790966 -23.778468) (xy 59.8467 -23.776431)
			(xy 59.902137 -23.782531) (xy 59.956094 -23.796637) (xy 60.007423 -23.818449) (xy 60.055029 -23.847503)
			(xy 60.097897 -23.883178) (xy 60.135114 -23.924715) (xy 60.165887 -23.971228) (xy 60.189559 -24.021725)
			(xy 60.205627 -24.075132) (xy 60.213747 -24.130308) (xy 60.214256 -24.158194) (xy 60.213747 -24.18608)
			(xy 60.213178 -24.189944) (xy 63.29883 -24.189944) (xy 63.302901 -24.134322) (xy 63.315027 -24.079885)
			(xy 63.33495 -24.027794) (xy 63.362246 -23.979159) (xy 63.396332 -23.935016) (xy 63.436481 -23.896307)
			(xy 63.481839 -23.863856) (xy 63.531439 -23.838355) (xy 63.584223 -23.820348) (xy 63.639066 -23.810218)
			(xy 63.6948 -23.808181) (xy 63.750237 -23.814281) (xy 63.804194 -23.828387) (xy 63.855523 -23.850199)
			(xy 63.903129 -23.879253) (xy 63.945997 -23.914928) (xy 63.983214 -23.956465) (xy 64.013987 -24.002978)
			(xy 64.037659 -24.053475) (xy 64.053727 -24.106882) (xy 64.061847 -24.162058) (xy 64.062356 -24.189944)
			(xy 65.821812 -24.189944) (xy 65.825883 -24.134322) (xy 65.838009 -24.079885) (xy 65.857932 -24.027794)
			(xy 65.885228 -23.979159) (xy 65.919314 -23.935016) (xy 65.959463 -23.896307) (xy 66.004821 -23.863856)
			(xy 66.054421 -23.838355) (xy 66.107205 -23.820348) (xy 66.162048 -23.810218) (xy 66.217782 -23.808181)
			(xy 66.273219 -23.814281) (xy 66.327176 -23.828387) (xy 66.378505 -23.850199) (xy 66.426111 -23.879253)
			(xy 66.468979 -23.914928) (xy 66.506196 -23.956465) (xy 66.536969 -24.002978) (xy 66.560641 -24.053475)
			(xy 66.576709 -24.106882) (xy 66.584829 -24.162058) (xy 66.585338 -24.189944) (xy 66.584829 -24.21783)
			(xy 66.576709 -24.273006) (xy 66.560641 -24.326413) (xy 66.536969 -24.37691) (xy 66.506196 -24.423423)
			(xy 66.468979 -24.46496) (xy 66.426111 -24.500635) (xy 66.378505 -24.529689) (xy 66.327176 -24.551501)
			(xy 66.273219 -24.565607) (xy 66.217782 -24.571707) (xy 66.162048 -24.56967) (xy 66.107205 -24.55954)
			(xy 66.054421 -24.541533) (xy 66.004821 -24.516032) (xy 65.959463 -24.483581) (xy 65.919314 -24.444872)
			(xy 65.885228 -24.400729) (xy 65.857932 -24.352094) (xy 65.838009 -24.300003) (xy 65.825883 -24.245566)
			(xy 65.821812 -24.189944) (xy 64.062356 -24.189944) (xy 64.061847 -24.21783) (xy 64.053727 -24.273006)
			(xy 64.037659 -24.326413) (xy 64.013987 -24.37691) (xy 63.983214 -24.423423) (xy 63.945997 -24.46496)
			(xy 63.903129 -24.500635) (xy 63.855523 -24.529689) (xy 63.804194 -24.551501) (xy 63.750237 -24.565607)
			(xy 63.6948 -24.571707) (xy 63.639066 -24.56967) (xy 63.584223 -24.55954) (xy 63.531439 -24.541533)
			(xy 63.481839 -24.516032) (xy 63.436481 -24.483581) (xy 63.396332 -24.444872) (xy 63.362246 -24.400729)
			(xy 63.33495 -24.352094) (xy 63.315027 -24.300003) (xy 63.302901 -24.245566) (xy 63.29883 -24.189944)
			(xy 60.213178 -24.189944) (xy 60.205627 -24.241256) (xy 60.189559 -24.294663) (xy 60.165887 -24.34516)
			(xy 60.135114 -24.391673) (xy 60.097897 -24.43321) (xy 60.055029 -24.468885) (xy 60.007423 -24.497939)
			(xy 59.956094 -24.519751) (xy 59.902137 -24.533857) (xy 59.8467 -24.539957) (xy 59.790966 -24.53792)
			(xy 59.736123 -24.52779) (xy 59.683339 -24.509783) (xy 59.633739 -24.484282) (xy 59.588381 -24.451831)
			(xy 59.548232 -24.413122) (xy 59.514146 -24.368979) (xy 59.48685 -24.320344) (xy 59.466927 -24.268253)
			(xy 59.454801 -24.213816) (xy 59.45073 -24.158194) (xy 54.787792 -24.158194) (xy 54.757172 -24.204475)
			(xy 54.719955 -24.246012) (xy 54.677087 -24.281687) (xy 54.629481 -24.310741) (xy 54.578152 -24.332553)
			(xy 54.524195 -24.346659) (xy 54.468758 -24.352759) (xy 54.413024 -24.350722) (xy 54.358181 -24.340592)
			(xy 54.305397 -24.322585) (xy 54.255797 -24.297084) (xy 54.210439 -24.264633) (xy 54.17029 -24.225924)
			(xy 54.136204 -24.181781) (xy 54.108908 -24.133146) (xy 54.088985 -24.081055) (xy 54.076859 -24.026618)
			(xy 54.072788 -23.970996) (xy 53.843518 -23.970996) (xy 53.843475 -23.9735) (xy 53.836074 -24.026252)
			(xy 53.82141 -24.077463) (xy 53.799768 -24.126137) (xy 53.771569 -24.17133) (xy 53.737361 -24.212163)
			(xy 53.697808 -24.247844) (xy 53.653678 -24.277679) (xy 53.605829 -24.301088) (xy 53.55519 -24.317617)
			(xy 53.502744 -24.326945) (xy 53.476144 -24.328374) (xy 53.47208 -24.328374) (xy 53.47081 -24.328628)
			(xy 53.465476 -24.329644) (xy 53.461953 -24.330628) (xy 53.455199 -24.333434) (xy 53.452014 -24.335232)
			(xy 53.447696 -24.338026) (xy 53.442616 -24.342598) (xy 53.421026 -24.364188) (xy 53.414111 -24.371559)
			(xy 53.406247 -24.39016) (xy 53.405786 -24.400256) (xy 53.405786 -24.807418) (xy 60.620146 -24.807418)
			(xy 60.624217 -24.751796) (xy 60.636343 -24.697359) (xy 60.656266 -24.645268) (xy 60.683562 -24.596633)
			(xy 60.717648 -24.55249) (xy 60.757797 -24.513781) (xy 60.803155 -24.48133) (xy 60.852755 -24.455829)
			(xy 60.905539 -24.437822) (xy 60.960382 -24.427692) (xy 61.016116 -24.425655) (xy 61.071553 -24.431755)
			(xy 61.12551 -24.445861) (xy 61.176839 -24.467673) (xy 61.224445 -24.496727) (xy 61.267313 -24.532402)
			(xy 61.30453 -24.573939) (xy 61.335303 -24.620452) (xy 61.358975 -24.670949) (xy 61.375043 -24.724356)
			(xy 61.38009 -24.75865) (xy 72.868534 -24.75865) (xy 72.872605 -24.703028) (xy 72.884731 -24.648591)
			(xy 72.904654 -24.5965) (xy 72.93195 -24.547865) (xy 72.966036 -24.503722) (xy 73.006185 -24.465013)
			(xy 73.051543 -24.432562) (xy 73.101143 -24.407061) (xy 73.153927 -24.389054) (xy 73.20877 -24.378924)
			(xy 73.264504 -24.376887) (xy 73.319941 -24.382987) (xy 73.373898 -24.397093) (xy 73.425227 -24.418905)
			(xy 73.472833 -24.447959) (xy 73.515701 -24.483634) (xy 73.552918 -24.525171) (xy 73.583691 -24.571684)
			(xy 73.607363 -24.622181) (xy 73.623431 -24.675588) (xy 73.631551 -24.730764) (xy 73.63206 -24.75865)
			(xy 73.631551 -24.786536) (xy 73.623431 -24.841712) (xy 73.607363 -24.895119) (xy 73.583691 -24.945616)
			(xy 73.552918 -24.992129) (xy 73.515701 -25.033666) (xy 73.472833 -25.069341) (xy 73.425227 -25.098395)
			(xy 73.373898 -25.120207) (xy 73.319941 -25.134313) (xy 73.264504 -25.140413) (xy 73.20877 -25.138376)
			(xy 73.153927 -25.128246) (xy 73.101143 -25.110239) (xy 73.051543 -25.084738) (xy 73.006185 -25.052287)
			(xy 72.966036 -25.013578) (xy 72.93195 -24.969435) (xy 72.904654 -24.9208) (xy 72.884731 -24.868709)
			(xy 72.872605 -24.814272) (xy 72.868534 -24.75865) (xy 61.38009 -24.75865) (xy 61.383163 -24.779532)
			(xy 61.383672 -24.807418) (xy 61.383163 -24.835304) (xy 61.375043 -24.89048) (xy 61.358975 -24.943887)
			(xy 61.335303 -24.994384) (xy 61.30453 -25.040897) (xy 61.267313 -25.082434) (xy 61.224445 -25.118109)
			(xy 61.176839 -25.147163) (xy 61.12551 -25.168975) (xy 61.071553 -25.183081) (xy 61.016116 -25.189181)
			(xy 60.960382 -25.187144) (xy 60.905539 -25.177014) (xy 60.852755 -25.159007) (xy 60.803155 -25.133506)
			(xy 60.757797 -25.101055) (xy 60.717648 -25.062346) (xy 60.683562 -25.018203) (xy 60.656266 -24.969568)
			(xy 60.636343 -24.917477) (xy 60.624217 -24.86304) (xy 60.620146 -24.807418) (xy 53.405786 -24.807418)
			(xy 53.405786 -25.390094) (xy 65.809622 -25.390094) (xy 65.810108 -25.362843) (xy 65.817864 -25.308895)
			(xy 65.833219 -25.2566) (xy 65.855861 -25.207023) (xy 65.885327 -25.161173) (xy 65.921018 -25.119982)
			(xy 65.962209 -25.084291) (xy 66.008059 -25.054825) (xy 66.057636 -25.032183) (xy 66.109931 -25.016828)
			(xy 66.163879 -25.009072) (xy 66.218381 -25.009072) (xy 66.272329 -25.016828) (xy 66.324624 -25.032183)
			(xy 66.374201 -25.054825) (xy 66.420051 -25.084291) (xy 66.461242 -25.119982) (xy 66.496933 -25.161173)
			(xy 66.526399 -25.207023) (xy 66.549041 -25.2566) (xy 66.564396 -25.308895) (xy 66.572152 -25.362843)
			(xy 66.572638 -25.390094) (xy 66.572072 -25.419114) (xy 66.563281 -25.476485) (xy 66.545902 -25.531862)
			(xy 66.520336 -25.583968) (xy 66.487173 -25.6316) (xy 66.447177 -25.673659) (xy 66.424556 -25.691846)
			(xy 66.414016 -25.700619) (xy 66.397581 -25.722555) (xy 66.38758 -25.748074) (xy 66.384734 -25.775336)
			(xy 66.38925 -25.802371) (xy 66.4008 -25.827228) (xy 66.418552 -25.848112) (xy 66.429636 -25.856184)
			(xy 66.451283 -25.871495) (xy 66.490538 -25.907135) (xy 66.524479 -25.947869) (xy 66.552451 -25.99291)
			(xy 66.573917 -26.041391) (xy 66.588461 -26.092378) (xy 66.595804 -26.144888) (xy 66.59626 -26.171398)
			(xy 66.595774 -26.198649) (xy 66.588018 -26.252597) (xy 66.572663 -26.304892) (xy 66.550021 -26.354469)
			(xy 66.520555 -26.400319) (xy 66.484864 -26.44151) (xy 66.443673 -26.477201) (xy 66.397823 -26.506667)
			(xy 66.348246 -26.529309) (xy 66.295951 -26.544664) (xy 66.242003 -26.55242) (xy 66.187501 -26.55242)
			(xy 66.133553 -26.544664) (xy 66.081258 -26.529309) (xy 66.031681 -26.506667) (xy 65.985831 -26.477201)
			(xy 65.94464 -26.44151) (xy 65.908949 -26.400319) (xy 65.879483 -26.354469) (xy 65.856841 -26.304892)
			(xy 65.841486 -26.252597) (xy 65.83373 -26.198649) (xy 65.833244 -26.171398) (xy 65.833812 -26.142378)
			(xy 65.842603 -26.085008) (xy 65.859982 -26.029631) (xy 65.885548 -25.977525) (xy 65.918711 -25.929893)
			(xy 65.958706 -25.887833) (xy 65.981326 -25.869646) (xy 65.991876 -25.860884) (xy 66.008314 -25.838946)
			(xy 66.018317 -25.813424) (xy 66.021162 -25.786159) (xy 66.016644 -25.759122) (xy 66.00509 -25.734263)
			(xy 65.987333 -25.713379) (xy 65.976246 -25.705308) (xy 65.954591 -25.690008) (xy 65.915337 -25.654365)
			(xy 65.881397 -25.61363) (xy 65.853426 -25.568587) (xy 65.831962 -25.520104) (xy 65.817419 -25.469116)
			(xy 65.810077 -25.416605) (xy 65.809622 -25.390094) (xy 53.405786 -25.390094) (xy 53.405786 -25.971246)
			(xy 53.959758 -25.971246) (xy 53.963829 -25.915624) (xy 53.975955 -25.861187) (xy 53.995878 -25.809096)
			(xy 54.023174 -25.760461) (xy 54.05726 -25.716318) (xy 54.097409 -25.677609) (xy 54.142767 -25.645158)
			(xy 54.192367 -25.619657) (xy 54.245151 -25.60165) (xy 54.299994 -25.59152) (xy 54.355728 -25.589483)
			(xy 54.411165 -25.595583) (xy 54.465122 -25.609689) (xy 54.516451 -25.631501) (xy 54.564057 -25.660555)
			(xy 54.606925 -25.69623) (xy 54.644142 -25.737767) (xy 54.674915 -25.78428) (xy 54.698587 -25.834777)
			(xy 54.714655 -25.888184) (xy 54.722775 -25.94336) (xy 54.723284 -25.971246) (xy 54.975758 -25.971246)
			(xy 54.979829 -25.915624) (xy 54.991955 -25.861187) (xy 55.011878 -25.809096) (xy 55.039174 -25.760461)
			(xy 55.07326 -25.716318) (xy 55.113409 -25.677609) (xy 55.158767 -25.645158) (xy 55.208367 -25.619657)
			(xy 55.261151 -25.60165) (xy 55.315994 -25.59152) (xy 55.371728 -25.589483) (xy 55.427165 -25.595583)
			(xy 55.481122 -25.609689) (xy 55.532451 -25.631501) (xy 55.580057 -25.660555) (xy 55.622925 -25.69623)
			(xy 55.660142 -25.737767) (xy 55.690915 -25.78428) (xy 55.714587 -25.834777) (xy 55.730655 -25.888184)
			(xy 55.738775 -25.94336) (xy 55.739284 -25.971246) (xy 55.991758 -25.971246) (xy 55.995829 -25.915624)
			(xy 56.007955 -25.861187) (xy 56.027878 -25.809096) (xy 56.055174 -25.760461) (xy 56.08926 -25.716318)
			(xy 56.129409 -25.677609) (xy 56.174767 -25.645158) (xy 56.224367 -25.619657) (xy 56.277151 -25.60165)
			(xy 56.331994 -25.59152) (xy 56.387728 -25.589483) (xy 56.443165 -25.595583) (xy 56.497122 -25.609689)
			(xy 56.548451 -25.631501) (xy 56.596057 -25.660555) (xy 56.638925 -25.69623) (xy 56.676142 -25.737767)
			(xy 56.706915 -25.78428) (xy 56.730587 -25.834777) (xy 56.746655 -25.888184) (xy 56.754775 -25.94336)
			(xy 56.755284 -25.971246) (xy 56.754775 -25.999132) (xy 56.749683 -26.03373) (xy 57.267854 -26.03373)
			(xy 57.271925 -25.978108) (xy 57.284051 -25.923671) (xy 57.303974 -25.87158) (xy 57.33127 -25.822945)
			(xy 57.365356 -25.778802) (xy 57.405505 -25.740093) (xy 57.450863 -25.707642) (xy 57.500463 -25.682141)
			(xy 57.553247 -25.664134) (xy 57.60809 -25.654004) (xy 57.663824 -25.651967) (xy 57.719261 -25.658067)
			(xy 57.773218 -25.672173) (xy 57.824547 -25.693985) (xy 57.872153 -25.723039) (xy 57.915021 -25.758714)
			(xy 57.952238 -25.800251) (xy 57.983011 -25.846764) (xy 58.006683 -25.897261) (xy 58.022751 -25.950668)
			(xy 58.030871 -26.005844) (xy 58.03138 -26.03373) (xy 58.030871 -26.061616) (xy 58.022751 -26.116792)
			(xy 58.006683 -26.170199) (xy 57.983011 -26.220696) (xy 57.952777 -26.266394) (xy 60.52058 -26.266394)
			(xy 60.521072 -26.239143) (xy 60.528829 -26.185196) (xy 60.544184 -26.132902) (xy 60.566825 -26.083326)
			(xy 60.596291 -26.037476) (xy 60.631982 -25.996286) (xy 60.673171 -25.960595) (xy 60.719021 -25.931128)
			(xy 60.768597 -25.908487) (xy 60.82089 -25.89313) (xy 60.874837 -25.885373) (xy 60.902088 -25.884886)
			(xy 60.931413 -25.88542) (xy 60.989371 -25.894401) (xy 61.04527 -25.912153) (xy 61.09779 -25.938256)
			(xy 61.122052 -25.954736) (xy 61.132569 -25.961177) (xy 61.156978 -25.964378) (xy 61.168788 -25.960832)
			(xy 61.247274 -25.931622) (xy 61.258705 -25.926795) (xy 61.275343 -25.908421) (xy 61.279024 -25.89657)
			(xy 61.286379 -25.869487) (xy 61.307938 -25.817676) (xy 61.336857 -25.769583) (xy 61.372512 -25.726247)
			(xy 61.414132 -25.688605) (xy 61.46082 -25.657468) (xy 61.511566 -25.633509) (xy 61.565276 -25.617245)
			(xy 61.620789 -25.609028) (xy 61.648848 -25.608534) (xy 61.6761 -25.608939) (xy 61.730048 -25.616702)
			(xy 61.782343 -25.632063) (xy 61.83192 -25.654709) (xy 61.877769 -25.68418) (xy 61.918958 -25.719876)
			(xy 61.954649 -25.761069) (xy 61.984114 -25.806922) (xy 62.006754 -25.856502) (xy 62.022108 -25.908798)
			(xy 62.029864 -25.962748) (xy 62.029864 -25.990042) (xy 63.29883 -25.990042) (xy 63.302901 -25.93442)
			(xy 63.315027 -25.879983) (xy 63.33495 -25.827892) (xy 63.362246 -25.779257) (xy 63.396332 -25.735114)
			(xy 63.436481 -25.696405) (xy 63.481839 -25.663954) (xy 63.531439 -25.638453) (xy 63.584223 -25.620446)
			(xy 63.639066 -25.610316) (xy 63.6948 -25.608279) (xy 63.750237 -25.614379) (xy 63.804194 -25.628485)
			(xy 63.855523 -25.650297) (xy 63.903129 -25.679351) (xy 63.945997 -25.715026) (xy 63.983214 -25.756563)
			(xy 64.013987 -25.803076) (xy 64.037659 -25.853573) (xy 64.053727 -25.90698) (xy 64.061847 -25.962156)
			(xy 64.062356 -25.990042) (xy 64.061847 -26.017928) (xy 64.053727 -26.073104) (xy 64.037659 -26.126511)
			(xy 64.013987 -26.177008) (xy 63.983214 -26.223521) (xy 63.945997 -26.265058) (xy 63.903129 -26.300733)
			(xy 63.855523 -26.329787) (xy 63.804194 -26.351599) (xy 63.750237 -26.365705) (xy 63.6948 -26.371805)
			(xy 63.639066 -26.369768) (xy 63.584223 -26.359638) (xy 63.531439 -26.341631) (xy 63.481839 -26.31613)
			(xy 63.436481 -26.283679) (xy 63.396332 -26.24497) (xy 63.362246 -26.200827) (xy 63.33495 -26.152192)
			(xy 63.315027 -26.100101) (xy 63.302901 -26.045664) (xy 63.29883 -25.990042) (xy 62.029864 -25.990042)
			(xy 62.029864 -26.017252) (xy 62.022108 -26.071202) (xy 62.006754 -26.123498) (xy 61.984114 -26.173078)
			(xy 61.954649 -26.218931) (xy 61.918958 -26.260124) (xy 61.877769 -26.29582) (xy 61.83192 -26.325291)
			(xy 61.782343 -26.347937) (xy 61.730048 -26.363298) (xy 61.6761 -26.371061) (xy 61.648848 -26.37155)
			(xy 61.619524 -26.370991) (xy 61.561567 -26.362017) (xy 61.505669 -26.344272) (xy 61.453147 -26.318176)
			(xy 61.428884 -26.3017) (xy 61.418387 -26.295218) (xy 61.39396 -26.292041) (xy 61.382148 -26.295604)
			(xy 61.303662 -26.324814) (xy 61.292228 -26.329637) (xy 61.275589 -26.348013) (xy 61.271912 -26.359866)
			(xy 61.265143 -26.384902) (xy 61.245725 -26.432993) (xy 61.219966 -26.478007) (xy 61.18834 -26.519113)
			(xy 61.151434 -26.55555) (xy 61.130942 -26.571448) (xy 61.121282 -26.579436) (xy 61.110625 -26.602092)
			(xy 61.110622 -26.614628) (xy 61.115194 -26.698956) (xy 61.116452 -26.711389) (xy 61.129243 -26.732825)
			(xy 61.139578 -26.73985) (xy 61.16331 -26.754763) (xy 61.206546 -26.790426) (xy 61.244099 -26.832032)
			(xy 61.27516 -26.878685) (xy 61.29906 -26.92938) (xy 61.315286 -26.983027) (xy 61.323487 -27.038471)
			(xy 61.323982 -27.066494) (xy 61.323496 -27.093745) (xy 61.31574 -27.147693) (xy 61.300385 -27.199988)
			(xy 61.277743 -27.249565) (xy 61.248277 -27.295415) (xy 61.212586 -27.336606) (xy 61.171395 -27.372297)
			(xy 61.125545 -27.401763) (xy 61.075968 -27.424405) (xy 61.023673 -27.43976) (xy 60.969725 -27.447516)
			(xy 60.915223 -27.447516) (xy 60.861275 -27.43976) (xy 60.80898 -27.424405) (xy 60.759403 -27.401763)
			(xy 60.713553 -27.372297) (xy 60.672362 -27.336606) (xy 60.636671 -27.295415) (xy 60.607205 -27.249565)
			(xy 60.584563 -27.199988) (xy 60.569208 -27.147693) (xy 60.561452 -27.093745) (xy 60.560966 -27.066494)
			(xy 60.561523 -27.037007) (xy 60.570618 -26.978737) (xy 60.588577 -26.922562) (xy 60.614969 -26.869822)
			(xy 60.649166 -26.821774) (xy 60.690353 -26.779564) (xy 60.71362 -26.76144) (xy 60.723296 -26.753468)
			(xy 60.733941 -26.730799) (xy 60.73394 -26.71826) (xy 60.729368 -26.633932) (xy 60.728132 -26.621495)
			(xy 60.715327 -26.600058) (xy 60.704984 -26.593038) (xy 60.681238 -26.578147) (xy 60.638004 -26.542478)
			(xy 60.600453 -26.500868) (xy 60.569395 -26.454212) (xy 60.545497 -26.403513) (xy 60.529273 -26.349864)
			(xy 60.521074 -26.294418) (xy 60.52058 -26.266394) (xy 57.952777 -26.266394) (xy 57.952238 -26.267209)
			(xy 57.915021 -26.308746) (xy 57.872153 -26.344421) (xy 57.824547 -26.373475) (xy 57.773218 -26.395287)
			(xy 57.719261 -26.409393) (xy 57.663824 -26.415493) (xy 57.60809 -26.413456) (xy 57.553247 -26.403326)
			(xy 57.500463 -26.385319) (xy 57.450863 -26.359818) (xy 57.405505 -26.327367) (xy 57.365356 -26.288658)
			(xy 57.33127 -26.244515) (xy 57.303974 -26.19588) (xy 57.284051 -26.143789) (xy 57.271925 -26.089352)
			(xy 57.267854 -26.03373) (xy 56.749683 -26.03373) (xy 56.746655 -26.054308) (xy 56.730587 -26.107715)
			(xy 56.706915 -26.158212) (xy 56.676142 -26.204725) (xy 56.638925 -26.246262) (xy 56.596057 -26.281937)
			(xy 56.548451 -26.310991) (xy 56.497122 -26.332803) (xy 56.443165 -26.346909) (xy 56.387728 -26.353009)
			(xy 56.331994 -26.350972) (xy 56.277151 -26.340842) (xy 56.224367 -26.322835) (xy 56.174767 -26.297334)
			(xy 56.129409 -26.264883) (xy 56.08926 -26.226174) (xy 56.055174 -26.182031) (xy 56.027878 -26.133396)
			(xy 56.007955 -26.081305) (xy 55.995829 -26.026868) (xy 55.991758 -25.971246) (xy 55.739284 -25.971246)
			(xy 55.738775 -25.999132) (xy 55.730655 -26.054308) (xy 55.714587 -26.107715) (xy 55.690915 -26.158212)
			(xy 55.660142 -26.204725) (xy 55.622925 -26.246262) (xy 55.580057 -26.281937) (xy 55.532451 -26.310991)
			(xy 55.481122 -26.332803) (xy 55.427165 -26.346909) (xy 55.371728 -26.353009) (xy 55.315994 -26.350972)
			(xy 55.261151 -26.340842) (xy 55.208367 -26.322835) (xy 55.158767 -26.297334) (xy 55.113409 -26.264883)
			(xy 55.07326 -26.226174) (xy 55.039174 -26.182031) (xy 55.011878 -26.133396) (xy 54.991955 -26.081305)
			(xy 54.979829 -26.026868) (xy 54.975758 -25.971246) (xy 54.723284 -25.971246) (xy 54.722775 -25.999132)
			(xy 54.714655 -26.054308) (xy 54.698587 -26.107715) (xy 54.674915 -26.158212) (xy 54.644142 -26.204725)
			(xy 54.606925 -26.246262) (xy 54.564057 -26.281937) (xy 54.516451 -26.310991) (xy 54.465122 -26.332803)
			(xy 54.411165 -26.346909) (xy 54.355728 -26.353009) (xy 54.299994 -26.350972) (xy 54.245151 -26.340842)
			(xy 54.192367 -26.322835) (xy 54.142767 -26.297334) (xy 54.097409 -26.264883) (xy 54.05726 -26.226174)
			(xy 54.023174 -26.182031) (xy 53.995878 -26.133396) (xy 53.975955 -26.081305) (xy 53.963829 -26.026868)
			(xy 53.959758 -25.971246) (xy 53.405786 -25.971246) (xy 53.405786 -27.649932) (xy 53.405926 -27.655515)
			(xy 53.408353 -27.666415) (xy 53.410612 -27.671522) (xy 53.434742 -27.695652) (xy 53.442108 -27.699208)
			(xy 53.467996 -27.712879) (xy 53.515608 -27.746942) (xy 53.525842 -27.756952) (xy 56.759066 -27.756952)
			(xy 56.759066 -27.702448) (xy 56.766822 -27.648499) (xy 56.782178 -27.596203) (xy 56.804819 -27.546625)
			(xy 56.834286 -27.500773) (xy 56.869978 -27.459582) (xy 56.911169 -27.423889) (xy 56.95702 -27.394422)
			(xy 57.006598 -27.37178) (xy 57.058893 -27.356424) (xy 57.112842 -27.348666) (xy 57.140094 -27.34818)
			(xy 57.154179 -27.348285) (xy 57.182275 -27.350316) (xy 57.196228 -27.352244) (xy 57.210198 -27.354276)
			(xy 57.235852 -27.343862) (xy 57.298082 -27.261058) (xy 57.303216 -27.253537) (xy 57.308276 -27.236057)
			(xy 57.306897 -27.217911) (xy 57.303416 -27.209496) (xy 57.303416 -27.209242) (xy 57.292377 -27.184111)
			(xy 57.276772 -27.131489) (xy 57.268864 -27.077173) (xy 57.268364 -27.04973) (xy 57.26885 -27.022479)
			(xy 57.276606 -26.968531) (xy 57.291961 -26.916236) (xy 57.314603 -26.866659) (xy 57.344069 -26.820809)
			(xy 57.37976 -26.779618) (xy 57.420951 -26.743927) (xy 57.466801 -26.714461) (xy 57.516378 -26.691819)
			(xy 57.568673 -26.676464) (xy 57.622621 -26.668708) (xy 57.677123 -26.668708) (xy 57.731071 -26.676464)
			(xy 57.783366 -26.691819) (xy 57.832943 -26.714461) (xy 57.878793 -26.743927) (xy 57.919984 -26.779618)
			(xy 57.955675 -26.820809) (xy 57.985141 -26.866659) (xy 58.007783 -26.916236) (xy 58.023138 -26.968531)
			(xy 58.030894 -27.022479) (xy 58.03138 -27.04973) (xy 58.03138 -27.050238) (xy 58.030726 -27.081568)
			(xy 58.020437 -27.14338) (xy 58.000189 -27.20268) (xy 57.985914 -27.230578) (xy 57.98058 -27.24023)
			(xy 57.979056 -27.26182) (xy 58.013346 -27.354276) (xy 58.028332 -27.369516) (xy 58.038492 -27.37358)
			(xy 58.039 -27.37358) (xy 58.06561 -27.384393) (xy 58.115525 -27.412805) (xy 58.160617 -27.448379)
			(xy 58.199866 -27.49031) (xy 58.232387 -27.537651) (xy 58.257444 -27.589332) (xy 58.27447 -27.644185)
			(xy 58.283082 -27.700971) (xy 58.283602 -27.729688) (xy 58.283133 -27.756941) (xy 58.275378 -27.810892)
			(xy 58.260023 -27.86319) (xy 58.237382 -27.91277) (xy 58.207914 -27.958624) (xy 58.172221 -27.999817)
			(xy 58.131029 -28.035511) (xy 58.085176 -28.064979) (xy 58.035596 -28.087621) (xy 57.983298 -28.102977)
			(xy 57.929347 -28.110733) (xy 57.902094 -28.111196) (xy 57.873177 -28.110683) (xy 57.816005 -28.101953)
			(xy 57.760806 -28.084694) (xy 57.708845 -28.059302) (xy 57.661311 -28.026357) (xy 57.619294 -27.986616)
			(xy 57.601104 -27.96413) (xy 57.593497 -27.955323) (xy 57.572596 -27.945142) (xy 57.560972 -27.944572)
			(xy 57.481216 -27.944572) (xy 57.469583 -27.94511) (xy 57.448672 -27.955297) (xy 57.441084 -27.96413)
			(xy 57.42291 -27.986627) (xy 57.380885 -28.02636) (xy 57.333347 -28.059297) (xy 57.281382 -28.084683)
			(xy 57.226182 -28.101936) (xy 57.169011 -28.110662) (xy 57.140094 -28.111196) (xy 57.112842 -28.110734)
			(xy 57.058893 -28.102976) (xy 57.006598 -28.08762) (xy 56.95702 -28.064978) (xy 56.911169 -28.035511)
			(xy 56.869978 -27.999818) (xy 56.834286 -27.958627) (xy 56.804819 -27.912775) (xy 56.782178 -27.863197)
			(xy 56.766822 -27.810901) (xy 56.759066 -27.756952) (xy 53.525842 -27.756952) (xy 53.557459 -27.787878)
			(xy 53.575458 -27.810968) (xy 53.581554 -27.819096) (xy 53.589936 -27.824176) (xy 53.593681 -27.826304)
			(xy 53.601726 -27.829376) (xy 53.605938 -27.830272) (xy 53.676804 -27.840686) (xy 53.689758 -27.842718)
			(xy 53.708808 -27.837892) (xy 53.71719 -27.831796) (xy 53.74191 -27.81433) (xy 53.795715 -27.786613)
			(xy 53.853222 -27.767742) (xy 53.912988 -27.758191) (xy 53.94325 -27.757628) (xy 53.971802 -27.758165)
			(xy 54.028269 -27.76668) (xy 54.082837 -27.783514) (xy 54.134287 -27.80829) (xy 54.181472 -27.840454)
			(xy 54.223338 -27.87929) (xy 54.25895 -27.923931) (xy 54.273704 -27.948382) (xy 54.275228 -27.951176)
			(xy 54.281832 -27.95905) (xy 54.286404 -27.963622) (xy 54.294024 -27.96794) (xy 54.298743 -27.970248)
			(xy 54.308858 -27.973071) (xy 54.31409 -27.973528) (xy 54.317646 -27.973782) (xy 54.40553 -27.973782)
			(xy 54.408578 -27.973528) (xy 54.409594 -27.973528) (xy 54.414697 -27.973027) (xy 54.424557 -27.970215)
			(xy 54.429152 -27.96794) (xy 54.436772 -27.963622) (xy 54.445916 -27.954224) (xy 54.449472 -27.948382)
			(xy 54.449726 -27.947874) (xy 54.464492 -27.923478) (xy 54.500126 -27.87896) (xy 54.541983 -27.840236)
			(xy 54.589134 -27.808168) (xy 54.64053 -27.783468) (xy 54.695028 -27.766686) (xy 54.751415 -27.758195)
			(xy 54.779926 -27.757628) (xy 54.807173 -27.758116) (xy 54.861113 -27.765875) (xy 54.9134 -27.781231)
			(xy 54.962969 -27.803871) (xy 55.008812 -27.833335) (xy 55.049995 -27.869023) (xy 55.08568 -27.910209)
			(xy 55.115141 -27.956054) (xy 55.137778 -28.005625) (xy 55.153131 -28.057912) (xy 55.160886 -28.111853)
			(xy 55.160886 -28.139136) (xy 55.667908 -28.139136) (xy 55.671979 -28.083514) (xy 55.684105 -28.029077)
			(xy 55.704028 -27.976986) (xy 55.731324 -27.928351) (xy 55.76541 -27.884208) (xy 55.805559 -27.845499)
			(xy 55.850917 -27.813048) (xy 55.900517 -27.787547) (xy 55.953301 -27.76954) (xy 56.008144 -27.75941)
			(xy 56.063878 -27.757373) (xy 56.119315 -27.763473) (xy 56.173272 -27.777579) (xy 56.224601 -27.799391)
			(xy 56.272207 -27.828445) (xy 56.315075 -27.86412) (xy 56.352292 -27.905657) (xy 56.383065 -27.95217)
			(xy 56.406737 -28.002667) (xy 56.422805 -28.056074) (xy 56.430925 -28.11125) (xy 56.431434 -28.139136)
			(xy 56.430925 -28.167022) (xy 56.422805 -28.222198) (xy 56.406737 -28.275605) (xy 56.383065 -28.326102)
			(xy 56.352292 -28.372615) (xy 56.315075 -28.414152) (xy 56.272207 -28.449827) (xy 56.224601 -28.478881)
			(xy 56.173272 -28.500693) (xy 56.119315 -28.514799) (xy 56.063878 -28.520899) (xy 56.008144 -28.518862)
			(xy 55.953301 -28.508732) (xy 55.900517 -28.490725) (xy 55.850917 -28.465224) (xy 55.805559 -28.432773)
			(xy 55.76541 -28.394064) (xy 55.731324 -28.349921) (xy 55.704028 -28.301286) (xy 55.684105 -28.249195)
			(xy 55.671979 -28.194758) (xy 55.667908 -28.139136) (xy 55.160886 -28.139136) (xy 55.160886 -28.166347)
			(xy 55.153131 -28.220288) (xy 55.137778 -28.272575) (xy 55.115141 -28.322146) (xy 55.08568 -28.367991)
			(xy 55.049995 -28.409177) (xy 55.008812 -28.444865) (xy 54.962969 -28.474329) (xy 54.9134 -28.496969)
			(xy 54.861113 -28.512325) (xy 54.807173 -28.520084) (xy 54.779926 -28.520644) (xy 54.751092 -28.520112)
			(xy 54.694082 -28.511432) (xy 54.639025 -28.49428) (xy 54.587172 -28.469045) (xy 54.539701 -28.436303)
			(xy 54.497693 -28.396796) (xy 54.462101 -28.351422) (xy 54.44744 -28.326588) (xy 54.440339 -28.317277)
			(xy 54.419964 -28.305787) (xy 54.408324 -28.30449) (xy 54.314852 -28.30449) (xy 54.303187 -28.305705)
			(xy 54.282786 -28.317217) (xy 54.275736 -28.326588) (xy 54.261102 -28.35144) (xy 54.225518 -28.396827)
			(xy 54.18351 -28.436342) (xy 54.136035 -28.469086) (xy 54.084173 -28.494314) (xy 54.029106 -28.511451)
			(xy 53.972086 -28.520107) (xy 53.94325 -28.520644) (xy 53.91405 -28.520083) (xy 53.856335 -28.511172)
			(xy 53.800653 -28.493564) (xy 53.748306 -28.467673) (xy 53.700519 -28.434103) (xy 53.658409 -28.39364)
			(xy 53.640228 -28.370784) (xy 53.63972 -28.370022) (xy 53.636672 -28.36672) (xy 53.628036 -28.358084)
			(xy 53.622853 -28.354435) (xy 53.611162 -28.349544) (xy 53.604922 -28.348432) (xy 53.538628 -28.338526)
			(xy 53.53812 -28.338526) (xy 53.533548 -28.337764) (xy 53.528765 -28.337298) (xy 53.519176 -28.337935)
			(xy 53.514498 -28.339034) (xy 53.514244 -28.339034) (xy 53.504846 -28.34132) (xy 53.496464 -28.347416)
			(xy 53.493924 -28.349194) (xy 53.492908 -28.35021) (xy 53.487066 -28.35402) (xy 53.485034 -28.355544)
			(xy 53.484018 -28.356306) (xy 53.47843 -28.360116) (xy 53.475128 -28.363672) (xy 53.46954 -28.371292)
			(xy 53.456078 -28.396184) (xy 53.453667 -28.401393) (xy 53.450967 -28.412547) (xy 53.450744 -28.418282)
			(xy 53.450744 -28.42387) (xy 53.450927 -28.429673) (xy 53.453614 -28.440965) (xy 53.456078 -28.446222)
			(xy 53.469286 -28.47086) (xy 53.475128 -28.47848) (xy 53.478938 -28.482544) (xy 53.479192 -28.482544)
			(xy 53.485542 -28.486862) (xy 53.50943 -28.503809) (xy 53.552195 -28.543827) (xy 53.588342 -28.589911)
			(xy 53.617022 -28.640977) (xy 53.627782 -28.668218) (xy 53.635541 -28.689869) (xy 53.646367 -28.73457)
			(xy 53.649372 -28.757372) (xy 53.650642 -28.769564) (xy 53.652166 -28.802076) (xy 53.651709 -28.828954)
			(xy 53.644173 -28.88218) (xy 53.629247 -28.933823) (xy 53.607226 -28.982862) (xy 53.578545 -29.028328)
			(xy 53.543771 -29.069323) (xy 53.503591 -29.105035) (xy 53.4588 -29.134759) (xy 53.434742 -29.146754)
			(xy 53.42763 -29.150056) (xy 53.417216 -29.159708) (xy 53.41366 -29.165042) (xy 53.410023 -29.171241)
			(xy 53.406022 -29.185037) (xy 53.405786 -29.19222) (xy 53.405786 -29.224732) (xy 53.406035 -29.231913)
			(xy 53.410034 -29.245707) (xy 53.41366 -29.25191) (xy 53.41747 -29.257752) (xy 53.427884 -29.26715)
			(xy 53.434742 -29.270452) (xy 53.459051 -29.282603) (xy 53.504264 -29.312756) (xy 53.544743 -29.349015)
			(xy 53.579672 -29.390648) (xy 53.608344 -29.436814) (xy 53.63018 -29.486579) (xy 53.644738 -29.538938)
			(xy 53.651724 -29.592832) (xy 53.650997 -29.647172) (xy 53.642571 -29.700859) (xy 53.626618 -29.75281)
			(xy 53.603458 -29.801973) (xy 53.58892 -29.824934) (xy 53.572335 -29.84916) (xy 53.532916 -29.892666)
			(xy 53.510434 -29.911548) (xy 53.504592 -29.91612) (xy 53.487828 -29.939996) (xy 53.487828 -29.94025)
			(xy 53.486672 -29.944085) (xy 53.485404 -29.951994) (xy 53.485288 -29.955998) (xy 53.485288 -30.036516)
			(xy 53.485796 -30.043374) (xy 53.487662 -30.05289) (xy 53.497456 -30.069607) (xy 53.504846 -30.075886)
			(xy 53.53177 -30.099) (xy 53.532278 -30.099508) (xy 53.539136 -30.105858) (xy 53.542184 -30.108652)
			(xy 53.551074 -30.118304) (xy 53.570903 -30.140684) (xy 53.604064 -30.190436) (xy 53.62906 -30.24475)
			(xy 53.64528 -30.302299) (xy 53.649372 -30.331918) (xy 53.650642 -30.344364) (xy 53.652166 -30.376876)
			(xy 53.651709 -30.403754) (xy 53.644173 -30.45698) (xy 53.629247 -30.508623) (xy 53.607226 -30.557662)
			(xy 53.578545 -30.603128) (xy 53.543771 -30.644123) (xy 53.503591 -30.679835) (xy 53.4588 -30.709559)
			(xy 53.434742 -30.721554) (xy 53.42763 -30.724856) (xy 53.417216 -30.734508) (xy 53.41366 -30.739842)
			(xy 53.410023 -30.746041) (xy 53.406022 -30.759837) (xy 53.405786 -30.76702) (xy 53.405786 -31.142432)
			(xy 53.406459 -31.153827) (xy 53.41638 -31.17435) (xy 53.434179 -31.188592) (xy 53.445156 -31.191708)
			(xy 53.445664 -31.191962) (xy 53.447696 -31.192216) (xy 53.473815 -31.19734) (xy 53.524408 -31.21387)
			(xy 53.572211 -31.237275) (xy 53.616295 -31.2671) (xy 53.655805 -31.302764) (xy 53.689971 -31.343575)
			(xy 53.718131 -31.388741) (xy 53.739738 -31.437383) (xy 53.754371 -31.488558) (xy 53.761746 -31.541269)
			(xy 53.762148 -31.567882) (xy 53.761689 -31.594478) (xy 53.754304 -31.647155) (xy 53.739676 -31.698297)
			(xy 53.730364 -31.719266) (xy 54.285386 -31.719266) (xy 54.289457 -31.663644) (xy 54.301583 -31.609207)
			(xy 54.321506 -31.557116) (xy 54.348802 -31.508481) (xy 54.382888 -31.464338) (xy 54.423037 -31.425629)
			(xy 54.468395 -31.393178) (xy 54.517995 -31.367677) (xy 54.570779 -31.34967) (xy 54.625622 -31.33954)
			(xy 54.681356 -31.337503) (xy 54.736793 -31.343603) (xy 54.79075 -31.357709) (xy 54.842079 -31.379521)
			(xy 54.889685 -31.408575) (xy 54.932553 -31.44425) (xy 54.96977 -31.485787) (xy 55.000543 -31.5323)
			(xy 55.024215 -31.582797) (xy 55.040283 -31.636204) (xy 55.044433 -31.664402) (xy 55.560974 -31.664402)
			(xy 55.565045 -31.60878) (xy 55.577171 -31.554343) (xy 55.597094 -31.502252) (xy 55.62439 -31.453617)
			(xy 55.658476 -31.409474) (xy 55.698625 -31.370765) (xy 55.743983 -31.338314) (xy 55.793583 -31.312813)
			(xy 55.846367 -31.294806) (xy 55.90121 -31.284676) (xy 55.956944 -31.282639) (xy 56.012381 -31.288739)
			(xy 56.066338 -31.302845) (xy 56.117667 -31.324657) (xy 56.165273 -31.353711) (xy 56.208141 -31.389386)
			(xy 56.245358 -31.430923) (xy 56.276131 -31.477436) (xy 56.299803 -31.527933) (xy 56.315871 -31.58134)
			(xy 56.323991 -31.636516) (xy 56.3245 -31.664402) (xy 56.323991 -31.692288) (xy 56.315871 -31.747464)
			(xy 56.306931 -31.777178) (xy 56.826148 -31.777178) (xy 56.830219 -31.721556) (xy 56.842345 -31.667119)
			(xy 56.862268 -31.615028) (xy 56.889564 -31.566393) (xy 56.92365 -31.52225) (xy 56.963799 -31.483541)
			(xy 57.009157 -31.45109) (xy 57.058757 -31.425589) (xy 57.111541 -31.407582) (xy 57.166384 -31.397452)
			(xy 57.222118 -31.395415) (xy 57.277555 -31.401515) (xy 57.331512 -31.415621) (xy 57.382841 -31.437433)
			(xy 57.430447 -31.466487) (xy 57.473315 -31.502162) (xy 57.510532 -31.543699) (xy 57.541305 -31.590212)
			(xy 57.564977 -31.640709) (xy 57.581045 -31.694116) (xy 57.589165 -31.749292) (xy 57.589674 -31.777178)
			(xy 57.589165 -31.805064) (xy 57.581045 -31.86024) (xy 57.564977 -31.913647) (xy 57.541305 -31.964144)
			(xy 57.510532 -32.010657) (xy 57.473315 -32.052194) (xy 57.430447 -32.087869) (xy 57.382841 -32.116923)
			(xy 57.331512 -32.138735) (xy 57.277555 -32.152841) (xy 57.222118 -32.158941) (xy 57.166384 -32.156904)
			(xy 57.111541 -32.146774) (xy 57.058757 -32.128767) (xy 57.009157 -32.103266) (xy 56.963799 -32.070815)
			(xy 56.92365 -32.032106) (xy 56.889564 -31.987963) (xy 56.862268 -31.939328) (xy 56.842345 -31.887237)
			(xy 56.830219 -31.8328) (xy 56.826148 -31.777178) (xy 56.306931 -31.777178) (xy 56.299803 -31.800871)
			(xy 56.276131 -31.851368) (xy 56.245358 -31.897881) (xy 56.208141 -31.939418) (xy 56.165273 -31.975093)
			(xy 56.117667 -32.004147) (xy 56.066338 -32.025959) (xy 56.012381 -32.040065) (xy 55.956944 -32.046165)
			(xy 55.90121 -32.044128) (xy 55.846367 -32.033998) (xy 55.793583 -32.015991) (xy 55.743983 -31.99049)
			(xy 55.698625 -31.958039) (xy 55.658476 -31.91933) (xy 55.62439 -31.875187) (xy 55.597094 -31.826552)
			(xy 55.577171 -31.774461) (xy 55.565045 -31.720024) (xy 55.560974 -31.664402) (xy 55.044433 -31.664402)
			(xy 55.048403 -31.69138) (xy 55.048912 -31.719266) (xy 55.048403 -31.747152) (xy 55.040283 -31.802328)
			(xy 55.024215 -31.855735) (xy 55.000543 -31.906232) (xy 54.96977 -31.952745) (xy 54.932553 -31.994282)
			(xy 54.889685 -32.029957) (xy 54.842079 -32.059011) (xy 54.79075 -32.080823) (xy 54.736793 -32.094929)
			(xy 54.681356 -32.101029) (xy 54.625622 -32.098992) (xy 54.570779 -32.088862) (xy 54.517995 -32.070855)
			(xy 54.468395 -32.045354) (xy 54.423037 -32.012903) (xy 54.382888 -31.974194) (xy 54.348802 -31.930051)
			(xy 54.321506 -31.881416) (xy 54.301583 -31.829325) (xy 54.289457 -31.774888) (xy 54.285386 -31.719266)
			(xy 53.730364 -31.719266) (xy 53.718088 -31.746912) (xy 53.689959 -31.792057) (xy 53.655832 -31.832859)
			(xy 53.61637 -31.868527) (xy 53.572337 -31.898369) (xy 53.524587 -31.921807) (xy 53.474045 -31.938387)
			(xy 53.44795 -31.943548) (xy 53.447696 -31.943548) (xy 53.436342 -31.946145) (xy 53.417554 -31.959869)
			(xy 53.406705 -31.980451) (xy 53.405786 -31.992062) (xy 53.405786 -33.507426) (xy 53.406045 -33.514837)
			(xy 53.410314 -33.52903) (xy 53.414168 -33.535366) (xy 53.418463 -33.54142) (xy 53.429817 -33.550973)
			(xy 53.43652 -33.554162) (xy 53.522372 -33.590992) (xy 53.529277 -33.593682) (xy 53.543994 -33.595355)
			(xy 53.551328 -33.594294) (xy 53.55844 -33.593024) (xy 53.571648 -33.58642) (xy 53.577236 -33.581086)
			(xy 53.598646 -33.561502) (xy 53.646285 -33.528378) (xy 53.698389 -33.502848) (xy 53.753758 -33.485501)
			(xy 53.811115 -33.476736) (xy 53.840126 -33.476184) (xy 53.866736 -33.476641) (xy 53.91944 -33.484025)
			(xy 53.970606 -33.498661) (xy 54.019243 -33.520264) (xy 54.064406 -33.548416) (xy 54.10522 -33.582571)
			(xy 54.140891 -33.622064) (xy 54.17073 -33.666132) (xy 54.194155 -33.713917) (xy 54.202838 -33.739074)
			(xy 54.203346 -33.740344) (xy 54.203346 -33.740598) (xy 54.206273 -33.747931) (xy 54.215836 -33.760485)
			(xy 54.222142 -33.765236) (xy 54.28615 -33.803336) (xy 54.299358 -33.807908) (xy 54.30774 -33.809432)
			(xy 54.312058 -33.80867) (xy 54.317392 -33.807654) (xy 54.334265 -33.804803) (xy 54.368352 -33.801753)
			(xy 54.385464 -33.801558) (xy 54.387496 -33.801558) (xy 54.414655 -33.802179) (xy 54.468389 -33.810166)
			(xy 54.520446 -33.825693) (xy 54.569775 -33.848446) (xy 54.584058 -33.857692) (xy 55.490108 -33.857692)
			(xy 55.494179 -33.80207) (xy 55.506305 -33.747633) (xy 55.526228 -33.695542) (xy 55.553524 -33.646907)
			(xy 55.58761 -33.602764) (xy 55.627759 -33.564055) (xy 55.673117 -33.531604) (xy 55.722717 -33.506103)
			(xy 55.775501 -33.488096) (xy 55.830344 -33.477966) (xy 55.886078 -33.475929) (xy 55.941515 -33.482029)
			(xy 55.995472 -33.496135) (xy 56.046801 -33.517947) (xy 56.094407 -33.547001) (xy 56.137275 -33.582676)
			(xy 56.174492 -33.624213) (xy 56.205265 -33.670726) (xy 56.228937 -33.721223) (xy 56.245005 -33.77463)
			(xy 56.253125 -33.829806) (xy 56.253634 -33.857692) (xy 56.253125 -33.885578) (xy 56.245005 -33.940754)
			(xy 56.228937 -33.994161) (xy 56.205265 -34.044658) (xy 56.174492 -34.091171) (xy 56.137275 -34.132708)
			(xy 56.094407 -34.168383) (xy 56.046801 -34.197437) (xy 55.995472 -34.219249) (xy 55.941515 -34.233355)
			(xy 55.886078 -34.239455) (xy 55.830344 -34.237418) (xy 55.775501 -34.227288) (xy 55.722717 -34.209281)
			(xy 55.673117 -34.18378) (xy 55.627759 -34.151329) (xy 55.58761 -34.11262) (xy 55.553524 -34.068477)
			(xy 55.526228 -34.019842) (xy 55.506305 -33.967751) (xy 55.494179 -33.913314) (xy 55.490108 -33.857692)
			(xy 54.584058 -33.857692) (xy 54.615378 -33.877966) (xy 54.656333 -33.913656) (xy 54.691812 -33.954794)
			(xy 54.721097 -34.000548) (xy 54.743597 -34.049994) (xy 54.758856 -34.10213) (xy 54.766565 -34.155904)
			(xy 54.766972 -34.183066) (xy 54.766511 -34.21032) (xy 54.758758 -34.264272) (xy 54.743404 -34.316572)
			(xy 54.720763 -34.366154) (xy 54.691296 -34.412009) (xy 54.655601 -34.453203) (xy 54.614407 -34.488897)
			(xy 54.568552 -34.518364) (xy 54.51897 -34.541005) (xy 54.46667 -34.556358) (xy 54.412718 -34.564111)
			(xy 54.385464 -34.564574) (xy 54.358856 -34.564117) (xy 54.306154 -34.556731) (xy 54.25499 -34.542093)
			(xy 54.206356 -34.520488) (xy 54.161197 -34.492334) (xy 54.120388 -34.458178) (xy 54.084721 -34.418683)
			(xy 54.054888 -34.374615) (xy 54.031468 -34.326829) (xy 54.022752 -34.301684) (xy 54.022244 -34.300414)
			(xy 54.022244 -34.30016) (xy 54.019312 -34.292831) (xy 54.009742 -34.280287) (xy 54.003448 -34.275522)
			(xy 53.93944 -34.237422) (xy 53.926232 -34.23285) (xy 53.91785 -34.231326) (xy 53.913532 -34.232088)
			(xy 53.908198 -34.233104) (xy 53.891388 -34.23595) (xy 53.857428 -34.239006) (xy 53.84038 -34.2392)
			(xy 53.840126 -34.2392) (xy 53.811117 -34.238655) (xy 53.753767 -34.229868) (xy 53.698407 -34.212507)
			(xy 53.646309 -34.186972) (xy 53.598674 -34.153851) (xy 53.577236 -34.134298) (xy 53.576474 -34.133536)
			(xy 53.571014 -34.128823) (xy 53.558121 -34.122372) (xy 53.551074 -34.120836) (xy 53.543962 -34.119566)
			(xy 53.536596 -34.120582) (xy 53.533004 -34.12102) (xy 53.52599 -34.122803) (xy 53.522626 -34.124138)
			(xy 53.43652 -34.161222) (xy 53.427637 -34.165536) (xy 53.413796 -34.179593) (xy 53.406299 -34.197841)
			(xy 53.405786 -34.207704) (xy 53.405786 -35.264852) (xy 55.90235 -35.264852) (xy 55.906421 -35.20923)
			(xy 55.918547 -35.154793) (xy 55.93847 -35.102702) (xy 55.965766 -35.054067) (xy 55.999852 -35.009924)
			(xy 56.040001 -34.971215) (xy 56.085359 -34.938764) (xy 56.134959 -34.913263) (xy 56.187743 -34.895256)
			(xy 56.242586 -34.885126) (xy 56.29832 -34.883089) (xy 56.353757 -34.889189) (xy 56.407714 -34.903295)
			(xy 56.459043 -34.925107) (xy 56.506649 -34.954161) (xy 56.549517 -34.989836) (xy 56.574355 -35.017557)
			(xy 58.219733 -35.017557) (xy 58.219733 -34.963043) (xy 58.227492 -34.909085) (xy 58.242851 -34.85678)
			(xy 58.265498 -34.807194) (xy 58.294973 -34.761336) (xy 58.330674 -34.72014) (xy 58.371874 -34.684444)
			(xy 58.417736 -34.654975) (xy 58.467325 -34.632334) (xy 58.519632 -34.616981) (xy 58.573591 -34.60923)
			(xy 58.600848 -34.60877) (xy 58.61796 -34.608963) (xy 58.652047 -34.612014) (xy 58.66892 -34.614866)
			(xy 58.680212 -34.616215) (xy 58.702099 -34.610153) (xy 58.711084 -34.603182) (xy 58.735468 -34.5821)
			(xy 58.743896 -34.574183) (xy 58.753159 -34.553023) (xy 58.753248 -34.54146) (xy 58.75274 -34.522664)
			(xy 58.75274 -33.65881) (xy 58.753248 -33.638744) (xy 58.753039 -33.627299) (xy 58.743939 -33.606328)
			(xy 58.735722 -33.598358) (xy 58.711084 -33.577022) (xy 58.702097 -33.569925) (xy 58.680004 -33.563983)
			(xy 58.668666 -33.565592) (xy 58.651859 -33.568458) (xy 58.617897 -33.571508) (xy 58.600848 -33.571688)
			(xy 58.573591 -33.571268) (xy 58.519632 -33.563517) (xy 58.467326 -33.548164) (xy 58.417737 -33.525523)
			(xy 58.371876 -33.496055) (xy 58.330675 -33.460359) (xy 58.294974 -33.419163) (xy 58.2655 -33.373305)
			(xy 58.242853 -33.323719) (xy 58.227494 -33.271415) (xy 58.219735 -33.217456) (xy 58.219735 -33.162944)
			(xy 58.227494 -33.108985) (xy 58.242853 -33.056681) (xy 58.2655 -33.007095) (xy 58.294974 -32.961237)
			(xy 58.330675 -32.920041) (xy 58.371876 -32.884345) (xy 58.417737 -32.854877) (xy 58.467326 -32.832236)
			(xy 58.519632 -32.816883) (xy 58.573591 -32.809132) (xy 58.600848 -32.808672) (xy 58.627858 -32.809075)
			(xy 58.681338 -32.816688) (xy 58.733209 -32.83177) (xy 58.782434 -32.854017) (xy 58.828029 -32.882986)
			(xy 58.869081 -32.918097) (xy 58.90477 -32.958649) (xy 58.934381 -33.003829) (xy 58.957323 -33.052734)
			(xy 58.973136 -33.104387) (xy 58.977784 -33.130998) (xy 58.979308 -33.141666) (xy 58.990738 -33.159446)
			(xy 59.062112 -33.206944) (xy 59.071047 -33.21228) (xy 59.091506 -33.215962) (xy 59.101736 -33.214056)
			(xy 59.102498 -33.214056) (xy 59.129069 -33.207946) (xy 59.183188 -33.20132) (xy 59.210448 -33.200848)
			(xy 59.237773 -33.201301) (xy 59.292021 -33.207924) (xy 59.318652 -33.214056) (xy 59.31916 -33.214056)
			(xy 59.329389 -33.215926) (xy 59.349838 -33.212247) (xy 59.358784 -33.206944) (xy 59.430158 -33.159446)
			(xy 59.441588 -33.141666) (xy 59.443112 -33.130998) (xy 59.447766 -33.104393) (xy 59.463598 -33.052755)
			(xy 59.486552 -33.003865) (xy 59.51617 -32.9587) (xy 59.55186 -32.918162) (xy 59.592908 -32.88306)
			(xy 59.638496 -32.854097) (xy 59.687712 -32.831851) (xy 59.739573 -32.816766) (xy 59.793043 -32.809144)
			(xy 59.820048 -32.808672) (xy 59.847418 -32.809151) (xy 59.901597 -32.816963) (xy 59.954101 -32.832448)
			(xy 60.003848 -32.855287) (xy 60.049815 -32.885011) (xy 60.070746 -32.902652) (xy 60.071 -32.902906)
			(xy 60.078082 -32.908499) (xy 60.095002 -32.914742) (xy 60.10402 -32.915098) (xy 60.171076 -32.915098)
			(xy 60.180092 -32.91473) (xy 60.197009 -32.90849) (xy 60.204096 -32.902906) (xy 60.204096 -32.902652)
			(xy 60.20435 -32.902652) (xy 60.225297 -32.885031) (xy 60.271265 -32.855315) (xy 60.321008 -32.832474)
			(xy 60.373506 -32.816979) (xy 60.42768 -32.809148) (xy 60.455048 -32.808672) (xy 60.47216 -32.808865)
			(xy 60.506247 -32.811916) (xy 60.52312 -32.814768) (xy 60.534412 -32.816117) (xy 60.556299 -32.810055)
			(xy 60.565284 -32.803084) (xy 60.589668 -32.782002) (xy 60.598095 -32.774084) (xy 60.607358 -32.752924)
			(xy 60.607448 -32.741362) (xy 60.60694 -32.722566) (xy 60.60694 -31.858712) (xy 60.607448 -31.838646)
			(xy 60.607238 -31.827201) (xy 60.598138 -31.80623) (xy 60.589922 -31.79826) (xy 60.565284 -31.776924)
			(xy 60.556297 -31.769828) (xy 60.534204 -31.763885) (xy 60.522866 -31.765494) (xy 60.506059 -31.76836)
			(xy 60.472097 -31.77141) (xy 60.455048 -31.77159) (xy 60.427679 -31.771098) (xy 60.373501 -31.763287)
			(xy 60.320998 -31.747804) (xy 60.27125 -31.724968) (xy 60.225282 -31.695249) (xy 60.20435 -31.67761)
			(xy 60.197492 -31.671514) (xy 60.180474 -31.665164) (xy 60.09513 -31.665164) (xy 60.077858 -31.671768)
			(xy 60.071 -31.677864) (xy 60.050048 -31.69548) (xy 60.004085 -31.725203) (xy 59.954343 -31.748047)
			(xy 59.901845 -31.763543) (xy 59.84767 -31.771372) (xy 59.820302 -31.771844) (xy 59.820048 -31.771844)
			(xy 59.793069 -31.771422) (xy 59.739648 -31.763833) (xy 59.687831 -31.748788) (xy 59.638653 -31.726585)
			(xy 59.593098 -31.697669) (xy 59.552076 -31.662618) (xy 59.516407 -31.622132) (xy 59.486803 -31.577021)
			(xy 59.463857 -31.528186) (xy 59.448027 -31.476603) (xy 59.443366 -31.450026) (xy 59.441171 -31.439805)
			(xy 59.429912 -31.422223) (xy 59.421522 -31.41599) (xy 59.350148 -31.368492) (xy 59.329066 -31.364682)
			(xy 59.318906 -31.367222) (xy 59.292203 -31.373291) (xy 59.237829 -31.379788) (xy 59.210448 -31.380176)
			(xy 59.183066 -31.379807) (xy 59.12869 -31.373308) (xy 59.10199 -31.367222) (xy 59.09183 -31.364682)
			(xy 59.070748 -31.368492) (xy 58.990484 -31.421832) (xy 58.979308 -31.439358) (xy 58.97753 -31.450026)
			(xy 58.972877 -31.4766) (xy 58.957019 -31.528165) (xy 58.934054 -31.576982) (xy 58.904441 -31.622076)
			(xy 58.868768 -31.662547) (xy 58.82775 -31.697589) (xy 58.782203 -31.726502) (xy 58.733036 -31.748708)
			(xy 58.681232 -31.763766) (xy 58.627822 -31.771374) (xy 58.600848 -31.771844) (xy 58.573595 -31.771312)
			(xy 58.519644 -31.763561) (xy 58.467346 -31.748211) (xy 58.417764 -31.725573) (xy 58.371909 -31.696109)
			(xy 58.330715 -31.660419) (xy 58.295019 -31.619229) (xy 58.26555 -31.573378) (xy 58.242906 -31.523799)
			(xy 58.227549 -31.471503) (xy 58.219791 -31.417552) (xy 58.219791 -31.363048) (xy 58.227549 -31.309097)
			(xy 58.242906 -31.256801) (xy 58.26555 -31.207222) (xy 58.295019 -31.161371) (xy 58.330715 -31.120181)
			(xy 58.371909 -31.084491) (xy 58.417764 -31.055027) (xy 58.467346 -31.032389) (xy 58.519644 -31.017039)
			(xy 58.573595 -31.009288) (xy 58.600848 -31.008828) (xy 58.61796 -31.009022) (xy 58.652047 -31.012072)
			(xy 58.66892 -31.014924) (xy 58.680212 -31.016283) (xy 58.702101 -31.010216) (xy 58.711084 -31.00324)
			(xy 58.735468 -30.982158) (xy 58.743916 -30.974259) (xy 58.753167 -30.953085) (xy 58.753248 -30.941518)
			(xy 58.75274 -30.922722) (xy 58.75274 -30.058868) (xy 58.753248 -30.038802) (xy 58.753063 -30.027355)
			(xy 58.743946 -30.006384) (xy 58.735722 -29.998416) (xy 58.711084 -29.97708) (xy 58.702093 -29.969988)
			(xy 58.680004 -29.96404) (xy 58.668666 -29.96565) (xy 58.651859 -29.968517) (xy 58.617897 -29.971566)
			(xy 58.600848 -29.971746) (xy 58.573596 -29.97121) (xy 58.519645 -29.963459) (xy 58.467346 -29.948109)
			(xy 58.417765 -29.925472) (xy 58.371911 -29.896008) (xy 58.330716 -29.860318) (xy 58.295021 -29.819128)
			(xy 58.265552 -29.773277) (xy 58.242908 -29.723699) (xy 58.227551 -29.671402) (xy 58.219793 -29.617452)
			(xy 58.219793 -29.562948) (xy 58.227551 -29.508998) (xy 58.242908 -29.456701) (xy 58.265552 -29.407123)
			(xy 58.295021 -29.361272) (xy 58.330716 -29.320082) (xy 58.371911 -29.284392) (xy 58.417765 -29.254928)
			(xy 58.467346 -29.232291) (xy 58.519645 -29.216941) (xy 58.573596 -29.20919) (xy 58.600848 -29.20873)
			(xy 58.627856 -29.209169) (xy 58.681333 -29.216781) (xy 58.733202 -29.23186) (xy 58.782425 -29.254104)
			(xy 58.828018 -29.28307) (xy 58.869069 -29.318177) (xy 58.904758 -29.358723) (xy 58.934371 -29.403898)
			(xy 58.957316 -29.452799) (xy 58.973134 -29.504447) (xy 58.977784 -29.531056) (xy 58.979308 -29.541724)
			(xy 58.990738 -29.559504) (xy 59.062112 -29.607002) (xy 59.071049 -29.612336) (xy 59.091506 -29.616021)
			(xy 59.101736 -29.614114) (xy 59.102498 -29.614114) (xy 59.129075 -29.608065) (xy 59.183194 -29.60157)
			(xy 59.210448 -29.60116) (xy 59.237766 -29.60155) (xy 59.292015 -29.608042) (xy 59.318652 -29.614114)
			(xy 59.31916 -29.614114) (xy 59.32939 -29.615975) (xy 59.349837 -29.6123) (xy 59.358784 -29.607002)
			(xy 59.430158 -29.559504) (xy 59.441588 -29.541724) (xy 59.443112 -29.531056) (xy 59.447811 -29.504459)
			(xy 59.463635 -29.452821) (xy 59.486582 -29.403931) (xy 59.516193 -29.358765) (xy 59.551878 -29.318225)
			(xy 59.592922 -29.283122) (xy 59.638506 -29.254158) (xy 59.687719 -29.23191) (xy 59.739577 -29.216824)
			(xy 59.793044 -29.209202) (xy 59.820048 -29.20873) (xy 59.847417 -29.209219) (xy 59.901596 -29.21703)
			(xy 59.954099 -29.232514) (xy 60.003846 -29.25535) (xy 60.049814 -29.285071) (xy 60.070746 -29.30271)
			(xy 60.071 -29.302964) (xy 60.078077 -29.308564) (xy 60.095001 -29.314801) (xy 60.10402 -29.315156)
			(xy 60.171076 -29.315156) (xy 60.180093 -29.314797) (xy 60.19701 -29.308552) (xy 60.204096 -29.302964)
			(xy 60.204096 -29.30271) (xy 60.20435 -29.30271) (xy 60.225291 -29.285082) (xy 60.271261 -29.255369)
			(xy 60.321007 -29.23253) (xy 60.373505 -29.217036) (xy 60.427679 -29.209205) (xy 60.455048 -29.20873)
			(xy 60.47216 -29.208923) (xy 60.506247 -29.211974) (xy 60.52312 -29.214826) (xy 60.534412 -29.216184)
			(xy 60.556301 -29.210118) (xy 60.565284 -29.203142) (xy 60.589668 -29.18206) (xy 60.598115 -29.17416)
			(xy 60.607367 -29.152986) (xy 60.607448 -29.14142) (xy 60.60694 -29.122624) (xy 60.60694 -28.25877)
			(xy 60.607448 -28.238704) (xy 60.607262 -28.227257) (xy 60.598145 -28.206286) (xy 60.589922 -28.198318)
			(xy 60.565284 -28.176982) (xy 60.556293 -28.169891) (xy 60.534203 -28.163942) (xy 60.522866 -28.165552)
			(xy 60.506059 -28.168419) (xy 60.472097 -28.171468) (xy 60.455048 -28.171648) (xy 60.427796 -28.171108)
			(xy 60.373845 -28.163357) (xy 60.321547 -28.148007) (xy 60.271966 -28.12537) (xy 60.226112 -28.095906)
			(xy 60.184918 -28.060216) (xy 60.149223 -28.019027) (xy 60.119753 -27.973176) (xy 60.09711 -27.923598)
			(xy 60.081753 -27.871302) (xy 60.073995 -27.817352) (xy 60.073995 -27.762848) (xy 60.081753 -27.708898)
			(xy 60.09711 -27.656602) (xy 60.119753 -27.607024) (xy 60.149223 -27.561173) (xy 60.184918 -27.519984)
			(xy 60.226112 -27.484294) (xy 60.271966 -27.45483) (xy 60.321547 -27.432193) (xy 60.373845 -27.416843)
			(xy 60.427796 -27.409092) (xy 60.455048 -27.408632) (xy 60.482056 -27.409069) (xy 60.535533 -27.416681)
			(xy 60.587402 -27.43176) (xy 60.636625 -27.454005) (xy 60.682218 -27.482971) (xy 60.72327 -27.518078)
			(xy 60.758959 -27.558624) (xy 60.788572 -27.6038) (xy 60.811516 -27.652701) (xy 60.827334 -27.704349)
			(xy 60.831984 -27.730958) (xy 60.833508 -27.741626) (xy 60.844938 -27.759406) (xy 60.916312 -27.806904)
			(xy 60.925249 -27.812238) (xy 60.945706 -27.815923) (xy 60.955936 -27.814016) (xy 60.956698 -27.814016)
			(xy 60.983269 -27.807906) (xy 61.037388 -27.80128) (xy 61.064648 -27.800808) (xy 61.086826 -27.801102)
			(xy 61.130972 -27.805429) (xy 61.152786 -27.809444) (xy 61.162946 -27.811476) (xy 61.183012 -27.807412)
			(xy 61.251338 -27.760168) (xy 61.259499 -27.753952) (xy 61.270512 -27.736667) (xy 61.272674 -27.72664)
			(xy 61.277552 -27.700297) (xy 61.293769 -27.649237) (xy 61.31697 -27.600948) (xy 61.3467 -27.55638)
			(xy 61.382373 -27.51641) (xy 61.423288 -27.481824) (xy 61.468639 -27.453304) (xy 61.517535 -27.431409)
			(xy 61.569013 -27.416571) (xy 61.622061 -27.409082) (xy 61.648848 -27.408632) (xy 61.6761 -27.409041)
			(xy 61.730048 -27.416804) (xy 61.782343 -27.432165) (xy 61.831919 -27.454811) (xy 61.877768 -27.484282)
			(xy 61.918957 -27.519977) (xy 61.954647 -27.56117) (xy 61.984112 -27.607023) (xy 62.006752 -27.656603)
			(xy 62.022106 -27.708899) (xy 62.029862 -27.762848) (xy 62.029862 -27.817352) (xy 62.022106 -27.871301)
			(xy 62.006752 -27.923597) (xy 61.984112 -27.973177) (xy 61.954647 -28.01903) (xy 61.918957 -28.060223)
			(xy 61.877768 -28.095918) (xy 61.831919 -28.125389) (xy 61.782343 -28.148035) (xy 61.730048 -28.163396)
			(xy 61.6761 -28.171159) (xy 61.648848 -28.171648) (xy 61.648086 -28.171648) (xy 61.636754 -28.171529)
			(xy 61.614134 -28.170134) (xy 61.602874 -28.168854) (xy 61.59196 -28.168133) (xy 61.571165 -28.174832)
			(xy 61.562742 -28.181808) (xy 61.538612 -28.203652) (xy 61.530869 -28.211485) (xy 61.522311 -28.231756)
			(xy 61.522102 -28.242768) (xy 61.522356 -28.25877) (xy 61.522356 -29.12237) (xy 61.522102 -29.13761)
			(xy 61.522286 -29.148662) (xy 61.531006 -29.168951) (xy 61.538866 -29.176726) (xy 61.562742 -29.198316)
			(xy 61.57115 -29.205317) (xy 61.591957 -29.212017) (xy 61.602874 -29.21127) (xy 61.614132 -29.209976)
			(xy 61.636754 -29.208579) (xy 61.648086 -29.208476) (xy 61.648848 -29.208476) (xy 61.676096 -29.208998)
			(xy 61.730036 -29.216759) (xy 61.782323 -29.232118) (xy 61.831892 -29.254761) (xy 61.877734 -29.284227)
			(xy 61.918917 -29.319917) (xy 61.954602 -29.361104) (xy 61.984062 -29.40695) (xy 62.006699 -29.456522)
			(xy 62.022051 -29.508811) (xy 62.029806 -29.562752) (xy 62.029806 -29.617248) (xy 62.022051 -29.671189)
			(xy 62.006699 -29.723478) (xy 61.984062 -29.77305) (xy 61.954602 -29.818896) (xy 61.918917 -29.860083)
			(xy 61.877734 -29.895773) (xy 61.831892 -29.925239) (xy 61.782323 -29.947882) (xy 61.730036 -29.963241)
			(xy 61.676096 -29.971002) (xy 61.648848 -29.971492) (xy 61.622102 -29.970978) (xy 61.569136 -29.963491)
			(xy 61.517734 -29.948685) (xy 61.468901 -29.926849) (xy 61.423593 -29.898412) (xy 61.382699 -29.863929)
			(xy 61.347017 -29.824076) (xy 61.317247 -29.779633) (xy 61.293971 -29.73147) (xy 61.277645 -29.68053)
			(xy 61.272674 -29.654246) (xy 61.270896 -29.643832) (xy 61.260228 -29.627068) (xy 61.183266 -29.573728)
			(xy 61.1632 -29.569664) (xy 61.15304 -29.571696) (xy 61.131167 -29.575747) (xy 61.086891 -29.580071)
			(xy 61.064648 -29.580332) (xy 61.03726 -29.579883) (xy 60.982884 -29.573265) (xy 60.95619 -29.567124)
			(xy 60.94603 -29.564584) (xy 60.924948 -29.568394) (xy 60.844684 -29.621734) (xy 60.833508 -29.63926)
			(xy 60.83173 -29.649928) (xy 60.827078 -29.676502) (xy 60.81122 -29.728067) (xy 60.788255 -29.776884)
			(xy 60.758641 -29.821978) (xy 60.722969 -29.86245) (xy 60.68195 -29.897491) (xy 60.636403 -29.926404)
			(xy 60.587237 -29.94861) (xy 60.535432 -29.963668) (xy 60.482022 -29.971276) (xy 60.455048 -29.971746)
			(xy 60.427678 -29.971265) (xy 60.373499 -29.963453) (xy 60.320996 -29.947968) (xy 60.271249 -29.925129)
			(xy 60.225282 -29.895407) (xy 60.20435 -29.877766) (xy 60.204096 -29.877512) (xy 60.197014 -29.871919)
			(xy 60.180094 -29.865676) (xy 60.171076 -29.86532) (xy 60.10402 -29.86532) (xy 60.095004 -29.865683)
			(xy 60.078086 -29.871926) (xy 60.071 -29.877512) (xy 60.071 -29.877766) (xy 60.070746 -29.877766)
			(xy 60.049803 -29.895392) (xy 60.003834 -29.925107) (xy 59.954089 -29.947946) (xy 59.901591 -29.96344)
			(xy 59.847417 -29.971271) (xy 59.820048 -29.971746) (xy 59.803 -29.971548) (xy 59.76904 -29.968494)
			(xy 59.75223 -29.96565) (xy 59.740903 -29.96422) (xy 59.718886 -29.970152) (xy 59.709812 -29.97708)
			(xy 59.685174 -29.998416) (xy 59.676838 -30.0063) (xy 59.667713 -30.027328) (xy 59.667648 -30.038802)
			(xy 59.668156 -30.058868) (xy 59.668156 -30.922722) (xy 59.667648 -30.941518) (xy 59.667734 -30.953079)
			(xy 59.677005 -30.974237) (xy 59.685428 -30.982158) (xy 59.709812 -31.00324) (xy 59.718791 -31.010228)
			(xy 59.740683 -31.016302) (xy 59.751976 -31.014924) (xy 59.768847 -31.012055) (xy 59.802935 -31.009002)
			(xy 59.820048 -31.008828) (xy 59.847417 -31.009318) (xy 59.901596 -31.017129) (xy 59.954099 -31.032612)
			(xy 60.003846 -31.055449) (xy 60.049814 -31.085169) (xy 60.070746 -31.102808) (xy 60.077604 -31.108904)
			(xy 60.094622 -31.115254) (xy 60.179966 -31.115254) (xy 60.197238 -31.10865) (xy 60.204096 -31.102554)
			(xy 60.225014 -31.084896) (xy 60.270986 -31.055178) (xy 60.320737 -31.032342) (xy 60.373243 -31.016856)
			(xy 60.427423 -31.00904) (xy 60.454794 -31.008574) (xy 60.455048 -31.008574) (xy 60.482058 -31.008976)
			(xy 60.535538 -31.016589) (xy 60.587409 -31.03167) (xy 60.636635 -31.053918) (xy 60.682229 -31.082887)
			(xy 60.723282 -31.117998) (xy 60.75897 -31.15855) (xy 60.788581 -31.20373) (xy 60.811523 -31.252636)
			(xy 60.827336 -31.304289) (xy 60.831984 -31.3309) (xy 60.833508 -31.341568) (xy 60.844938 -31.359348)
			(xy 60.916312 -31.406846) (xy 60.925247 -31.412182) (xy 60.945706 -31.415864) (xy 60.955936 -31.413958)
			(xy 60.956698 -31.413958) (xy 60.983275 -31.40791) (xy 61.037394 -31.401414) (xy 61.064648 -31.401004)
			(xy 61.086821 -31.401226) (xy 61.130968 -31.405428) (xy 61.152786 -31.409386) (xy 61.162946 -31.411418)
			(xy 61.183012 -31.407354) (xy 61.251338 -31.36011) (xy 61.259519 -31.353917) (xy 61.270521 -31.336615)
			(xy 61.272674 -31.326582) (xy 61.277508 -31.300231) (xy 61.293732 -31.24917) (xy 61.316941 -31.200881)
			(xy 61.346677 -31.156314) (xy 61.382355 -31.116346) (xy 61.423274 -31.081762) (xy 61.468629 -31.053243)
			(xy 61.517528 -31.031349) (xy 61.569009 -31.016512) (xy 61.62206 -31.009024) (xy 61.648848 -31.008574)
			(xy 61.676096 -31.0091) (xy 61.730036 -31.016861) (xy 61.782322 -31.03222) (xy 61.831891 -31.054863)
			(xy 61.877733 -31.084329) (xy 61.918916 -31.120018) (xy 61.9546 -31.161205) (xy 61.984061 -31.207051)
			(xy 62.006697 -31.256623) (xy 62.022049 -31.308911) (xy 62.029804 -31.362852) (xy 62.029804 -31.417348)
			(xy 62.022049 -31.471289) (xy 62.006697 -31.523577) (xy 61.984061 -31.573149) (xy 61.9546 -31.618995)
			(xy 61.918916 -31.660182) (xy 61.877733 -31.695871) (xy 61.831891 -31.725337) (xy 61.782322 -31.74798)
			(xy 61.730036 -31.763339) (xy 61.676096 -31.7711) (xy 61.648848 -31.77159) (xy 61.648086 -31.77159)
			(xy 61.636754 -31.771471) (xy 61.614134 -31.770076) (xy 61.602874 -31.768796) (xy 61.59196 -31.768065)
			(xy 61.571163 -31.77477) (xy 61.562742 -31.78175) (xy 61.538612 -31.803594) (xy 61.53085 -31.811411)
			(xy 61.522302 -31.831694) (xy 61.522102 -31.84271) (xy 61.522356 -31.858712) (xy 61.522356 -32.722312)
			(xy 61.522102 -32.737806) (xy 61.522288 -32.748858) (xy 61.531006 -32.769147) (xy 61.538866 -32.776922)
			(xy 61.562742 -32.798512) (xy 61.57115 -32.805512) (xy 61.591957 -32.812213) (xy 61.602874 -32.811466)
			(xy 61.614132 -32.810172) (xy 61.636754 -32.808775) (xy 61.648086 -32.808672) (xy 61.648848 -32.808672)
			(xy 61.676096 -32.809202) (xy 61.730035 -32.816963) (xy 61.782321 -32.832322) (xy 61.83189 -32.854964)
			(xy 61.877732 -32.88443) (xy 61.918914 -32.92012) (xy 61.954599 -32.961307) (xy 61.984059 -33.007152)
			(xy 62.006695 -33.056724) (xy 62.022047 -33.109012) (xy 62.029802 -33.162952) (xy 62.029802 -33.217448)
			(xy 62.022047 -33.271388) (xy 62.006695 -33.323676) (xy 61.984059 -33.373248) (xy 61.954599 -33.419093)
			(xy 61.918914 -33.46028) (xy 61.877732 -33.49597) (xy 61.83189 -33.525436) (xy 61.782321 -33.548078)
			(xy 61.730035 -33.563437) (xy 61.676096 -33.571198) (xy 61.648848 -33.571688) (xy 61.622082 -33.571273)
			(xy 61.569072 -33.563808) (xy 61.517627 -33.549004) (xy 61.468757 -33.527152) (xy 61.423423 -33.498682)
			(xy 61.382516 -33.464152) (xy 61.346838 -33.424241) (xy 61.317092 -33.379734) (xy 61.293862 -33.331504)
			(xy 61.277603 -33.2805) (xy 61.272674 -33.254188) (xy 61.270896 -33.243774) (xy 61.260228 -33.22701)
			(xy 61.183266 -33.17367) (xy 61.1632 -33.169606) (xy 61.15304 -33.171638) (xy 61.131161 -33.175621)
			(xy 61.086886 -33.179819) (xy 61.064648 -33.18002) (xy 61.037266 -33.179652) (xy 60.98289 -33.173153)
			(xy 60.95619 -33.167066) (xy 60.94603 -33.164526) (xy 60.924948 -33.168336) (xy 60.844684 -33.221676)
			(xy 60.833508 -33.239202) (xy 60.83173 -33.24987) (xy 60.827034 -33.276436) (xy 60.811184 -33.328001)
			(xy 60.788226 -33.376818) (xy 60.758618 -33.421913) (xy 60.722951 -33.462386) (xy 60.681936 -33.497429)
			(xy 60.636393 -33.526343) (xy 60.58723 -33.548551) (xy 60.535428 -33.563609) (xy 60.482021 -33.571218)
			(xy 60.455048 -33.571688) (xy 60.427679 -33.571197) (xy 60.373501 -33.563385) (xy 60.320998 -33.547902)
			(xy 60.27125 -33.525066) (xy 60.225282 -33.495347) (xy 60.20435 -33.477708) (xy 60.204096 -33.477454)
			(xy 60.197019 -33.471854) (xy 60.180095 -33.465617) (xy 60.171076 -33.465262) (xy 60.10402 -33.465262)
			(xy 60.095005 -33.465637) (xy 60.078089 -33.471873) (xy 60.071 -33.477454) (xy 60.071 -33.477708)
			(xy 60.070746 -33.477708) (xy 60.049808 -33.49534) (xy 60.003837 -33.525053) (xy 59.954091 -33.54789)
			(xy 59.901591 -33.563383) (xy 59.847417 -33.571213) (xy 59.820048 -33.571688) (xy 59.803 -33.571491)
			(xy 59.76904 -33.568437) (xy 59.75223 -33.565592) (xy 59.740903 -33.564152) (xy 59.718885 -33.570089)
			(xy 59.709812 -33.577022) (xy 59.685174 -33.598358) (xy 59.676866 -33.606267) (xy 59.667725 -33.627276)
			(xy 59.667648 -33.638744) (xy 59.668156 -33.65881) (xy 59.668156 -34.522664) (xy 59.667648 -34.54146)
			(xy 59.667768 -34.553018) (xy 59.677015 -34.574175) (xy 59.685428 -34.5821) (xy 59.709812 -34.603182)
			(xy 59.718795 -34.610165) (xy 59.740684 -34.616244) (xy 59.751976 -34.614866) (xy 59.768847 -34.611997)
			(xy 59.802935 -34.608944) (xy 59.820048 -34.60877) (xy 59.847295 -34.609303) (xy 59.901235 -34.617065)
			(xy 59.953521 -34.632423) (xy 60.003089 -34.655066) (xy 60.048931 -34.684532) (xy 60.090113 -34.720221)
			(xy 60.125797 -34.761408) (xy 60.155257 -34.807253) (xy 60.177893 -34.856824) (xy 60.193245 -34.909112)
			(xy 60.201 -34.963053) (xy 60.201 -34.990024) (xy 61.26683 -34.990024) (xy 61.270901 -34.934402)
			(xy 61.283027 -34.879965) (xy 61.30295 -34.827874) (xy 61.330246 -34.779239) (xy 61.364332 -34.735096)
			(xy 61.404481 -34.696387) (xy 61.449839 -34.663936) (xy 61.499439 -34.638435) (xy 61.552223 -34.620428)
			(xy 61.607066 -34.610298) (xy 61.6628 -34.608261) (xy 61.718237 -34.614361) (xy 61.772194 -34.628467)
			(xy 61.823523 -34.650279) (xy 61.871129 -34.679333) (xy 61.913997 -34.715008) (xy 61.951214 -34.756545)
			(xy 61.981987 -34.803058) (xy 62.005659 -34.853555) (xy 62.021727 -34.906962) (xy 62.029847 -34.962138)
			(xy 62.030356 -34.990024) (xy 62.029847 -35.01791) (xy 62.021727 -35.073086) (xy 62.005659 -35.126493)
			(xy 61.981987 -35.17699) (xy 61.951214 -35.223503) (xy 61.913997 -35.26504) (xy 61.871129 -35.300715)
			(xy 61.823523 -35.329769) (xy 61.772194 -35.351581) (xy 61.718237 -35.365687) (xy 61.6628 -35.371787)
			(xy 61.607066 -35.36975) (xy 61.552223 -35.35962) (xy 61.499439 -35.341613) (xy 61.449839 -35.316112)
			(xy 61.404481 -35.283661) (xy 61.364332 -35.244952) (xy 61.330246 -35.200809) (xy 61.30295 -35.152174)
			(xy 61.283027 -35.100083) (xy 61.270901 -35.045646) (xy 61.26683 -34.990024) (xy 60.201 -34.990024)
			(xy 60.201 -35.017547) (xy 60.193245 -35.071488) (xy 60.177893 -35.123776) (xy 60.155257 -35.173347)
			(xy 60.125797 -35.219192) (xy 60.090113 -35.260379) (xy 60.048931 -35.296068) (xy 60.003089 -35.325534)
			(xy 59.953521 -35.348177) (xy 59.901235 -35.363535) (xy 59.847295 -35.371297) (xy 59.820048 -35.371786)
			(xy 59.793071 -35.371328) (xy 59.739653 -35.363741) (xy 59.687838 -35.348697) (xy 59.638663 -35.326497)
			(xy 59.59311 -35.297585) (xy 59.552088 -35.262539) (xy 59.516418 -35.222058) (xy 59.486813 -35.176951)
			(xy 59.463864 -35.128121) (xy 59.448029 -35.076543) (xy 59.443366 -35.049968) (xy 59.441198 -35.03974)
			(xy 59.429919 -35.022161) (xy 59.421522 -35.015932) (xy 59.350148 -34.968434) (xy 59.329066 -34.964624)
			(xy 59.318906 -34.967164) (xy 59.292213 -34.973311) (xy 59.237836 -34.979928) (xy 59.210448 -34.980372)
			(xy 59.18306 -34.979922) (xy 59.128684 -34.973305) (xy 59.10199 -34.967164) (xy 59.09183 -34.964624)
			(xy 59.070748 -34.968434) (xy 58.990484 -35.021774) (xy 58.979308 -35.0393) (xy 58.97753 -35.049968)
			(xy 58.972909 -35.076547) (xy 58.957046 -35.128113) (xy 58.934076 -35.17693) (xy 58.904458 -35.222023)
			(xy 58.868782 -35.262493) (xy 58.82776 -35.297534) (xy 58.78221 -35.326446) (xy 58.733041 -35.348651)
			(xy 58.681234 -35.363708) (xy 58.627823 -35.371316) (xy 58.600848 -35.371786) (xy 58.573591 -35.37137)
			(xy 58.519632 -35.363619) (xy 58.467325 -35.348266) (xy 58.417736 -35.325625) (xy 58.371874 -35.296156)
			(xy 58.330674 -35.26046) (xy 58.294973 -35.219264) (xy 58.265498 -35.173406) (xy 58.242851 -35.12382)
			(xy 58.227492 -35.071515) (xy 58.219733 -35.017557) (xy 56.574355 -35.017557) (xy 56.586734 -35.031373)
			(xy 56.617507 -35.077886) (xy 56.641179 -35.128383) (xy 56.657247 -35.18179) (xy 56.665367 -35.236966)
			(xy 56.665876 -35.264852) (xy 56.665367 -35.292738) (xy 56.657247 -35.347914) (xy 56.641179 -35.401321)
			(xy 56.617507 -35.451818) (xy 56.586734 -35.498331) (xy 56.549517 -35.539868) (xy 56.506649 -35.575543)
			(xy 56.459043 -35.604597) (xy 56.407714 -35.626409) (xy 56.353757 -35.640515) (xy 56.29832 -35.646615)
			(xy 56.242586 -35.644578) (xy 56.187743 -35.634448) (xy 56.134959 -35.616441) (xy 56.085359 -35.59094)
			(xy 56.040001 -35.558489) (xy 55.999852 -35.51978) (xy 55.965766 -35.475637) (xy 55.93847 -35.427002)
			(xy 55.918547 -35.374911) (xy 55.906421 -35.320474) (xy 55.90235 -35.264852) (xy 53.405786 -35.264852)
			(xy 53.405786 -37.087048) (xy 57.2008 -37.087048) (xy 57.201285 -37.060445) (xy 57.20866 -37.007754)
			(xy 57.223288 -36.956599) (xy 57.244885 -36.907974) (xy 57.273031 -36.862823) (xy 57.30718 -36.822023)
			(xy 57.346668 -36.786366) (xy 57.36844 -36.771072) (xy 57.378272 -36.763461) (xy 57.389962 -36.741566)
			(xy 57.390792 -36.729162) (xy 57.390792 -36.644834) (xy 57.390139 -36.632381) (xy 57.378418 -36.610404)
			(xy 57.36844 -36.602924) (xy 57.346672 -36.587626) (xy 57.307193 -36.55196) (xy 57.27305 -36.511157)
			(xy 57.244904 -36.466008) (xy 57.223301 -36.417387) (xy 57.20866 -36.366237) (xy 57.201264 -36.31355)
			(xy 57.2008 -36.286948) (xy 57.2013 -36.259696) (xy 57.209051 -36.205746) (xy 57.224401 -36.153448)
			(xy 57.247038 -36.103868) (xy 57.276502 -36.058014) (xy 57.312192 -36.016821) (xy 57.353382 -35.981126)
			(xy 57.399233 -35.951658) (xy 57.448811 -35.929015) (xy 57.501107 -35.913659) (xy 57.555056 -35.905903)
			(xy 57.582308 -35.90544) (xy 57.58688 -35.90544) (xy 57.596092 -35.905193) (xy 57.61341 -35.898935)
			(xy 57.620662 -35.893248) (xy 57.671462 -35.84956) (xy 57.678176 -35.843332) (xy 57.68703 -35.827316)
			(xy 57.688734 -35.818318) (xy 57.688734 -35.818064) (xy 57.693032 -35.791124) (xy 57.708345 -35.738765)
			(xy 57.73096 -35.68912) (xy 57.760416 -35.643203) (xy 57.796112 -35.60195) (xy 57.837321 -35.566202)
			(xy 57.883201 -35.536689) (xy 57.932817 -35.514011) (xy 57.985158 -35.498633) (xy 58.039155 -35.490867)
			(xy 58.066432 -35.490404) (xy 58.093683 -35.490868) (xy 58.147629 -35.498628) (xy 58.199921 -35.513987)
			(xy 58.249496 -35.536631) (xy 58.295344 -35.566099) (xy 58.336531 -35.601791) (xy 58.372221 -35.642982)
			(xy 58.401685 -35.688832) (xy 58.424324 -35.738409) (xy 58.439678 -35.790703) (xy 58.447434 -35.844649)
			(xy 58.447434 -35.899151) (xy 58.439678 -35.953097) (xy 58.424324 -36.005391) (xy 58.401685 -36.054968)
			(xy 58.372221 -36.100818) (xy 58.336531 -36.142009) (xy 58.295344 -36.177701) (xy 58.249496 -36.207169)
			(xy 58.199921 -36.229813) (xy 58.147629 -36.245172) (xy 58.093683 -36.252932) (xy 58.066432 -36.25342)
			(xy 58.06186 -36.25342) (xy 58.052649 -36.253673) (xy 58.035329 -36.259925) (xy 58.028078 -36.265612)
			(xy 57.977278 -36.3093) (xy 57.970549 -36.315514) (xy 57.961703 -36.33154) (xy 57.960006 -36.340542)
			(xy 57.960006 -36.340796) (xy 57.955786 -36.366995) (xy 57.941104 -36.417988) (xy 57.919494 -36.466453)
			(xy 57.891375 -36.511454) (xy 57.887944 -36.515548) (xy 59.014104 -36.515548) (xy 59.018175 -36.459926)
			(xy 59.030301 -36.405489) (xy 59.050224 -36.353398) (xy 59.07752 -36.304763) (xy 59.111606 -36.26062)
			(xy 59.151755 -36.221911) (xy 59.197113 -36.18946) (xy 59.246713 -36.163959) (xy 59.299497 -36.145952)
			(xy 59.35434 -36.135822) (xy 59.410074 -36.133785) (xy 59.465511 -36.139885) (xy 59.519468 -36.153991)
			(xy 59.570797 -36.175803) (xy 59.618403 -36.204857) (xy 59.661271 -36.240532) (xy 59.698488 -36.282069)
			(xy 59.729261 -36.328582) (xy 59.752933 -36.379079) (xy 59.769001 -36.432486) (xy 59.777121 -36.487662)
			(xy 59.77763 -36.515548) (xy 59.777121 -36.543434) (xy 59.769001 -36.59861) (xy 59.752933 -36.652017)
			(xy 59.729261 -36.702514) (xy 59.698488 -36.749027) (xy 59.661271 -36.790564) (xy 59.618403 -36.826239)
			(xy 59.570797 -36.855293) (xy 59.519468 -36.877105) (xy 59.465511 -36.891211) (xy 59.410074 -36.897311)
			(xy 59.35434 -36.895274) (xy 59.299497 -36.885144) (xy 59.246713 -36.867137) (xy 59.197113 -36.841636)
			(xy 59.151755 -36.809185) (xy 59.111606 -36.770476) (xy 59.07752 -36.726333) (xy 59.050224 -36.677698)
			(xy 59.030301 -36.625607) (xy 59.018175 -36.57117) (xy 59.014104 -36.515548) (xy 57.887944 -36.515548)
			(xy 57.857288 -36.552123) (xy 57.817892 -36.587673) (xy 57.796176 -36.602924) (xy 57.786247 -36.610448)
			(xy 57.774523 -36.632397) (xy 57.773824 -36.644834) (xy 57.773824 -36.729162) (xy 57.774474 -36.741616)
			(xy 57.786197 -36.763593) (xy 57.796176 -36.771072) (xy 57.817946 -36.786368) (xy 57.857424 -36.822034)
			(xy 57.891567 -36.862838) (xy 57.919712 -36.907988) (xy 57.941315 -36.956609) (xy 57.955956 -37.007759)
			(xy 57.963351 -37.060446) (xy 57.963816 -37.087048) (xy 57.963816 -37.087302) (xy 57.963192 -37.119019)
			(xy 57.952692 -37.181576) (xy 57.931967 -37.241528) (xy 57.917334 -37.269674) (xy 57.912 -37.27958)
			(xy 57.910476 -37.301678) (xy 57.94248 -37.384482) (xy 57.946951 -37.394581) (xy 57.962754 -37.409979)
			(xy 57.97296 -37.4142) (xy 57.997484 -37.423289) (xy 58.044015 -37.447168) (xy 58.086848 -37.477179)
			(xy 58.125178 -37.512762) (xy 58.158287 -37.553248) (xy 58.185555 -37.597878) (xy 58.206468 -37.645815)
			(xy 58.220637 -37.696159) (xy 58.227794 -37.747968) (xy 58.22823 -37.774118) (xy 58.227744 -37.801369)
			(xy 58.219988 -37.855317) (xy 58.204633 -37.907612) (xy 58.181991 -37.957189) (xy 58.152525 -38.003039)
			(xy 58.116834 -38.04423) (xy 58.075643 -38.079921) (xy 58.029793 -38.109387) (xy 57.980216 -38.132029)
			(xy 57.927921 -38.147384) (xy 57.873973 -38.15514) (xy 57.819471 -38.15514) (xy 57.765523 -38.147384)
			(xy 57.713228 -38.132029) (xy 57.663651 -38.109387) (xy 57.617801 -38.079921) (xy 57.57661 -38.04423)
			(xy 57.540919 -38.003039) (xy 57.511453 -37.957189) (xy 57.488811 -37.907612) (xy 57.473456 -37.855317)
			(xy 57.4657 -37.801369) (xy 57.465214 -37.774118) (xy 57.465214 -37.773864) (xy 57.465821 -37.742147)
			(xy 57.476327 -37.679588) (xy 57.49706 -37.619637) (xy 57.511696 -37.591492) (xy 57.51703 -37.581586)
			(xy 57.518554 -37.559488) (xy 57.48655 -37.476684) (xy 57.482078 -37.466586) (xy 57.466275 -37.451189)
			(xy 57.45607 -37.446966) (xy 57.431519 -37.437946) (xy 57.384988 -37.414057) (xy 57.342157 -37.384034)
			(xy 57.303829 -37.348442) (xy 57.270723 -37.307947) (xy 57.243459 -37.263309) (xy 57.22255 -37.215366)
			(xy 57.208386 -37.165015) (xy 57.201234 -37.113201) (xy 57.2008 -37.087048) (xy 53.405786 -37.087048)
			(xy 53.405786 -38.315138) (xy 58.417966 -38.315138) (xy 58.422037 -38.259516) (xy 58.434163 -38.205079)
			(xy 58.454086 -38.152988) (xy 58.481382 -38.104353) (xy 58.515468 -38.06021) (xy 58.555617 -38.021501)
			(xy 58.600975 -37.98905) (xy 58.650575 -37.963549) (xy 58.703359 -37.945542) (xy 58.758202 -37.935412)
			(xy 58.813936 -37.933375) (xy 58.869373 -37.939475) (xy 58.92333 -37.953581) (xy 58.974659 -37.975393)
			(xy 59.022265 -38.004447) (xy 59.065133 -38.040122) (xy 59.10235 -38.081659) (xy 59.133123 -38.128172)
			(xy 59.156795 -38.178669) (xy 59.172863 -38.232076) (xy 59.180983 -38.287252) (xy 59.181492 -38.315138)
			(xy 59.180983 -38.343024) (xy 59.172863 -38.3982) (xy 59.156795 -38.451607) (xy 59.133123 -38.502104)
			(xy 59.10235 -38.548617) (xy 59.065133 -38.590154) (xy 59.022265 -38.625829) (xy 58.974659 -38.654883)
			(xy 58.92333 -38.676695) (xy 58.869373 -38.690801) (xy 58.813936 -38.696901) (xy 58.758202 -38.694864)
			(xy 58.703359 -38.684734) (xy 58.650575 -38.666727) (xy 58.600975 -38.641226) (xy 58.555617 -38.608775)
			(xy 58.515468 -38.570066) (xy 58.481382 -38.525923) (xy 58.454086 -38.477288) (xy 58.434163 -38.425197)
			(xy 58.422037 -38.37076) (xy 58.417966 -38.315138) (xy 53.405786 -38.315138) (xy 53.405786 -42.432478)
			(xy 53.406072 -42.440354) (xy 53.410842 -42.455366) (xy 53.415184 -42.461942) (xy 53.419756 -42.468546)
			(xy 53.432202 -42.47769) (xy 53.440076 -42.480484) (xy 53.46615 -42.490055) (xy 53.515432 -42.515669)
			(xy 53.560479 -42.548159) (xy 53.600338 -42.586839) (xy 53.634167 -42.630889) (xy 53.661249 -42.67938)
			(xy 53.681014 -42.731286) (xy 53.693042 -42.785509) (xy 53.697079 -42.840903) (xy 53.693041 -42.896297)
			(xy 53.681012 -42.95052) (xy 53.661247 -43.002426) (xy 53.634163 -43.050916) (xy 53.600334 -43.094966)
			(xy 53.560474 -43.133645) (xy 53.515427 -43.166134) (xy 53.466144 -43.191747) (xy 53.440076 -43.201336)
			(xy 53.439568 -43.20159) (xy 53.432333 -43.204408) (xy 53.419925 -43.213728) (xy 53.415184 -43.219878)
			(xy 53.410612 -43.226482) (xy 53.408326 -43.233594) (xy 53.407165 -43.237428) (xy 53.40589 -43.245337)
			(xy 53.405786 -43.249342) (xy 53.405786 -43.448478) (xy 53.406072 -43.456354) (xy 53.410842 -43.471366)
			(xy 53.415184 -43.477942) (xy 53.419756 -43.484546) (xy 53.432202 -43.49369) (xy 53.440076 -43.496484)
			(xy 53.46615 -43.506055) (xy 53.515432 -43.531669) (xy 53.560479 -43.564159) (xy 53.600338 -43.602839)
			(xy 53.634167 -43.646889) (xy 53.661249 -43.69538) (xy 53.681014 -43.747286) (xy 53.693042 -43.801509)
			(xy 53.697079 -43.856903) (xy 53.693041 -43.912297) (xy 53.681012 -43.96652) (xy 53.661247 -44.018426)
			(xy 53.634163 -44.066916) (xy 53.600334 -44.110966) (xy 53.560474 -44.149645) (xy 53.515427 -44.182134)
			(xy 53.466144 -44.207747) (xy 53.440076 -44.217336) (xy 53.439568 -44.21759) (xy 53.432333 -44.220408)
			(xy 53.419925 -44.229728) (xy 53.415184 -44.235878) (xy 53.410612 -44.242482) (xy 53.408326 -44.249594)
			(xy 53.407165 -44.253428) (xy 53.40589 -44.261337) (xy 53.405786 -44.265342) (xy 53.405786 -44.464478)
			(xy 53.406072 -44.472354) (xy 53.410842 -44.487366) (xy 53.415184 -44.493942) (xy 53.419756 -44.500546)
			(xy 53.432202 -44.50969) (xy 53.440076 -44.512484) (xy 53.46615 -44.522055) (xy 53.515432 -44.547669)
			(xy 53.560479 -44.580159) (xy 53.600338 -44.618839) (xy 53.634167 -44.662889) (xy 53.661249 -44.71138)
			(xy 53.681014 -44.763286) (xy 53.693042 -44.817509) (xy 53.697079 -44.872903) (xy 53.693041 -44.928297)
			(xy 53.681012 -44.98252) (xy 53.661247 -45.034426) (xy 53.634163 -45.082916) (xy 53.600334 -45.126966)
			(xy 53.560474 -45.165645) (xy 53.515427 -45.198134) (xy 53.466144 -45.223747) (xy 53.440076 -45.233336)
			(xy 53.439568 -45.23359) (xy 53.432333 -45.236408) (xy 53.419925 -45.245728) (xy 53.415184 -45.251878)
			(xy 53.410612 -45.258482) (xy 53.408326 -45.265594) (xy 53.407165 -45.269428) (xy 53.40589 -45.277337)
			(xy 53.405786 -45.281342) (xy 53.405786 -45.480478) (xy 53.406072 -45.488354) (xy 53.410842 -45.503366)
			(xy 53.415184 -45.509942) (xy 53.419756 -45.516546) (xy 53.432202 -45.52569) (xy 53.440076 -45.528484)
			(xy 53.46615 -45.538055) (xy 53.515432 -45.563669) (xy 53.560479 -45.596159) (xy 53.600338 -45.634839)
			(xy 53.634167 -45.678889) (xy 53.661249 -45.72738) (xy 53.681014 -45.779286) (xy 53.693042 -45.833509)
			(xy 53.697079 -45.888903) (xy 53.693041 -45.944297) (xy 53.681012 -45.99852) (xy 53.661247 -46.050426)
			(xy 53.634163 -46.098916) (xy 53.600334 -46.142966) (xy 53.560474 -46.181645) (xy 53.515427 -46.214134)
			(xy 53.466144 -46.239747) (xy 53.440076 -46.249336) (xy 53.439568 -46.24959) (xy 53.432333 -46.252408)
			(xy 53.419925 -46.261728) (xy 53.415184 -46.267878) (xy 53.410612 -46.274482) (xy 53.408326 -46.281594)
			(xy 53.407165 -46.285428) (xy 53.40589 -46.293337) (xy 53.405786 -46.297342) (xy 53.405786 -47.02556)
			(xy 53.406454 -47.034918) (xy 53.41363 -47.052235) (xy 53.419756 -47.059342) (xy 53.442616 -47.065438)
			(xy 53.469971 -47.073138) (xy 53.522261 -47.095383) (xy 53.570758 -47.125002) (xy 53.614426 -47.161365)
			(xy 53.652336 -47.203696) (xy 53.683682 -47.251095) (xy 53.707794 -47.302551) (xy 53.72416 -47.356969)
			(xy 53.732431 -47.41319) (xy 53.73243 -47.470016) (xy 53.724159 -47.526236) (xy 53.707792 -47.580654)
			(xy 53.683679 -47.63211) (xy 53.652333 -47.679509) (xy 53.614421 -47.72184) (xy 53.570753 -47.758202)
			(xy 53.522256 -47.78782) (xy 53.469965 -47.810064) (xy 53.442616 -47.817786) (xy 53.419756 -47.823882)
			(xy 53.413599 -47.830967) (xy 53.406436 -47.848299) (xy 53.405786 -47.857664) (xy 53.405786 -48.528478)
			(xy 53.406072 -48.536354) (xy 53.410842 -48.551366) (xy 53.415184 -48.557942) (xy 53.419756 -48.564546)
			(xy 53.432202 -48.57369) (xy 53.440076 -48.576484) (xy 53.46615 -48.586055) (xy 53.515432 -48.611669)
			(xy 53.560479 -48.644159) (xy 53.600338 -48.682839) (xy 53.634167 -48.726889) (xy 53.661249 -48.77538)
			(xy 53.681014 -48.827286) (xy 53.693042 -48.881509) (xy 53.697079 -48.936903) (xy 53.693041 -48.992297)
			(xy 53.681012 -49.04652) (xy 53.661247 -49.098426) (xy 53.634163 -49.146916) (xy 53.600334 -49.190966)
			(xy 53.560474 -49.229645) (xy 53.515427 -49.262134) (xy 53.466144 -49.287747) (xy 53.440076 -49.297336)
			(xy 53.439568 -49.29759) (xy 53.432333 -49.300408) (xy 53.419925 -49.309728) (xy 53.415184 -49.315878)
			(xy 53.410612 -49.322482) (xy 53.408326 -49.329594) (xy 53.407165 -49.333428) (xy 53.40589 -49.341337)
			(xy 53.405786 -49.345342) (xy 53.405786 -49.544478) (xy 53.406072 -49.552354) (xy 53.410842 -49.567366)
			(xy 53.415184 -49.573942) (xy 53.419756 -49.580546) (xy 53.432202 -49.58969) (xy 53.440076 -49.592484)
			(xy 53.465864 -49.60195) (xy 54.290982 -49.60195) (xy 54.290982 -49.54745) (xy 54.298738 -49.493505)
			(xy 54.314091 -49.441213) (xy 54.33673 -49.391638) (xy 54.366194 -49.345789) (xy 54.401883 -49.3046)
			(xy 54.44307 -49.268909) (xy 54.488917 -49.239442) (xy 54.53849 -49.2168) (xy 54.590782 -49.201443)
			(xy 54.644726 -49.193683) (xy 54.671976 -49.193196) (xy 54.699346 -49.193677) (xy 54.753524 -49.201491)
			(xy 54.806027 -49.216977) (xy 54.855774 -49.239815) (xy 54.901742 -49.269536) (xy 54.922674 -49.287176)
			(xy 54.922928 -49.28743) (xy 54.930029 -49.292996) (xy 54.946935 -49.299254) (xy 54.955948 -49.299622)
			(xy 55.023004 -49.299622) (xy 55.03202 -49.299262) (xy 55.048937 -49.293016) (xy 55.056024 -49.28743)
			(xy 55.056024 -49.287176) (xy 55.056278 -49.287176) (xy 55.077211 -49.269535) (xy 55.123179 -49.239811)
			(xy 55.172925 -49.216965) (xy 55.225427 -49.201469) (xy 55.279605 -49.19364) (xy 55.334347 -49.19364)
			(xy 55.388525 -49.201469) (xy 55.441027 -49.216965) (xy 55.490773 -49.239811) (xy 55.536741 -49.269535)
			(xy 55.557674 -49.287176) (xy 55.557928 -49.28743) (xy 55.565029 -49.292996) (xy 55.581935 -49.299254)
			(xy 55.590948 -49.299622) (xy 55.658004 -49.299622) (xy 55.66702 -49.299262) (xy 55.683937 -49.293016)
			(xy 55.691024 -49.28743) (xy 55.691024 -49.287176) (xy 55.691278 -49.287176) (xy 55.712204 -49.26953)
			(xy 55.758179 -49.23982) (xy 55.807928 -49.216986) (xy 55.86043 -49.201496) (xy 55.914607 -49.193669)
			(xy 55.941976 -49.193196) (xy 55.968289 -49.193681) (xy 56.020417 -49.200912) (xy 56.071059 -49.215228)
			(xy 56.119258 -49.236357) (xy 56.164102 -49.2639) (xy 56.204743 -49.297336) (xy 56.2229 -49.316386)
			(xy 56.230422 -49.323788) (xy 56.249702 -49.332312) (xy 56.260238 -49.332896) (xy 56.334914 -49.332896)
			(xy 56.345466 -49.332389) (xy 56.364762 -49.323839) (xy 56.372252 -49.316386) (xy 56.390387 -49.29731)
			(xy 56.431021 -49.263855) (xy 56.475866 -49.236299) (xy 56.524071 -49.215164) (xy 56.574722 -49.200851)
			(xy 56.626859 -49.193632) (xy 56.653176 -49.193196) (xy 56.68043 -49.19365) (xy 56.734384 -49.201404)
			(xy 56.786686 -49.216758) (xy 56.836269 -49.239399) (xy 56.882126 -49.268867) (xy 56.923322 -49.304561)
			(xy 56.959018 -49.345755) (xy 56.988489 -49.39161) (xy 57.011133 -49.441192) (xy 57.026491 -49.493492)
			(xy 57.034249 -49.547446) (xy 57.034249 -49.601954) (xy 57.026491 -49.655908) (xy 57.011133 -49.708208)
			(xy 56.988489 -49.75779) (xy 56.959018 -49.803645) (xy 56.923322 -49.844839) (xy 56.882126 -49.880533)
			(xy 56.836269 -49.910001) (xy 56.786686 -49.932642) (xy 56.734384 -49.947996) (xy 56.68043 -49.95575)
			(xy 56.653176 -49.956212) (xy 56.626862 -49.955757) (xy 56.574733 -49.948519) (xy 56.52409 -49.934197)
			(xy 56.475891 -49.913062) (xy 56.431048 -49.885514) (xy 56.390409 -49.852074) (xy 56.372252 -49.833022)
			(xy 56.364747 -49.8256) (xy 56.345455 -49.817087) (xy 56.334914 -49.816512) (xy 56.260238 -49.816512)
			(xy 56.249689 -49.817044) (xy 56.230393 -49.825577) (xy 56.2229 -49.833022) (xy 56.204742 -49.852075)
			(xy 56.164112 -49.885531) (xy 56.119272 -49.91309) (xy 56.071072 -49.934229) (xy 56.020425 -49.948547)
			(xy 55.968292 -49.955773) (xy 55.941976 -49.956212) (xy 55.914605 -49.955757) (xy 55.860426 -49.947936)
			(xy 55.807923 -49.932444) (xy 55.758176 -49.9096) (xy 55.71221 -49.879874) (xy 55.691278 -49.862232)
			(xy 55.691024 -49.861978) (xy 55.683937 -49.856393) (xy 55.66702 -49.850146) (xy 55.658004 -49.849786)
			(xy 55.590948 -49.849786) (xy 55.581934 -49.850169) (xy 55.565017 -49.856399) (xy 55.557928 -49.861978)
			(xy 55.557928 -49.862232) (xy 55.557674 -49.862232) (xy 55.536741 -49.879873) (xy 55.490773 -49.909597)
			(xy 55.441027 -49.932443) (xy 55.388525 -49.947939) (xy 55.334347 -49.955768) (xy 55.279605 -49.955768)
			(xy 55.225427 -49.947939) (xy 55.172925 -49.932443) (xy 55.123179 -49.909597) (xy 55.077211 -49.879873)
			(xy 55.056278 -49.862232) (xy 55.056024 -49.861978) (xy 55.048937 -49.856393) (xy 55.03202 -49.850146)
			(xy 55.023004 -49.849786) (xy 54.955948 -49.849786) (xy 54.946934 -49.850169) (xy 54.930017 -49.856399)
			(xy 54.922928 -49.861978) (xy 54.922928 -49.862232) (xy 54.922674 -49.862232) (xy 54.901729 -49.879855)
			(xy 54.855759 -49.909568) (xy 54.806015 -49.932407) (xy 54.753517 -49.947902) (xy 54.699344 -49.955735)
			(xy 54.671976 -49.956212) (xy 54.644726 -49.955717) (xy 54.590782 -49.947957) (xy 54.53849 -49.9326)
			(xy 54.488917 -49.909958) (xy 54.44307 -49.880491) (xy 54.401883 -49.8448) (xy 54.366194 -49.803611)
			(xy 54.33673 -49.757762) (xy 54.314091 -49.708187) (xy 54.298738 -49.655895) (xy 54.290982 -49.60195)
			(xy 53.465864 -49.60195) (xy 53.46615 -49.602055) (xy 53.515432 -49.627669) (xy 53.560479 -49.660159)
			(xy 53.600338 -49.698839) (xy 53.634167 -49.742889) (xy 53.661249 -49.79138) (xy 53.681014 -49.843286)
			(xy 53.693042 -49.897509) (xy 53.697079 -49.952903) (xy 53.693041 -50.008297) (xy 53.681012 -50.06252)
			(xy 53.661247 -50.114426) (xy 53.634163 -50.162916) (xy 53.600334 -50.206966) (xy 53.560474 -50.245645)
			(xy 53.515427 -50.278134) (xy 53.466144 -50.303747) (xy 53.440076 -50.313336) (xy 53.439568 -50.31359)
			(xy 53.432333 -50.316408) (xy 53.419925 -50.325728) (xy 53.415184 -50.331878) (xy 53.410612 -50.338482)
			(xy 53.408326 -50.345594) (xy 53.407165 -50.349428) (xy 53.40589 -50.357337) (xy 53.405786 -50.361342)
			(xy 53.405786 -50.60823) (xy 53.406049 -50.615874) (xy 53.410577 -50.630475) (xy 53.414676 -50.636932)
			(xy 53.420264 -50.644552) (xy 53.432964 -50.65395) (xy 53.440838 -50.65649) (xy 53.467543 -50.66568)
			(xy 53.518116 -50.690819) (xy 53.564431 -50.723136) (xy 53.605476 -50.761928) (xy 53.640357 -50.806345)
			(xy 53.668309 -50.855418) (xy 53.688724 -50.908075) (xy 53.701155 -50.963165) (xy 53.70533 -51.019486)
			(xy 53.701159 -51.075808) (xy 53.688732 -51.130899) (xy 53.668321 -51.183558) (xy 53.640372 -51.232633)
			(xy 53.605495 -51.277052) (xy 53.564452 -51.315846) (xy 53.518139 -51.348167) (xy 53.467569 -51.37331)
			(xy 53.440838 -51.382422) (xy 53.432964 -51.384962) (xy 53.420264 -51.39436) (xy 53.414676 -51.40198)
			(xy 53.410569 -51.408433) (xy 53.406043 -51.423037) (xy 53.405786 -51.430682) (xy 53.405786 -51.62423)
			(xy 53.406049 -51.631874) (xy 53.410577 -51.646475) (xy 53.414676 -51.652932) (xy 53.420264 -51.660552)
			(xy 53.432964 -51.66995) (xy 53.440838 -51.67249) (xy 53.467543 -51.68168) (xy 53.482374 -51.689052)
			(xy 54.255377 -51.689052) (xy 54.255377 -51.634548) (xy 54.263134 -51.580599) (xy 54.27849 -51.528303)
			(xy 54.301133 -51.478724) (xy 54.3306 -51.432873) (xy 54.366294 -51.391682) (xy 54.407486 -51.355991)
			(xy 54.453338 -51.326525) (xy 54.502918 -51.303885) (xy 54.555214 -51.288531) (xy 54.609164 -51.280776)
			(xy 54.636416 -51.280314) (xy 54.663787 -51.280767) (xy 54.717966 -51.288588) (xy 54.77047 -51.30408)
			(xy 54.820217 -51.326924) (xy 54.866183 -51.356651) (xy 54.887114 -51.374294) (xy 54.887368 -51.374548)
			(xy 54.894455 -51.380133) (xy 54.911372 -51.386379) (xy 54.920388 -51.38674) (xy 54.987444 -51.38674)
			(xy 54.99646 -51.386369) (xy 55.013378 -51.380133) (xy 55.020464 -51.374548) (xy 55.020464 -51.374294)
			(xy 55.020718 -51.374294) (xy 55.041669 -51.356679) (xy 55.087637 -51.326964) (xy 55.13738 -51.304123)
			(xy 55.189876 -51.288626) (xy 55.244048 -51.280792) (xy 55.271416 -51.280314) (xy 55.289759 -51.280541)
			(xy 55.326272 -51.284108) (xy 55.344314 -51.287426) (xy 55.354947 -51.289006) (xy 55.375864 -51.284148)
			(xy 55.3847 -51.278028) (xy 55.453788 -51.225704) (xy 55.464202 -51.206908) (xy 55.464964 -51.195986)
			(xy 55.467849 -51.167701) (xy 55.480888 -51.112363) (xy 55.501986 -51.059569) (xy 55.530677 -51.010486)
			(xy 55.566327 -50.966199) (xy 55.586884 -50.946558) (xy 55.594304 -50.939052) (xy 55.602818 -50.91976)
			(xy 55.603394 -50.90922) (xy 55.603394 -50.834544) (xy 55.602857 -50.823995) (xy 55.594327 -50.8047)
			(xy 55.586884 -50.797206) (xy 55.567835 -50.779044) (xy 55.534378 -50.738415) (xy 55.506819 -50.693576)
			(xy 55.485679 -50.645377) (xy 55.47136 -50.594731) (xy 55.464134 -50.542598) (xy 55.463694 -50.516282)
			(xy 55.46418 -50.489031) (xy 55.471936 -50.435083) (xy 55.487291 -50.382788) (xy 55.509933 -50.333211)
			(xy 55.539399 -50.287361) (xy 55.57509 -50.24617) (xy 55.616281 -50.210479) (xy 55.662131 -50.181013)
			(xy 55.711708 -50.158371) (xy 55.764003 -50.143016) (xy 55.817951 -50.13526) (xy 55.872453 -50.13526)
			(xy 55.926401 -50.143016) (xy 55.978696 -50.158371) (xy 56.028273 -50.181013) (xy 56.074123 -50.210479)
			(xy 56.115314 -50.24617) (xy 56.151005 -50.287361) (xy 56.180471 -50.333211) (xy 56.203113 -50.382788)
			(xy 56.218468 -50.435083) (xy 56.226224 -50.489031) (xy 56.22671 -50.516282) (xy 56.226227 -50.542595)
			(xy 56.218995 -50.594723) (xy 56.204679 -50.645365) (xy 56.183549 -50.693564) (xy 56.156006 -50.738408)
			(xy 56.12257 -50.779049) (xy 56.10352 -50.797206) (xy 56.096117 -50.804726) (xy 56.087593 -50.824007)
			(xy 56.08701 -50.834544) (xy 56.08701 -50.90922) (xy 56.087566 -50.919767) (xy 56.096082 -50.939062)
			(xy 56.10352 -50.946558) (xy 56.1226 -50.964688) (xy 56.156055 -51.005324) (xy 56.18361 -51.05017)
			(xy 56.204744 -51.098375) (xy 56.219056 -51.149027) (xy 56.226275 -51.201164) (xy 56.22671 -51.227482)
			(xy 56.226228 -51.254734) (xy 56.218473 -51.308684) (xy 56.20312 -51.360982) (xy 56.18048 -51.410562)
			(xy 56.151014 -51.456415) (xy 56.115322 -51.497608) (xy 56.074131 -51.533302) (xy 56.028279 -51.56277)
			(xy 55.978701 -51.585413) (xy 55.926404 -51.600769) (xy 55.872454 -51.608527) (xy 55.845202 -51.60899)
			(xy 55.826859 -51.608761) (xy 55.790346 -51.605196) (xy 55.772304 -51.601878) (xy 55.761674 -51.600268)
			(xy 55.740754 -51.60515) (xy 55.731918 -51.611276) (xy 55.66283 -51.6636) (xy 55.652416 -51.682396)
			(xy 55.651654 -51.693318) (xy 55.64876 -51.721576) (xy 55.635727 -51.776862) (xy 55.614642 -51.829604)
			(xy 55.585971 -51.878638) (xy 55.550347 -51.922879) (xy 55.508557 -51.96135) (xy 55.461526 -51.9932)
			(xy 55.410293 -52.017725) (xy 55.355989 -52.034383) (xy 55.299816 -52.042807) (xy 55.271416 -52.04333)
			(xy 55.244045 -52.042872) (xy 55.189865 -52.035055) (xy 55.137361 -52.019565) (xy 55.087615 -51.996721)
			(xy 55.041649 -51.966993) (xy 55.020718 -51.94935) (xy 55.020464 -51.949096) (xy 55.013364 -51.94353)
			(xy 54.996457 -51.937271) (xy 54.987444 -51.936904) (xy 54.920388 -51.936904) (xy 54.91137 -51.937254)
			(xy 54.894454 -51.943506) (xy 54.887368 -51.949096) (xy 54.887368 -51.94935) (xy 54.887114 -51.94935)
			(xy 54.866181 -51.966988) (xy 54.820209 -51.996702) (xy 54.770462 -52.019539) (xy 54.717961 -52.03503)
			(xy 54.663785 -52.042857) (xy 54.636416 -52.04333) (xy 54.609164 -52.042824) (xy 54.555214 -52.035069)
			(xy 54.502918 -52.019715) (xy 54.453338 -51.997075) (xy 54.407486 -51.967609) (xy 54.366294 -51.931918)
			(xy 54.3306 -51.890727) (xy 54.301133 -51.844876) (xy 54.27849 -51.795297) (xy 54.263134 -51.743001)
			(xy 54.255377 -51.689052) (xy 53.482374 -51.689052) (xy 53.518116 -51.706819) (xy 53.564431 -51.739136)
			(xy 53.605476 -51.777928) (xy 53.640357 -51.822345) (xy 53.668309 -51.871418) (xy 53.688724 -51.924075)
			(xy 53.701155 -51.979165) (xy 53.70533 -52.035486) (xy 53.701159 -52.091808) (xy 53.688732 -52.146899)
			(xy 53.668321 -52.199558) (xy 53.640372 -52.248633) (xy 53.605495 -52.293052) (xy 53.564452 -52.331846)
			(xy 53.518139 -52.364167) (xy 53.467569 -52.38931) (xy 53.440838 -52.398422) (xy 53.432964 -52.400962)
			(xy 53.420264 -52.41036) (xy 53.414676 -52.41798) (xy 53.410569 -52.424433) (xy 53.406043 -52.439037)
			(xy 53.405786 -52.446682) (xy 53.405786 -52.564153) (xy 55.82713 -52.564153) (xy 55.82713 -52.509647)
			(xy 55.834886 -52.455695) (xy 55.850242 -52.403396) (xy 55.872884 -52.353815) (xy 55.902351 -52.30796)
			(xy 55.938043 -52.266766) (xy 55.979235 -52.23107) (xy 56.025087 -52.201599) (xy 56.074666 -52.178953)
			(xy 56.126964 -52.163593) (xy 56.180915 -52.155832) (xy 56.208168 -52.155344) (xy 56.235538 -52.155818)
			(xy 56.289717 -52.163632) (xy 56.342221 -52.179119) (xy 56.391968 -52.201959) (xy 56.437934 -52.231683)
			(xy 56.458866 -52.249324) (xy 56.45912 -52.249578) (xy 56.46619 -52.255188) (xy 56.48312 -52.261419)
			(xy 56.49214 -52.26177) (xy 56.559196 -52.26177) (xy 56.568214 -52.261418) (xy 56.585131 -52.255168)
			(xy 56.592216 -52.249578) (xy 56.592216 -52.249324) (xy 56.59247 -52.249324) (xy 56.613406 -52.231689)
			(xy 56.659377 -52.201976) (xy 56.709124 -52.179139) (xy 56.761624 -52.163647) (xy 56.815799 -52.155818)
			(xy 56.843168 -52.155344) (xy 56.870419 -52.155901) (xy 56.924367 -52.163653) (xy 56.976662 -52.179005)
			(xy 57.02624 -52.201642) (xy 57.072091 -52.231106) (xy 57.113282 -52.266795) (xy 57.148975 -52.307983)
			(xy 57.178442 -52.353832) (xy 57.201084 -52.403408) (xy 57.21644 -52.455702) (xy 57.224197 -52.509649)
			(xy 57.224197 -52.564151) (xy 57.21644 -52.618098) (xy 57.201084 -52.670392) (xy 57.178442 -52.719968)
			(xy 57.148975 -52.765817) (xy 57.113282 -52.807005) (xy 57.072091 -52.842694) (xy 57.02624 -52.872158)
			(xy 56.976662 -52.894795) (xy 56.924367 -52.910147) (xy 56.870419 -52.917899) (xy 56.843168 -52.91836)
			(xy 56.815797 -52.917922) (xy 56.761616 -52.910099) (xy 56.709112 -52.894604) (xy 56.659366 -52.871756)
			(xy 56.6134 -52.842025) (xy 56.59247 -52.82438) (xy 56.592216 -52.824126) (xy 56.585135 -52.818531)
			(xy 56.568214 -52.812291) (xy 56.559196 -52.811934) (xy 56.49214 -52.811934) (xy 56.483124 -52.812303)
			(xy 56.466207 -52.818541) (xy 56.45912 -52.824126) (xy 56.45912 -52.82438) (xy 56.458866 -52.82438)
			(xy 56.437917 -52.841999) (xy 56.391949 -52.871714) (xy 56.342206 -52.894554) (xy 56.289709 -52.91005)
			(xy 56.235536 -52.917883) (xy 56.208168 -52.91836) (xy 56.180915 -52.917968) (xy 56.126964 -52.910207)
			(xy 56.074666 -52.894847) (xy 56.025087 -52.872201) (xy 55.979235 -52.84273) (xy 55.938043 -52.807034)
			(xy 55.902351 -52.76584) (xy 55.872884 -52.719985) (xy 55.850242 -52.670404) (xy 55.834886 -52.618105)
			(xy 55.82713 -52.564153) (xy 53.405786 -52.564153) (xy 53.405786 -52.64023) (xy 53.406049 -52.647874)
			(xy 53.410577 -52.662475) (xy 53.414676 -52.668932) (xy 53.420264 -52.676552) (xy 53.432964 -52.68595)
			(xy 53.440838 -52.68849) (xy 53.467543 -52.69768) (xy 53.518116 -52.722819) (xy 53.564431 -52.755136)
			(xy 53.605476 -52.793928) (xy 53.640357 -52.838345) (xy 53.668309 -52.887418) (xy 53.688724 -52.940075)
			(xy 53.701155 -52.995165) (xy 53.70533 -53.051486) (xy 53.701159 -53.107808) (xy 53.688732 -53.162899)
			(xy 53.668321 -53.215558) (xy 53.640372 -53.264633) (xy 53.605495 -53.309052) (xy 53.564452 -53.347846)
			(xy 53.518139 -53.380167) (xy 53.467569 -53.40531) (xy 53.440838 -53.414422) (xy 53.432964 -53.416962)
			(xy 53.420264 -53.42636) (xy 53.414676 -53.43398) (xy 53.410569 -53.440433) (xy 53.406043 -53.455037)
			(xy 53.405786 -53.462682) (xy 53.405786 -53.65623) (xy 53.406049 -53.663874) (xy 53.410577 -53.678475)
			(xy 53.414676 -53.684932) (xy 53.420264 -53.692552) (xy 53.432964 -53.70195) (xy 53.440838 -53.70449)
			(xy 53.467543 -53.71368) (xy 53.518116 -53.738819) (xy 53.564431 -53.771136) (xy 53.605476 -53.809928)
			(xy 53.640357 -53.854345) (xy 53.668309 -53.903418) (xy 53.688724 -53.956075) (xy 53.701155 -54.011165)
			(xy 53.70533 -54.067486) (xy 53.701159 -54.123808) (xy 53.688732 -54.178899) (xy 53.668321 -54.231558)
			(xy 53.664136 -54.238906) (xy 60.385958 -54.238906) (xy 60.390029 -54.183284) (xy 60.402155 -54.128847)
			(xy 60.422078 -54.076756) (xy 60.449374 -54.028121) (xy 60.48346 -53.983978) (xy 60.523609 -53.945269)
			(xy 60.568967 -53.912818) (xy 60.618567 -53.887317) (xy 60.671351 -53.86931) (xy 60.726194 -53.85918)
			(xy 60.781928 -53.857143) (xy 60.837365 -53.863243) (xy 60.891322 -53.877349) (xy 60.942651 -53.899161)
			(xy 60.990257 -53.928215) (xy 61.033125 -53.96389) (xy 61.070342 -54.005427) (xy 61.101115 -54.05194)
			(xy 61.124787 -54.102437) (xy 61.140855 -54.155844) (xy 61.148975 -54.21102) (xy 61.149484 -54.238906)
			(xy 61.148975 -54.266792) (xy 61.140855 -54.321968) (xy 61.124787 -54.375375) (xy 61.101115 -54.425872)
			(xy 61.070342 -54.472385) (xy 61.033125 -54.513922) (xy 60.990257 -54.549597) (xy 60.942651 -54.578651)
			(xy 60.891322 -54.600463) (xy 60.837365 -54.614569) (xy 60.781928 -54.620669) (xy 60.726194 -54.618632)
			(xy 60.671351 -54.608502) (xy 60.618567 -54.590495) (xy 60.568967 -54.564994) (xy 60.523609 -54.532543)
			(xy 60.48346 -54.493834) (xy 60.449374 -54.449691) (xy 60.422078 -54.401056) (xy 60.402155 -54.348965)
			(xy 60.390029 -54.294528) (xy 60.385958 -54.238906) (xy 53.664136 -54.238906) (xy 53.640372 -54.280633)
			(xy 53.605495 -54.325052) (xy 53.564452 -54.363846) (xy 53.518139 -54.396167) (xy 53.467569 -54.42131)
			(xy 53.440838 -54.430422) (xy 53.432964 -54.432962) (xy 53.420264 -54.44236) (xy 53.414676 -54.44998)
			(xy 53.410569 -54.456433) (xy 53.406043 -54.471037) (xy 53.405786 -54.478682) (xy 53.405786 -54.67223)
			(xy 53.406049 -54.679874) (xy 53.410577 -54.694475) (xy 53.414676 -54.700932) (xy 53.420264 -54.708552)
			(xy 53.432964 -54.71795) (xy 53.440838 -54.72049) (xy 53.467543 -54.72968) (xy 53.518116 -54.754819)
			(xy 53.564431 -54.787136) (xy 53.605476 -54.825928) (xy 53.640357 -54.870345) (xy 53.668309 -54.919418)
			(xy 53.688724 -54.972075) (xy 53.692555 -54.989051) (xy 55.901068 -54.989051) (xy 55.901068 -54.934549)
			(xy 55.908824 -54.880601) (xy 55.924179 -54.828307) (xy 55.946819 -54.778729) (xy 55.976284 -54.732879)
			(xy 56.011975 -54.691688) (xy 56.053164 -54.655995) (xy 56.099013 -54.626528) (xy 56.14859 -54.603885)
			(xy 56.200884 -54.588528) (xy 56.254831 -54.580769) (xy 56.282082 -54.580282) (xy 56.310173 -54.580791)
			(xy 56.36575 -54.589016) (xy 56.419518 -54.605304) (xy 56.470316 -54.629305) (xy 56.517043 -54.660497)
			(xy 56.558688 -54.698207) (xy 56.594351 -54.741619) (xy 56.609234 -54.765448) (xy 56.614568 -54.774338)
			(xy 56.631586 -54.78653) (xy 56.724804 -54.80685) (xy 56.745378 -54.802532) (xy 56.754014 -54.79669)
			(xy 56.778072 -54.780681) (xy 56.830006 -54.75534) (xy 56.885165 -54.738117) (xy 56.942291 -54.729405)
			(xy 56.971184 -54.728872) (xy 56.998434 -54.729393) (xy 57.052379 -54.737147) (xy 57.104672 -54.752499)
			(xy 57.154248 -54.775137) (xy 57.200097 -54.804599) (xy 57.241287 -54.840287) (xy 57.276979 -54.881474)
			(xy 57.306446 -54.92732) (xy 57.329088 -54.976894) (xy 57.344445 -55.029185) (xy 57.352204 -55.08313)
			(xy 57.352692 -55.11038) (xy 57.352216 -55.13775) (xy 57.344401 -55.191929) (xy 57.328914 -55.244432)
			(xy 57.306075 -55.294179) (xy 57.276352 -55.340146) (xy 57.258712 -55.361078) (xy 57.258458 -55.361332)
			(xy 57.252889 -55.36843) (xy 57.246633 -55.385338) (xy 57.246266 -55.394352) (xy 57.246266 -55.461408)
			(xy 57.246626 -55.470424) (xy 57.252872 -55.487341) (xy 57.258458 -55.494428) (xy 57.258712 -55.494428)
			(xy 57.258712 -55.494682) (xy 57.276331 -55.515631) (xy 57.306054 -55.561597) (xy 57.328898 -55.611341)
			(xy 57.344394 -55.66384) (xy 57.352224 -55.718016) (xy 57.352226 -55.772754) (xy 57.344401 -55.82693)
			(xy 57.328909 -55.879431) (xy 57.306069 -55.929176) (xy 57.27635 -55.975145) (xy 57.258712 -55.996078)
			(xy 57.258458 -55.996332) (xy 57.252889 -56.00343) (xy 57.246633 -56.020338) (xy 57.246266 -56.029352)
			(xy 57.246266 -56.096408) (xy 57.246626 -56.105424) (xy 57.252872 -56.122341) (xy 57.258458 -56.129428)
			(xy 57.258712 -56.129428) (xy 57.258712 -56.129682) (xy 57.276358 -56.150608) (xy 57.306068 -56.196583)
			(xy 57.328903 -56.246332) (xy 57.344392 -56.298834) (xy 57.352219 -56.35301) (xy 57.352692 -56.38038)
			(xy 57.352206 -56.407631) (xy 57.34445 -56.461579) (xy 57.329095 -56.513874) (xy 57.306453 -56.563451)
			(xy 57.276987 -56.609301) (xy 57.241296 -56.650492) (xy 57.200105 -56.686183) (xy 57.154255 -56.715649)
			(xy 57.104678 -56.738291) (xy 57.052383 -56.753646) (xy 56.998435 -56.761402) (xy 56.943933 -56.761402)
			(xy 56.889985 -56.753646) (xy 56.83769 -56.738291) (xy 56.788113 -56.715649) (xy 56.742263 -56.686183)
			(xy 56.701072 -56.650492) (xy 56.665381 -56.609301) (xy 56.635915 -56.563451) (xy 56.613273 -56.513874)
			(xy 56.597918 -56.461579) (xy 56.590162 -56.407631) (xy 56.589676 -56.38038) (xy 56.590112 -56.353008)
			(xy 56.597934 -56.298827) (xy 56.613429 -56.246323) (xy 56.636278 -56.196577) (xy 56.666011 -56.150612)
			(xy 56.683656 -56.129682) (xy 56.68391 -56.129428) (xy 56.689492 -56.122338) (xy 56.695741 -56.105424)
			(xy 56.696102 -56.096408) (xy 56.696102 -56.029352) (xy 56.695719 -56.020338) (xy 56.689489 -56.003421)
			(xy 56.68391 -55.996332) (xy 56.683656 -55.996332) (xy 56.683656 -55.996078) (xy 56.665995 -55.975162)
			(xy 56.636268 -55.929192) (xy 56.613422 -55.879443) (xy 56.597926 -55.826938) (xy 56.590099 -55.772757)
			(xy 56.590101 -55.718013) (xy 56.597933 -55.663832) (xy 56.613433 -55.611329) (xy 56.636283 -55.561582)
			(xy 56.666013 -55.515614) (xy 56.683656 -55.494682) (xy 56.68391 -55.494428) (xy 56.689492 -55.487338)
			(xy 56.695741 -55.470424) (xy 56.696102 -55.461408) (xy 56.696102 -55.394352) (xy 56.695719 -55.385338)
			(xy 56.689489 -55.368421) (xy 56.68391 -55.361332) (xy 56.683656 -55.360824) (xy 56.67271 -55.348091)
			(xy 56.65287 -55.320999) (xy 56.644032 -55.306722) (xy 56.638698 -55.297832) (xy 56.62168 -55.28564)
			(xy 56.528462 -55.26532) (xy 56.507888 -55.269638) (xy 56.499252 -55.27548) (xy 56.475174 -55.291458)
			(xy 56.423248 -55.316806) (xy 56.368094 -55.334038) (xy 56.310973 -55.34276) (xy 56.282082 -55.343298)
			(xy 56.254831 -55.342831) (xy 56.200884 -55.335072) (xy 56.14859 -55.319715) (xy 56.099013 -55.297072)
			(xy 56.053164 -55.267605) (xy 56.011975 -55.231912) (xy 55.976284 -55.190721) (xy 55.946819 -55.144871)
			(xy 55.924179 -55.095293) (xy 55.908824 -55.042999) (xy 55.901068 -54.989051) (xy 53.692555 -54.989051)
			(xy 53.701155 -55.027165) (xy 53.70533 -55.083486) (xy 53.701159 -55.139808) (xy 53.688732 -55.194899)
			(xy 53.668321 -55.247558) (xy 53.640372 -55.296633) (xy 53.605495 -55.341052) (xy 53.564452 -55.379846)
			(xy 53.518139 -55.412167) (xy 53.500673 -55.420851) (xy 54.224668 -55.420851) (xy 54.224668 -55.366349)
			(xy 54.232424 -55.312401) (xy 54.247779 -55.260107) (xy 54.270419 -55.210529) (xy 54.299884 -55.164679)
			(xy 54.335575 -55.123488) (xy 54.376764 -55.087795) (xy 54.422613 -55.058328) (xy 54.47219 -55.035685)
			(xy 54.524484 -55.020328) (xy 54.578431 -55.012569) (xy 54.605682 -55.012082) (xy 54.631995 -55.012567)
			(xy 54.684123 -55.019799) (xy 54.734765 -55.034115) (xy 54.782964 -55.055244) (xy 54.827808 -55.082787)
			(xy 54.868449 -55.116222) (xy 54.886606 -55.135272) (xy 54.894127 -55.142674) (xy 54.913407 -55.151199)
			(xy 54.923944 -55.151782) (xy 54.99862 -55.151782) (xy 55.009167 -55.151228) (xy 55.028463 -55.142711)
			(xy 55.035958 -55.135272) (xy 55.054087 -55.11619) (xy 55.094723 -55.082736) (xy 55.139569 -55.055181)
			(xy 55.187775 -55.034048) (xy 55.238427 -55.019736) (xy 55.290564 -55.012517) (xy 55.316882 -55.012082)
			(xy 55.344135 -55.012564) (xy 55.398086 -55.020319) (xy 55.450385 -55.035673) (xy 55.499966 -55.058314)
			(xy 55.54582 -55.08778) (xy 55.587014 -55.123473) (xy 55.622709 -55.164665) (xy 55.652178 -55.210518)
			(xy 55.674821 -55.260098) (xy 55.690177 -55.312396) (xy 55.697935 -55.366347) (xy 55.697935 -55.420853)
			(xy 55.690177 -55.474804) (xy 55.674821 -55.527102) (xy 55.652178 -55.576682) (xy 55.622709 -55.622535)
			(xy 55.587014 -55.663727) (xy 55.54582 -55.69942) (xy 55.499966 -55.728886) (xy 55.450385 -55.751527)
			(xy 55.398086 -55.766881) (xy 55.344135 -55.774636) (xy 55.316882 -55.775098) (xy 55.290568 -55.774643)
			(xy 55.238439 -55.767406) (xy 55.187796 -55.753084) (xy 55.139597 -55.73195) (xy 55.094753 -55.704401)
			(xy 55.054114 -55.670961) (xy 55.035958 -55.651908) (xy 55.028453 -55.644487) (xy 55.00916 -55.635974)
			(xy 54.99862 -55.635398) (xy 54.923944 -55.635398) (xy 54.913396 -55.635938) (xy 54.8941 -55.644466)
			(xy 54.886606 -55.651908) (xy 54.868442 -55.670955) (xy 54.827814 -55.704413) (xy 54.782975 -55.731973)
			(xy 54.734776 -55.753113) (xy 54.68413 -55.767432) (xy 54.631998 -55.774658) (xy 54.605682 -55.775098)
			(xy 54.578431 -55.774631) (xy 54.524484 -55.766872) (xy 54.47219 -55.751515) (xy 54.422613 -55.728872)
			(xy 54.376764 -55.699405) (xy 54.335575 -55.663712) (xy 54.299884 -55.622521) (xy 54.270419 -55.576671)
			(xy 54.247779 -55.527093) (xy 54.232424 -55.474799) (xy 54.224668 -55.420851) (xy 53.500673 -55.420851)
			(xy 53.467569 -55.43731) (xy 53.440838 -55.446422) (xy 53.432964 -55.448962) (xy 53.420264 -55.45836)
			(xy 53.414676 -55.46598) (xy 53.410569 -55.472433) (xy 53.406043 -55.487037) (xy 53.405786 -55.494682)
			(xy 53.405786 -55.94223) (xy 53.406049 -55.949874) (xy 53.410577 -55.964475) (xy 53.414676 -55.970932)
			(xy 53.420264 -55.978552) (xy 53.432964 -55.98795) (xy 53.440838 -55.99049) (xy 53.467543 -55.99968)
			(xy 53.518116 -56.024819) (xy 53.564431 -56.057136) (xy 53.605476 -56.095928) (xy 53.640357 -56.140345)
			(xy 53.668309 -56.189418) (xy 53.688724 -56.242075) (xy 53.701155 -56.297165) (xy 53.70533 -56.353486)
			(xy 53.701159 -56.409808) (xy 53.688732 -56.464899) (xy 53.668321 -56.517558) (xy 53.640372 -56.566633)
			(xy 53.605495 -56.611052) (xy 53.564452 -56.649846) (xy 53.518139 -56.682167) (xy 53.467569 -56.70731)
			(xy 53.440838 -56.716422) (xy 53.432964 -56.718962) (xy 53.420264 -56.72836) (xy 53.414676 -56.73598)
			(xy 53.410569 -56.742433) (xy 53.406043 -56.757037) (xy 53.405786 -56.764682) (xy 53.405786 -57.48528)
			(xy 56.60593 -57.48528) (xy 56.610001 -57.429658) (xy 56.622127 -57.375221) (xy 56.64205 -57.32313)
			(xy 56.669346 -57.274495) (xy 56.703432 -57.230352) (xy 56.743581 -57.191643) (xy 56.788939 -57.159192)
			(xy 56.838539 -57.133691) (xy 56.891323 -57.115684) (xy 56.946166 -57.105554) (xy 57.0019 -57.103517)
			(xy 57.057337 -57.109617) (xy 57.111294 -57.123723) (xy 57.162623 -57.145535) (xy 57.210229 -57.174589)
			(xy 57.253097 -57.210264) (xy 57.290314 -57.251801) (xy 57.321087 -57.298314) (xy 57.344759 -57.348811)
			(xy 57.360827 -57.402218) (xy 57.368947 -57.457394) (xy 57.369456 -57.48528) (xy 57.368947 -57.513166)
			(xy 57.360827 -57.568342) (xy 57.344759 -57.621749) (xy 57.321087 -57.672246) (xy 57.290314 -57.718759)
			(xy 57.253097 -57.760296) (xy 57.210229 -57.795971) (xy 57.162623 -57.825025) (xy 57.111294 -57.846837)
			(xy 57.057337 -57.860943) (xy 57.0019 -57.867043) (xy 56.946166 -57.865006) (xy 56.891323 -57.854876)
			(xy 56.838539 -57.836869) (xy 56.788939 -57.811368) (xy 56.743581 -57.778917) (xy 56.703432 -57.740208)
			(xy 56.669346 -57.696065) (xy 56.64205 -57.64743) (xy 56.622127 -57.595339) (xy 56.610001 -57.540902)
			(xy 56.60593 -57.48528) (xy 53.405786 -57.48528) (xy 53.405786 -58.076084) (xy 57.358024 -58.076084)
			(xy 57.362095 -58.020462) (xy 57.374221 -57.966025) (xy 57.394144 -57.913934) (xy 57.42144 -57.865299)
			(xy 57.455526 -57.821156) (xy 57.495675 -57.782447) (xy 57.541033 -57.749996) (xy 57.590633 -57.724495)
			(xy 57.643417 -57.706488) (xy 57.69826 -57.696358) (xy 57.753994 -57.694321) (xy 57.809431 -57.700421)
			(xy 57.863388 -57.714527) (xy 57.914717 -57.736339) (xy 57.962323 -57.765393) (xy 58.005191 -57.801068)
			(xy 58.042408 -57.842605) (xy 58.058744 -57.867296) (xy 59.642754 -57.867296) (xy 59.646827 -57.811637)
			(xy 59.658962 -57.757164) (xy 59.678898 -57.705038) (xy 59.706212 -57.65637) (xy 59.74032 -57.612198)
			(xy 59.780497 -57.573463) (xy 59.825885 -57.540991) (xy 59.875517 -57.515473) (xy 59.928337 -57.497454)
			(xy 59.983216 -57.487317) (xy 60.038987 -57.485279) (xy 60.094461 -57.491382) (xy 60.148454 -57.505498)
			(xy 60.199817 -57.527325) (xy 60.247455 -57.556398) (xy 60.290351 -57.592097) (xy 60.327593 -57.633661)
			(xy 60.358387 -57.680205) (xy 60.382075 -57.730736) (xy 60.398153 -57.784178) (xy 60.406279 -57.839392)
			(xy 60.406788 -57.867296) (xy 60.406279 -57.8952) (xy 60.398153 -57.950414) (xy 60.382075 -58.003856)
			(xy 60.358387 -58.054387) (xy 60.327593 -58.100931) (xy 60.290351 -58.142495) (xy 60.247455 -58.178194)
			(xy 60.199817 -58.207267) (xy 60.148454 -58.229094) (xy 60.094461 -58.24321) (xy 60.038987 -58.249313)
			(xy 59.983216 -58.247275) (xy 59.928337 -58.237138) (xy 59.875517 -58.219119) (xy 59.825885 -58.193601)
			(xy 59.780497 -58.161129) (xy 59.74032 -58.122394) (xy 59.706212 -58.078222) (xy 59.678898 -58.029554)
			(xy 59.658962 -57.977428) (xy 59.646827 -57.922955) (xy 59.642754 -57.867296) (xy 58.058744 -57.867296)
			(xy 58.073181 -57.889118) (xy 58.096853 -57.939615) (xy 58.112921 -57.993022) (xy 58.121041 -58.048198)
			(xy 58.12155 -58.076084) (xy 58.121041 -58.10397) (xy 58.112921 -58.159146) (xy 58.096853 -58.212553)
			(xy 58.073181 -58.26305) (xy 58.042408 -58.309563) (xy 58.005191 -58.3511) (xy 57.962323 -58.386775)
			(xy 57.914717 -58.415829) (xy 57.863388 -58.437641) (xy 57.809431 -58.451747) (xy 57.753994 -58.457847)
			(xy 57.69826 -58.45581) (xy 57.643417 -58.44568) (xy 57.590633 -58.427673) (xy 57.541033 -58.402172)
			(xy 57.495675 -58.369721) (xy 57.455526 -58.331012) (xy 57.42144 -58.286869) (xy 57.394144 -58.238234)
			(xy 57.374221 -58.186143) (xy 57.362095 -58.131706) (xy 57.358024 -58.076084) (xy 53.405786 -58.076084)
			(xy 53.405786 -58.561224) (xy 58.562238 -58.561224) (xy 58.566309 -58.505602) (xy 58.578435 -58.451165)
			(xy 58.598358 -58.399074) (xy 58.625654 -58.350439) (xy 58.65974 -58.306296) (xy 58.699889 -58.267587)
			(xy 58.745247 -58.235136) (xy 58.794847 -58.209635) (xy 58.847631 -58.191628) (xy 58.902474 -58.181498)
			(xy 58.958208 -58.179461) (xy 59.013645 -58.185561) (xy 59.067602 -58.199667) (xy 59.118931 -58.221479)
			(xy 59.166537 -58.250533) (xy 59.209405 -58.286208) (xy 59.246622 -58.327745) (xy 59.277395 -58.374258)
			(xy 59.301067 -58.424755) (xy 59.308577 -58.449718) (xy 60.808868 -58.449718) (xy 60.812939 -58.394096)
			(xy 60.825065 -58.339659) (xy 60.844988 -58.287568) (xy 60.872284 -58.238933) (xy 60.90637 -58.19479)
			(xy 60.946519 -58.156081) (xy 60.991877 -58.12363) (xy 61.041477 -58.098129) (xy 61.094261 -58.080122)
			(xy 61.149104 -58.069992) (xy 61.204838 -58.067955) (xy 61.260275 -58.074055) (xy 61.314232 -58.088161)
			(xy 61.365561 -58.109973) (xy 61.413167 -58.139027) (xy 61.456035 -58.174702) (xy 61.493252 -58.216239)
			(xy 61.524025 -58.262752) (xy 61.547697 -58.313249) (xy 61.563765 -58.366656) (xy 61.571885 -58.421832)
			(xy 61.572394 -58.449718) (xy 61.571885 -58.477604) (xy 61.563765 -58.53278) (xy 61.547697 -58.586187)
			(xy 61.524025 -58.636684) (xy 61.493252 -58.683197) (xy 61.456035 -58.724734) (xy 61.413167 -58.760409)
			(xy 61.365561 -58.789463) (xy 61.314232 -58.811275) (xy 61.260275 -58.825381) (xy 61.204838 -58.831481)
			(xy 61.149104 -58.829444) (xy 61.094261 -58.819314) (xy 61.041477 -58.801307) (xy 60.991877 -58.775806)
			(xy 60.946519 -58.743355) (xy 60.90637 -58.704646) (xy 60.872284 -58.660503) (xy 60.844988 -58.611868)
			(xy 60.825065 -58.559777) (xy 60.812939 -58.50534) (xy 60.808868 -58.449718) (xy 59.308577 -58.449718)
			(xy 59.317135 -58.478162) (xy 59.325255 -58.533338) (xy 59.325764 -58.561224) (xy 59.325255 -58.58911)
			(xy 59.317135 -58.644286) (xy 59.301067 -58.697693) (xy 59.277395 -58.74819) (xy 59.246622 -58.794703)
			(xy 59.209405 -58.83624) (xy 59.166537 -58.871915) (xy 59.118931 -58.900969) (xy 59.067602 -58.922781)
			(xy 59.013645 -58.936887) (xy 58.958208 -58.942987) (xy 58.902474 -58.94095) (xy 58.847631 -58.93082)
			(xy 58.794847 -58.912813) (xy 58.745247 -58.887312) (xy 58.699889 -58.854861) (xy 58.65974 -58.816152)
			(xy 58.625654 -58.772009) (xy 58.598358 -58.723374) (xy 58.578435 -58.671283) (xy 58.566309 -58.616846)
			(xy 58.562238 -58.561224) (xy 53.405786 -58.561224) (xy 53.405786 -59.974734) (xy 57.087008 -59.974734)
			(xy 57.087436 -59.947907) (xy 57.094957 -59.894782) (xy 57.10984 -59.843233) (xy 57.131794 -59.794276)
			(xy 57.160386 -59.748874) (xy 57.195052 -59.707922) (xy 57.23511 -59.672227) (xy 57.257188 -59.65698)
			(xy 57.268757 -59.648764) (xy 57.287167 -59.627186) (xy 57.298924 -59.601372) (xy 57.30312 -59.573319)
			(xy 57.299431 -59.545196) (xy 57.288141 -59.519175) (xy 57.270123 -59.497268) (xy 57.258712 -59.488832)
			(xy 57.237263 -59.473469) (xy 57.198349 -59.437844) (xy 57.164715 -59.397198) (xy 57.137002 -59.352304)
			(xy 57.11574 -59.30402) (xy 57.101335 -59.253267) (xy 57.09406 -59.201013) (xy 57.093612 -59.174634)
			(xy 57.094098 -59.147383) (xy 57.101854 -59.093435) (xy 57.117209 -59.04114) (xy 57.139851 -58.991563)
			(xy 57.169317 -58.945713) (xy 57.205008 -58.904522) (xy 57.246199 -58.868831) (xy 57.292049 -58.839365)
			(xy 57.341626 -58.816723) (xy 57.393921 -58.801368) (xy 57.447869 -58.793612) (xy 57.502371 -58.793612)
			(xy 57.556319 -58.801368) (xy 57.608614 -58.816723) (xy 57.658191 -58.839365) (xy 57.704041 -58.868831)
			(xy 57.745232 -58.904522) (xy 57.780923 -58.945713) (xy 57.810389 -58.991563) (xy 57.833031 -59.04114)
			(xy 57.848386 -59.093435) (xy 57.856142 -59.147383) (xy 57.856628 -59.174634) (xy 57.85616 -59.20146)
			(xy 57.848644 -59.254582) (xy 57.833766 -59.306129) (xy 57.811819 -59.355086) (xy 57.783234 -59.400488)
			(xy 57.748574 -59.441441) (xy 57.708523 -59.47714) (xy 57.686448 -59.492388) (xy 57.674915 -59.500647)
			(xy 57.656518 -59.52222) (xy 57.644767 -59.548023) (xy 57.64057 -59.576063) (xy 57.644251 -59.604175)
			(xy 57.655526 -59.630189) (xy 57.673524 -59.652097) (xy 57.684924 -59.660536) (xy 57.706413 -59.675846)
			(xy 57.745324 -59.71148) (xy 57.778954 -59.752137) (xy 57.806661 -59.797039) (xy 57.827916 -59.845332)
			(xy 57.842314 -59.896092) (xy 57.84958 -59.948352) (xy 57.850024 -59.974734) (xy 57.849538 -60.001985)
			(xy 57.841782 -60.055933) (xy 57.826427 -60.108228) (xy 57.803785 -60.157805) (xy 57.774319 -60.203655)
			(xy 57.738628 -60.244846) (xy 57.697437 -60.280537) (xy 57.651587 -60.310003) (xy 57.60201 -60.332645)
			(xy 57.549715 -60.348) (xy 57.495767 -60.355756) (xy 57.441265 -60.355756) (xy 57.387317 -60.348)
			(xy 57.335022 -60.332645) (xy 57.285445 -60.310003) (xy 57.239595 -60.280537) (xy 57.198404 -60.244846)
			(xy 57.162713 -60.203655) (xy 57.133247 -60.157805) (xy 57.110605 -60.108228) (xy 57.09525 -60.055933)
			(xy 57.087494 -60.001985) (xy 57.087008 -59.974734) (xy 53.405786 -59.974734) (xy 53.405786 -60.601606)
			(xy 56.333134 -60.601606) (xy 56.337205 -60.545984) (xy 56.349331 -60.491547) (xy 56.369254 -60.439456)
			(xy 56.39655 -60.390821) (xy 56.430636 -60.346678) (xy 56.470785 -60.307969) (xy 56.516143 -60.275518)
			(xy 56.565743 -60.250017) (xy 56.618527 -60.23201) (xy 56.67337 -60.22188) (xy 56.729104 -60.219843)
			(xy 56.784541 -60.225943) (xy 56.838498 -60.240049) (xy 56.889827 -60.261861) (xy 56.937433 -60.290915)
			(xy 56.980301 -60.32659) (xy 57.017518 -60.368127) (xy 57.048291 -60.41464) (xy 57.071963 -60.465137)
			(xy 57.088031 -60.518544) (xy 57.096151 -60.57372) (xy 57.09666 -60.601606) (xy 57.096196 -60.627006)
			(xy 58.721242 -60.627006) (xy 58.725313 -60.571384) (xy 58.737439 -60.516947) (xy 58.757362 -60.464856)
			(xy 58.784658 -60.416221) (xy 58.818744 -60.372078) (xy 58.858893 -60.333369) (xy 58.904251 -60.300918)
			(xy 58.953851 -60.275417) (xy 59.006635 -60.25741) (xy 59.061478 -60.24728) (xy 59.117212 -60.245243)
			(xy 59.172649 -60.251343) (xy 59.226606 -60.265449) (xy 59.277935 -60.287261) (xy 59.325541 -60.316315)
			(xy 59.368409 -60.35199) (xy 59.405626 -60.393527) (xy 59.436399 -60.44004) (xy 59.460071 -60.490537)
			(xy 59.476139 -60.543944) (xy 59.484259 -60.59912) (xy 59.484768 -60.627006) (xy 59.484652 -60.633356)
			(xy 60.812932 -60.633356) (xy 60.817003 -60.577734) (xy 60.829129 -60.523297) (xy 60.849052 -60.471206)
			(xy 60.876348 -60.422571) (xy 60.910434 -60.378428) (xy 60.950583 -60.339719) (xy 60.995941 -60.307268)
			(xy 61.045541 -60.281767) (xy 61.098325 -60.26376) (xy 61.153168 -60.25363) (xy 61.208902 -60.251593)
			(xy 61.264339 -60.257693) (xy 61.318296 -60.271799) (xy 61.369625 -60.293611) (xy 61.417231 -60.322665)
			(xy 61.460099 -60.35834) (xy 61.497316 -60.399877) (xy 61.528089 -60.44639) (xy 61.551761 -60.496887)
			(xy 61.567829 -60.550294) (xy 61.575949 -60.60547) (xy 61.576458 -60.633356) (xy 61.575949 -60.661242)
			(xy 61.567829 -60.716418) (xy 61.551761 -60.769825) (xy 61.528089 -60.820322) (xy 61.497316 -60.866835)
			(xy 61.460099 -60.908372) (xy 61.417231 -60.944047) (xy 61.369625 -60.973101) (xy 61.318296 -60.994913)
			(xy 61.264339 -61.009019) (xy 61.208902 -61.015119) (xy 61.153168 -61.013082) (xy 61.098325 -61.002952)
			(xy 61.045541 -60.984945) (xy 60.995941 -60.959444) (xy 60.950583 -60.926993) (xy 60.910434 -60.888284)
			(xy 60.876348 -60.844141) (xy 60.849052 -60.795506) (xy 60.829129 -60.743415) (xy 60.817003 -60.688978)
			(xy 60.812932 -60.633356) (xy 59.484652 -60.633356) (xy 59.484259 -60.654892) (xy 59.476139 -60.710068)
			(xy 59.460071 -60.763475) (xy 59.436399 -60.813972) (xy 59.405626 -60.860485) (xy 59.368409 -60.902022)
			(xy 59.325541 -60.937697) (xy 59.277935 -60.966751) (xy 59.226606 -60.988563) (xy 59.172649 -61.002669)
			(xy 59.117212 -61.008769) (xy 59.061478 -61.006732) (xy 59.006635 -60.996602) (xy 58.953851 -60.978595)
			(xy 58.904251 -60.953094) (xy 58.858893 -60.920643) (xy 58.818744 -60.881934) (xy 58.784658 -60.837791)
			(xy 58.757362 -60.789156) (xy 58.737439 -60.737065) (xy 58.725313 -60.682628) (xy 58.721242 -60.627006)
			(xy 57.096196 -60.627006) (xy 57.096151 -60.629492) (xy 57.088031 -60.684668) (xy 57.071963 -60.738075)
			(xy 57.048291 -60.788572) (xy 57.017518 -60.835085) (xy 56.980301 -60.876622) (xy 56.937433 -60.912297)
			(xy 56.889827 -60.941351) (xy 56.838498 -60.963163) (xy 56.784541 -60.977269) (xy 56.729104 -60.983369)
			(xy 56.67337 -60.981332) (xy 56.618527 -60.971202) (xy 56.565743 -60.953195) (xy 56.516143 -60.927694)
			(xy 56.470785 -60.895243) (xy 56.430636 -60.856534) (xy 56.39655 -60.812391) (xy 56.369254 -60.763756)
			(xy 56.349331 -60.711665) (xy 56.337205 -60.657228) (xy 56.333134 -60.601606) (xy 53.405786 -60.601606)
			(xy 53.405786 -61.328046) (xy 53.406802 -61.337444) (xy 53.406802 -61.337952) (xy 53.408503 -61.345113)
			(xy 53.41533 -61.358145) (xy 53.420264 -61.363606) (xy 53.613558 -61.5569) (xy 53.620966 -61.563591)
			(xy 53.639401 -61.571188) (xy 53.649372 -61.571632) (xy 56.181752 -61.571632) (xy 56.189372 -61.571886)
			(xy 57.060592 -61.571886)
		)
		(stroke
			(width 0)
			(type solid)
		)
		(fill yes)
		(layer "In9.Cu")
		(net "P3V3_SSD2")
	)
	(gr_poly
		(pts
			(xy 379.326648 -61.576458) (xy 379.335946 -61.575394) (xy 379.354628 -61.574251) (xy 379.363986 -61.574172)
			(xy 380.500128 -61.574172) (xy 380.505716 -61.573664) (xy 380.522734 -61.570362) (xy 380.530862 -61.565028)
			(xy 380.586742 -61.511434) (xy 380.589532 -61.508299) (xy 380.594125 -61.501274) (xy 380.595886 -61.497464)
			(xy 380.599696 -61.489082) (xy 380.600204 -61.478668) (xy 380.600204 -61.478414) (xy 380.601294 -61.457132)
			(xy 380.60766 -61.414994) (xy 380.612904 -61.39434) (xy 380.620217 -61.368733) (xy 380.640961 -61.319686)
			(xy 380.668308 -61.273992) (xy 380.701731 -61.232533) (xy 380.720854 -61.214) (xy 380.721616 -61.213238)
			(xy 380.743071 -61.193277) (xy 380.790966 -61.159514) (xy 380.843463 -61.133476) (xy 380.899325 -61.115776)
			(xy 380.957238 -61.106832) (xy 380.986538 -61.106304) (xy 381.013548 -61.106775) (xy 381.067026 -61.114399)
			(xy 381.118895 -61.129488) (xy 381.168118 -61.151741) (xy 381.21371 -61.180714) (xy 381.254761 -61.215827)
			(xy 381.29045 -61.256378) (xy 381.320063 -61.301557) (xy 381.343008 -61.350461) (xy 381.358828 -61.402112)
			(xy 381.367205 -61.455478) (xy 381.368046 -61.482478) (xy 381.368046 -61.484002) (xy 381.3683 -61.500766)
			(xy 381.37084 -61.5061) (xy 381.417322 -61.550804) (xy 381.432054 -61.565028) (xy 381.440182 -61.570362)
			(xy 381.4572 -61.573664) (xy 381.462788 -61.574172) (xy 382.443228 -61.574172) (xy 382.452011 -61.574241)
			(xy 382.469548 -61.575255) (xy 382.47828 -61.576204) (xy 382.482598 -61.576458) (xy 383.339594 -61.576458)
			(xy 383.343912 -61.576204) (xy 383.352644 -61.575255) (xy 383.370181 -61.574236) (xy 383.378964 -61.574172)
			(xy 385.058666 -61.574172) (xy 385.061714 -61.573918) (xy 385.077462 -61.57087) (xy 385.078478 -61.570362)
			(xy 385.725162 -60.923678) (xy 385.728092 -60.918012) (xy 385.731296 -60.905669) (xy 385.731512 -60.899294)
			(xy 385.731512 -38.904672) (xy 385.731004 -38.899592) (xy 385.727956 -38.882828) (xy 385.726178 -38.877748)
			(xy 385.724146 -38.872922) (xy 385.712462 -38.861238) (xy 385.711192 -38.860222) (xy 385.679338 -38.831519)
			(xy 385.620432 -38.769205) (xy 385.567446 -38.701784) (xy 385.520821 -38.629818) (xy 385.480943 -38.553905)
			(xy 385.448144 -38.474675) (xy 385.422697 -38.392788) (xy 385.404814 -38.308924) (xy 385.394643 -38.223779)
			(xy 385.392268 -38.138062) (xy 385.39771 -38.052485) (xy 385.410923 -37.967759) (xy 385.431797 -37.884588)
			(xy 385.460158 -37.803664) (xy 385.495772 -37.72566) (xy 385.538342 -37.651223) (xy 385.587514 -37.580972)
			(xy 385.64288 -37.515491) (xy 385.673092 -37.485066) (xy 385.673346 -37.484812) (xy 385.703318 -37.45611)
			(xy 385.710684 -37.449506) (xy 385.716272 -37.444172) (xy 385.722622 -37.42944) (xy 385.722622 -37.428932)
			(xy 385.727448 -37.418264) (xy 385.728918 -37.414602) (xy 385.730829 -37.406947) (xy 385.731258 -37.403024)
			(xy 385.731512 -37.398198) (xy 385.731512 -31.77667) (xy 385.728718 -31.768542) (xy 385.71868 -31.737951)
			(xy 385.707833 -31.674493) (xy 385.707128 -31.642304) (xy 385.707815 -31.610114) (xy 385.718663 -31.546653)
			(xy 385.728718 -31.516066) (xy 385.731512 -31.507938) (xy 385.731512 -31.23819) (xy 385.731632 -31.233236)
			(xy 385.733553 -31.223515) (xy 385.735322 -31.218886) (xy 385.740402 -31.206694) (xy 385.742174 -31.202066)
			(xy 385.74409 -31.192344) (xy 385.744212 -31.18739) (xy 385.744212 -29.841444) (xy 385.743993 -29.834198)
			(xy 385.739998 -29.820269) (xy 385.736338 -29.814012) (xy 385.721069 -29.792203) (xy 385.696078 -29.745197)
			(xy 385.677872 -29.695169) (xy 385.666805 -29.643095) (xy 385.663093 -29.589987) (xy 385.666809 -29.53688)
			(xy 385.677879 -29.484806) (xy 385.696088 -29.43478) (xy 385.721082 -29.387775) (xy 385.736338 -29.365956)
			(xy 385.740001 -29.359699) (xy 385.744002 -29.345771) (xy 385.744212 -29.338524) (xy 385.744212 -28.112974)
			(xy 385.744212 -28.112466) (xy 385.744259 -28.107927) (xy 385.745792 -28.098981) (xy 385.74726 -28.094686)
			(xy 385.748276 -28.092146) (xy 385.749542 -28.087625) (xy 385.750561 -28.078292) (xy 385.750308 -28.073604)
			(xy 385.748784 -28.051506) (xy 385.748487 -28.047866) (xy 385.746952 -28.040726) (xy 385.745736 -28.037282)
			(xy 385.73837 -28.01747) (xy 385.73456 -28.012136) (xy 385.734306 -28.011882) (xy 385.717615 -27.987523)
			(xy 385.691149 -27.934739) (xy 385.673133 -27.878507) (xy 385.663997 -27.820171) (xy 385.66344 -27.790648)
			(xy 385.66344 -27.79014) (xy 385.663901 -27.762887) (xy 385.671653 -27.708934) (xy 385.687006 -27.656634)
			(xy 385.709647 -27.607052) (xy 385.739115 -27.561197) (xy 385.774809 -27.520004) (xy 385.816004 -27.48431)
			(xy 385.861859 -27.454843) (xy 385.911441 -27.432204) (xy 385.963742 -27.416852) (xy 386.017695 -27.4091)
			(xy 386.044948 -27.408632) (xy 386.070469 -27.409075) (xy 386.121052 -27.415909) (xy 386.170273 -27.429423)
			(xy 386.217254 -27.449375) (xy 386.261158 -27.475409) (xy 386.281422 -27.490928) (xy 386.281676 -27.491182)
			(xy 386.290642 -27.497501) (xy 386.31197 -27.502533) (xy 386.333449 -27.498195) (xy 386.342636 -27.492198)
			(xy 386.348732 -27.487118) (xy 386.488432 -27.347418) (xy 386.495831 -27.340575) (xy 386.51443 -27.332849)
			(xy 386.5245 -27.332432) (xy 386.672582 -27.332432) (xy 386.6769 -27.33167) (xy 386.689442 -27.32968)
			(xy 386.714748 -27.327519) (xy 386.727446 -27.327352) (xy 390.772904 -27.327352) (xy 390.782921 -27.326931)
			(xy 390.801429 -27.319259) (xy 390.815588 -27.305085) (xy 390.823241 -27.28657) (xy 390.823704 -27.276552)
			(xy 390.823704 -26.479246) (xy 390.82393 -26.457847) (xy 390.827875 -26.415233) (xy 390.831578 -26.394156)
			(xy 390.832848 -26.38679) (xy 390.831578 -26.373074) (xy 390.827514 -26.363168) (xy 390.824964 -26.358001)
			(xy 390.81791 -26.348893) (xy 390.813544 -26.345134) (xy 390.800082 -26.335736) (xy 390.789658 -26.330124)
			(xy 390.766095 -26.328158) (xy 390.75487 -26.331926) (xy 390.750552 -26.334212) (xy 390.723448 -26.347495)
			(xy 390.666089 -26.366283) (xy 390.606487 -26.375804) (xy 390.576308 -26.376376) (xy 390.5758 -26.376376)
			(xy 390.548548 -26.375913) (xy 390.494599 -26.368155) (xy 390.442303 -26.352799) (xy 390.392725 -26.330156)
			(xy 390.346874 -26.300688) (xy 390.305684 -26.264994) (xy 390.269993 -26.223801) (xy 390.240528 -26.177947)
			(xy 390.21789 -26.128367) (xy 390.202538 -26.07607) (xy 390.194785 -26.02212) (xy 390.194292 -25.994868)
			(xy 390.194737 -25.968826) (xy 390.201827 -25.917227) (xy 390.215871 -25.867073) (xy 390.236608 -25.819295)
			(xy 390.263651 -25.774783) (xy 390.296499 -25.734363) (xy 390.315196 -25.71623) (xy 390.315958 -25.715468)
			(xy 390.337413 -25.695508) (xy 390.385309 -25.661748) (xy 390.437806 -25.635713) (xy 390.493668 -25.618018)
			(xy 390.551581 -25.609079) (xy 390.58088 -25.608534) (xy 390.609827 -25.609077) (xy 390.667055 -25.617835)
			(xy 390.722303 -25.635137) (xy 390.774303 -25.660588) (xy 390.821861 -25.693602) (xy 390.863886 -25.733422)
			(xy 390.899413 -25.779133) (xy 390.927627 -25.829687) (xy 390.928511 -25.832054) (xy 392.48791 -25.832054)
			(xy 392.491981 -25.776432) (xy 392.504107 -25.721995) (xy 392.52403 -25.669904) (xy 392.551326 -25.621269)
			(xy 392.585412 -25.577126) (xy 392.625561 -25.538417) (xy 392.670919 -25.505966) (xy 392.720519 -25.480465)
			(xy 392.773303 -25.462458) (xy 392.828146 -25.452328) (xy 392.88388 -25.450291) (xy 392.939317 -25.456391)
			(xy 392.993274 -25.470497) (xy 393.044603 -25.492309) (xy 393.092209 -25.521363) (xy 393.135077 -25.557038)
			(xy 393.136611 -25.55875) (xy 396.94231 -25.55875) (xy 396.942796 -25.531499) (xy 396.950552 -25.477551)
			(xy 396.965907 -25.425256) (xy 396.988549 -25.375679) (xy 397.018015 -25.329829) (xy 397.053706 -25.288638)
			(xy 397.094897 -25.252947) (xy 397.140747 -25.223481) (xy 397.190324 -25.200839) (xy 397.242619 -25.185484)
			(xy 397.296567 -25.177728) (xy 397.351069 -25.177728) (xy 397.405017 -25.185484) (xy 397.457312 -25.200839)
			(xy 397.506889 -25.223481) (xy 397.552739 -25.252947) (xy 397.59393 -25.288638) (xy 397.629621 -25.329829)
			(xy 397.659087 -25.375679) (xy 397.681729 -25.425256) (xy 397.697084 -25.477551) (xy 397.70484 -25.531499)
			(xy 397.705326 -25.55875) (xy 397.704772 -25.589013) (xy 397.695219 -25.648779) (xy 397.676346 -25.706287)
			(xy 397.648626 -25.760091) (xy 397.631158 -25.78481) (xy 397.622885 -25.796959) (xy 397.612937 -25.824602)
			(xy 397.611271 -25.853932) (xy 397.618023 -25.882523) (xy 397.632635 -25.908009) (xy 397.653899 -25.928281)
			(xy 397.680053 -25.94166) (xy 397.694404 -25.94483) (xy 397.720297 -25.950171) (xy 397.77042 -25.966988)
			(xy 397.817739 -25.990567) (xy 397.861348 -26.020456) (xy 397.90041 -26.056082) (xy 397.934176 -26.096763)
			(xy 397.962 -26.141718) (xy 397.983346 -26.190085) (xy 397.997808 -26.240937) (xy 398.005106 -26.2933)
			(xy 398.005554 -26.319734) (xy 399.141948 -26.319734) (xy 399.146019 -26.264112) (xy 399.158145 -26.209675)
			(xy 399.178068 -26.157584) (xy 399.205364 -26.108949) (xy 399.23945 -26.064806) (xy 399.279599 -26.026097)
			(xy 399.324957 -25.993646) (xy 399.374557 -25.968145) (xy 399.427341 -25.950138) (xy 399.482184 -25.940008)
			(xy 399.537918 -25.937971) (xy 399.593355 -25.944071) (xy 399.647312 -25.958177) (xy 399.698641 -25.979989)
			(xy 399.746247 -26.009043) (xy 399.789115 -26.044718) (xy 399.826332 -26.086255) (xy 399.857105 -26.132768)
			(xy 399.880777 -26.183265) (xy 399.896845 -26.236672) (xy 399.904965 -26.291848) (xy 399.905474 -26.319734)
			(xy 399.904965 -26.34762) (xy 399.896845 -26.402796) (xy 399.880777 -26.456203) (xy 399.857105 -26.5067)
			(xy 399.826332 -26.553213) (xy 399.789115 -26.59475) (xy 399.746247 -26.630425) (xy 399.698641 -26.659479)
			(xy 399.647312 -26.681291) (xy 399.593355 -26.695397) (xy 399.537918 -26.701497) (xy 399.482184 -26.69946)
			(xy 399.427341 -26.68933) (xy 399.374557 -26.671323) (xy 399.324957 -26.645822) (xy 399.279599 -26.613371)
			(xy 399.23945 -26.574662) (xy 399.205364 -26.530519) (xy 399.178068 -26.481884) (xy 399.158145 -26.429793)
			(xy 399.146019 -26.375356) (xy 399.141948 -26.319734) (xy 398.005554 -26.319734) (xy 398.005068 -26.346985)
			(xy 397.997312 -26.400933) (xy 397.981957 -26.453228) (xy 397.959315 -26.502805) (xy 397.929849 -26.548655)
			(xy 397.894158 -26.589846) (xy 397.852967 -26.625537) (xy 397.807117 -26.655003) (xy 397.75754 -26.677645)
			(xy 397.705245 -26.693) (xy 397.651297 -26.700756) (xy 397.596795 -26.700756) (xy 397.542847 -26.693)
			(xy 397.490552 -26.677645) (xy 397.440975 -26.655003) (xy 397.395125 -26.625537) (xy 397.353934 -26.589846)
			(xy 397.318243 -26.548655) (xy 397.288777 -26.502805) (xy 397.266135 -26.453228) (xy 397.25078 -26.400933)
			(xy 397.243024 -26.346985) (xy 397.242538 -26.319734) (xy 397.243091 -26.289471) (xy 397.252645 -26.229705)
			(xy 397.271519 -26.172198) (xy 397.299238 -26.118393) (xy 397.316706 -26.093674) (xy 397.325021 -26.08155)
			(xy 397.334972 -26.053899) (xy 397.336638 -26.024559) (xy 397.32988 -25.995959) (xy 397.315258 -25.970468)
			(xy 397.293983 -25.950195) (xy 397.267817 -25.93682) (xy 397.25346 -25.933654) (xy 397.227557 -25.928354)
			(xy 397.177434 -25.911532) (xy 397.130114 -25.887948) (xy 397.086506 -25.858053) (xy 397.047444 -25.822422)
			(xy 397.013679 -25.781737) (xy 396.985858 -25.736778) (xy 396.964512 -25.688407) (xy 396.950053 -25.637551)
			(xy 396.942757 -25.585186) (xy 396.94231 -25.55875) (xy 393.136611 -25.55875) (xy 393.172294 -25.598575)
			(xy 393.203067 -25.645088) (xy 393.226739 -25.695585) (xy 393.242807 -25.748992) (xy 393.250927 -25.804168)
			(xy 393.251436 -25.832054) (xy 393.250927 -25.85994) (xy 393.242807 -25.915116) (xy 393.226739 -25.968523)
			(xy 393.203067 -26.01902) (xy 393.172294 -26.065533) (xy 393.135077 -26.10707) (xy 393.092209 -26.142745)
			(xy 393.044603 -26.171799) (xy 392.993274 -26.193611) (xy 392.939317 -26.207717) (xy 392.88388 -26.213817)
			(xy 392.828146 -26.21178) (xy 392.773303 -26.20165) (xy 392.720519 -26.183643) (xy 392.670919 -26.158142)
			(xy 392.625561 -26.125691) (xy 392.585412 -26.086982) (xy 392.551326 -26.042839) (xy 392.52403 -25.994204)
			(xy 392.504107 -25.942113) (xy 392.491981 -25.887676) (xy 392.48791 -25.832054) (xy 390.928511 -25.832054)
			(xy 390.94788 -25.883923) (xy 390.959707 -25.940596) (xy 390.96188 -25.969468) (xy 390.962642 -25.982422)
			(xy 390.968484 -25.992328) (xy 390.970763 -25.996034) (xy 390.976381 -26.002676) (xy 390.97966 -26.005536)
			(xy 390.98093 -26.006552) (xy 390.983978 -26.008838) (xy 391.013188 -26.027126) (xy 391.056114 -26.05405)
			(xy 391.056368 -26.05405) (xy 391.061622 -26.057132) (xy 391.073175 -26.060987) (xy 391.079228 -26.06167)
			(xy 391.09142 -26.062432) (xy 391.102596 -26.057606) (xy 391.130912 -26.046145) (xy 391.189823 -26.029986)
			(xy 391.250361 -26.021815) (xy 391.280904 -26.021284) (xy 391.298938 -26.021284) (xy 391.307066 -26.022046)
			(xy 391.338502 -26.024338) (xy 391.400353 -26.036472) (xy 391.459954 -26.056977) (xy 391.516178 -26.085465)
			(xy 391.567962 -26.121397) (xy 391.614327 -26.164094) (xy 391.654396 -26.212749) (xy 391.687411 -26.26644)
			(xy 391.712748 -26.324153) (xy 391.723152 -26.360882) (xy 394.40561 -26.360882) (xy 394.409681 -26.30526)
			(xy 394.421807 -26.250823) (xy 394.44173 -26.198732) (xy 394.469026 -26.150097) (xy 394.503112 -26.105954)
			(xy 394.543261 -26.067245) (xy 394.588619 -26.034794) (xy 394.638219 -26.009293) (xy 394.691003 -25.991286)
			(xy 394.745846 -25.981156) (xy 394.80158 -25.979119) (xy 394.857017 -25.985219) (xy 394.910974 -25.999325)
			(xy 394.962303 -26.021137) (xy 395.009909 -26.050191) (xy 395.052777 -26.085866) (xy 395.089994 -26.127403)
			(xy 395.120767 -26.173916) (xy 395.144439 -26.224413) (xy 395.160507 -26.27782) (xy 395.168627 -26.332996)
			(xy 395.169136 -26.360882) (xy 395.168627 -26.388768) (xy 395.160507 -26.443944) (xy 395.144439 -26.497351)
			(xy 395.120767 -26.547848) (xy 395.089994 -26.594361) (xy 395.052777 -26.635898) (xy 395.009909 -26.671573)
			(xy 394.962303 -26.700627) (xy 394.910974 -26.722439) (xy 394.857017 -26.736545) (xy 394.80158 -26.742645)
			(xy 394.745846 -26.740608) (xy 394.691003 -26.730478) (xy 394.638219 -26.712471) (xy 394.588619 -26.68697)
			(xy 394.543261 -26.654519) (xy 394.503112 -26.61581) (xy 394.469026 -26.571667) (xy 394.44173 -26.523032)
			(xy 394.421807 -26.470941) (xy 394.409681 -26.416504) (xy 394.40561 -26.360882) (xy 391.723152 -26.360882)
			(xy 391.729927 -26.384797) (xy 391.738623 -26.447224) (xy 391.73912 -26.478738) (xy 391.73912 -27.276552)
			(xy 391.739532 -27.286578) (xy 391.747194 -27.305108) (xy 391.761369 -27.31929) (xy 391.779894 -27.326963)
			(xy 391.78992 -27.327352) (xy 400.995388 -27.327352) (xy 401.004786 -27.326336) (xy 401.005294 -27.326336)
			(xy 401.012453 -27.324631) (xy 401.025481 -27.3178) (xy 401.030948 -27.312874) (xy 401.39112 -26.952702)
			(xy 401.396105 -26.947274) (xy 401.402961 -26.934236) (xy 401.404582 -26.927048) (xy 401.404582 -26.92654)
			(xy 401.405598 -26.917142) (xy 401.405598 -24.081994) (xy 401.402804 -24.073866) (xy 401.392641 -24.043102)
			(xy 401.381651 -23.979257) (xy 401.38096 -23.946866) (xy 401.381664 -23.914475) (xy 401.392641 -23.850629)
			(xy 401.402804 -23.819866) (xy 401.405598 -23.811738) (xy 401.405598 -22.254718) (xy 401.405363 -22.247216)
			(xy 401.400965 -22.232873) (xy 401.396962 -22.226524) (xy 401.393152 -22.220428) (xy 401.381722 -22.21103)
			(xy 401.38096 -22.210776) (xy 401.3546 -22.199838) (xy 401.305194 -22.171272) (xy 401.260598 -22.135662)
			(xy 401.221806 -22.093804) (xy 401.189686 -22.046632) (xy 401.164955 -21.995199) (xy 401.148166 -21.940656)
			(xy 401.139693 -21.884219) (xy 401.139152 -21.855684) (xy 401.139645 -21.8276) (xy 401.147872 -21.772038)
			(xy 401.164159 -21.718284) (xy 401.188155 -21.667501) (xy 401.219341 -21.620786) (xy 401.257041 -21.579151)
			(xy 401.300441 -21.543497) (xy 401.348601 -21.514594) (xy 401.374356 -21.503386) (xy 401.374864 -21.503132)
			(xy 401.381563 -21.500024) (xy 401.392925 -21.4906) (xy 401.397216 -21.48459) (xy 401.40128 -21.478494)
			(xy 401.403312 -21.47189) (xy 401.404362 -21.468232) (xy 401.405503 -21.460709) (xy 401.405598 -21.456904)
			(xy 401.405598 -15.832328) (xy 401.405344 -15.829534) (xy 401.404333 -15.821411) (xy 401.397844 -15.806393)
			(xy 401.392644 -15.80007) (xy 401.37842 -15.785592) (xy 401.340828 -15.747492) (xy 401.337349 -15.744204)
			(xy 401.329425 -15.738835) (xy 401.32508 -15.736824) (xy 401.31619 -15.733014) (xy 401.305268 -15.73276)
			(xy 401.305014 -15.73276) (xy 401.284186 -15.731744) (xy 401.255603 -15.729134) (xy 401.199632 -15.716429)
			(xy 401.14619 -15.695497) (xy 401.096479 -15.666809) (xy 401.051618 -15.631009) (xy 401.03171 -15.610332)
			(xy 401.031456 -15.609824) (xy 401.027667 -15.606001) (xy 401.018832 -15.599855) (xy 401.01393 -15.597632)
			(xy 401.004278 -15.593568) (xy 400.967702 -15.594584) (xy 400.916394 -15.595854) (xy 400.910993 -15.596129)
			(xy 400.90049 -15.598697) (xy 400.895566 -15.600934) (xy 400.885914 -15.605506) (xy 400.878802 -15.614142)
			(xy 400.860592 -15.635293) (xy 400.819046 -15.672562) (xy 400.772515 -15.703382) (xy 400.721991 -15.727097)
			(xy 400.668552 -15.7432) (xy 400.613338 -15.751348) (xy 400.585432 -15.75181) (xy 400.558178 -15.751349)
			(xy 400.504223 -15.743596) (xy 400.451921 -15.728242) (xy 400.402336 -15.705601) (xy 400.356479 -15.676134)
			(xy 400.315282 -15.64044) (xy 400.279585 -15.599247) (xy 400.250114 -15.553392) (xy 400.227469 -15.503809)
			(xy 400.212111 -15.451508) (xy 400.204353 -15.397554) (xy 400.204353 -15.343046) (xy 400.212111 -15.289092)
			(xy 400.227469 -15.236791) (xy 400.250114 -15.187208) (xy 400.279585 -15.141353) (xy 400.315282 -15.10016)
			(xy 400.356479 -15.064466) (xy 400.402336 -15.034999) (xy 400.451921 -15.012358) (xy 400.504223 -14.997004)
			(xy 400.558178 -14.989251) (xy 400.585432 -14.988794) (xy 400.58594 -14.988794) (xy 400.612125 -14.989245)
			(xy 400.663997 -14.996448) (xy 400.714395 -15.010686) (xy 400.762368 -15.031691) (xy 400.807014 -15.059067)
			(xy 400.84749 -15.092298) (xy 400.865594 -15.111222) (xy 400.865848 -15.11173) (xy 400.869636 -15.115556)
			(xy 400.878468 -15.121706) (xy 400.883374 -15.123922) (xy 400.893026 -15.127986) (xy 400.929602 -15.12697)
			(xy 400.98091 -15.1257) (xy 400.986311 -15.125425) (xy 400.996812 -15.122853) (xy 401.001738 -15.12062)
			(xy 401.01139 -15.116048) (xy 401.018502 -15.107412) (xy 401.040727 -15.081735) (xy 401.0926 -15.037918)
			(xy 401.121626 -15.02029) (xy 401.122134 -15.02029) (xy 401.126452 -15.017496) (xy 401.139406 -14.997684)
			(xy 401.150328 -14.90599) (xy 401.151154 -14.894371) (xy 401.143474 -14.872407) (xy 401.135596 -14.863826)
			(xy 401.114393 -14.842166) (xy 401.07843 -14.793378) (xy 401.050631 -14.739519) (xy 401.031696 -14.681943)
			(xy 401.0221 -14.622097) (xy 401.02155 -14.591792) (xy 401.022062 -14.563953) (xy 401.030167 -14.508867)
			(xy 401.046187 -14.455542) (xy 401.069784 -14.405111) (xy 401.100457 -14.358642) (xy 401.137555 -14.317123)
			(xy 401.180291 -14.281433) (xy 401.227758 -14.252329) (xy 401.27895 -14.230431) (xy 401.33278 -14.216201)
			(xy 401.360386 -14.21257) (xy 401.369593 -14.211136) (xy 401.386142 -14.202609) (xy 401.398551 -14.18873)
			(xy 401.405179 -14.171333) (xy 401.405598 -14.162024) (xy 401.405598 -13.730986) (xy 401.405435 -13.724975)
			(xy 401.402618 -13.713289) (xy 401.40001 -13.707872) (xy 401.39817 -13.704398) (xy 401.393576 -13.698019)
			(xy 401.390866 -13.695172) (xy 401.08505 -13.389356) (xy 401.082201 -13.386647) (xy 401.075827 -13.382047)
			(xy 401.07235 -13.380212) (xy 401.066923 -13.377629) (xy 401.055243 -13.374806) (xy 401.049236 -13.374624)
			(xy 396.342616 -13.374624) (xy 396.336608 -13.374795) (xy 396.324929 -13.377627) (xy 396.319502 -13.380212)
			(xy 396.316027 -13.382051) (xy 396.309647 -13.386643) (xy 396.306802 -13.389356) (xy 395.000734 -14.695424)
			(xy 394.995522 -14.700337) (xy 394.98302 -14.707312) (xy 394.976096 -14.70914) (xy 394.972794 -14.709902)
			(xy 394.965175 -14.712599) (xy 394.951976 -14.721912) (xy 394.946886 -14.72819) (xy 394.915136 -14.775434)
			(xy 394.889228 -14.814042) (xy 394.888212 -14.824202) (xy 394.894816 -14.840458) (xy 394.919339 -14.901619)
			(xy 394.961691 -15.026412) (xy 394.996262 -15.153581) (xy 395.022919 -15.282641) (xy 395.041562 -15.4131)
			(xy 395.052119 -15.54446) (xy 395.05382 -15.610332) (xy 395.054074 -15.648686) (xy 395.054074 -15.649956)
			(xy 395.053547 -15.716978) (xy 395.045132 -15.850757) (xy 395.028338 -15.983744) (xy 395.003233 -16.115415)
			(xy 394.969914 -16.245252) (xy 394.928513 -16.372741) (xy 394.879193 -16.497382) (xy 394.822149 -16.618682)
			(xy 394.757605 -16.736163) (xy 394.685817 -16.849362) (xy 394.607066 -16.957833) (xy 394.521664 -17.061148)
			(xy 394.429946 -17.158901) (xy 394.381482 -17.205198) (xy 394.33217 -17.251111) (xy 394.228624 -17.33734)
			(xy 394.119843 -17.416866) (xy 394.006263 -17.48937) (xy 393.888334 -17.554565) (xy 393.766528 -17.61219)
			(xy 393.641329 -17.662016) (xy 393.513236 -17.703845) (xy 393.38276 -17.73751) (xy 393.250419 -17.762876)
			(xy 393.116742 -17.779843) (xy 392.982261 -17.788343) (xy 392.914886 -17.78889) (xy 392.850415 -17.788412)
			(xy 392.721708 -17.780626) (xy 392.593706 -17.765083) (xy 392.466876 -17.74184) (xy 392.341681 -17.710981)
			(xy 392.218578 -17.672619) (xy 392.098015 -17.626895) (xy 391.980433 -17.573975) (xy 391.866261 -17.514052)
			(xy 391.755915 -17.447344) (xy 391.649799 -17.374096) (xy 391.548298 -17.294574) (xy 391.451784 -17.209069)
			(xy 391.360609 -17.117892) (xy 391.275105 -17.021377) (xy 391.195585 -16.919876) (xy 391.122339 -16.813758)
			(xy 391.055633 -16.703411) (xy 390.995711 -16.589238) (xy 390.942793 -16.471655) (xy 390.89707 -16.351092)
			(xy 390.858711 -16.227988) (xy 390.827854 -16.102792) (xy 390.804612 -15.975962) (xy 390.789071 -15.84796)
			(xy 390.781287 -15.719253) (xy 390.780778 -15.654782) (xy 390.781328 -15.586451) (xy 390.790085 -15.45007)
			(xy 390.807555 -15.31453) (xy 390.833666 -15.180386) (xy 390.868312 -15.048188) (xy 390.91135 -14.91848)
			(xy 390.93648 -14.854936) (xy 390.939274 -14.845538) (xy 390.942068 -14.83106) (xy 390.941868 -14.825464)
			(xy 390.939307 -14.814566) (xy 390.936988 -14.80947) (xy 390.936988 -14.808962) (xy 390.93394 -14.803628)
			(xy 390.92251 -14.78661) (xy 390.886188 -14.732762) (xy 390.879625 -14.723967) (xy 390.860937 -14.712503)
			(xy 390.85012 -14.710664) (xy 390.845802 -14.71041) (xy 389.02894 -14.71041) (xy 389.020304 -14.711172)
			(xy 389.016263 -14.711959) (xy 389.008481 -14.714642) (xy 389.00481 -14.716506) (xy 389.00481 -14.71676)
			(xy 388.998311 -14.72066) (xy 388.987741 -14.731513) (xy 388.983982 -14.738096) (xy 388.943088 -14.818868)
			(xy 388.942834 -14.819376) (xy 388.93995 -14.825572) (xy 388.937241 -14.838963) (xy 388.9375 -14.845792)
			(xy 388.937754 -14.847062) (xy 388.950962 -14.865096) (xy 388.975608 -14.89961) (xy 389.019284 -14.972315)
			(xy 389.056232 -15.04866) (xy 389.08615 -15.128023) (xy 389.108795 -15.20976) (xy 389.123984 -15.293204)
			(xy 389.131591 -15.377678) (xy 389.132064 -15.420086) (xy 389.13151 -15.466593) (xy 389.122349 -15.559154)
			(xy 389.104095 -15.650359) (xy 389.076927 -15.739316) (xy 389.041109 -15.825157) (xy 389.019542 -15.866364)
			(xy 389.019542 -15.866618) (xy 389.016744 -15.872188) (xy 389.013669 -15.884264) (xy 389.013446 -15.890494)
			(xy 389.013446 -15.903194) (xy 389.05561 -15.981172) (xy 389.058744 -15.986666) (xy 389.067222 -15.996046)
			(xy 389.072374 -15.999714) (xy 389.083042 -16.006572) (xy 389.095996 -16.007588) (xy 389.140339 -16.011837)
			(xy 389.228044 -16.027459) (xy 389.313938 -16.05109) (xy 389.397291 -16.08253) (xy 389.477395 -16.121512)
			(xy 389.55357 -16.167705) (xy 389.625167 -16.220715) (xy 389.691578 -16.280093) (xy 389.75224 -16.345334)
			(xy 389.806637 -16.415884) (xy 389.854306 -16.491143) (xy 389.894843 -16.570471) (xy 389.927903 -16.653196)
			(xy 389.953205 -16.738613) (xy 389.970534 -16.825996) (xy 389.979744 -16.914605) (xy 389.980755 -17.003685)
			(xy 389.973559 -17.092479) (xy 389.958217 -17.180234) (xy 389.93486 -17.266203) (xy 389.903686 -17.349656)
			(xy 389.86496 -17.429884) (xy 389.81901 -17.506206) (xy 389.766229 -17.577972) (xy 389.707063 -17.644573)
			(xy 389.674862 -17.675352) (xy 389.674608 -17.675606) (xy 389.642355 -17.705532) (xy 389.573275 -17.760031)
			(xy 389.499524 -17.808021) (xy 389.421713 -17.849104) (xy 389.340488 -17.882938) (xy 389.256523 -17.909245)
			(xy 389.170512 -17.927804) (xy 389.08317 -17.938463) (xy 388.99522 -17.941133) (xy 388.907393 -17.935793)
			(xy 388.820415 -17.922485) (xy 388.735008 -17.901321) (xy 388.65188 -17.872477) (xy 388.57172 -17.83619)
			(xy 388.495193 -17.792763) (xy 388.422934 -17.742555) (xy 388.355541 -17.685982) (xy 388.293574 -17.623514)
			(xy 388.237545 -17.555668) (xy 388.187921 -17.483007) (xy 388.145111 -17.406133) (xy 388.109471 -17.325684)
			(xy 388.081296 -17.242327) (xy 388.06082 -17.156752) (xy 388.048213 -17.06967) (xy 388.04358 -16.981802)
			(xy 388.046958 -16.893876) (xy 388.05832 -16.806623) (xy 388.077571 -16.720765) (xy 388.104552 -16.637013)
			(xy 388.139039 -16.556063) (xy 388.159498 -16.517112) (xy 388.161022 -16.514064) (xy 388.163054 -16.509238)
			(xy 388.166822 -16.498311) (xy 388.165106 -16.475285) (xy 388.159752 -16.465042) (xy 388.157974 -16.462248)
			(xy 388.114794 -16.389858) (xy 388.112215 -16.385811) (xy 388.105825 -16.378653) (xy 388.102094 -16.375634)
			(xy 388.095308 -16.370721) (xy 388.079478 -16.365269) (xy 388.071106 -16.364966) (xy 386.33273 -16.364966)
			(xy 386.28929 -16.364481) (xy 386.202781 -16.356467) (xy 386.11738 -16.340506) (xy 386.033816 -16.316732)
			(xy 385.952802 -16.28535) (xy 385.875029 -16.246626) (xy 385.801161 -16.200892) (xy 385.731829 -16.148537)
			(xy 385.667622 -16.090007) (xy 385.60909 -16.025804) (xy 385.556732 -15.956473) (xy 385.510994 -15.882607)
			(xy 385.472267 -15.804837) (xy 385.440881 -15.723824) (xy 385.417104 -15.640261) (xy 385.401139 -15.554861)
			(xy 385.393121 -15.468352) (xy 385.392676 -15.424912) (xy 385.392676 -15.424404) (xy 385.39315 -15.38219)
			(xy 385.400748 -15.298103) (xy 385.415856 -15.215037) (xy 385.438352 -15.13366) (xy 385.468056 -15.054629)
			(xy 385.504727 -14.97858) (xy 385.548071 -14.906126) (xy 385.572508 -14.8717) (xy 385.576826 -14.865858)
			(xy 385.581398 -14.853158) (xy 385.58216 -14.845792) (xy 385.582435 -14.838817) (xy 385.579605 -14.825154)
			(xy 385.576572 -14.818868) (xy 385.570984 -14.807946) (xy 385.5339 -14.734794) (xy 385.530764 -14.730129)
			(xy 385.522812 -14.722189) (xy 385.518152 -14.719046) (xy 385.51231 -14.715744) (xy 385.507045 -14.713302)
			(xy 385.495759 -14.710602) (xy 385.489958 -14.71041) (xy 376.169428 -14.71041) (xy 376.163419 -14.71058)
			(xy 376.151739 -14.713409) (xy 376.146314 -14.715998) (xy 376.142838 -14.717836) (xy 376.136456 -14.722426)
			(xy 376.133614 -14.725142) (xy 375.938796 -14.91996) (xy 375.93217 -14.927285) (xy 375.924573 -14.945498)
			(xy 375.924402 -14.965231) (xy 375.92762 -14.97457) (xy 375.945146 -15.01394) (xy 375.96826 -15.065502)
			(xy 375.971114 -15.07074) (xy 375.978814 -15.079846) (xy 375.9835 -15.083536) (xy 375.98731 -15.085822)
			(xy 375.990466 -15.087773) (xy 375.997225 -15.090831) (xy 376.000772 -15.091918) (xy 376.007376 -15.093696)
			(xy 376.012202 -15.093442) (xy 376.03684 -15.09268) (xy 376.06409 -15.093169) (xy 376.118035 -15.10093)
			(xy 376.170327 -15.116289) (xy 376.219901 -15.138933) (xy 376.265748 -15.168401) (xy 376.306934 -15.204094)
			(xy 376.342623 -15.245285) (xy 376.372086 -15.291134) (xy 376.394725 -15.340711) (xy 376.410079 -15.393004)
			(xy 376.417834 -15.44695) (xy 376.417834 -15.50145) (xy 376.410079 -15.555396) (xy 376.394725 -15.607689)
			(xy 376.372086 -15.657266) (xy 376.342623 -15.703115) (xy 376.306934 -15.744306) (xy 376.265748 -15.779999)
			(xy 376.219901 -15.809467) (xy 376.170327 -15.832111) (xy 376.118035 -15.84747) (xy 376.06409 -15.855231)
			(xy 376.03684 -15.855696) (xy 376.006849 -15.855144) (xy 375.947606 -15.845758) (xy 375.890569 -15.827195)
			(xy 375.863612 -15.81404) (xy 375.863358 -15.81404) (xy 375.863104 -15.813786) (xy 375.857306 -15.811126)
			(xy 375.844844 -15.808419) (xy 375.838466 -15.808452) (xy 375.825512 -15.80896) (xy 375.751852 -15.853918)
			(xy 375.751344 -15.854426) (xy 375.737882 -15.862808) (xy 375.728136 -15.870378) (xy 375.716601 -15.892149)
			(xy 375.715784 -15.904464) (xy 375.715784 -18.44421) (xy 396.576294 -18.44421) (xy 396.580365 -18.388588)
			(xy 396.592491 -18.334151) (xy 396.612414 -18.28206) (xy 396.63971 -18.233425) (xy 396.673796 -18.189282)
			(xy 396.713945 -18.150573) (xy 396.759303 -18.118122) (xy 396.808903 -18.092621) (xy 396.861687 -18.074614)
			(xy 396.91653 -18.064484) (xy 396.972264 -18.062447) (xy 397.027701 -18.068547) (xy 397.081658 -18.082653)
			(xy 397.132987 -18.104465) (xy 397.180593 -18.133519) (xy 397.223461 -18.169194) (xy 397.260678 -18.210731)
			(xy 397.291451 -18.257244) (xy 397.315123 -18.307741) (xy 397.331191 -18.361148) (xy 397.339311 -18.416324)
			(xy 397.33982 -18.44421) (xy 397.339311 -18.472096) (xy 397.331191 -18.527272) (xy 397.315123 -18.580679)
			(xy 397.291451 -18.631176) (xy 397.260678 -18.677689) (xy 397.223461 -18.719226) (xy 397.180593 -18.754901)
			(xy 397.132987 -18.783955) (xy 397.081658 -18.805767) (xy 397.027701 -18.819873) (xy 396.972264 -18.825973)
			(xy 396.91653 -18.823936) (xy 396.861687 -18.813806) (xy 396.808903 -18.795799) (xy 396.759303 -18.770298)
			(xy 396.713945 -18.737847) (xy 396.673796 -18.699138) (xy 396.63971 -18.654995) (xy 396.612414 -18.60636)
			(xy 396.592491 -18.554269) (xy 396.580365 -18.499832) (xy 396.576294 -18.44421) (xy 375.715784 -18.44421)
			(xy 375.715784 -20.72005) (xy 379.48541 -20.72005) (xy 379.48938 -20.589916) (xy 379.501276 -20.460266)
			(xy 379.521055 -20.331583) (xy 379.548641 -20.204344) (xy 379.583934 -20.079025) (xy 379.6268 -19.956089)
			(xy 379.677082 -19.835996) (xy 379.734591 -19.719192) (xy 379.799115 -19.60611) (xy 379.870412 -19.497173)
			(xy 379.948217 -19.392785) (xy 380.032242 -19.293334) (xy 380.122174 -19.199191) (xy 380.217678 -19.110706)
			(xy 380.318398 -19.028207) (xy 380.42396 -18.952002) (xy 380.533972 -18.882375) (xy 380.648024 -18.819584)
			(xy 380.765692 -18.763862) (xy 380.886538 -18.715418) (xy 381.010113 -18.674431) (xy 381.135956 -18.641054)
			(xy 381.263601 -18.615411) (xy 381.392571 -18.597597) (xy 381.522387 -18.587679) (xy 381.652566 -18.585694)
			(xy 381.782625 -18.591648) (xy 381.912078 -18.605521) (xy 382.040445 -18.627259) (xy 382.167248 -18.656783)
			(xy 382.292015 -18.693982) (xy 382.414282 -18.738718) (xy 382.533595 -18.790826) (xy 382.649508 -18.850109)
			(xy 382.761593 -18.91635) (xy 382.86943 -18.9893) (xy 382.972619 -19.068688) (xy 383.070777 -19.15422)
			(xy 383.163538 -19.245577) (xy 383.250557 -19.342419) (xy 383.33151 -19.444386) (xy 383.406096 -19.551098)
			(xy 383.474037 -19.662159) (xy 383.535082 -19.777155) (xy 383.589003 -19.895659) (xy 383.635598 -20.01723)
			(xy 383.674696 -20.141415) (xy 383.70615 -20.267753) (xy 383.729844 -20.395774) (xy 383.745688 -20.525)
			(xy 383.753626 -20.654953) (xy 383.754122 -20.72005) (xy 383.753626 -20.785147) (xy 383.745688 -20.9151)
			(xy 383.729844 -21.044326) (xy 383.70615 -21.172347) (xy 383.674696 -21.298685) (xy 383.635598 -21.42287)
			(xy 383.589003 -21.544441) (xy 383.535082 -21.662945) (xy 383.495061 -21.738336) (xy 385.71678 -21.738336)
			(xy 385.71727 -21.709596) (xy 385.725902 -21.652767) (xy 385.74296 -21.597876) (xy 385.768059 -21.546165)
			(xy 385.80063 -21.498804) (xy 385.819904 -21.477478) (xy 385.826508 -21.47062) (xy 385.83362 -21.452586)
			(xy 385.83362 -21.363686) (xy 385.826508 -21.345652) (xy 385.819904 -21.338794) (xy 385.80067 -21.317436)
			(xy 385.768105 -21.270078) (xy 385.743013 -21.218371) (xy 385.725961 -21.163486) (xy 385.717336 -21.106663)
			(xy 385.717332 -21.049189) (xy 385.725949 -20.992366) (xy 385.742994 -20.937478) (xy 385.768079 -20.885767)
			(xy 385.800637 -20.838405) (xy 385.819904 -20.817078) (xy 385.826508 -20.81022) (xy 385.83362 -20.792186)
			(xy 385.83362 -20.703286) (xy 385.826508 -20.685252) (xy 385.819904 -20.678394) (xy 385.80067 -20.657036)
			(xy 385.768105 -20.609678) (xy 385.743013 -20.557971) (xy 385.725961 -20.503086) (xy 385.717336 -20.446263)
			(xy 385.717332 -20.388789) (xy 385.725949 -20.331966) (xy 385.742994 -20.277078) (xy 385.768079 -20.225367)
			(xy 385.800637 -20.178005) (xy 385.819904 -20.156678) (xy 385.826508 -20.14982) (xy 385.83362 -20.131786)
			(xy 385.83362 -20.042886) (xy 385.826508 -20.024852) (xy 385.819904 -20.017994) (xy 385.80067 -19.996636)
			(xy 385.768105 -19.949278) (xy 385.743013 -19.897571) (xy 385.725961 -19.842686) (xy 385.717336 -19.785863)
			(xy 385.717332 -19.728389) (xy 385.725949 -19.671566) (xy 385.742994 -19.616678) (xy 385.768079 -19.564967)
			(xy 385.800637 -19.517605) (xy 385.819904 -19.496278) (xy 385.826508 -19.48942) (xy 385.83362 -19.471386)
			(xy 385.83362 -19.382486) (xy 385.826508 -19.364452) (xy 385.819904 -19.357594) (xy 385.800662 -19.336242)
			(xy 385.768089 -19.288888) (xy 385.74299 -19.237183) (xy 385.725933 -19.182297) (xy 385.717304 -19.125473)
			(xy 385.71678 -19.096736) (xy 385.717266 -19.069485) (xy 385.725022 -19.015537) (xy 385.740377 -18.963242)
			(xy 385.763019 -18.913665) (xy 385.792485 -18.867815) (xy 385.828176 -18.826624) (xy 385.869367 -18.790933)
			(xy 385.915217 -18.761467) (xy 385.964794 -18.738825) (xy 386.017089 -18.72347) (xy 386.071037 -18.715714)
			(xy 386.125539 -18.715714) (xy 386.179487 -18.72347) (xy 386.231782 -18.738825) (xy 386.281359 -18.761467)
			(xy 386.327209 -18.790933) (xy 386.3684 -18.826624) (xy 386.404091 -18.867815) (xy 386.433557 -18.913665)
			(xy 386.456199 -18.963242) (xy 386.471554 -19.015537) (xy 386.47931 -19.069485) (xy 386.479796 -19.096736)
			(xy 386.479295 -19.125476) (xy 386.470667 -19.182304) (xy 386.453612 -19.237195) (xy 386.428515 -19.288907)
			(xy 386.395945 -19.336268) (xy 386.376672 -19.357594) (xy 386.370068 -19.364452) (xy 386.362956 -19.382486)
			(xy 386.362956 -19.471386) (xy 386.370068 -19.48942) (xy 386.376672 -19.496278) (xy 386.395979 -19.517574)
			(xy 386.428543 -19.564941) (xy 386.453633 -19.616658) (xy 386.470681 -19.671554) (xy 386.4793 -19.728385)
			(xy 386.479296 -19.785867) (xy 386.470669 -19.842698) (xy 386.453614 -19.897591) (xy 386.428517 -19.949304)
			(xy 386.395946 -19.996667) (xy 386.376672 -20.017994) (xy 386.370068 -20.024852) (xy 386.362956 -20.042886)
			(xy 386.362956 -20.131786) (xy 386.370068 -20.14982) (xy 386.376672 -20.156678) (xy 386.395979 -20.177974)
			(xy 386.428543 -20.225341) (xy 386.453633 -20.277058) (xy 386.470681 -20.331954) (xy 386.4793 -20.388785)
			(xy 386.479296 -20.446267) (xy 386.470669 -20.503098) (xy 386.453614 -20.557991) (xy 386.428517 -20.609704)
			(xy 386.395946 -20.657067) (xy 386.376672 -20.678394) (xy 386.370068 -20.685252) (xy 386.362956 -20.703286)
			(xy 386.362956 -20.792186) (xy 386.370068 -20.81022) (xy 386.376672 -20.817078) (xy 386.395979 -20.838374)
			(xy 386.428543 -20.885741) (xy 386.453633 -20.937458) (xy 386.470681 -20.992354) (xy 386.4793 -21.049185)
			(xy 386.479296 -21.106667) (xy 386.470669 -21.163498) (xy 386.453614 -21.218391) (xy 386.428517 -21.270104)
			(xy 386.395946 -21.317467) (xy 386.376672 -21.338794) (xy 386.370068 -21.345652) (xy 386.362956 -21.363686)
			(xy 386.362956 -21.452586) (xy 386.370068 -21.47062) (xy 386.376672 -21.477478) (xy 386.395961 -21.498789)
			(xy 386.428525 -21.546155) (xy 386.453613 -21.597871) (xy 386.47066 -21.652766) (xy 386.479278 -21.709596)
			(xy 386.47959 -21.726906) (xy 390.37387 -21.726906) (xy 390.374405 -21.698168) (xy 390.383026 -21.641341)
			(xy 390.400074 -21.586451) (xy 390.425163 -21.534739) (xy 390.457725 -21.487376) (xy 390.476994 -21.466048)
			(xy 390.483598 -21.45919) (xy 390.49071 -21.441156) (xy 390.49071 -21.352256) (xy 390.483598 -21.334222)
			(xy 390.476994 -21.327364) (xy 390.45773 -21.306031) (xy 390.425168 -21.258669) (xy 390.400078 -21.206958)
			(xy 390.383029 -21.152068) (xy 390.374406 -21.095243) (xy 390.374406 -21.037766) (xy 390.383027 -20.98094)
			(xy 390.400074 -20.92605) (xy 390.425163 -20.874339) (xy 390.457725 -20.826975) (xy 390.476994 -20.805648)
			(xy 390.483598 -20.79879) (xy 390.49071 -20.780756) (xy 390.49071 -20.691856) (xy 390.483598 -20.673822)
			(xy 390.476994 -20.666964) (xy 390.45773 -20.645631) (xy 390.425168 -20.598269) (xy 390.400078 -20.546558)
			(xy 390.383029 -20.491668) (xy 390.374406 -20.434843) (xy 390.374406 -20.377366) (xy 390.383027 -20.32054)
			(xy 390.400074 -20.26565) (xy 390.425163 -20.213939) (xy 390.457725 -20.166575) (xy 390.476994 -20.145248)
			(xy 390.483598 -20.13839) (xy 390.49071 -20.120356) (xy 390.49071 -20.031456) (xy 390.483598 -20.013422)
			(xy 390.476994 -20.006564) (xy 390.45773 -19.985231) (xy 390.425168 -19.937869) (xy 390.400078 -19.886158)
			(xy 390.383029 -19.831268) (xy 390.374406 -19.774443) (xy 390.374406 -19.716966) (xy 390.383027 -19.66014)
			(xy 390.400074 -19.60525) (xy 390.425163 -19.553539) (xy 390.457725 -19.506175) (xy 390.476994 -19.484848)
			(xy 390.483598 -19.47799) (xy 390.49071 -19.459956) (xy 390.49071 -19.371056) (xy 390.483598 -19.353022)
			(xy 390.476994 -19.346164) (xy 390.457736 -19.324826) (xy 390.425166 -19.277468) (xy 390.40007 -19.225759)
			(xy 390.383017 -19.17087) (xy 390.374392 -19.114044) (xy 390.37387 -19.085306) (xy 390.374356 -19.058055)
			(xy 390.382112 -19.004107) (xy 390.397467 -18.951812) (xy 390.420109 -18.902235) (xy 390.449575 -18.856385)
			(xy 390.485266 -18.815194) (xy 390.526457 -18.779503) (xy 390.572307 -18.750037) (xy 390.621884 -18.727395)
			(xy 390.674179 -18.71204) (xy 390.728127 -18.704284) (xy 390.782629 -18.704284) (xy 390.836577 -18.71204)
			(xy 390.888872 -18.727395) (xy 390.938449 -18.750037) (xy 390.984299 -18.779503) (xy 391.02549 -18.815194)
			(xy 391.061181 -18.856385) (xy 391.090647 -18.902235) (xy 391.113289 -18.951812) (xy 391.128644 -19.004107)
			(xy 391.1364 -19.058055) (xy 391.136886 -19.085306) (xy 391.136343 -19.114044) (xy 391.127722 -19.170869)
			(xy 391.110675 -19.225759) (xy 391.085588 -19.277471) (xy 391.053029 -19.324835) (xy 391.033762 -19.346164)
			(xy 391.027158 -19.353022) (xy 391.021702 -19.366857) (xy 395.879215 -19.366857) (xy 395.879215 -19.312343)
			(xy 395.886973 -19.258385) (xy 395.902332 -19.20608) (xy 395.924978 -19.156493) (xy 395.954451 -19.110634)
			(xy 395.990151 -19.069437) (xy 396.03135 -19.033739) (xy 396.077211 -19.004269) (xy 396.126799 -18.981625)
			(xy 396.179105 -18.966269) (xy 396.233063 -18.958514) (xy 396.26032 -18.958052) (xy 396.287091 -18.958512)
			(xy 396.340106 -18.966013) (xy 396.391553 -18.980849) (xy 396.44042 -19.002731) (xy 396.485749 -19.031228)
			(xy 396.526651 -19.065782) (xy 396.562321 -19.105712) (xy 396.577566 -19.127724) (xy 396.57782 -19.127978)
			(xy 396.584034 -19.136386) (xy 396.601626 -19.147654) (xy 396.611856 -19.149822) (xy 396.685008 -19.16176)
			(xy 396.695456 -19.162928) (xy 396.715791 -19.157667) (xy 396.724378 -19.1516) (xy 396.744514 -19.136503)
			(xy 396.787987 -19.111148) (xy 396.83442 -19.091737) (xy 396.883005 -19.078609) (xy 396.932894 -19.071991)
			(xy 396.958058 -19.07159) (xy 396.958312 -19.07159) (xy 396.985563 -19.072081) (xy 397.039509 -19.079838)
			(xy 397.091802 -19.095195) (xy 397.141377 -19.117836) (xy 397.187226 -19.147303) (xy 397.228414 -19.182994)
			(xy 397.264104 -19.224184) (xy 397.29357 -19.270033) (xy 397.31621 -19.31961) (xy 397.331564 -19.371903)
			(xy 397.33932 -19.425849) (xy 397.33932 -19.480351) (xy 397.331564 -19.534297) (xy 397.31621 -19.58659)
			(xy 397.29357 -19.636167) (xy 397.264104 -19.682016) (xy 397.228414 -19.723206) (xy 397.187226 -19.758897)
			(xy 397.141377 -19.788364) (xy 397.091802 -19.811005) (xy 397.039509 -19.826362) (xy 396.985563 -19.834119)
			(xy 396.958312 -19.834606) (xy 396.931541 -19.83414) (xy 396.878525 -19.826643) (xy 396.827078 -19.811809)
			(xy 396.77821 -19.789928) (xy 396.73288 -19.761432) (xy 396.691979 -19.726878) (xy 396.65631 -19.686946)
			(xy 396.641066 -19.664934) (xy 396.640812 -19.66468) (xy 396.634572 -19.656294) (xy 396.617 -19.645013)
			(xy 396.606776 -19.642836) (xy 396.533624 -19.630898) (xy 396.523175 -19.629737) (xy 396.502841 -19.634991)
			(xy 396.494254 -19.641058) (xy 396.474136 -19.65618) (xy 396.430658 -19.681532) (xy 396.384221 -19.700938)
			(xy 396.335632 -19.714061) (xy 396.285739 -19.720672) (xy 396.260574 -19.721068) (xy 396.26032 -19.721068)
			(xy 396.233063 -19.720686) (xy 396.179105 -19.712931) (xy 396.126799 -19.697575) (xy 396.077211 -19.674931)
			(xy 396.03135 -19.645461) (xy 395.990151 -19.609763) (xy 395.954451 -19.568566) (xy 395.924978 -19.522707)
			(xy 395.902332 -19.47312) (xy 395.886973 -19.420815) (xy 395.879215 -19.366857) (xy 391.021702 -19.366857)
			(xy 391.020046 -19.371056) (xy 391.020046 -19.459956) (xy 391.027158 -19.47799) (xy 391.033762 -19.484848)
			(xy 391.053039 -19.506169) (xy 391.085606 -19.553532) (xy 391.110698 -19.605245) (xy 391.127748 -19.660137)
			(xy 391.13637 -19.716965) (xy 391.13637 -19.774444) (xy 391.127746 -19.831272) (xy 391.110695 -19.886163)
			(xy 391.085601 -19.937875) (xy 391.053034 -19.985238) (xy 391.033762 -20.006564) (xy 391.027158 -20.013422)
			(xy 391.020046 -20.031456) (xy 391.020046 -20.120356) (xy 391.027158 -20.13839) (xy 391.033762 -20.145248)
			(xy 391.053039 -20.166569) (xy 391.085606 -20.213932) (xy 391.110698 -20.265645) (xy 391.127748 -20.320537)
			(xy 391.133062 -20.35556) (xy 395.878302 -20.35556) (xy 395.882373 -20.299938) (xy 395.894499 -20.245501)
			(xy 395.914422 -20.19341) (xy 395.941718 -20.144775) (xy 395.975804 -20.100632) (xy 396.015953 -20.061923)
			(xy 396.061311 -20.029472) (xy 396.110911 -20.003971) (xy 396.163695 -19.985964) (xy 396.218538 -19.975834)
			(xy 396.274272 -19.973797) (xy 396.329709 -19.979897) (xy 396.383666 -19.994003) (xy 396.434995 -20.015815)
			(xy 396.482601 -20.044869) (xy 396.525469 -20.080544) (xy 396.562686 -20.122081) (xy 396.593459 -20.168594)
			(xy 396.617131 -20.219091) (xy 396.633199 -20.272498) (xy 396.641319 -20.327674) (xy 396.641828 -20.35556)
			(xy 396.641319 -20.383446) (xy 396.633199 -20.438622) (xy 396.617131 -20.492029) (xy 396.593459 -20.542526)
			(xy 396.562686 -20.589039) (xy 396.525469 -20.630576) (xy 396.482601 -20.666251) (xy 396.434995 -20.695305)
			(xy 396.383666 -20.717117) (xy 396.329709 -20.731223) (xy 396.274272 -20.737323) (xy 396.218538 -20.735286)
			(xy 396.163695 -20.725156) (xy 396.110911 -20.707149) (xy 396.061311 -20.681648) (xy 396.015953 -20.649197)
			(xy 395.975804 -20.610488) (xy 395.941718 -20.566345) (xy 395.914422 -20.51771) (xy 395.894499 -20.465619)
			(xy 395.882373 -20.411182) (xy 395.878302 -20.35556) (xy 391.133062 -20.35556) (xy 391.13637 -20.377365)
			(xy 391.13637 -20.434844) (xy 391.127746 -20.491672) (xy 391.110695 -20.546563) (xy 391.085601 -20.598275)
			(xy 391.053034 -20.645638) (xy 391.033762 -20.666964) (xy 391.027158 -20.673822) (xy 391.020046 -20.691856)
			(xy 391.020046 -20.780756) (xy 391.027158 -20.79879) (xy 391.033762 -20.805648) (xy 391.053039 -20.826969)
			(xy 391.085606 -20.874332) (xy 391.110698 -20.926045) (xy 391.127748 -20.980937) (xy 391.13637 -21.037765)
			(xy 391.13637 -21.095244) (xy 391.127746 -21.152072) (xy 391.110695 -21.206963) (xy 391.085601 -21.258675)
			(xy 391.053034 -21.306038) (xy 391.033762 -21.327364) (xy 391.027158 -21.334222) (xy 391.020046 -21.352256)
			(xy 391.020046 -21.37156) (xy 395.878302 -21.37156) (xy 395.882373 -21.315938) (xy 395.894499 -21.261501)
			(xy 395.914422 -21.20941) (xy 395.941718 -21.160775) (xy 395.975804 -21.116632) (xy 396.015953 -21.077923)
			(xy 396.061311 -21.045472) (xy 396.110911 -21.019971) (xy 396.163695 -21.001964) (xy 396.218538 -20.991834)
			(xy 396.274272 -20.989797) (xy 396.329709 -20.995897) (xy 396.383666 -21.010003) (xy 396.434995 -21.031815)
			(xy 396.482601 -21.060869) (xy 396.525469 -21.096544) (xy 396.562686 -21.138081) (xy 396.593459 -21.184594)
			(xy 396.617131 -21.235091) (xy 396.633199 -21.288498) (xy 396.641319 -21.343674) (xy 396.641828 -21.37156)
			(xy 396.641319 -21.399446) (xy 396.633199 -21.454622) (xy 396.617131 -21.508029) (xy 396.593459 -21.558526)
			(xy 396.562686 -21.605039) (xy 396.525469 -21.646576) (xy 396.482601 -21.682251) (xy 396.434995 -21.711305)
			(xy 396.383666 -21.733117) (xy 396.329709 -21.747223) (xy 396.274272 -21.753323) (xy 396.218538 -21.751286)
			(xy 396.163695 -21.741156) (xy 396.110911 -21.723149) (xy 396.061311 -21.697648) (xy 396.015953 -21.665197)
			(xy 395.975804 -21.626488) (xy 395.941718 -21.582345) (xy 395.914422 -21.53371) (xy 395.894499 -21.481619)
			(xy 395.882373 -21.427182) (xy 395.878302 -21.37156) (xy 391.020046 -21.37156) (xy 391.020046 -21.441156)
			(xy 391.027158 -21.45919) (xy 391.033762 -21.466048) (xy 391.053036 -21.487373) (xy 391.085601 -21.534735)
			(xy 391.110693 -21.586448) (xy 391.127743 -21.641339) (xy 391.136365 -21.698167) (xy 391.136886 -21.726906)
			(xy 391.1364 -21.754157) (xy 391.133307 -21.775674) (xy 400.235926 -21.775674) (xy 400.239997 -21.720052)
			(xy 400.252123 -21.665615) (xy 400.272046 -21.613524) (xy 400.299342 -21.564889) (xy 400.333428 -21.520746)
			(xy 400.373577 -21.482037) (xy 400.418935 -21.449586) (xy 400.468535 -21.424085) (xy 400.521319 -21.406078)
			(xy 400.576162 -21.395948) (xy 400.631896 -21.393911) (xy 400.687333 -21.400011) (xy 400.74129 -21.414117)
			(xy 400.792619 -21.435929) (xy 400.840225 -21.464983) (xy 400.883093 -21.500658) (xy 400.92031 -21.542195)
			(xy 400.951083 -21.588708) (xy 400.974755 -21.639205) (xy 400.990823 -21.692612) (xy 400.998943 -21.747788)
			(xy 400.999452 -21.775674) (xy 400.998943 -21.80356) (xy 400.990823 -21.858736) (xy 400.974755 -21.912143)
			(xy 400.951083 -21.96264) (xy 400.92031 -22.009153) (xy 400.883093 -22.05069) (xy 400.840225 -22.086365)
			(xy 400.792619 -22.115419) (xy 400.74129 -22.137231) (xy 400.687333 -22.151337) (xy 400.631896 -22.157437)
			(xy 400.576162 -22.1554) (xy 400.521319 -22.14527) (xy 400.468535 -22.127263) (xy 400.418935 -22.101762)
			(xy 400.373577 -22.069311) (xy 400.333428 -22.030602) (xy 400.299342 -21.986459) (xy 400.272046 -21.937824)
			(xy 400.252123 -21.885733) (xy 400.239997 -21.831296) (xy 400.235926 -21.775674) (xy 391.133307 -21.775674)
			(xy 391.128644 -21.808105) (xy 391.113289 -21.8604) (xy 391.090647 -21.909977) (xy 391.061181 -21.955827)
			(xy 391.02549 -21.997018) (xy 390.984299 -22.032709) (xy 390.938449 -22.062175) (xy 390.888872 -22.084817)
			(xy 390.836577 -22.100172) (xy 390.782629 -22.107928) (xy 390.728127 -22.107928) (xy 390.674179 -22.100172)
			(xy 390.621884 -22.084817) (xy 390.572307 -22.062175) (xy 390.526457 -22.032709) (xy 390.485266 -21.997018)
			(xy 390.449575 -21.955827) (xy 390.420109 -21.909977) (xy 390.397467 -21.8604) (xy 390.382112 -21.808105)
			(xy 390.374356 -21.754157) (xy 390.37387 -21.726906) (xy 386.47959 -21.726906) (xy 386.479796 -21.738336)
			(xy 386.47931 -21.765587) (xy 386.471554 -21.819535) (xy 386.456199 -21.87183) (xy 386.433557 -21.921407)
			(xy 386.404091 -21.967257) (xy 386.3684 -22.008448) (xy 386.327209 -22.044139) (xy 386.281359 -22.073605)
			(xy 386.231782 -22.096247) (xy 386.179487 -22.111602) (xy 386.125539 -22.119358) (xy 386.071037 -22.119358)
			(xy 386.017089 -22.111602) (xy 385.964794 -22.096247) (xy 385.915217 -22.073605) (xy 385.869367 -22.044139)
			(xy 385.828176 -22.008448) (xy 385.792485 -21.967257) (xy 385.763019 -21.921407) (xy 385.740377 -21.87183)
			(xy 385.725022 -21.819535) (xy 385.717266 -21.765587) (xy 385.71678 -21.738336) (xy 383.495061 -21.738336)
			(xy 383.474037 -21.777941) (xy 383.406096 -21.889002) (xy 383.33151 -21.995714) (xy 383.250557 -22.097681)
			(xy 383.163538 -22.194523) (xy 383.070777 -22.28588) (xy 382.972619 -22.371412) (xy 382.86943 -22.4508)
			(xy 382.761593 -22.52375) (xy 382.649508 -22.589991) (xy 382.533595 -22.649274) (xy 382.414282 -22.701382)
			(xy 382.292015 -22.746118) (xy 382.167248 -22.783317) (xy 382.040445 -22.812841) (xy 381.912078 -22.834579)
			(xy 381.782625 -22.848452) (xy 381.652566 -22.854406) (xy 381.522387 -22.852421) (xy 381.392571 -22.842503)
			(xy 381.263601 -22.824689) (xy 381.135956 -22.799046) (xy 381.010113 -22.765669) (xy 380.886538 -22.724682)
			(xy 380.765692 -22.676238) (xy 380.648024 -22.620516) (xy 380.533972 -22.557725) (xy 380.42396 -22.488098)
			(xy 380.318398 -22.411893) (xy 380.217678 -22.329394) (xy 380.122174 -22.240909) (xy 380.032242 -22.146766)
			(xy 379.948217 -22.047315) (xy 379.870412 -21.942927) (xy 379.799115 -21.83399) (xy 379.734591 -21.720908)
			(xy 379.677082 -21.604104) (xy 379.6268 -21.484011) (xy 379.583934 -21.361075) (xy 379.548641 -21.235756)
			(xy 379.521055 -21.108517) (xy 379.501276 -20.979834) (xy 379.48938 -20.850184) (xy 379.48541 -20.72005)
			(xy 375.715784 -20.72005) (xy 375.715784 -21.50364) (xy 375.716688 -21.511872) (xy 375.723042 -21.527156)
			(xy 375.72823 -21.533612) (xy 375.733056 -21.538438) (xy 375.73458 -21.539708) (xy 375.758022 -21.556196)
			(xy 375.800145 -21.595056) (xy 375.835982 -21.639779) (xy 375.864728 -21.689359) (xy 375.885735 -21.742679)
			(xy 375.898533 -21.798542) (xy 375.902181 -21.847048) (xy 376.37288 -21.847048) (xy 376.376951 -21.791426)
			(xy 376.389077 -21.736989) (xy 376.409 -21.684898) (xy 376.436296 -21.636263) (xy 376.470382 -21.59212)
			(xy 376.510531 -21.553411) (xy 376.555889 -21.52096) (xy 376.605489 -21.495459) (xy 376.658273 -21.477452)
			(xy 376.713116 -21.467322) (xy 376.76885 -21.465285) (xy 376.824287 -21.471385) (xy 376.878244 -21.485491)
			(xy 376.929573 -21.507303) (xy 376.977179 -21.536357) (xy 377.020047 -21.572032) (xy 377.057264 -21.613569)
			(xy 377.088037 -21.660082) (xy 377.111709 -21.710579) (xy 377.127777 -21.763986) (xy 377.135897 -21.819162)
			(xy 377.136406 -21.847048) (xy 377.135897 -21.874934) (xy 377.127777 -21.93011) (xy 377.111709 -21.983517)
			(xy 377.088037 -22.034014) (xy 377.057264 -22.080527) (xy 377.020047 -22.122064) (xy 376.977179 -22.157739)
			(xy 376.929573 -22.186793) (xy 376.878244 -22.208605) (xy 376.824287 -22.222711) (xy 376.76885 -22.228811)
			(xy 376.713116 -22.226774) (xy 376.658273 -22.216644) (xy 376.605489 -22.198637) (xy 376.555889 -22.173136)
			(xy 376.510531 -22.140685) (xy 376.470382 -22.101976) (xy 376.436296 -22.057833) (xy 376.409 -22.009198)
			(xy 376.389077 -21.957107) (xy 376.376951 -21.90267) (xy 376.37288 -21.847048) (xy 375.902181 -21.847048)
			(xy 375.902831 -21.855691) (xy 375.898535 -21.91284) (xy 375.885741 -21.968703) (xy 375.864735 -22.022025)
			(xy 375.835992 -22.071606) (xy 375.800157 -22.116331) (xy 375.758036 -22.155193) (xy 375.73458 -22.17166)
			(xy 375.726734 -22.178659) (xy 375.717035 -22.197288) (xy 375.715784 -22.207728) (xy 375.715784 -23.0251)
			(xy 385.662422 -23.0251) (xy 385.666493 -22.969478) (xy 385.678619 -22.915041) (xy 385.698542 -22.86295)
			(xy 385.725838 -22.814315) (xy 385.759924 -22.770172) (xy 385.800073 -22.731463) (xy 385.845431 -22.699012)
			(xy 385.895031 -22.673511) (xy 385.947815 -22.655504) (xy 386.002658 -22.645374) (xy 386.058392 -22.643337)
			(xy 386.113829 -22.649437) (xy 386.167786 -22.663543) (xy 386.219115 -22.685355) (xy 386.266721 -22.714409)
			(xy 386.309589 -22.750084) (xy 386.346806 -22.791621) (xy 386.377579 -22.838134) (xy 386.401251 -22.888631)
			(xy 386.417319 -22.942038) (xy 386.425439 -22.997214) (xy 386.425948 -23.0251) (xy 386.425439 -23.052986)
			(xy 386.417319 -23.108162) (xy 386.401251 -23.161569) (xy 386.377579 -23.212066) (xy 386.346806 -23.258579)
			(xy 386.309589 -23.300116) (xy 386.266721 -23.335791) (xy 386.219115 -23.364845) (xy 386.167786 -23.386657)
			(xy 386.113829 -23.400763) (xy 386.058392 -23.406863) (xy 386.002658 -23.404826) (xy 385.947815 -23.394696)
			(xy 385.895031 -23.376689) (xy 385.845431 -23.351188) (xy 385.800073 -23.318737) (xy 385.759924 -23.280028)
			(xy 385.725838 -23.235885) (xy 385.698542 -23.18725) (xy 385.678619 -23.135159) (xy 385.666493 -23.080722)
			(xy 385.662422 -23.0251) (xy 375.715784 -23.0251) (xy 375.715784 -23.493984) (xy 375.716038 -23.49881)
			(xy 375.716931 -23.505821) (xy 375.722076 -23.518978) (xy 375.726198 -23.524718) (xy 375.72696 -23.52548)
			(xy 375.730516 -23.529544) (xy 375.751852 -23.551134) (xy 375.753122 -23.552404) (xy 375.759882 -23.558215)
			(xy 375.776256 -23.56523) (xy 375.785126 -23.56612) (xy 375.813882 -23.568365) (xy 375.870284 -23.580427)
			(xy 375.924228 -23.60084) (xy 375.974486 -23.629141) (xy 376.019911 -23.664683) (xy 376.059469 -23.706657)
			(xy 376.092259 -23.754107) (xy 376.117534 -23.805952) (xy 376.134718 -23.86101) (xy 376.143419 -23.918027)
			(xy 376.144028 -23.946866) (xy 376.144282 -23.946866) (xy 376.143845 -23.970996) (xy 376.37288 -23.970996)
			(xy 376.376951 -23.915374) (xy 376.389077 -23.860937) (xy 376.409 -23.808846) (xy 376.436296 -23.760211)
			(xy 376.470382 -23.716068) (xy 376.510531 -23.677359) (xy 376.555889 -23.644908) (xy 376.605489 -23.619407)
			(xy 376.658273 -23.6014) (xy 376.713116 -23.59127) (xy 376.76885 -23.589233) (xy 376.824287 -23.595333)
			(xy 376.878244 -23.609439) (xy 376.881515 -23.610829) (xy 386.366023 -23.610829) (xy 386.366025 -23.556335)
			(xy 386.373783 -23.502395) (xy 386.389138 -23.450109) (xy 386.411778 -23.400539) (xy 386.441241 -23.354697)
			(xy 386.476929 -23.313513) (xy 386.518114 -23.277828) (xy 386.563959 -23.248367) (xy 386.613529 -23.22573)
			(xy 386.665817 -23.210378) (xy 386.719757 -23.202624) (xy 386.747004 -23.202138) (xy 386.771033 -23.202514)
			(xy 386.818711 -23.208553) (xy 386.865252 -23.220534) (xy 386.88772 -23.229062) (xy 386.900879 -23.233826)
			(xy 386.928703 -23.236731) (xy 386.956273 -23.23198) (xy 386.981521 -23.219932) (xy 387.002556 -23.201487)
			(xy 387.0178 -23.178029) (xy 387.026111 -23.151317) (xy 387.026866 -23.123351) (xy 387.023864 -23.109682)
			(xy 387.018414 -23.086699) (xy 387.012552 -23.039828) (xy 387.01218 -23.01621) (xy 387.012644 -22.988956)
			(xy 387.0204 -22.935003) (xy 387.035756 -22.882703) (xy 387.058398 -22.83312) (xy 387.087866 -22.787264)
			(xy 387.123561 -22.74607) (xy 387.164754 -22.710374) (xy 387.210609 -22.680904) (xy 387.260191 -22.65826)
			(xy 387.31249 -22.642903) (xy 387.366443 -22.635145) (xy 387.420951 -22.635145) (xy 387.474904 -22.642902)
			(xy 387.527204 -22.658258) (xy 387.576786 -22.680901) (xy 387.622641 -22.710371) (xy 387.663836 -22.746066)
			(xy 387.699531 -22.78726) (xy 387.729 -22.833115) (xy 387.751643 -22.882698) (xy 387.766999 -22.934998)
			(xy 387.774755 -22.988951) (xy 387.774755 -23.043459) (xy 387.766997 -23.097412) (xy 387.751639 -23.149711)
			(xy 387.728995 -23.199293) (xy 387.699525 -23.245147) (xy 387.663829 -23.286341) (xy 387.622634 -23.322035)
			(xy 387.576778 -23.351503) (xy 387.527196 -23.374145) (xy 387.474895 -23.3895) (xy 387.420942 -23.397256)
			(xy 387.393688 -23.397718) (xy 387.369659 -23.397341) (xy 387.321981 -23.391302) (xy 387.27544 -23.379321)
			(xy 387.252972 -23.370794) (xy 387.239802 -23.366072) (xy 387.211986 -23.363173) (xy 387.184426 -23.367923)
			(xy 387.159186 -23.379968) (xy 387.138156 -23.398404) (xy 387.122913 -23.421851) (xy 387.114597 -23.448552)
			(xy 387.113832 -23.476508) (xy 387.116828 -23.490174) (xy 387.122288 -23.513155) (xy 387.128144 -23.560028)
			(xy 387.128512 -23.583646) (xy 387.128386 -23.589996) (xy 390.384536 -23.589996) (xy 390.388607 -23.534374)
			(xy 390.400733 -23.479937) (xy 390.420656 -23.427846) (xy 390.447952 -23.379211) (xy 390.482038 -23.335068)
			(xy 390.522187 -23.296359) (xy 390.567545 -23.263908) (xy 390.617145 -23.238407) (xy 390.669929 -23.2204)
			(xy 390.724772 -23.21027) (xy 390.780506 -23.208233) (xy 390.835943 -23.214333) (xy 390.8899 -23.228439)
			(xy 390.941229 -23.250251) (xy 390.988835 -23.279305) (xy 391.031703 -23.31498) (xy 391.068057 -23.355554)
			(xy 399.630646 -23.355554) (xy 399.631138 -23.328744) (xy 399.638644 -23.275652) (xy 399.653516 -23.224135)
			(xy 399.675461 -23.175211) (xy 399.704044 -23.129844) (xy 399.738703 -23.088931) (xy 399.778753 -23.053278)
			(xy 399.800826 -23.038054) (xy 399.812366 -23.029766) (xy 399.830765 -23.008135) (xy 399.842499 -22.982275)
			(xy 399.846661 -22.954184) (xy 399.84293 -22.926032) (xy 399.831594 -22.899995) (xy 399.813529 -22.878084)
			(xy 399.802096 -22.869652) (xy 399.780653 -22.854281) (xy 399.741739 -22.818657) (xy 399.708105 -22.778012)
			(xy 399.680392 -22.73312) (xy 399.65913 -22.684837) (xy 399.644722 -22.634085) (xy 399.637446 -22.581832)
			(xy 399.636996 -22.555454) (xy 399.637482 -22.528203) (xy 399.645238 -22.474255) (xy 399.660593 -22.42196)
			(xy 399.683235 -22.372383) (xy 399.712701 -22.326533) (xy 399.748392 -22.285342) (xy 399.789583 -22.249651)
			(xy 399.835433 -22.220185) (xy 399.88501 -22.197543) (xy 399.937305 -22.182188) (xy 399.991253 -22.174432)
			(xy 400.045755 -22.174432) (xy 400.099703 -22.182188) (xy 400.151998 -22.197543) (xy 400.201575 -22.220185)
			(xy 400.247425 -22.249651) (xy 400.288616 -22.285342) (xy 400.324307 -22.326533) (xy 400.353773 -22.372383)
			(xy 400.376415 -22.42196) (xy 400.39177 -22.474255) (xy 400.399526 -22.528203) (xy 400.400012 -22.555454)
			(xy 400.399545 -22.582265) (xy 400.392037 -22.635359) (xy 400.377162 -22.686877) (xy 400.355214 -22.735802)
			(xy 400.326626 -22.781169) (xy 400.291962 -22.822081) (xy 400.251908 -22.857732) (xy 400.229832 -22.872954)
			(xy 400.218279 -22.881229) (xy 400.19987 -22.90286) (xy 400.188129 -22.928724) (xy 400.183965 -22.956821)
			(xy 400.1877 -22.984978) (xy 400.199045 -23.011018) (xy 400.217122 -23.032927) (xy 400.228562 -23.041356)
			(xy 400.250022 -23.056704) (xy 400.288932 -23.092334) (xy 400.322563 -23.132984) (xy 400.350273 -23.17788)
			(xy 400.371533 -23.226166) (xy 400.385938 -23.27692) (xy 400.393213 -23.329175) (xy 400.393662 -23.355554)
			(xy 400.393176 -23.382805) (xy 400.38542 -23.436753) (xy 400.370065 -23.489048) (xy 400.347423 -23.538625)
			(xy 400.317957 -23.584475) (xy 400.282266 -23.625666) (xy 400.241075 -23.661357) (xy 400.195225 -23.690823)
			(xy 400.145648 -23.713465) (xy 400.093353 -23.72882) (xy 400.039405 -23.736576) (xy 399.984903 -23.736576)
			(xy 399.930955 -23.72882) (xy 399.87866 -23.713465) (xy 399.829083 -23.690823) (xy 399.783233 -23.661357)
			(xy 399.742042 -23.625666) (xy 399.706351 -23.584475) (xy 399.676885 -23.538625) (xy 399.654243 -23.489048)
			(xy 399.638888 -23.436753) (xy 399.631132 -23.382805) (xy 399.630646 -23.355554) (xy 391.068057 -23.355554)
			(xy 391.06892 -23.356517) (xy 391.099693 -23.40303) (xy 391.123365 -23.453527) (xy 391.139433 -23.506934)
			(xy 391.147553 -23.56211) (xy 391.148062 -23.589996) (xy 391.147553 -23.617882) (xy 391.139433 -23.673058)
			(xy 391.123365 -23.726465) (xy 391.099693 -23.776962) (xy 391.06892 -23.823475) (xy 391.031703 -23.865012)
			(xy 391.013311 -23.880318) (xy 391.540744 -23.880318) (xy 391.544815 -23.824696) (xy 391.556941 -23.770259)
			(xy 391.576864 -23.718168) (xy 391.60416 -23.669533) (xy 391.638246 -23.62539) (xy 391.678395 -23.586681)
			(xy 391.723753 -23.55423) (xy 391.773353 -23.528729) (xy 391.826137 -23.510722) (xy 391.88098 -23.500592)
			(xy 391.936714 -23.498555) (xy 391.992151 -23.504655) (xy 392.046108 -23.518761) (xy 392.097437 -23.540573)
			(xy 392.145043 -23.569627) (xy 392.187911 -23.605302) (xy 392.225128 -23.646839) (xy 392.255901 -23.693352)
			(xy 392.279573 -23.743849) (xy 392.295641 -23.797256) (xy 392.303761 -23.852432) (xy 392.30427 -23.880318)
			(xy 392.556744 -23.880318) (xy 392.560815 -23.824696) (xy 392.572941 -23.770259) (xy 392.592864 -23.718168)
			(xy 392.62016 -23.669533) (xy 392.654246 -23.62539) (xy 392.694395 -23.586681) (xy 392.739753 -23.55423)
			(xy 392.789353 -23.528729) (xy 392.842137 -23.510722) (xy 392.89698 -23.500592) (xy 392.952714 -23.498555)
			(xy 393.008151 -23.504655) (xy 393.062108 -23.518761) (xy 393.113437 -23.540573) (xy 393.161043 -23.569627)
			(xy 393.203911 -23.605302) (xy 393.241128 -23.646839) (xy 393.271901 -23.693352) (xy 393.295573 -23.743849)
			(xy 393.311641 -23.797256) (xy 393.319761 -23.852432) (xy 393.32027 -23.880318) (xy 393.572744 -23.880318)
			(xy 393.576815 -23.824696) (xy 393.588941 -23.770259) (xy 393.608864 -23.718168) (xy 393.63616 -23.669533)
			(xy 393.670246 -23.62539) (xy 393.710395 -23.586681) (xy 393.755753 -23.55423) (xy 393.805353 -23.528729)
			(xy 393.858137 -23.510722) (xy 393.91298 -23.500592) (xy 393.968714 -23.498555) (xy 394.024151 -23.504655)
			(xy 394.078108 -23.518761) (xy 394.129437 -23.540573) (xy 394.177043 -23.569627) (xy 394.219911 -23.605302)
			(xy 394.257128 -23.646839) (xy 394.287901 -23.693352) (xy 394.311573 -23.743849) (xy 394.327641 -23.797256)
			(xy 394.335761 -23.852432) (xy 394.33627 -23.880318) (xy 394.59103 -23.880318) (xy 394.595101 -23.824696)
			(xy 394.607227 -23.770259) (xy 394.62715 -23.718168) (xy 394.654446 -23.669533) (xy 394.688532 -23.62539)
			(xy 394.728681 -23.586681) (xy 394.774039 -23.55423) (xy 394.823639 -23.528729) (xy 394.876423 -23.510722)
			(xy 394.931266 -23.500592) (xy 394.987 -23.498555) (xy 395.042437 -23.504655) (xy 395.096394 -23.518761)
			(xy 395.147723 -23.540573) (xy 395.195329 -23.569627) (xy 395.238197 -23.605302) (xy 395.275414 -23.646839)
			(xy 395.306187 -23.693352) (xy 395.329859 -23.743849) (xy 395.345927 -23.797256) (xy 395.354047 -23.852432)
			(xy 395.354556 -23.880318) (xy 395.354047 -23.908204) (xy 395.345927 -23.96338) (xy 395.345393 -23.965154)
			(xy 400.377404 -23.965154) (xy 400.381475 -23.909532) (xy 400.393601 -23.855095) (xy 400.413524 -23.803004)
			(xy 400.44082 -23.754369) (xy 400.474906 -23.710226) (xy 400.515055 -23.671517) (xy 400.560413 -23.639066)
			(xy 400.610013 -23.613565) (xy 400.662797 -23.595558) (xy 400.71764 -23.585428) (xy 400.773374 -23.583391)
			(xy 400.828811 -23.589491) (xy 400.882768 -23.603597) (xy 400.934097 -23.625409) (xy 400.981703 -23.654463)
			(xy 401.024571 -23.690138) (xy 401.061788 -23.731675) (xy 401.092561 -23.778188) (xy 401.116233 -23.828685)
			(xy 401.132301 -23.882092) (xy 401.140421 -23.937268) (xy 401.14093 -23.965154) (xy 401.140421 -23.99304)
			(xy 401.132301 -24.048216) (xy 401.116233 -24.101623) (xy 401.092561 -24.15212) (xy 401.061788 -24.198633)
			(xy 401.024571 -24.24017) (xy 400.981703 -24.275845) (xy 400.934097 -24.304899) (xy 400.882768 -24.326711)
			(xy 400.828811 -24.340817) (xy 400.773374 -24.346917) (xy 400.71764 -24.34488) (xy 400.662797 -24.33475)
			(xy 400.610013 -24.316743) (xy 400.560413 -24.291242) (xy 400.515055 -24.258791) (xy 400.474906 -24.220082)
			(xy 400.44082 -24.175939) (xy 400.413524 -24.127304) (xy 400.393601 -24.075213) (xy 400.381475 -24.020776)
			(xy 400.377404 -23.965154) (xy 395.345393 -23.965154) (xy 395.329859 -24.016787) (xy 395.306187 -24.067284)
			(xy 395.275414 -24.113797) (xy 395.238197 -24.155334) (xy 395.195329 -24.191009) (xy 395.147723 -24.220063)
			(xy 395.096394 -24.241875) (xy 395.042437 -24.255981) (xy 394.987 -24.262081) (xy 394.931266 -24.260044)
			(xy 394.876423 -24.249914) (xy 394.823639 -24.231907) (xy 394.774039 -24.206406) (xy 394.728681 -24.173955)
			(xy 394.688532 -24.135246) (xy 394.654446 -24.091103) (xy 394.62715 -24.042468) (xy 394.607227 -23.990377)
			(xy 394.595101 -23.93594) (xy 394.59103 -23.880318) (xy 394.33627 -23.880318) (xy 394.335761 -23.908204)
			(xy 394.327641 -23.96338) (xy 394.311573 -24.016787) (xy 394.287901 -24.067284) (xy 394.257128 -24.113797)
			(xy 394.219911 -24.155334) (xy 394.177043 -24.191009) (xy 394.129437 -24.220063) (xy 394.078108 -24.241875)
			(xy 394.024151 -24.255981) (xy 393.968714 -24.262081) (xy 393.91298 -24.260044) (xy 393.858137 -24.249914)
			(xy 393.805353 -24.231907) (xy 393.755753 -24.206406) (xy 393.710395 -24.173955) (xy 393.670246 -24.135246)
			(xy 393.63616 -24.091103) (xy 393.608864 -24.042468) (xy 393.588941 -23.990377) (xy 393.576815 -23.93594)
			(xy 393.572744 -23.880318) (xy 393.32027 -23.880318) (xy 393.319761 -23.908204) (xy 393.311641 -23.96338)
			(xy 393.295573 -24.016787) (xy 393.271901 -24.067284) (xy 393.241128 -24.113797) (xy 393.203911 -24.155334)
			(xy 393.161043 -24.191009) (xy 393.113437 -24.220063) (xy 393.062108 -24.241875) (xy 393.008151 -24.255981)
			(xy 392.952714 -24.262081) (xy 392.89698 -24.260044) (xy 392.842137 -24.249914) (xy 392.789353 -24.231907)
			(xy 392.739753 -24.206406) (xy 392.694395 -24.173955) (xy 392.654246 -24.135246) (xy 392.62016 -24.091103)
			(xy 392.592864 -24.042468) (xy 392.572941 -23.990377) (xy 392.560815 -23.93594) (xy 392.556744 -23.880318)
			(xy 392.30427 -23.880318) (xy 392.303761 -23.908204) (xy 392.295641 -23.96338) (xy 392.279573 -24.016787)
			(xy 392.255901 -24.067284) (xy 392.225128 -24.113797) (xy 392.187911 -24.155334) (xy 392.145043 -24.191009)
			(xy 392.097437 -24.220063) (xy 392.046108 -24.241875) (xy 391.992151 -24.255981) (xy 391.936714 -24.262081)
			(xy 391.88098 -24.260044) (xy 391.826137 -24.249914) (xy 391.773353 -24.231907) (xy 391.723753 -24.206406)
			(xy 391.678395 -24.173955) (xy 391.638246 -24.135246) (xy 391.60416 -24.091103) (xy 391.576864 -24.042468)
			(xy 391.556941 -23.990377) (xy 391.544815 -23.93594) (xy 391.540744 -23.880318) (xy 391.013311 -23.880318)
			(xy 390.988835 -23.900687) (xy 390.941229 -23.929741) (xy 390.8899 -23.951553) (xy 390.835943 -23.965659)
			(xy 390.780506 -23.971759) (xy 390.724772 -23.969722) (xy 390.669929 -23.959592) (xy 390.617145 -23.941585)
			(xy 390.567545 -23.916084) (xy 390.522187 -23.883633) (xy 390.482038 -23.844924) (xy 390.447952 -23.800781)
			(xy 390.420656 -23.752146) (xy 390.400733 -23.700055) (xy 390.388607 -23.645618) (xy 390.384536 -23.589996)
			(xy 387.128386 -23.589996) (xy 387.127973 -23.610893) (xy 387.120211 -23.664832) (xy 387.104852 -23.717118)
			(xy 387.082209 -23.766685) (xy 387.052742 -23.812526) (xy 387.017051 -23.853706) (xy 386.975863 -23.889389)
			(xy 386.930017 -23.918846) (xy 386.880444 -23.941479) (xy 386.828156 -23.956827) (xy 386.774215 -23.964578)
			(xy 386.719721 -23.964574) (xy 386.665781 -23.956814) (xy 386.613495 -23.941457) (xy 386.563927 -23.918815)
			(xy 386.518085 -23.88935) (xy 386.476904 -23.853661) (xy 386.44122 -23.812474) (xy 386.411761 -23.766629)
			(xy 386.389126 -23.717058) (xy 386.373775 -23.66477) (xy 386.366023 -23.610829) (xy 376.881515 -23.610829)
			(xy 376.929573 -23.631251) (xy 376.977179 -23.660305) (xy 377.020047 -23.69598) (xy 377.057264 -23.737517)
			(xy 377.088037 -23.78403) (xy 377.111709 -23.834527) (xy 377.127777 -23.887934) (xy 377.135897 -23.94311)
			(xy 377.136406 -23.970996) (xy 377.135897 -23.998882) (xy 377.127777 -24.054058) (xy 377.111709 -24.107465)
			(xy 377.088037 -24.157962) (xy 377.087884 -24.158194) (xy 381.750822 -24.158194) (xy 381.754893 -24.102572)
			(xy 381.767019 -24.048135) (xy 381.786942 -23.996044) (xy 381.814238 -23.947409) (xy 381.848324 -23.903266)
			(xy 381.888473 -23.864557) (xy 381.933831 -23.832106) (xy 381.983431 -23.806605) (xy 382.036215 -23.788598)
			(xy 382.091058 -23.778468) (xy 382.146792 -23.776431) (xy 382.202229 -23.782531) (xy 382.256186 -23.796637)
			(xy 382.307515 -23.818449) (xy 382.355121 -23.847503) (xy 382.397989 -23.883178) (xy 382.435206 -23.924715)
			(xy 382.465979 -23.971228) (xy 382.489651 -24.021725) (xy 382.505719 -24.075132) (xy 382.513839 -24.130308)
			(xy 382.514348 -24.158194) (xy 382.513839 -24.18608) (xy 382.51327 -24.189944) (xy 385.598922 -24.189944)
			(xy 385.602993 -24.134322) (xy 385.615119 -24.079885) (xy 385.635042 -24.027794) (xy 385.662338 -23.979159)
			(xy 385.696424 -23.935016) (xy 385.736573 -23.896307) (xy 385.781931 -23.863856) (xy 385.831531 -23.838355)
			(xy 385.884315 -23.820348) (xy 385.939158 -23.810218) (xy 385.994892 -23.808181) (xy 386.050329 -23.814281)
			(xy 386.104286 -23.828387) (xy 386.155615 -23.850199) (xy 386.203221 -23.879253) (xy 386.246089 -23.914928)
			(xy 386.283306 -23.956465) (xy 386.314079 -24.002978) (xy 386.337751 -24.053475) (xy 386.353819 -24.106882)
			(xy 386.361939 -24.162058) (xy 386.362448 -24.189944) (xy 388.121904 -24.189944) (xy 388.125975 -24.134322)
			(xy 388.138101 -24.079885) (xy 388.158024 -24.027794) (xy 388.18532 -23.979159) (xy 388.219406 -23.935016)
			(xy 388.259555 -23.896307) (xy 388.304913 -23.863856) (xy 388.354513 -23.838355) (xy 388.407297 -23.820348)
			(xy 388.46214 -23.810218) (xy 388.517874 -23.808181) (xy 388.573311 -23.814281) (xy 388.627268 -23.828387)
			(xy 388.678597 -23.850199) (xy 388.726203 -23.879253) (xy 388.769071 -23.914928) (xy 388.806288 -23.956465)
			(xy 388.837061 -24.002978) (xy 388.860733 -24.053475) (xy 388.876801 -24.106882) (xy 388.884921 -24.162058)
			(xy 388.88543 -24.189944) (xy 388.884921 -24.21783) (xy 388.876801 -24.273006) (xy 388.860733 -24.326413)
			(xy 388.837061 -24.37691) (xy 388.806288 -24.423423) (xy 388.769071 -24.46496) (xy 388.726203 -24.500635)
			(xy 388.678597 -24.529689) (xy 388.627268 -24.551501) (xy 388.573311 -24.565607) (xy 388.517874 -24.571707)
			(xy 388.46214 -24.56967) (xy 388.407297 -24.55954) (xy 388.354513 -24.541533) (xy 388.304913 -24.516032)
			(xy 388.259555 -24.483581) (xy 388.219406 -24.444872) (xy 388.18532 -24.400729) (xy 388.158024 -24.352094)
			(xy 388.138101 -24.300003) (xy 388.125975 -24.245566) (xy 388.121904 -24.189944) (xy 386.362448 -24.189944)
			(xy 386.361939 -24.21783) (xy 386.353819 -24.273006) (xy 386.337751 -24.326413) (xy 386.314079 -24.37691)
			(xy 386.283306 -24.423423) (xy 386.246089 -24.46496) (xy 386.203221 -24.500635) (xy 386.155615 -24.529689)
			(xy 386.104286 -24.551501) (xy 386.050329 -24.565607) (xy 385.994892 -24.571707) (xy 385.939158 -24.56967)
			(xy 385.884315 -24.55954) (xy 385.831531 -24.541533) (xy 385.781931 -24.516032) (xy 385.736573 -24.483581)
			(xy 385.696424 -24.444872) (xy 385.662338 -24.400729) (xy 385.635042 -24.352094) (xy 385.615119 -24.300003)
			(xy 385.602993 -24.245566) (xy 385.598922 -24.189944) (xy 382.51327 -24.189944) (xy 382.505719 -24.241256)
			(xy 382.489651 -24.294663) (xy 382.465979 -24.34516) (xy 382.435206 -24.391673) (xy 382.397989 -24.43321)
			(xy 382.355121 -24.468885) (xy 382.307515 -24.497939) (xy 382.256186 -24.519751) (xy 382.202229 -24.533857)
			(xy 382.146792 -24.539957) (xy 382.091058 -24.53792) (xy 382.036215 -24.52779) (xy 381.983431 -24.509783)
			(xy 381.933831 -24.484282) (xy 381.888473 -24.451831) (xy 381.848324 -24.413122) (xy 381.814238 -24.368979)
			(xy 381.786942 -24.320344) (xy 381.767019 -24.268253) (xy 381.754893 -24.213816) (xy 381.750822 -24.158194)
			(xy 377.087884 -24.158194) (xy 377.057264 -24.204475) (xy 377.020047 -24.246012) (xy 376.977179 -24.281687)
			(xy 376.929573 -24.310741) (xy 376.878244 -24.332553) (xy 376.824287 -24.346659) (xy 376.76885 -24.352759)
			(xy 376.713116 -24.350722) (xy 376.658273 -24.340592) (xy 376.605489 -24.322585) (xy 376.555889 -24.297084)
			(xy 376.510531 -24.264633) (xy 376.470382 -24.225924) (xy 376.436296 -24.181781) (xy 376.409 -24.133146)
			(xy 376.389077 -24.081055) (xy 376.376951 -24.026618) (xy 376.37288 -23.970996) (xy 376.143845 -23.970996)
			(xy 376.143769 -23.975184) (xy 376.135405 -24.031199) (xy 376.118855 -24.085363) (xy 376.094483 -24.136487)
			(xy 376.062824 -24.183448) (xy 376.024573 -24.225216) (xy 375.980571 -24.260872) (xy 375.931782 -24.289635)
			(xy 375.879278 -24.310873) (xy 375.824213 -24.324118) (xy 375.796048 -24.327104) (xy 375.78411 -24.327866)
			(xy 375.775982 -24.332184) (xy 375.775728 -24.332184) (xy 375.774458 -24.332946) (xy 375.77105 -24.334875)
			(xy 375.764801 -24.339595) (xy 375.762012 -24.342344) (xy 375.744994 -24.360632) (xy 375.711974 -24.396446)
			(xy 375.708392 -24.401149) (xy 375.703255 -24.411795) (xy 375.701814 -24.417528) (xy 375.700798 -24.42718)
			(xy 375.700798 -24.807418) (xy 382.920238 -24.807418) (xy 382.924309 -24.751796) (xy 382.936435 -24.697359)
			(xy 382.956358 -24.645268) (xy 382.983654 -24.596633) (xy 383.01774 -24.55249) (xy 383.057889 -24.513781)
			(xy 383.103247 -24.48133) (xy 383.152847 -24.455829) (xy 383.205631 -24.437822) (xy 383.260474 -24.427692)
			(xy 383.316208 -24.425655) (xy 383.371645 -24.431755) (xy 383.425602 -24.445861) (xy 383.476931 -24.467673)
			(xy 383.524537 -24.496727) (xy 383.567405 -24.532402) (xy 383.604622 -24.573939) (xy 383.635395 -24.620452)
			(xy 383.659067 -24.670949) (xy 383.675135 -24.724356) (xy 383.680182 -24.75865) (xy 395.168626 -24.75865)
			(xy 395.172697 -24.703028) (xy 395.184823 -24.648591) (xy 395.204746 -24.5965) (xy 395.232042 -24.547865)
			(xy 395.266128 -24.503722) (xy 395.306277 -24.465013) (xy 395.351635 -24.432562) (xy 395.401235 -24.407061)
			(xy 395.454019 -24.389054) (xy 395.508862 -24.378924) (xy 395.564596 -24.376887) (xy 395.620033 -24.382987)
			(xy 395.67399 -24.397093) (xy 395.725319 -24.418905) (xy 395.772925 -24.447959) (xy 395.815793 -24.483634)
			(xy 395.85301 -24.525171) (xy 395.883783 -24.571684) (xy 395.907455 -24.622181) (xy 395.923523 -24.675588)
			(xy 395.931643 -24.730764) (xy 395.932152 -24.75865) (xy 395.931643 -24.786536) (xy 395.923523 -24.841712)
			(xy 395.907455 -24.895119) (xy 395.883783 -24.945616) (xy 395.85301 -24.992129) (xy 395.815793 -25.033666)
			(xy 395.772925 -25.069341) (xy 395.725319 -25.098395) (xy 395.67399 -25.120207) (xy 395.620033 -25.134313)
			(xy 395.564596 -25.140413) (xy 395.508862 -25.138376) (xy 395.454019 -25.128246) (xy 395.401235 -25.110239)
			(xy 395.351635 -25.084738) (xy 395.306277 -25.052287) (xy 395.266128 -25.013578) (xy 395.232042 -24.969435)
			(xy 395.204746 -24.9208) (xy 395.184823 -24.868709) (xy 395.172697 -24.814272) (xy 395.168626 -24.75865)
			(xy 383.680182 -24.75865) (xy 383.683255 -24.779532) (xy 383.683764 -24.807418) (xy 383.683255 -24.835304)
			(xy 383.675135 -24.89048) (xy 383.659067 -24.943887) (xy 383.635395 -24.994384) (xy 383.604622 -25.040897)
			(xy 383.567405 -25.082434) (xy 383.524537 -25.118109) (xy 383.476931 -25.147163) (xy 383.425602 -25.168975)
			(xy 383.371645 -25.183081) (xy 383.316208 -25.189181) (xy 383.260474 -25.187144) (xy 383.205631 -25.177014)
			(xy 383.152847 -25.159007) (xy 383.103247 -25.133506) (xy 383.057889 -25.101055) (xy 383.01774 -25.062346)
			(xy 382.983654 -25.018203) (xy 382.956358 -24.969568) (xy 382.936435 -24.917477) (xy 382.924309 -24.86304)
			(xy 382.920238 -24.807418) (xy 375.700798 -24.807418) (xy 375.700798 -25.390094) (xy 388.109714 -25.390094)
			(xy 388.1102 -25.362843) (xy 388.117956 -25.308895) (xy 388.133311 -25.2566) (xy 388.155953 -25.207023)
			(xy 388.185419 -25.161173) (xy 388.22111 -25.119982) (xy 388.262301 -25.084291) (xy 388.308151 -25.054825)
			(xy 388.357728 -25.032183) (xy 388.410023 -25.016828) (xy 388.463971 -25.009072) (xy 388.518473 -25.009072)
			(xy 388.572421 -25.016828) (xy 388.624716 -25.032183) (xy 388.674293 -25.054825) (xy 388.720143 -25.084291)
			(xy 388.761334 -25.119982) (xy 388.797025 -25.161173) (xy 388.826491 -25.207023) (xy 388.849133 -25.2566)
			(xy 388.864488 -25.308895) (xy 388.872244 -25.362843) (xy 388.87273 -25.390094) (xy 388.872167 -25.419114)
			(xy 388.863376 -25.476485) (xy 388.845997 -25.531862) (xy 388.82043 -25.583968) (xy 388.787266 -25.6316)
			(xy 388.747269 -25.673659) (xy 388.724648 -25.691846) (xy 388.714109 -25.70062) (xy 388.697676 -25.722556)
			(xy 388.687675 -25.748075) (xy 388.68483 -25.775336) (xy 388.689345 -25.80237) (xy 388.700894 -25.827227)
			(xy 388.718644 -25.848111) (xy 388.729728 -25.856184) (xy 388.751373 -25.871498) (xy 388.790628 -25.907137)
			(xy 388.82457 -25.94787) (xy 388.852543 -25.992911) (xy 388.874008 -26.041392) (xy 388.888553 -26.092378)
			(xy 388.895896 -26.144888) (xy 388.896352 -26.171398) (xy 388.895866 -26.198649) (xy 388.88811 -26.252597)
			(xy 388.872755 -26.304892) (xy 388.850113 -26.354469) (xy 388.820647 -26.400319) (xy 388.784956 -26.44151)
			(xy 388.743765 -26.477201) (xy 388.697915 -26.506667) (xy 388.648338 -26.529309) (xy 388.596043 -26.544664)
			(xy 388.542095 -26.55242) (xy 388.487593 -26.55242) (xy 388.433645 -26.544664) (xy 388.38135 -26.529309)
			(xy 388.331773 -26.506667) (xy 388.285923 -26.477201) (xy 388.244732 -26.44151) (xy 388.209041 -26.400319)
			(xy 388.179575 -26.354469) (xy 388.156933 -26.304892) (xy 388.141578 -26.252597) (xy 388.133822 -26.198649)
			(xy 388.133336 -26.171398) (xy 388.133907 -26.142378) (xy 388.142698 -26.085008) (xy 388.160076 -26.029632)
			(xy 388.185642 -25.977526) (xy 388.218804 -25.929894) (xy 388.258798 -25.887833) (xy 388.281418 -25.869646)
			(xy 388.291969 -25.860884) (xy 388.308409 -25.838947) (xy 388.318412 -25.813424) (xy 388.321257 -25.786159)
			(xy 388.316739 -25.759121) (xy 388.305184 -25.734262) (xy 388.287426 -25.713379) (xy 388.276338 -25.705308)
			(xy 388.254704 -25.689979) (xy 388.215445 -25.654344) (xy 388.181501 -25.613615) (xy 388.153525 -25.568577)
			(xy 388.132058 -25.520098) (xy 388.117513 -25.469112) (xy 388.110169 -25.416604) (xy 388.109714 -25.390094)
			(xy 375.700798 -25.390094) (xy 375.700798 -25.971246) (xy 376.25985 -25.971246) (xy 376.263921 -25.915624)
			(xy 376.276047 -25.861187) (xy 376.29597 -25.809096) (xy 376.323266 -25.760461) (xy 376.357352 -25.716318)
			(xy 376.397501 -25.677609) (xy 376.442859 -25.645158) (xy 376.492459 -25.619657) (xy 376.545243 -25.60165)
			(xy 376.600086 -25.59152) (xy 376.65582 -25.589483) (xy 376.711257 -25.595583) (xy 376.765214 -25.609689)
			(xy 376.816543 -25.631501) (xy 376.864149 -25.660555) (xy 376.907017 -25.69623) (xy 376.944234 -25.737767)
			(xy 376.975007 -25.78428) (xy 376.998679 -25.834777) (xy 377.014747 -25.888184) (xy 377.022867 -25.94336)
			(xy 377.023376 -25.971246) (xy 377.27585 -25.971246) (xy 377.279921 -25.915624) (xy 377.292047 -25.861187)
			(xy 377.31197 -25.809096) (xy 377.339266 -25.760461) (xy 377.373352 -25.716318) (xy 377.413501 -25.677609)
			(xy 377.458859 -25.645158) (xy 377.508459 -25.619657) (xy 377.561243 -25.60165) (xy 377.616086 -25.59152)
			(xy 377.67182 -25.589483) (xy 377.727257 -25.595583) (xy 377.781214 -25.609689) (xy 377.832543 -25.631501)
			(xy 377.880149 -25.660555) (xy 377.923017 -25.69623) (xy 377.960234 -25.737767) (xy 377.991007 -25.78428)
			(xy 378.014679 -25.834777) (xy 378.030747 -25.888184) (xy 378.038867 -25.94336) (xy 378.039376 -25.971246)
			(xy 378.29185 -25.971246) (xy 378.295921 -25.915624) (xy 378.308047 -25.861187) (xy 378.32797 -25.809096)
			(xy 378.355266 -25.760461) (xy 378.389352 -25.716318) (xy 378.429501 -25.677609) (xy 378.474859 -25.645158)
			(xy 378.524459 -25.619657) (xy 378.577243 -25.60165) (xy 378.632086 -25.59152) (xy 378.68782 -25.589483)
			(xy 378.743257 -25.595583) (xy 378.797214 -25.609689) (xy 378.848543 -25.631501) (xy 378.896149 -25.660555)
			(xy 378.939017 -25.69623) (xy 378.976234 -25.737767) (xy 379.007007 -25.78428) (xy 379.030679 -25.834777)
			(xy 379.046747 -25.888184) (xy 379.054867 -25.94336) (xy 379.055376 -25.971246) (xy 379.054867 -25.999132)
			(xy 379.049775 -26.03373) (xy 379.567946 -26.03373) (xy 379.572017 -25.978108) (xy 379.584143 -25.923671)
			(xy 379.604066 -25.87158) (xy 379.631362 -25.822945) (xy 379.665448 -25.778802) (xy 379.705597 -25.740093)
			(xy 379.750955 -25.707642) (xy 379.800555 -25.682141) (xy 379.853339 -25.664134) (xy 379.908182 -25.654004)
			(xy 379.963916 -25.651967) (xy 380.019353 -25.658067) (xy 380.07331 -25.672173) (xy 380.124639 -25.693985)
			(xy 380.172245 -25.723039) (xy 380.215113 -25.758714) (xy 380.25233 -25.800251) (xy 380.283103 -25.846764)
			(xy 380.306775 -25.897261) (xy 380.322843 -25.950668) (xy 380.330963 -26.005844) (xy 380.331472 -26.03373)
			(xy 380.330963 -26.061616) (xy 380.322843 -26.116792) (xy 380.306775 -26.170199) (xy 380.283103 -26.220696)
			(xy 380.252869 -26.266394) (xy 382.820672 -26.266394) (xy 382.821172 -26.239144) (xy 382.828929 -26.185197)
			(xy 382.844284 -26.132904) (xy 382.866924 -26.083328) (xy 382.896389 -26.037479) (xy 382.932079 -25.996289)
			(xy 382.973268 -25.960598) (xy 383.019116 -25.931131) (xy 383.068691 -25.908489) (xy 383.120984 -25.893132)
			(xy 383.17493 -25.885373) (xy 383.20218 -25.884886) (xy 383.231505 -25.885424) (xy 383.289463 -25.894404)
			(xy 383.345361 -25.912154) (xy 383.397882 -25.938257) (xy 383.422144 -25.954736) (xy 383.432631 -25.961236)
			(xy 383.457066 -25.9644) (xy 383.46888 -25.960832) (xy 383.547366 -25.931622) (xy 383.558796 -25.926792)
			(xy 383.575435 -25.90842) (xy 383.579116 -25.89657) (xy 383.586479 -25.86949) (xy 383.608037 -25.817678)
			(xy 383.636955 -25.769586) (xy 383.672609 -25.72625) (xy 383.714228 -25.688608) (xy 383.760915 -25.65747)
			(xy 383.81166 -25.633511) (xy 383.865369 -25.617247) (xy 383.920881 -25.609029) (xy 383.94894 -25.608534)
			(xy 383.976192 -25.608939) (xy 384.030142 -25.616701) (xy 384.082437 -25.632061) (xy 384.132015 -25.654707)
			(xy 384.177865 -25.684177) (xy 384.219055 -25.719873) (xy 384.254747 -25.761067) (xy 384.284212 -25.80692)
			(xy 384.306853 -25.8565) (xy 384.322208 -25.908797) (xy 384.329964 -25.962748) (xy 384.329964 -25.990042)
			(xy 385.598922 -25.990042) (xy 385.602993 -25.93442) (xy 385.615119 -25.879983) (xy 385.635042 -25.827892)
			(xy 385.662338 -25.779257) (xy 385.696424 -25.735114) (xy 385.736573 -25.696405) (xy 385.781931 -25.663954)
			(xy 385.831531 -25.638453) (xy 385.884315 -25.620446) (xy 385.939158 -25.610316) (xy 385.994892 -25.608279)
			(xy 386.050329 -25.614379) (xy 386.104286 -25.628485) (xy 386.155615 -25.650297) (xy 386.203221 -25.679351)
			(xy 386.246089 -25.715026) (xy 386.283306 -25.756563) (xy 386.314079 -25.803076) (xy 386.337751 -25.853573)
			(xy 386.353819 -25.90698) (xy 386.361939 -25.962156) (xy 386.362448 -25.990042) (xy 386.361939 -26.017928)
			(xy 386.353819 -26.073104) (xy 386.337751 -26.126511) (xy 386.314079 -26.177008) (xy 386.283306 -26.223521)
			(xy 386.246089 -26.265058) (xy 386.203221 -26.300733) (xy 386.155615 -26.329787) (xy 386.104286 -26.351599)
			(xy 386.050329 -26.365705) (xy 385.994892 -26.371805) (xy 385.939158 -26.369768) (xy 385.884315 -26.359638)
			(xy 385.831531 -26.341631) (xy 385.781931 -26.31613) (xy 385.736573 -26.283679) (xy 385.696424 -26.24497)
			(xy 385.662338 -26.200827) (xy 385.635042 -26.152192) (xy 385.615119 -26.100101) (xy 385.602993 -26.045664)
			(xy 385.598922 -25.990042) (xy 384.329964 -25.990042) (xy 384.329964 -26.017252) (xy 384.322208 -26.071203)
			(xy 384.306853 -26.1235) (xy 384.284212 -26.17308) (xy 384.254747 -26.218933) (xy 384.219055 -26.260127)
			(xy 384.177865 -26.295823) (xy 384.132015 -26.325293) (xy 384.082437 -26.347939) (xy 384.030142 -26.363299)
			(xy 383.976192 -26.371061) (xy 383.94894 -26.37155) (xy 383.919616 -26.370995) (xy 383.861659 -26.362019)
			(xy 383.805761 -26.344274) (xy 383.753239 -26.318177) (xy 383.728976 -26.3017) (xy 383.718482 -26.295213)
			(xy 383.694053 -26.292039) (xy 383.68224 -26.295604) (xy 383.603754 -26.324814) (xy 383.592318 -26.329634)
			(xy 383.57568 -26.348012) (xy 383.572004 -26.359866) (xy 383.565238 -26.384903) (xy 383.545819 -26.432994)
			(xy 383.520059 -26.478008) (xy 383.488433 -26.519113) (xy 383.451526 -26.55555) (xy 383.431034 -26.571448)
			(xy 383.421373 -26.579435) (xy 383.410717 -26.602092) (xy 383.410714 -26.614628) (xy 383.415286 -26.698956)
			(xy 383.416548 -26.711388) (xy 383.429336 -26.732824) (xy 383.43967 -26.73985) (xy 383.4634 -26.754766)
			(xy 383.506636 -26.790428) (xy 383.54419 -26.832033) (xy 383.575251 -26.878686) (xy 383.599152 -26.929381)
			(xy 383.615378 -26.983027) (xy 383.623579 -27.038471) (xy 383.624074 -27.066494) (xy 383.623588 -27.093745)
			(xy 383.615832 -27.147693) (xy 383.600477 -27.199988) (xy 383.577835 -27.249565) (xy 383.548369 -27.295415)
			(xy 383.512678 -27.336606) (xy 383.471487 -27.372297) (xy 383.425637 -27.401763) (xy 383.37606 -27.424405)
			(xy 383.323765 -27.43976) (xy 383.269817 -27.447516) (xy 383.215315 -27.447516) (xy 383.161367 -27.43976)
			(xy 383.109072 -27.424405) (xy 383.059495 -27.401763) (xy 383.013645 -27.372297) (xy 382.972454 -27.336606)
			(xy 382.936763 -27.295415) (xy 382.907297 -27.249565) (xy 382.884655 -27.199988) (xy 382.8693 -27.147693)
			(xy 382.861544 -27.093745) (xy 382.861058 -27.066494) (xy 382.861618 -27.037007) (xy 382.870713 -26.978737)
			(xy 382.888671 -26.922563) (xy 382.915063 -26.869823) (xy 382.949259 -26.821775) (xy 382.990445 -26.779564)
			(xy 383.013712 -26.76144) (xy 383.023387 -26.753467) (xy 383.034033 -26.730799) (xy 383.034032 -26.71826)
			(xy 383.02946 -26.633932) (xy 383.028228 -26.621494) (xy 383.01542 -26.600058) (xy 383.005076 -26.593038)
			(xy 382.981329 -26.57815) (xy 382.938095 -26.542481) (xy 382.900544 -26.50087) (xy 382.869486 -26.454213)
			(xy 382.845588 -26.403514) (xy 382.829365 -26.349864) (xy 382.821166 -26.294418) (xy 382.820672 -26.266394)
			(xy 380.252869 -26.266394) (xy 380.25233 -26.267209) (xy 380.215113 -26.308746) (xy 380.172245 -26.344421)
			(xy 380.124639 -26.373475) (xy 380.07331 -26.395287) (xy 380.019353 -26.409393) (xy 379.963916 -26.415493)
			(xy 379.908182 -26.413456) (xy 379.853339 -26.403326) (xy 379.800555 -26.385319) (xy 379.750955 -26.359818)
			(xy 379.705597 -26.327367) (xy 379.665448 -26.288658) (xy 379.631362 -26.244515) (xy 379.604066 -26.19588)
			(xy 379.584143 -26.143789) (xy 379.572017 -26.089352) (xy 379.567946 -26.03373) (xy 379.049775 -26.03373)
			(xy 379.046747 -26.054308) (xy 379.030679 -26.107715) (xy 379.007007 -26.158212) (xy 378.976234 -26.204725)
			(xy 378.939017 -26.246262) (xy 378.896149 -26.281937) (xy 378.848543 -26.310991) (xy 378.797214 -26.332803)
			(xy 378.743257 -26.346909) (xy 378.68782 -26.353009) (xy 378.632086 -26.350972) (xy 378.577243 -26.340842)
			(xy 378.524459 -26.322835) (xy 378.474859 -26.297334) (xy 378.429501 -26.264883) (xy 378.389352 -26.226174)
			(xy 378.355266 -26.182031) (xy 378.32797 -26.133396) (xy 378.308047 -26.081305) (xy 378.295921 -26.026868)
			(xy 378.29185 -25.971246) (xy 378.039376 -25.971246) (xy 378.038867 -25.999132) (xy 378.030747 -26.054308)
			(xy 378.014679 -26.107715) (xy 377.991007 -26.158212) (xy 377.960234 -26.204725) (xy 377.923017 -26.246262)
			(xy 377.880149 -26.281937) (xy 377.832543 -26.310991) (xy 377.781214 -26.332803) (xy 377.727257 -26.346909)
			(xy 377.67182 -26.353009) (xy 377.616086 -26.350972) (xy 377.561243 -26.340842) (xy 377.508459 -26.322835)
			(xy 377.458859 -26.297334) (xy 377.413501 -26.264883) (xy 377.373352 -26.226174) (xy 377.339266 -26.182031)
			(xy 377.31197 -26.133396) (xy 377.292047 -26.081305) (xy 377.279921 -26.026868) (xy 377.27585 -25.971246)
			(xy 377.023376 -25.971246) (xy 377.022867 -25.999132) (xy 377.014747 -26.054308) (xy 376.998679 -26.107715)
			(xy 376.975007 -26.158212) (xy 376.944234 -26.204725) (xy 376.907017 -26.246262) (xy 376.864149 -26.281937)
			(xy 376.816543 -26.310991) (xy 376.765214 -26.332803) (xy 376.711257 -26.346909) (xy 376.65582 -26.353009)
			(xy 376.600086 -26.350972) (xy 376.545243 -26.340842) (xy 376.492459 -26.322835) (xy 376.442859 -26.297334)
			(xy 376.397501 -26.264883) (xy 376.357352 -26.226174) (xy 376.323266 -26.182031) (xy 376.29597 -26.133396)
			(xy 376.276047 -26.081305) (xy 376.263921 -26.026868) (xy 376.25985 -25.971246) (xy 375.700798 -25.971246)
			(xy 375.700798 -27.654758) (xy 375.701051 -27.661938) (xy 375.705057 -27.675727) (xy 375.708672 -27.681936)
			(xy 375.712482 -27.687778) (xy 375.722896 -27.697176) (xy 375.729754 -27.700478) (xy 375.756579 -27.713866)
			(xy 375.806006 -27.747791) (xy 375.815667 -27.756951) (xy 379.059166 -27.756951) (xy 379.059166 -27.702449)
			(xy 379.066922 -27.6485) (xy 379.082277 -27.596205) (xy 379.104918 -27.546627) (xy 379.134384 -27.500776)
			(xy 379.170075 -27.459585) (xy 379.211265 -27.423892) (xy 379.257115 -27.394425) (xy 379.306692 -27.371782)
			(xy 379.358987 -27.356425) (xy 379.412935 -27.348667) (xy 379.440186 -27.34818) (xy 379.454271 -27.348275)
			(xy 379.482367 -27.350313) (xy 379.49632 -27.352244) (xy 379.51029 -27.354276) (xy 379.535944 -27.343862)
			(xy 379.598174 -27.261058) (xy 379.603308 -27.253537) (xy 379.608369 -27.236057) (xy 379.606989 -27.217911)
			(xy 379.603508 -27.209496) (xy 379.603508 -27.209242) (xy 379.592469 -27.184111) (xy 379.576864 -27.131489)
			(xy 379.568956 -27.077173) (xy 379.568456 -27.04973) (xy 379.568942 -27.022479) (xy 379.576698 -26.968531)
			(xy 379.592053 -26.916236) (xy 379.614695 -26.866659) (xy 379.644161 -26.820809) (xy 379.679852 -26.779618)
			(xy 379.721043 -26.743927) (xy 379.766893 -26.714461) (xy 379.81647 -26.691819) (xy 379.868765 -26.676464)
			(xy 379.922713 -26.668708) (xy 379.977215 -26.668708) (xy 380.031163 -26.676464) (xy 380.083458 -26.691819)
			(xy 380.133035 -26.714461) (xy 380.178885 -26.743927) (xy 380.220076 -26.779618) (xy 380.255767 -26.820809)
			(xy 380.285233 -26.866659) (xy 380.307875 -26.916236) (xy 380.32323 -26.968531) (xy 380.330986 -27.022479)
			(xy 380.331472 -27.04973) (xy 380.331472 -27.050238) (xy 380.330819 -27.081569) (xy 380.320529 -27.14338)
			(xy 380.300281 -27.202681) (xy 380.286006 -27.230578) (xy 380.280672 -27.24023) (xy 380.279148 -27.26182)
			(xy 380.313438 -27.354276) (xy 380.328424 -27.369516) (xy 380.338584 -27.37358) (xy 380.339092 -27.37358)
			(xy 380.3657 -27.384397) (xy 380.415615 -27.412808) (xy 380.460707 -27.448381) (xy 380.499958 -27.490312)
			(xy 380.532479 -27.537652) (xy 380.557536 -27.589333) (xy 380.574562 -27.644185) (xy 380.583174 -27.700971)
			(xy 380.583694 -27.729688) (xy 380.583233 -27.756941) (xy 380.575478 -27.810893) (xy 380.560123 -27.863192)
			(xy 380.53748 -27.912773) (xy 380.508012 -27.958627) (xy 380.472318 -27.99982) (xy 380.431125 -28.035514)
			(xy 380.385271 -28.064981) (xy 380.33569 -28.087623) (xy 380.283391 -28.102978) (xy 380.229439 -28.110734)
			(xy 380.202186 -28.111196) (xy 380.173271 -28.110618) (xy 380.116103 -28.101901) (xy 380.060905 -28.084655)
			(xy 380.008943 -28.059275) (xy 379.961408 -28.026342) (xy 379.919388 -27.986611) (xy 379.901196 -27.96413)
			(xy 379.893593 -27.955319) (xy 379.872689 -27.94514) (xy 379.861064 -27.944572) (xy 379.781308 -27.944572)
			(xy 379.769675 -27.945105) (xy 379.748764 -27.955296) (xy 379.741176 -27.96413) (xy 379.723006 -27.986631)
			(xy 379.680981 -28.026364) (xy 379.633442 -28.0593) (xy 379.581476 -28.084685) (xy 379.526275 -28.101938)
			(xy 379.469103 -28.110663) (xy 379.440186 -28.111196) (xy 379.412935 -28.110733) (xy 379.358987 -28.102975)
			(xy 379.306692 -28.087618) (xy 379.257115 -28.064975) (xy 379.211265 -28.035508) (xy 379.170075 -27.999815)
			(xy 379.134384 -27.958624) (xy 379.104918 -27.912773) (xy 379.082277 -27.863195) (xy 379.066922 -27.8109)
			(xy 379.059166 -27.756951) (xy 375.815667 -27.756951) (xy 375.849511 -27.789038) (xy 375.868184 -27.812492)
			(xy 375.868184 -27.812746) (xy 375.870216 -27.815286) (xy 375.871994 -27.817318) (xy 375.88063 -27.825954)
			(xy 375.885817 -27.829594) (xy 375.89751 -27.834466) (xy 375.903744 -27.835606) (xy 375.90857 -27.836368)
			(xy 375.977912 -27.846274) (xy 375.982128 -27.846567) (xy 375.990553 -27.84593) (xy 375.994676 -27.845004)
			(xy 376.002042 -27.842972) (xy 376.011694 -27.83586) (xy 376.012202 -27.835352) (xy 376.037261 -27.817055)
			(xy 376.092065 -27.78797) (xy 376.150849 -27.768122) (xy 376.212067 -27.758032) (xy 376.243088 -27.757374)
			(xy 376.243596 -27.757374) (xy 376.255788 -27.757628) (xy 376.267472 -27.75839) (xy 376.294843 -27.760598)
			(xy 376.348582 -27.771882) (xy 376.400149 -27.790753) (xy 376.448478 -27.81682) (xy 376.492571 -27.849546)
			(xy 376.531518 -27.888255) (xy 376.564514 -27.932147) (xy 376.578114 -27.956002) (xy 376.584938 -27.965098)
			(xy 376.604455 -27.976709) (xy 376.615706 -27.978354) (xy 376.616214 -27.978354) (xy 376.620278 -27.978608)
			(xy 376.703336 -27.978608) (xy 376.715527 -27.977214) (xy 376.736606 -27.964731) (xy 376.743722 -27.954732)
			(xy 376.751606 -27.94122) (xy 376.769281 -27.915406) (xy 376.779028 -27.90317) (xy 376.78751 -27.892911)
			(xy 376.805686 -27.873461) (xy 376.81535 -27.864308) (xy 376.816112 -27.863546) (xy 376.837559 -27.843793)
			(xy 376.88533 -27.810364) (xy 376.937628 -27.784588) (xy 376.993238 -27.767065) (xy 377.050865 -27.758201)
			(xy 377.080018 -27.757628) (xy 377.107269 -27.758093) (xy 377.161216 -27.765852) (xy 377.21351 -27.78121)
			(xy 377.263085 -27.803854) (xy 377.308934 -27.833323) (xy 377.350121 -27.869017) (xy 377.38581 -27.91021)
			(xy 377.415272 -27.956062) (xy 377.437909 -28.005641) (xy 377.45326 -28.057937) (xy 377.461011 -28.111885)
			(xy 377.461526 -28.139136) (xy 377.968 -28.139136) (xy 377.972071 -28.083514) (xy 377.984197 -28.029077)
			(xy 378.00412 -27.976986) (xy 378.031416 -27.928351) (xy 378.065502 -27.884208) (xy 378.105651 -27.845499)
			(xy 378.151009 -27.813048) (xy 378.200609 -27.787547) (xy 378.253393 -27.76954) (xy 378.308236 -27.75941)
			(xy 378.36397 -27.757373) (xy 378.419407 -27.763473) (xy 378.473364 -27.777579) (xy 378.524693 -27.799391)
			(xy 378.572299 -27.828445) (xy 378.615167 -27.86412) (xy 378.652384 -27.905657) (xy 378.683157 -27.95217)
			(xy 378.706829 -28.002667) (xy 378.722897 -28.056074) (xy 378.731017 -28.11125) (xy 378.731526 -28.139136)
			(xy 378.731017 -28.167022) (xy 378.722897 -28.222198) (xy 378.706829 -28.275605) (xy 378.683157 -28.326102)
			(xy 378.652384 -28.372615) (xy 378.615167 -28.414152) (xy 378.572299 -28.449827) (xy 378.524693 -28.478881)
			(xy 378.473364 -28.500693) (xy 378.419407 -28.514799) (xy 378.36397 -28.520899) (xy 378.308236 -28.518862)
			(xy 378.253393 -28.508732) (xy 378.200609 -28.490725) (xy 378.151009 -28.465224) (xy 378.105651 -28.432773)
			(xy 378.065502 -28.394064) (xy 378.031416 -28.349921) (xy 378.00412 -28.301286) (xy 377.984197 -28.249195)
			(xy 377.972071 -28.194758) (xy 377.968 -28.139136) (xy 377.461526 -28.139136) (xy 377.461081 -28.165178)
			(xy 377.453991 -28.216777) (xy 377.439947 -28.266931) (xy 377.419211 -28.314709) (xy 377.392168 -28.359222)
			(xy 377.359321 -28.399643) (xy 377.340622 -28.417774) (xy 377.33986 -28.418536) (xy 377.318405 -28.438497)
			(xy 377.27051 -28.472259) (xy 377.218013 -28.498296) (xy 377.16215 -28.515993) (xy 377.104238 -28.524935)
			(xy 377.074938 -28.52547) (xy 377.046263 -28.524956) (xy 376.989559 -28.516374) (xy 376.934778 -28.499399)
			(xy 376.883158 -28.474412) (xy 376.83586 -28.441978) (xy 376.793953 -28.402827) (xy 376.75838 -28.357843)
			(xy 376.743722 -28.333192) (xy 376.736629 -28.323177) (xy 376.71553 -28.310718) (xy 376.703336 -28.309316)
			(xy 376.628152 -28.309316) (xy 376.614944 -28.311094) (xy 376.60326 -28.31592) (xy 376.582432 -28.327858)
			(xy 376.57278 -28.33497) (xy 376.568208 -28.339288) (xy 376.56643 -28.342336) (xy 376.564906 -28.344622)
			(xy 376.551869 -28.364304) (xy 376.521684 -28.400605) (xy 376.504708 -28.417012) (xy 376.504454 -28.417266)
			(xy 376.482955 -28.43744) (xy 376.434896 -28.471586) (xy 376.382157 -28.497932) (xy 376.325992 -28.515851)
			(xy 376.267739 -28.524915) (xy 376.238262 -28.52547) (xy 376.209106 -28.524915) (xy 376.151473 -28.516037)
			(xy 376.095863 -28.498493) (xy 376.043569 -28.472692) (xy 375.99581 -28.439235) (xy 375.953697 -28.398901)
			(xy 375.935494 -28.376118) (xy 375.933462 -28.373578) (xy 375.931684 -28.371546) (xy 375.923048 -28.36291)
			(xy 375.917863 -28.359264) (xy 375.906172 -28.354378) (xy 375.899934 -28.353258) (xy 375.829068 -28.342844)
			(xy 375.821194 -28.342336) (xy 375.79173 -28.352242) (xy 375.787158 -28.35529) (xy 375.779284 -28.360624)
			(xy 375.774204 -28.36418) (xy 375.770394 -28.368244) (xy 375.763536 -28.37815) (xy 375.7549 -28.393644)
			(xy 375.750582 -28.401772) (xy 375.748378 -28.406831) (xy 375.745952 -28.417593) (xy 375.745756 -28.423108)
			(xy 375.745756 -28.428696) (xy 375.745929 -28.434848) (xy 375.748889 -28.446791) (xy 375.751598 -28.452318)
			(xy 375.758964 -28.46451) (xy 375.763536 -28.470606) (xy 375.767854 -28.475178) (xy 375.774204 -28.479242)
			(xy 375.797884 -28.494813) (xy 375.840796 -28.531832) (xy 375.877763 -28.574788) (xy 375.907973 -28.622737)
			(xy 375.930764 -28.674625) (xy 375.945633 -28.729312) (xy 375.952255 -28.785596) (xy 375.950483 -28.842241)
			(xy 375.940357 -28.898002) (xy 375.922099 -28.951653) (xy 375.909586 -28.977082) (xy 375.894383 -29.005155)
			(xy 375.856076 -29.056222) (xy 375.833386 -29.078682) (xy 375.832878 -29.07919) (xy 375.809872 -29.100903)
			(xy 375.75804 -29.137162) (xy 375.729754 -29.151326) (xy 375.7295 -29.15158) (xy 375.723151 -29.154826)
			(xy 375.712454 -29.164243) (xy 375.708418 -29.170122) (xy 375.704608 -29.175964) (xy 375.702576 -29.183076)
			(xy 375.700798 -29.196284) (xy 375.700798 -29.223462) (xy 375.701052 -29.228034) (xy 375.701874 -29.233903)
			(xy 375.705852 -29.245065) (xy 375.708926 -29.250132) (xy 375.71299 -29.256228) (xy 375.72315 -29.265118)
			(xy 375.723404 -29.265118) (xy 375.724928 -29.26588) (xy 375.749905 -29.277481) (xy 375.796522 -29.306802)
			(xy 375.838441 -29.342517) (xy 375.874795 -29.383885) (xy 375.904827 -29.430047) (xy 375.927915 -29.480045)
			(xy 375.943579 -29.532841) (xy 375.951495 -29.58734) (xy 375.952004 -29.614876) (xy 375.951564 -29.640889)
			(xy 375.944497 -29.692434) (xy 375.930491 -29.74254) (xy 375.909805 -29.790278) (xy 375.882824 -29.834761)
			(xy 375.850048 -29.875166) (xy 375.831354 -29.89326) (xy 375.830846 -29.893768) (xy 375.823424 -29.900864)
			(xy 375.807922 -29.914334) (xy 375.799858 -29.920692) (xy 375.792465 -29.926971) (xy 375.78265 -29.943683)
			(xy 375.780808 -29.953204) (xy 375.7803 -29.960062) (xy 375.7803 -30.032452) (xy 375.780457 -30.037279)
			(xy 375.782368 -30.046744) (xy 375.78411 -30.051248) (xy 375.78411 -30.051756) (xy 375.78637 -30.056902)
			(xy 375.792773 -30.066135) (xy 375.79681 -30.070044) (xy 375.817487 -30.085821) (xy 375.854787 -30.122067)
			(xy 375.886818 -30.163043) (xy 375.912987 -30.20799) (xy 375.932808 -30.256075) (xy 375.945916 -30.306406)
			(xy 375.949464 -30.332172) (xy 375.951242 -30.347412) (xy 375.952258 -30.376876) (xy 375.951835 -30.402667)
			(xy 375.944894 -30.453781) (xy 375.931135 -30.503495) (xy 375.91081 -30.550904) (xy 375.884287 -30.595146)
			(xy 375.85205 -30.635415) (xy 375.83364 -30.653482) (xy 375.833132 -30.65399) (xy 375.829322 -30.657546)
			(xy 375.806953 -30.678097) (xy 375.756929 -30.712552) (xy 375.729754 -30.726126) (xy 375.7295 -30.72638)
			(xy 375.723151 -30.729626) (xy 375.712454 -30.739043) (xy 375.708418 -30.744922) (xy 375.704608 -30.750764)
			(xy 375.702576 -30.757876) (xy 375.700798 -30.771084) (xy 375.700798 -31.141416) (xy 375.70116 -31.150431)
			(xy 375.707411 -31.167344) (xy 375.71299 -31.174436) (xy 375.718832 -31.181294) (xy 375.734072 -31.18993)
			(xy 375.743216 -31.191454) (xy 375.76962 -31.196298) (xy 375.820822 -31.212422) (xy 375.869257 -31.235567)
			(xy 375.913968 -31.265275) (xy 375.954072 -31.300958) (xy 375.988775 -31.341913) (xy 376.017393 -31.38733)
			(xy 376.03936 -31.43631) (xy 376.054241 -31.487887) (xy 376.061743 -31.541041) (xy 376.06224 -31.567882)
			(xy 376.061798 -31.593925) (xy 376.054715 -31.645528) (xy 376.040677 -31.695688) (xy 376.030448 -31.719266)
			(xy 376.585478 -31.719266) (xy 376.589549 -31.663644) (xy 376.601675 -31.609207) (xy 376.621598 -31.557116)
			(xy 376.648894 -31.508481) (xy 376.68298 -31.464338) (xy 376.723129 -31.425629) (xy 376.768487 -31.393178)
			(xy 376.818087 -31.367677) (xy 376.870871 -31.34967) (xy 376.925714 -31.33954) (xy 376.981448 -31.337503)
			(xy 377.036885 -31.343603) (xy 377.090842 -31.357709) (xy 377.142171 -31.379521) (xy 377.189777 -31.408575)
			(xy 377.232645 -31.44425) (xy 377.269862 -31.485787) (xy 377.300635 -31.5323) (xy 377.324307 -31.582797)
			(xy 377.340375 -31.636204) (xy 377.344525 -31.664402) (xy 377.861066 -31.664402) (xy 377.865137 -31.60878)
			(xy 377.877263 -31.554343) (xy 377.897186 -31.502252) (xy 377.924482 -31.453617) (xy 377.958568 -31.409474)
			(xy 377.998717 -31.370765) (xy 378.044075 -31.338314) (xy 378.093675 -31.312813) (xy 378.146459 -31.294806)
			(xy 378.201302 -31.284676) (xy 378.257036 -31.282639) (xy 378.312473 -31.288739) (xy 378.36643 -31.302845)
			(xy 378.417759 -31.324657) (xy 378.465365 -31.353711) (xy 378.508233 -31.389386) (xy 378.54545 -31.430923)
			(xy 378.576223 -31.477436) (xy 378.599895 -31.527933) (xy 378.615963 -31.58134) (xy 378.624083 -31.636516)
			(xy 378.624592 -31.664402) (xy 378.624083 -31.692288) (xy 378.615963 -31.747464) (xy 378.607023 -31.777178)
			(xy 379.12624 -31.777178) (xy 379.130311 -31.721556) (xy 379.142437 -31.667119) (xy 379.16236 -31.615028)
			(xy 379.189656 -31.566393) (xy 379.223742 -31.52225) (xy 379.263891 -31.483541) (xy 379.309249 -31.45109)
			(xy 379.358849 -31.425589) (xy 379.411633 -31.407582) (xy 379.466476 -31.397452) (xy 379.52221 -31.395415)
			(xy 379.577647 -31.401515) (xy 379.631604 -31.415621) (xy 379.682933 -31.437433) (xy 379.730539 -31.466487)
			(xy 379.773407 -31.502162) (xy 379.810624 -31.543699) (xy 379.841397 -31.590212) (xy 379.865069 -31.640709)
			(xy 379.881137 -31.694116) (xy 379.889257 -31.749292) (xy 379.889766 -31.777178) (xy 379.889257 -31.805064)
			(xy 379.881137 -31.86024) (xy 379.865069 -31.913647) (xy 379.841397 -31.964144) (xy 379.810624 -32.010657)
			(xy 379.773407 -32.052194) (xy 379.730539 -32.087869) (xy 379.682933 -32.116923) (xy 379.631604 -32.138735)
			(xy 379.577647 -32.152841) (xy 379.52221 -32.158941) (xy 379.466476 -32.156904) (xy 379.411633 -32.146774)
			(xy 379.358849 -32.128767) (xy 379.309249 -32.103266) (xy 379.263891 -32.070815) (xy 379.223742 -32.032106)
			(xy 379.189656 -31.987963) (xy 379.16236 -31.939328) (xy 379.142437 -31.887237) (xy 379.130311 -31.8328)
			(xy 379.12624 -31.777178) (xy 378.607023 -31.777178) (xy 378.599895 -31.800871) (xy 378.576223 -31.851368)
			(xy 378.54545 -31.897881) (xy 378.508233 -31.939418) (xy 378.465365 -31.975093) (xy 378.417759 -32.004147)
			(xy 378.36643 -32.025959) (xy 378.312473 -32.040065) (xy 378.257036 -32.046165) (xy 378.201302 -32.044128)
			(xy 378.146459 -32.033998) (xy 378.093675 -32.015991) (xy 378.044075 -31.99049) (xy 377.998717 -31.958039)
			(xy 377.958568 -31.91933) (xy 377.924482 -31.875187) (xy 377.897186 -31.826552) (xy 377.877263 -31.774461)
			(xy 377.865137 -31.720024) (xy 377.861066 -31.664402) (xy 377.344525 -31.664402) (xy 377.348495 -31.69138)
			(xy 377.349004 -31.719266) (xy 377.348495 -31.747152) (xy 377.340375 -31.802328) (xy 377.324307 -31.855735)
			(xy 377.300635 -31.906232) (xy 377.269862 -31.952745) (xy 377.232645 -31.994282) (xy 377.189777 -32.029957)
			(xy 377.142171 -32.059011) (xy 377.090842 -32.080823) (xy 377.036885 -32.094929) (xy 376.981448 -32.101029)
			(xy 376.925714 -32.098992) (xy 376.870871 -32.088862) (xy 376.818087 -32.070855) (xy 376.768487 -32.045354)
			(xy 376.723129 -32.012903) (xy 376.68298 -31.974194) (xy 376.648894 -31.930051) (xy 376.621598 -31.881416)
			(xy 376.601675 -31.829325) (xy 376.589549 -31.774888) (xy 376.585478 -31.719266) (xy 376.030448 -31.719266)
			(xy 376.019946 -31.743471) (xy 375.992907 -31.78799) (xy 375.960064 -31.828417) (xy 375.941336 -31.84652)
			(xy 375.941082 -31.846774) (xy 375.94032 -31.847536) (xy 375.919879 -31.866529) (xy 375.874499 -31.898992)
			(xy 375.824881 -31.924512) (xy 375.77208 -31.942546) (xy 375.74474 -31.94812) (xy 375.742708 -31.948374)
			(xy 375.736358 -31.950152) (xy 375.72624 -31.953822) (xy 375.710134 -31.968071) (xy 375.701266 -31.987661)
			(xy 375.700798 -31.998412) (xy 375.700798 -33.512252) (xy 375.700881 -33.516928) (xy 375.702543 -33.52613)
			(xy 375.7041 -33.53054) (xy 375.710704 -33.542478) (xy 375.714577 -33.547384) (xy 375.724206 -33.555348)
			(xy 375.729754 -33.558226) (xy 375.731532 -33.558988) (xy 375.817384 -33.595818) (xy 375.824289 -33.598505)
			(xy 375.839005 -33.600174) (xy 375.84634 -33.59912) (xy 375.853452 -33.59785) (xy 375.86666 -33.591246)
			(xy 375.872248 -33.585912) (xy 375.881257 -33.57751) (xy 375.900196 -33.56175) (xy 375.910094 -33.554416)
			(xy 375.911364 -33.5534) (xy 375.91619 -33.54578) (xy 375.918222 -33.542224) (xy 375.922286 -33.53181)
			(xy 375.929906 -33.497012) (xy 375.932192 -33.486598) (xy 375.933856 -33.477217) (xy 375.930853 -33.458418)
			(xy 375.92635 -33.450022) (xy 375.913226 -33.426999) (xy 375.892532 -33.378214) (xy 375.87852 -33.327106)
			(xy 375.871437 -33.274588) (xy 375.870978 -33.248092) (xy 375.871483 -33.21977) (xy 375.879544 -33.163703)
			(xy 375.895502 -33.109355) (xy 375.919033 -33.05783) (xy 375.949657 -33.010178) (xy 375.98675 -32.96737)
			(xy 376.029558 -32.930277) (xy 376.07721 -32.899653) (xy 376.128735 -32.876122) (xy 376.183083 -32.860164)
			(xy 376.23915 -32.852103) (xy 376.295794 -32.852103) (xy 376.351861 -32.860164) (xy 376.406209 -32.876122)
			(xy 376.457734 -32.899653) (xy 376.505386 -32.930277) (xy 376.548194 -32.96737) (xy 376.585287 -33.010178)
			(xy 376.615911 -33.05783) (xy 376.639442 -33.109355) (xy 376.6554 -33.163703) (xy 376.663461 -33.21977)
			(xy 376.663966 -33.248092) (xy 376.663523 -33.275251) (xy 376.656122 -33.329061) (xy 376.641457 -33.381361)
			(xy 376.619801 -33.431175) (xy 376.591559 -33.477573) (xy 376.557258 -33.519689) (xy 376.517537 -33.556738)
			(xy 376.495564 -33.572704) (xy 376.48799 -33.578452) (xy 376.477426 -33.594246) (xy 376.47499 -33.603438)
			(xy 376.465338 -33.648904) (xy 376.464778 -33.65269) (xy 376.464647 -33.660342) (xy 376.465084 -33.664144)
			(xy 376.466354 -33.672272) (xy 376.470926 -33.681162) (xy 376.47118 -33.681416) (xy 376.47905 -33.696431)
			(xy 376.492402 -33.727593) (xy 376.49785 -33.743646) (xy 376.49785 -33.7439) (xy 376.500898 -33.753044)
			(xy 376.506486 -33.759902) (xy 376.509084 -33.762973) (xy 376.515084 -33.768328) (xy 376.518424 -33.77057)
			(xy 376.58548 -33.810956) (xy 376.594116 -33.812734) (xy 376.616615 -33.807512) (xy 376.662462 -33.801913)
			(xy 376.685556 -33.801558) (xy 376.712812 -33.802018) (xy 376.766769 -33.80977) (xy 376.819075 -33.825121)
			(xy 376.868662 -33.847761) (xy 376.884119 -33.857692) (xy 377.7902 -33.857692) (xy 377.794271 -33.80207)
			(xy 377.806397 -33.747633) (xy 377.82632 -33.695542) (xy 377.853616 -33.646907) (xy 377.887702 -33.602764)
			(xy 377.927851 -33.564055) (xy 377.973209 -33.531604) (xy 378.022809 -33.506103) (xy 378.075593 -33.488096)
			(xy 378.130436 -33.477966) (xy 378.18617 -33.475929) (xy 378.241607 -33.482029) (xy 378.295564 -33.496135)
			(xy 378.346893 -33.517947) (xy 378.394499 -33.547001) (xy 378.437367 -33.582676) (xy 378.474584 -33.624213)
			(xy 378.505357 -33.670726) (xy 378.529029 -33.721223) (xy 378.545097 -33.77463) (xy 378.553217 -33.829806)
			(xy 378.553726 -33.857692) (xy 378.553217 -33.885578) (xy 378.545097 -33.940754) (xy 378.529029 -33.994161)
			(xy 378.505357 -34.044658) (xy 378.474584 -34.091171) (xy 378.437367 -34.132708) (xy 378.394499 -34.168383)
			(xy 378.346893 -34.197437) (xy 378.295564 -34.219249) (xy 378.241607 -34.233355) (xy 378.18617 -34.239455)
			(xy 378.130436 -34.237418) (xy 378.075593 -34.227288) (xy 378.022809 -34.209281) (xy 377.973209 -34.18378)
			(xy 377.927851 -34.151329) (xy 377.887702 -34.11262) (xy 377.853616 -34.068477) (xy 377.82632 -34.019842)
			(xy 377.806397 -33.967751) (xy 377.794271 -33.913314) (xy 377.7902 -33.857692) (xy 376.884119 -33.857692)
			(xy 376.914524 -33.877227) (xy 376.955724 -33.91292) (xy 376.991426 -33.954114) (xy 377.020902 -33.999969)
			(xy 377.043551 -34.049552) (xy 377.058914 -34.101854) (xy 377.066677 -34.15581) (xy 377.067064 -34.183066)
			(xy 377.066623 -34.20911) (xy 377.059542 -34.260714) (xy 377.045507 -34.310876) (xy 377.024778 -34.358662)
			(xy 376.997742 -34.403183) (xy 376.9649 -34.443613) (xy 376.94616 -34.461704) (xy 376.945398 -34.462466)
			(xy 376.923943 -34.482428) (xy 376.876048 -34.516192) (xy 376.823552 -34.542232) (xy 376.767689 -34.559933)
			(xy 376.709776 -34.56888) (xy 376.680476 -34.5694) (xy 376.653867 -34.568944) (xy 376.601163 -34.561559)
			(xy 376.549997 -34.546923) (xy 376.501361 -34.525319) (xy 376.456198 -34.497167) (xy 376.415386 -34.463012)
			(xy 376.379715 -34.423518) (xy 376.349878 -34.37945) (xy 376.326454 -34.331664) (xy 376.317764 -34.30651)
			(xy 376.314716 -34.297366) (xy 376.309382 -34.290508) (xy 376.306441 -34.287004) (xy 376.299542 -34.281)
			(xy 376.295666 -34.27857) (xy 376.26671 -34.261298) (xy 376.23496 -34.242502) (xy 376.231703 -34.240853)
			(xy 376.224817 -34.238424) (xy 376.221244 -34.237676) (xy 376.213116 -34.236152) (xy 376.20321 -34.23793)
			(xy 376.186399 -34.240772) (xy 376.15244 -34.24382) (xy 376.135392 -34.244026) (xy 376.135138 -34.244026)
			(xy 376.105638 -34.24348) (xy 376.047338 -34.234415) (xy 375.991126 -34.216495) (xy 375.938336 -34.190145)
			(xy 375.890226 -34.155993) (xy 375.868692 -34.135822) (xy 375.865136 -34.13252) (xy 375.861072 -34.128456)
			(xy 375.846594 -34.125916) (xy 375.839944 -34.124968) (xy 375.826568 -34.126133) (xy 375.820178 -34.128202)
			(xy 375.728484 -34.167318) (xy 375.717982 -34.173483) (xy 375.703809 -34.193244) (xy 375.701306 -34.205164)
			(xy 375.700798 -34.212022) (xy 375.700798 -35.264852) (xy 378.202442 -35.264852) (xy 378.206513 -35.20923)
			(xy 378.218639 -35.154793) (xy 378.238562 -35.102702) (xy 378.265858 -35.054067) (xy 378.299944 -35.009924)
			(xy 378.340093 -34.971215) (xy 378.385451 -34.938764) (xy 378.435051 -34.913263) (xy 378.487835 -34.895256)
			(xy 378.542678 -34.885126) (xy 378.598412 -34.883089) (xy 378.653849 -34.889189) (xy 378.707806 -34.903295)
			(xy 378.759135 -34.925107) (xy 378.806741 -34.954161) (xy 378.849609 -34.989836) (xy 378.874446 -35.017556)
			(xy 380.519833 -35.017556) (xy 380.519833 -34.963044) (xy 380.527591 -34.909086) (xy 380.54295 -34.856782)
			(xy 380.565597 -34.807196) (xy 380.595071 -34.761339) (xy 380.630771 -34.720142) (xy 380.671971 -34.684447)
			(xy 380.717831 -34.654978) (xy 380.76742 -34.632336) (xy 380.819725 -34.616983) (xy 380.873684 -34.60923)
			(xy 380.90094 -34.60877) (xy 380.918052 -34.608964) (xy 380.952139 -34.612014) (xy 380.969012 -34.614866)
			(xy 380.980304 -34.61621) (xy 381.002191 -34.610152) (xy 381.011176 -34.603182) (xy 381.03556 -34.5821)
			(xy 381.043987 -34.574182) (xy 381.053251 -34.553022) (xy 381.05334 -34.54146) (xy 381.052832 -34.522664)
			(xy 381.052832 -33.65881) (xy 381.05334 -33.638744) (xy 381.053133 -33.627299) (xy 381.044031 -33.606328)
			(xy 381.035814 -33.598358) (xy 381.011176 -33.577022) (xy 381.002192 -33.569921) (xy 380.980097 -33.563981)
			(xy 380.968758 -33.565592) (xy 380.951951 -33.568459) (xy 380.917989 -33.571508) (xy 380.90094 -33.571688)
			(xy 380.873684 -33.571268) (xy 380.819726 -33.563515) (xy 380.76742 -33.548162) (xy 380.717832 -33.52552)
			(xy 380.671972 -33.496052) (xy 380.630772 -33.460356) (xy 380.595072 -33.41916) (xy 380.565599 -33.373303)
			(xy 380.542952 -33.323717) (xy 380.527593 -33.271413) (xy 380.519835 -33.217456) (xy 380.519835 -33.162944)
			(xy 380.527593 -33.108987) (xy 380.542952 -33.056683) (xy 380.565599 -33.007097) (xy 380.595072 -32.96124)
			(xy 380.630772 -32.920044) (xy 380.671972 -32.884348) (xy 380.717832 -32.85488) (xy 380.76742 -32.832238)
			(xy 380.819726 -32.816885) (xy 380.873684 -32.809132) (xy 380.90094 -32.808672) (xy 380.927949 -32.809083)
			(xy 380.981429 -32.816695) (xy 381.0333 -32.831775) (xy 381.082526 -32.854021) (xy 381.12812 -32.88299)
			(xy 381.169172 -32.9181) (xy 381.204861 -32.958651) (xy 381.234473 -33.00383) (xy 381.257414 -33.052735)
			(xy 381.273228 -33.104387) (xy 381.277876 -33.130998) (xy 381.2794 -33.141666) (xy 381.29083 -33.159446)
			(xy 381.362204 -33.206944) (xy 381.371141 -33.212276) (xy 381.391598 -33.215961) (xy 381.401828 -33.214056)
			(xy 381.40259 -33.214056) (xy 381.429161 -33.207948) (xy 381.48328 -33.20132) (xy 381.51054 -33.200848)
			(xy 381.537864 -33.201303) (xy 381.592113 -33.207924) (xy 381.618744 -33.214056) (xy 381.619252 -33.214056)
			(xy 381.629482 -33.215921) (xy 381.64993 -33.212245) (xy 381.658876 -33.206944) (xy 381.73025 -33.159446)
			(xy 381.74168 -33.141666) (xy 381.743204 -33.130998) (xy 381.747866 -33.104394) (xy 381.763697 -33.052757)
			(xy 381.786651 -33.003868) (xy 381.816268 -32.958703) (xy 381.851956 -32.918165) (xy 381.893004 -32.883063)
			(xy 381.938591 -32.8541) (xy 381.987806 -32.831853) (xy 382.039666 -32.816767) (xy 382.093135 -32.809144)
			(xy 382.12014 -32.808672) (xy 382.14751 -32.809156) (xy 382.201689 -32.816967) (xy 382.254192 -32.832451)
			(xy 382.30394 -32.855289) (xy 382.349907 -32.885011) (xy 382.370838 -32.902652) (xy 382.371092 -32.902906)
			(xy 382.378176 -32.908496) (xy 382.395095 -32.91474) (xy 382.404112 -32.915098) (xy 382.471168 -32.915098)
			(xy 382.480183 -32.914726) (xy 382.497101 -32.908489) (xy 382.504188 -32.902906) (xy 382.504188 -32.902652)
			(xy 382.504442 -32.902652) (xy 382.525392 -32.885035) (xy 382.571359 -32.855318) (xy 382.621102 -32.832477)
			(xy 382.673599 -32.816981) (xy 382.727772 -32.809148) (xy 382.75514 -32.808672) (xy 382.772252 -32.808866)
			(xy 382.806339 -32.811916) (xy 382.823212 -32.814768) (xy 382.834504 -32.816112) (xy 382.856391 -32.810054)
			(xy 382.865376 -32.803084) (xy 382.88976 -32.782002) (xy 382.898186 -32.774083) (xy 382.90745 -32.752924)
			(xy 382.90754 -32.741362) (xy 382.907032 -32.722566) (xy 382.907032 -31.858712) (xy 382.90754 -31.838646)
			(xy 382.907332 -31.827201) (xy 382.898231 -31.80623) (xy 382.890014 -31.79826) (xy 382.865376 -31.776924)
			(xy 382.856392 -31.769823) (xy 382.834297 -31.763883) (xy 382.822958 -31.765494) (xy 382.806151 -31.768361)
			(xy 382.772189 -31.77141) (xy 382.75514 -31.77159) (xy 382.72777 -31.771103) (xy 382.673592 -31.763291)
			(xy 382.621089 -31.747807) (xy 382.571342 -31.724969) (xy 382.525374 -31.695249) (xy 382.504442 -31.67761)
			(xy 382.497584 -31.671514) (xy 382.480566 -31.665164) (xy 382.395222 -31.665164) (xy 382.37795 -31.671768)
			(xy 382.371092 -31.677864) (xy 382.350143 -31.695484) (xy 382.304179 -31.725206) (xy 382.254436 -31.74805)
			(xy 382.201938 -31.763545) (xy 382.147763 -31.771372) (xy 382.120394 -31.771844) (xy 382.12014 -31.771844)
			(xy 382.093161 -31.771429) (xy 382.03974 -31.76384) (xy 381.987922 -31.748793) (xy 381.938745 -31.726589)
			(xy 381.89319 -31.697672) (xy 381.852168 -31.662621) (xy 381.816498 -31.622134) (xy 381.786895 -31.577022)
			(xy 381.763949 -31.528187) (xy 381.748119 -31.476603) (xy 381.743458 -31.450026) (xy 381.741266 -31.439804)
			(xy 381.730005 -31.422222) (xy 381.721614 -31.41599) (xy 381.65024 -31.368492) (xy 381.629158 -31.364682)
			(xy 381.618998 -31.367222) (xy 381.592296 -31.373293) (xy 381.537921 -31.379789) (xy 381.51054 -31.380176)
			(xy 381.483158 -31.379808) (xy 381.428782 -31.373309) (xy 381.402082 -31.367222) (xy 381.391922 -31.364682)
			(xy 381.37084 -31.368492) (xy 381.290576 -31.421832) (xy 381.2794 -31.439358) (xy 381.277622 -31.450026)
			(xy 381.272976 -31.476601) (xy 381.257118 -31.528167) (xy 381.234153 -31.576984) (xy 381.204538 -31.622079)
			(xy 381.168865 -31.66255) (xy 381.127846 -31.697592) (xy 381.082298 -31.726504) (xy 381.033131 -31.74871)
			(xy 380.981325 -31.763767) (xy 380.927915 -31.771374) (xy 380.90094 -31.771844) (xy 380.873688 -31.771311)
			(xy 380.819738 -31.76356) (xy 380.76744 -31.748209) (xy 380.717859 -31.725571) (xy 380.672006 -31.696107)
			(xy 380.630812 -31.660416) (xy 380.595117 -31.619226) (xy 380.565649 -31.573376) (xy 380.543005 -31.523798)
			(xy 380.527649 -31.471501) (xy 380.519891 -31.417552) (xy 380.519891 -31.363048) (xy 380.527649 -31.309099)
			(xy 380.543005 -31.256802) (xy 380.565649 -31.207224) (xy 380.595117 -31.161374) (xy 380.630812 -31.120184)
			(xy 380.672006 -31.084493) (xy 380.717859 -31.055029) (xy 380.76744 -31.032391) (xy 380.819738 -31.01704)
			(xy 380.873688 -31.009289) (xy 380.90094 -31.008828) (xy 380.918052 -31.009023) (xy 380.952139 -31.012073)
			(xy 380.969012 -31.014924) (xy 380.980304 -31.016278) (xy 381.002193 -31.010214) (xy 381.011176 -31.00324)
			(xy 381.03556 -30.982158) (xy 381.044007 -30.974258) (xy 381.053259 -30.953084) (xy 381.05334 -30.941518)
			(xy 381.052832 -30.922722) (xy 381.052832 -30.058868) (xy 381.05334 -30.038802) (xy 381.053157 -30.027354)
			(xy 381.044039 -30.006383) (xy 381.035814 -29.998416) (xy 381.011176 -29.97708) (xy 381.002188 -29.969984)
			(xy 380.980096 -29.964038) (xy 380.968758 -29.96565) (xy 380.951951 -29.968518) (xy 380.917989 -29.971566)
			(xy 380.90094 -29.971746) (xy 380.873688 -29.971209) (xy 380.819738 -29.963458) (xy 380.767441 -29.948107)
			(xy 380.71786 -29.925469) (xy 380.672007 -29.896005) (xy 380.630814 -29.860315) (xy 380.595119 -29.819125)
			(xy 380.56565 -29.773275) (xy 380.543007 -29.723697) (xy 380.527651 -29.671401) (xy 380.519893 -29.617452)
			(xy 380.519893 -29.562948) (xy 380.527651 -29.508999) (xy 380.543007 -29.456703) (xy 380.56565 -29.407125)
			(xy 380.595119 -29.361275) (xy 380.630814 -29.320085) (xy 380.672007 -29.284395) (xy 380.71786 -29.254931)
			(xy 380.767441 -29.232293) (xy 380.819738 -29.216942) (xy 380.873688 -29.209191) (xy 380.90094 -29.20873)
			(xy 380.927948 -29.209176) (xy 380.981425 -29.216787) (xy 381.033293 -29.231865) (xy 381.082516 -29.254109)
			(xy 381.128109 -29.283073) (xy 381.169161 -29.318179) (xy 381.20485 -29.358725) (xy 381.234463 -29.4039)
			(xy 381.257408 -29.4528) (xy 381.273226 -29.504447) (xy 381.277876 -29.531056) (xy 381.2794 -29.541724)
			(xy 381.29083 -29.559504) (xy 381.362204 -29.607002) (xy 381.371143 -29.612332) (xy 381.391599 -29.616019)
			(xy 381.401828 -29.614114) (xy 381.40259 -29.614114) (xy 381.429167 -29.608067) (xy 381.483287 -29.601571)
			(xy 381.51054 -29.60116) (xy 381.537858 -29.601551) (xy 381.592106 -29.608043) (xy 381.618744 -29.614114)
			(xy 381.619252 -29.614114) (xy 381.629482 -29.615971) (xy 381.649928 -29.612298) (xy 381.658876 -29.607002)
			(xy 381.73025 -29.559504) (xy 381.74168 -29.541724) (xy 381.743204 -29.531056) (xy 381.74791 -29.504461)
			(xy 381.763734 -29.452824) (xy 381.78668 -29.403933) (xy 381.816291 -29.358768) (xy 381.851975 -29.318228)
			(xy 381.893018 -29.283125) (xy 381.938601 -29.25416) (xy 381.987813 -29.231912) (xy 382.03967 -29.216826)
			(xy 382.093137 -29.209202) (xy 382.12014 -29.20873) (xy 382.147509 -29.209224) (xy 382.201687 -29.217034)
			(xy 382.254191 -29.232516) (xy 382.303938 -29.255352) (xy 382.349906 -29.285071) (xy 382.370838 -29.30271)
			(xy 382.371092 -29.302964) (xy 382.378171 -29.308561) (xy 382.395094 -29.3148) (xy 382.404112 -29.315156)
			(xy 382.471168 -29.315156) (xy 382.480184 -29.314793) (xy 382.497102 -29.308551) (xy 382.504188 -29.302964)
			(xy 382.504188 -29.30271) (xy 382.504442 -29.30271) (xy 382.525386 -29.285086) (xy 382.571356 -29.255372)
			(xy 382.6211 -29.232533) (xy 382.673598 -29.217038) (xy 382.727772 -29.209206) (xy 382.75514 -29.20873)
			(xy 382.772252 -29.208925) (xy 382.806339 -29.211975) (xy 382.823212 -29.214826) (xy 382.834504 -29.216179)
			(xy 382.856393 -29.210116) (xy 382.865376 -29.203142) (xy 382.88976 -29.18206) (xy 382.898206 -29.174159)
			(xy 382.907459 -29.152986) (xy 382.90754 -29.14142) (xy 382.907032 -29.122624) (xy 382.907032 -28.25877)
			(xy 382.90754 -28.238704) (xy 382.907356 -28.227257) (xy 382.898238 -28.206285) (xy 382.890014 -28.198318)
			(xy 382.865376 -28.176982) (xy 382.856388 -28.169886) (xy 382.834296 -28.16394) (xy 382.822958 -28.165552)
			(xy 382.806151 -28.16842) (xy 382.772189 -28.171468) (xy 382.75514 -28.171648) (xy 382.727888 -28.171107)
			(xy 382.673939 -28.163356) (xy 382.621641 -28.148005) (xy 382.572061 -28.125367) (xy 382.526208 -28.095903)
			(xy 382.485015 -28.060213) (xy 382.449321 -28.019024) (xy 382.419852 -27.973174) (xy 382.397209 -27.923596)
			(xy 382.381853 -27.871301) (xy 382.374095 -27.817352) (xy 382.374095 -27.762848) (xy 382.381853 -27.708899)
			(xy 382.397209 -27.656604) (xy 382.419852 -27.607026) (xy 382.449321 -27.561176) (xy 382.485015 -27.519987)
			(xy 382.526208 -27.484297) (xy 382.572061 -27.454833) (xy 382.621641 -27.432195) (xy 382.673939 -27.416844)
			(xy 382.727888 -27.409093) (xy 382.75514 -27.408632) (xy 382.782148 -27.409076) (xy 382.835625 -27.416687)
			(xy 382.887493 -27.431766) (xy 382.936716 -27.454009) (xy 382.98231 -27.482974) (xy 383.023361 -27.51808)
			(xy 383.05905 -27.558626) (xy 383.088663 -27.603801) (xy 383.111608 -27.652702) (xy 383.127426 -27.704349)
			(xy 383.132076 -27.730958) (xy 383.1336 -27.741626) (xy 383.14503 -27.759406) (xy 383.216404 -27.806904)
			(xy 383.225343 -27.812234) (xy 383.245799 -27.815921) (xy 383.256028 -27.814016) (xy 383.25679 -27.814016)
			(xy 383.283361 -27.807907) (xy 383.33748 -27.80128) (xy 383.36474 -27.800808) (xy 383.386918 -27.801103)
			(xy 383.431064 -27.805429) (xy 383.452878 -27.809444) (xy 383.463038 -27.811476) (xy 383.483104 -27.807412)
			(xy 383.55143 -27.760168) (xy 383.559589 -27.75395) (xy 383.570603 -27.736667) (xy 383.572766 -27.72664)
			(xy 383.577652 -27.700299) (xy 383.593868 -27.649239) (xy 383.617069 -27.60095) (xy 383.646798 -27.556383)
			(xy 383.68247 -27.516413) (xy 383.723384 -27.481827) (xy 383.768734 -27.453306) (xy 383.817629 -27.431411)
			(xy 383.869106 -27.416573) (xy 383.922153 -27.409083) (xy 383.94894 -27.408632) (xy 383.976192 -27.409041)
			(xy 384.030141 -27.416803) (xy 384.082437 -27.432163) (xy 384.132014 -27.454809) (xy 384.177864 -27.484279)
			(xy 384.219054 -27.519974) (xy 384.254745 -27.561168) (xy 384.284211 -27.607021) (xy 384.306851 -27.656601)
			(xy 384.322206 -27.708898) (xy 384.329962 -27.762848) (xy 384.329962 -27.817352) (xy 384.322206 -27.871302)
			(xy 384.306851 -27.923599) (xy 384.284211 -27.973179) (xy 384.254745 -28.019032) (xy 384.219054 -28.060226)
			(xy 384.177864 -28.095921) (xy 384.132014 -28.125391) (xy 384.082437 -28.148037) (xy 384.030141 -28.163397)
			(xy 383.976192 -28.171159) (xy 383.94894 -28.171648) (xy 383.948178 -28.171648) (xy 383.936846 -28.17153)
			(xy 383.914226 -28.170134) (xy 383.902966 -28.168854) (xy 383.892052 -28.168128) (xy 383.871256 -28.174831)
			(xy 383.862834 -28.181808) (xy 383.838704 -28.203652) (xy 383.83096 -28.211484) (xy 383.822403 -28.231756)
			(xy 383.822194 -28.242768) (xy 383.822448 -28.25877) (xy 383.822448 -29.12237) (xy 383.822194 -29.13761)
			(xy 383.82238 -29.148662) (xy 383.831099 -29.168951) (xy 383.838958 -29.176726) (xy 383.862834 -29.198316)
			(xy 383.871244 -29.205313) (xy 383.89205 -29.212016) (xy 383.902966 -29.21127) (xy 383.914225 -29.209977)
			(xy 383.936846 -29.208579) (xy 383.948178 -29.208476) (xy 383.94894 -29.208476) (xy 383.976188 -29.208997)
			(xy 384.030129 -29.216758) (xy 384.082417 -29.232116) (xy 384.131987 -29.254758) (xy 384.17783 -29.284224)
			(xy 384.219014 -29.319914) (xy 384.2547 -29.361102) (xy 384.284161 -29.406948) (xy 384.306798 -29.456521)
			(xy 384.322151 -29.50881) (xy 384.329906 -29.562752) (xy 384.329906 -29.617248) (xy 384.322151 -29.67119)
			(xy 384.306798 -29.723479) (xy 384.284161 -29.773052) (xy 384.2547 -29.818898) (xy 384.219014 -29.860086)
			(xy 384.17783 -29.895776) (xy 384.131987 -29.925242) (xy 384.082417 -29.947884) (xy 384.030129 -29.963242)
			(xy 383.976188 -29.971003) (xy 383.94894 -29.971492) (xy 383.922194 -29.970986) (xy 383.869228 -29.963497)
			(xy 383.817825 -29.94869) (xy 383.768992 -29.926854) (xy 383.723685 -29.898415) (xy 383.68279 -29.863932)
			(xy 383.647108 -29.824078) (xy 383.617338 -29.779635) (xy 383.594063 -29.731471) (xy 383.577737 -29.68053)
			(xy 383.572766 -29.654246) (xy 383.570988 -29.643832) (xy 383.56032 -29.627068) (xy 383.483358 -29.573728)
			(xy 383.463292 -29.569664) (xy 383.453132 -29.571696) (xy 383.431259 -29.575748) (xy 383.386983 -29.580071)
			(xy 383.36474 -29.580332) (xy 383.337352 -29.579885) (xy 383.282976 -29.573266) (xy 383.256282 -29.567124)
			(xy 383.246122 -29.564584) (xy 383.22504 -29.568394) (xy 383.144776 -29.621734) (xy 383.1336 -29.63926)
			(xy 383.131822 -29.649928) (xy 383.127178 -29.676503) (xy 383.11132 -29.728069) (xy 383.088354 -29.776887)
			(xy 383.058739 -29.821981) (xy 383.023066 -29.862453) (xy 382.982046 -29.897494) (xy 382.936498 -29.926406)
			(xy 382.887331 -29.948613) (xy 382.835525 -29.963669) (xy 382.782115 -29.971276) (xy 382.75514 -29.971746)
			(xy 382.72777 -29.97127) (xy 382.673591 -29.963456) (xy 382.621087 -29.94797) (xy 382.57134 -29.925131)
			(xy 382.525373 -29.895407) (xy 382.504442 -29.877766) (xy 382.504188 -29.877512) (xy 382.497108 -29.871916)
			(xy 382.480186 -29.865674) (xy 382.471168 -29.86532) (xy 382.404112 -29.86532) (xy 382.395095 -29.865678)
			(xy 382.378178 -29.871924) (xy 382.371092 -29.877512) (xy 382.371092 -29.877766) (xy 382.370838 -29.877766)
			(xy 382.349898 -29.895395) (xy 382.303928 -29.92511) (xy 382.254183 -29.947948) (xy 382.201683 -29.963441)
			(xy 382.147509 -29.971271) (xy 382.12014 -29.971746) (xy 382.103092 -29.971549) (xy 382.069132 -29.968495)
			(xy 382.052322 -29.96565) (xy 382.040995 -29.964215) (xy 382.018978 -29.97015) (xy 382.009904 -29.97708)
			(xy 381.985266 -29.998416) (xy 381.976929 -30.006299) (xy 381.967805 -30.027328) (xy 381.96774 -30.038802)
			(xy 381.968248 -30.058868) (xy 381.968248 -30.922722) (xy 381.96774 -30.941518) (xy 381.967828 -30.953079)
			(xy 381.977098 -30.974236) (xy 381.98552 -30.982158) (xy 382.009904 -31.00324) (xy 382.018886 -31.010224)
			(xy 382.040776 -31.0163) (xy 382.052068 -31.014924) (xy 382.068939 -31.012056) (xy 382.103028 -31.009002)
			(xy 382.12014 -31.008828) (xy 382.147509 -31.009322) (xy 382.201687 -31.017132) (xy 382.25419 -31.032614)
			(xy 382.303938 -31.05545) (xy 382.349906 -31.085169) (xy 382.370838 -31.102808) (xy 382.377696 -31.108904)
			(xy 382.394714 -31.115254) (xy 382.480058 -31.115254) (xy 382.49733 -31.10865) (xy 382.504188 -31.102554)
			(xy 382.525109 -31.0849) (xy 382.571081 -31.055181) (xy 382.62083 -31.032344) (xy 382.673335 -31.016858)
			(xy 382.727515 -31.00904) (xy 382.754886 -31.008574) (xy 382.75514 -31.008574) (xy 382.78215 -31.008983)
			(xy 382.835629 -31.016595) (xy 382.887501 -31.031675) (xy 382.936726 -31.053922) (xy 382.982321 -31.08289)
			(xy 383.023373 -31.118001) (xy 383.059062 -31.158552) (xy 383.088673 -31.203732) (xy 383.111615 -31.252637)
			(xy 383.127428 -31.304289) (xy 383.132076 -31.3309) (xy 383.1336 -31.341568) (xy 383.14503 -31.359348)
			(xy 383.216404 -31.406846) (xy 383.225341 -31.412178) (xy 383.245798 -31.415863) (xy 383.256028 -31.413958)
			(xy 383.25679 -31.413958) (xy 383.283368 -31.407912) (xy 383.337487 -31.401415) (xy 383.36474 -31.401004)
			(xy 383.386913 -31.401227) (xy 383.431059 -31.405429) (xy 383.452878 -31.409386) (xy 383.463038 -31.411418)
			(xy 383.483104 -31.407354) (xy 383.55143 -31.36011) (xy 383.55961 -31.353915) (xy 383.570613 -31.336615)
			(xy 383.572766 -31.326582) (xy 383.577607 -31.300232) (xy 383.593831 -31.249172) (xy 383.617039 -31.200884)
			(xy 383.646774 -31.156317) (xy 383.682452 -31.116349) (xy 383.72337 -31.081765) (xy 383.768724 -31.053245)
			(xy 383.817622 -31.031352) (xy 383.869102 -31.016514) (xy 383.922152 -31.009024) (xy 383.94894 -31.008574)
			(xy 383.976188 -31.009099) (xy 384.030129 -31.01686) (xy 384.082416 -31.032218) (xy 384.131986 -31.05486)
			(xy 384.177829 -31.084326) (xy 384.219013 -31.120016) (xy 384.254698 -31.161203) (xy 384.284159 -31.207049)
			(xy 384.306796 -31.256621) (xy 384.322149 -31.30891) (xy 384.329904 -31.362852) (xy 384.329904 -31.417348)
			(xy 384.322149 -31.47129) (xy 384.306796 -31.523579) (xy 384.284159 -31.573151) (xy 384.254698 -31.618997)
			(xy 384.219013 -31.660184) (xy 384.177829 -31.695874) (xy 384.131986 -31.72534) (xy 384.082416 -31.747982)
			(xy 384.030129 -31.76334) (xy 383.976188 -31.771101) (xy 383.94894 -31.77159) (xy 383.948178 -31.77159)
			(xy 383.936846 -31.771472) (xy 383.914226 -31.770076) (xy 383.902966 -31.768796) (xy 383.892052 -31.76806)
			(xy 383.871255 -31.774769) (xy 383.862834 -31.78175) (xy 383.838704 -31.803594) (xy 383.83094 -31.81141)
			(xy 383.822394 -31.831694) (xy 383.822194 -31.84271) (xy 383.822448 -31.858712) (xy 383.822448 -32.722312)
			(xy 383.822194 -32.737806) (xy 383.822383 -32.748858) (xy 383.831099 -32.769147) (xy 383.838958 -32.776922)
			(xy 383.862834 -32.798512) (xy 383.871245 -32.805508) (xy 383.89205 -32.812212) (xy 383.902966 -32.811466)
			(xy 383.914225 -32.810173) (xy 383.936846 -32.808775) (xy 383.948178 -32.808672) (xy 383.94894 -32.808672)
			(xy 383.976188 -32.809201) (xy 384.030128 -32.816962) (xy 384.082416 -32.832319) (xy 384.131985 -32.854962)
			(xy 384.177828 -32.884427) (xy 384.219011 -32.920117) (xy 384.254697 -32.961304) (xy 384.284158 -33.00715)
			(xy 384.306795 -33.056722) (xy 384.322147 -33.109011) (xy 384.329902 -33.162952) (xy 384.329902 -33.217448)
			(xy 384.322147 -33.271389) (xy 384.306795 -33.323678) (xy 384.284158 -33.37325) (xy 384.254697 -33.419096)
			(xy 384.219011 -33.460283) (xy 384.177828 -33.495973) (xy 384.131985 -33.525438) (xy 384.082416 -33.548081)
			(xy 384.030128 -33.563438) (xy 383.976188 -33.571199) (xy 383.94894 -33.571688) (xy 383.922173 -33.57128)
			(xy 383.869163 -33.563814) (xy 383.817718 -33.54901) (xy 383.768849 -33.527157) (xy 383.723515 -33.498685)
			(xy 383.682607 -33.464155) (xy 383.64693 -33.424243) (xy 383.617184 -33.379735) (xy 383.593953 -33.331505)
			(xy 383.577695 -33.280501) (xy 383.572766 -33.254188) (xy 383.570988 -33.243774) (xy 383.56032 -33.22701)
			(xy 383.483358 -33.17367) (xy 383.463292 -33.169606) (xy 383.453132 -33.171638) (xy 383.431253 -33.175623)
			(xy 383.386978 -33.179819) (xy 383.36474 -33.18002) (xy 383.337358 -33.179654) (xy 383.282982 -33.173153)
			(xy 383.256282 -33.167066) (xy 383.246122 -33.164526) (xy 383.22504 -33.168336) (xy 383.144776 -33.221676)
			(xy 383.1336 -33.239202) (xy 383.131822 -33.24987) (xy 383.127133 -33.276437) (xy 383.111283 -33.328003)
			(xy 383.088324 -33.376821) (xy 383.058716 -33.421916) (xy 383.023048 -33.462389) (xy 382.982032 -33.497432)
			(xy 382.936488 -33.526346) (xy 382.887324 -33.548553) (xy 382.835521 -33.563611) (xy 382.782113 -33.571218)
			(xy 382.75514 -33.571688) (xy 382.72777 -33.571201) (xy 382.673592 -33.563389) (xy 382.621089 -33.547905)
			(xy 382.571342 -33.525068) (xy 382.525374 -33.495347) (xy 382.504442 -33.477708) (xy 382.504188 -33.477454)
			(xy 382.497113 -33.471851) (xy 382.480187 -33.465615) (xy 382.471168 -33.465262) (xy 382.404112 -33.465262)
			(xy 382.395097 -33.465633) (xy 382.37818 -33.471872) (xy 382.371092 -33.477454) (xy 382.371092 -33.477708)
			(xy 382.370838 -33.477708) (xy 382.349903 -33.495344) (xy 382.303931 -33.525056) (xy 382.254184 -33.547892)
			(xy 382.201684 -33.563384) (xy 382.147509 -33.571213) (xy 382.12014 -33.571688) (xy 382.103092 -33.571492)
			(xy 382.069132 -33.568437) (xy 382.052322 -33.565592) (xy 382.040995 -33.564148) (xy 382.018976 -33.570088)
			(xy 382.009904 -33.577022) (xy 381.985266 -33.598358) (xy 381.976957 -33.606266) (xy 381.967817 -33.627276)
			(xy 381.96774 -33.638744) (xy 381.968248 -33.65881) (xy 381.968248 -34.522664) (xy 381.96774 -34.54146)
			(xy 381.967862 -34.553018) (xy 381.977108 -34.574175) (xy 381.98552 -34.5821) (xy 382.009904 -34.603182)
			(xy 382.01889 -34.61016) (xy 382.040776 -34.616243) (xy 382.052068 -34.614866) (xy 382.068939 -34.611999)
			(xy 382.103028 -34.608944) (xy 382.12014 -34.60877) (xy 382.147388 -34.609303) (xy 382.201328 -34.617064)
			(xy 382.253615 -34.632421) (xy 382.303184 -34.655063) (xy 382.349027 -34.684529) (xy 382.39021 -34.720218)
			(xy 382.425895 -34.761405) (xy 382.455356 -34.807251) (xy 382.477993 -34.856823) (xy 382.493345 -34.909111)
			(xy 382.5011 -34.963052) (xy 382.5011 -34.990024) (xy 383.566922 -34.990024) (xy 383.570993 -34.934402)
			(xy 383.583119 -34.879965) (xy 383.603042 -34.827874) (xy 383.630338 -34.779239) (xy 383.664424 -34.735096)
			(xy 383.704573 -34.696387) (xy 383.749931 -34.663936) (xy 383.799531 -34.638435) (xy 383.852315 -34.620428)
			(xy 383.907158 -34.610298) (xy 383.962892 -34.608261) (xy 384.018329 -34.614361) (xy 384.072286 -34.628467)
			(xy 384.123615 -34.650279) (xy 384.171221 -34.679333) (xy 384.214089 -34.715008) (xy 384.251306 -34.756545)
			(xy 384.282079 -34.803058) (xy 384.305751 -34.853555) (xy 384.321819 -34.906962) (xy 384.329939 -34.962138)
			(xy 384.330448 -34.990024) (xy 384.329939 -35.01791) (xy 384.321819 -35.073086) (xy 384.305751 -35.126493)
			(xy 384.282079 -35.17699) (xy 384.251306 -35.223503) (xy 384.214089 -35.26504) (xy 384.171221 -35.300715)
			(xy 384.123615 -35.329769) (xy 384.072286 -35.351581) (xy 384.018329 -35.365687) (xy 383.962892 -35.371787)
			(xy 383.907158 -35.36975) (xy 383.852315 -35.35962) (xy 383.799531 -35.341613) (xy 383.749931 -35.316112)
			(xy 383.704573 -35.283661) (xy 383.664424 -35.244952) (xy 383.630338 -35.200809) (xy 383.603042 -35.152174)
			(xy 383.583119 -35.100083) (xy 383.570993 -35.045646) (xy 383.566922 -34.990024) (xy 382.5011 -34.990024)
			(xy 382.5011 -35.017548) (xy 382.493345 -35.071489) (xy 382.477993 -35.123777) (xy 382.455356 -35.173349)
			(xy 382.425895 -35.219195) (xy 382.39021 -35.260382) (xy 382.349027 -35.296071) (xy 382.303184 -35.325537)
			(xy 382.253615 -35.348179) (xy 382.201328 -35.363536) (xy 382.147388 -35.371297) (xy 382.12014 -35.371786)
			(xy 382.093163 -35.371336) (xy 382.039744 -35.363747) (xy 381.98793 -35.348703) (xy 381.938754 -35.326502)
			(xy 381.893201 -35.297589) (xy 381.852179 -35.262541) (xy 381.81651 -35.22206) (xy 381.786905 -35.176953)
			(xy 381.763956 -35.128122) (xy 381.748121 -35.076543) (xy 381.743458 -35.049968) (xy 381.741293 -35.039739)
			(xy 381.730012 -35.022161) (xy 381.721614 -35.015932) (xy 381.65024 -34.968434) (xy 381.629158 -34.964624)
			(xy 381.618998 -34.967164) (xy 381.592305 -34.973312) (xy 381.537928 -34.979929) (xy 381.51054 -34.980372)
			(xy 381.483152 -34.979924) (xy 381.428776 -34.973305) (xy 381.402082 -34.967164) (xy 381.391922 -34.964624)
			(xy 381.37084 -34.968434) (xy 381.290576 -35.021774) (xy 381.2794 -35.0393) (xy 381.277622 -35.049968)
			(xy 381.273008 -35.076549) (xy 381.257145 -35.128115) (xy 381.234174 -35.176932) (xy 381.204555 -35.222026)
			(xy 381.168878 -35.262496) (xy 381.127856 -35.297537) (xy 381.082305 -35.326448) (xy 381.033135 -35.348653)
			(xy 380.981328 -35.36371) (xy 380.927916 -35.371316) (xy 380.90094 -35.371786) (xy 380.873684 -35.37137)
			(xy 380.819725 -35.363617) (xy 380.76742 -35.348264) (xy 380.717831 -35.325622) (xy 380.671971 -35.296153)
			(xy 380.630771 -35.260458) (xy 380.595071 -35.219261) (xy 380.565597 -35.173404) (xy 380.54295 -35.123818)
			(xy 380.527591 -35.071514) (xy 380.519833 -35.017556) (xy 378.874446 -35.017556) (xy 378.886826 -35.031373)
			(xy 378.917599 -35.077886) (xy 378.941271 -35.128383) (xy 378.957339 -35.18179) (xy 378.965459 -35.236966)
			(xy 378.965968 -35.264852) (xy 378.965459 -35.292738) (xy 378.957339 -35.347914) (xy 378.941271 -35.401321)
			(xy 378.917599 -35.451818) (xy 378.886826 -35.498331) (xy 378.849609 -35.539868) (xy 378.806741 -35.575543)
			(xy 378.759135 -35.604597) (xy 378.707806 -35.626409) (xy 378.653849 -35.640515) (xy 378.598412 -35.646615)
			(xy 378.542678 -35.644578) (xy 378.487835 -35.634448) (xy 378.435051 -35.616441) (xy 378.385451 -35.59094)
			(xy 378.340093 -35.558489) (xy 378.299944 -35.51978) (xy 378.265858 -35.475637) (xy 378.238562 -35.427002)
			(xy 378.218639 -35.374911) (xy 378.206513 -35.320474) (xy 378.202442 -35.264852) (xy 375.700798 -35.264852)
			(xy 375.700798 -37.087048) (xy 379.500892 -37.087048) (xy 379.501381 -37.060445) (xy 379.508756 -37.007754)
			(xy 379.523383 -36.9566) (xy 379.544979 -36.907975) (xy 379.573125 -36.862824) (xy 379.607273 -36.822024)
			(xy 379.646761 -36.786366) (xy 379.668532 -36.771072) (xy 379.678464 -36.763551) (xy 379.690186 -36.7416)
			(xy 379.690884 -36.729162) (xy 379.690884 -36.644834) (xy 379.690233 -36.632381) (xy 379.678511 -36.610403)
			(xy 379.668532 -36.602924) (xy 379.646762 -36.587628) (xy 379.607284 -36.551962) (xy 379.573141 -36.511158)
			(xy 379.544995 -36.466009) (xy 379.523393 -36.417388) (xy 379.508752 -36.366238) (xy 379.501356 -36.31355)
			(xy 379.500892 -36.286948) (xy 379.5014 -36.259696) (xy 379.50915 -36.205747) (xy 379.5245 -36.15345)
			(xy 379.547137 -36.10387) (xy 379.5766 -36.058017) (xy 379.612289 -36.016823) (xy 379.653478 -35.981129)
			(xy 379.699328 -35.95166) (xy 379.748905 -35.929017) (xy 379.8012 -35.913661) (xy 379.855148 -35.905903)
			(xy 379.8824 -35.90544) (xy 379.886972 -35.90544) (xy 379.896183 -35.905189) (xy 379.913502 -35.898934)
			(xy 379.920754 -35.893248) (xy 379.971554 -35.84956) (xy 379.978267 -35.84333) (xy 379.987121 -35.827316)
			(xy 379.988826 -35.818318) (xy 379.988826 -35.818064) (xy 379.993131 -35.791126) (xy 380.008444 -35.738767)
			(xy 380.031059 -35.689122) (xy 380.060514 -35.643206) (xy 380.096209 -35.601953) (xy 380.137417 -35.566205)
			(xy 380.183296 -35.536691) (xy 380.232911 -35.514014) (xy 380.285251 -35.498634) (xy 380.339248 -35.490867)
			(xy 380.366524 -35.490404) (xy 380.393775 -35.490867) (xy 380.447722 -35.498627) (xy 380.500015 -35.513985)
			(xy 380.549591 -35.536628) (xy 380.59544 -35.566096) (xy 380.636629 -35.601788) (xy 380.672319 -35.642979)
			(xy 380.701784 -35.68883) (xy 380.724424 -35.738407) (xy 380.739778 -35.790702) (xy 380.747534 -35.844649)
			(xy 380.747534 -35.899151) (xy 380.739778 -35.953098) (xy 380.724424 -36.005393) (xy 380.701784 -36.05497)
			(xy 380.672319 -36.100821) (xy 380.636629 -36.142012) (xy 380.59544 -36.177704) (xy 380.549591 -36.207172)
			(xy 380.500015 -36.229815) (xy 380.447722 -36.245173) (xy 380.393775 -36.252933) (xy 380.366524 -36.25342)
			(xy 380.361952 -36.25342) (xy 380.35274 -36.253669) (xy 380.335421 -36.259924) (xy 380.32817 -36.265612)
			(xy 380.27737 -36.3093) (xy 380.27064 -36.315513) (xy 380.261795 -36.33154) (xy 380.260098 -36.340542)
			(xy 380.260098 -36.340796) (xy 380.255881 -36.366996) (xy 380.241199 -36.417989) (xy 380.219589 -36.466454)
			(xy 380.191468 -36.511455) (xy 380.188037 -36.515548) (xy 381.314196 -36.515548) (xy 381.318267 -36.459926)
			(xy 381.330393 -36.405489) (xy 381.350316 -36.353398) (xy 381.377612 -36.304763) (xy 381.411698 -36.26062)
			(xy 381.451847 -36.221911) (xy 381.497205 -36.18946) (xy 381.546805 -36.163959) (xy 381.599589 -36.145952)
			(xy 381.654432 -36.135822) (xy 381.710166 -36.133785) (xy 381.765603 -36.139885) (xy 381.81956 -36.153991)
			(xy 381.870889 -36.175803) (xy 381.918495 -36.204857) (xy 381.961363 -36.240532) (xy 381.99858 -36.282069)
			(xy 382.029353 -36.328582) (xy 382.053025 -36.379079) (xy 382.069093 -36.432486) (xy 382.077213 -36.487662)
			(xy 382.077722 -36.515548) (xy 382.077213 -36.543434) (xy 382.069093 -36.59861) (xy 382.053025 -36.652017)
			(xy 382.029353 -36.702514) (xy 381.99858 -36.749027) (xy 381.961363 -36.790564) (xy 381.918495 -36.826239)
			(xy 381.870889 -36.855293) (xy 381.81956 -36.877105) (xy 381.765603 -36.891211) (xy 381.710166 -36.897311)
			(xy 381.654432 -36.895274) (xy 381.599589 -36.885144) (xy 381.546805 -36.867137) (xy 381.497205 -36.841636)
			(xy 381.451847 -36.809185) (xy 381.411698 -36.770476) (xy 381.377612 -36.726333) (xy 381.350316 -36.677698)
			(xy 381.330393 -36.625607) (xy 381.318267 -36.57117) (xy 381.314196 -36.515548) (xy 380.188037 -36.515548)
			(xy 380.157381 -36.552123) (xy 380.117984 -36.587673) (xy 380.096268 -36.602924) (xy 380.086337 -36.610447)
			(xy 380.074615 -36.632397) (xy 380.073916 -36.644834) (xy 380.073916 -36.729162) (xy 380.074569 -36.741615)
			(xy 380.08629 -36.763592) (xy 380.096268 -36.771072) (xy 380.118036 -36.78637) (xy 380.157515 -36.822036)
			(xy 380.191658 -36.862839) (xy 380.219803 -36.907989) (xy 380.241406 -36.956609) (xy 380.256048 -37.007759)
			(xy 380.263443 -37.060446) (xy 380.263908 -37.087048) (xy 380.263908 -37.087302) (xy 380.263285 -37.119019)
			(xy 380.252785 -37.181576) (xy 380.232059 -37.241528) (xy 380.217426 -37.269674) (xy 380.212092 -37.27958)
			(xy 380.210568 -37.301678) (xy 380.242572 -37.384482) (xy 380.247046 -37.394579) (xy 380.262847 -37.409978)
			(xy 380.273052 -37.4142) (xy 380.297575 -37.423294) (xy 380.344106 -37.447171) (xy 380.386939 -37.477182)
			(xy 380.425269 -37.512764) (xy 380.458379 -37.55325) (xy 380.485646 -37.597879) (xy 380.50656 -37.645815)
			(xy 380.520729 -37.69616) (xy 380.527886 -37.747968) (xy 380.528322 -37.774118) (xy 380.527836 -37.801369)
			(xy 380.52008 -37.855317) (xy 380.504725 -37.907612) (xy 380.482083 -37.957189) (xy 380.452617 -38.003039)
			(xy 380.416926 -38.04423) (xy 380.375735 -38.079921) (xy 380.329885 -38.109387) (xy 380.280308 -38.132029)
			(xy 380.228013 -38.147384) (xy 380.174065 -38.15514) (xy 380.119563 -38.15514) (xy 380.065615 -38.147384)
			(xy 380.01332 -38.132029) (xy 379.963743 -38.109387) (xy 379.917893 -38.079921) (xy 379.876702 -38.04423)
			(xy 379.841011 -38.003039) (xy 379.811545 -37.957189) (xy 379.788903 -37.907612) (xy 379.773548 -37.855317)
			(xy 379.765792 -37.801369) (xy 379.765306 -37.774118) (xy 379.765306 -37.773864) (xy 379.765914 -37.742147)
			(xy 379.77642 -37.679588) (xy 379.797152 -37.619638) (xy 379.811788 -37.591492) (xy 379.817122 -37.581586)
			(xy 379.818646 -37.559488) (xy 379.786642 -37.476684) (xy 379.782174 -37.466584) (xy 379.766368 -37.451188)
			(xy 379.756162 -37.446966) (xy 379.731609 -37.437951) (xy 379.685079 -37.41406) (xy 379.642248 -37.384037)
			(xy 379.60392 -37.348444) (xy 379.570814 -37.307949) (xy 379.543551 -37.263311) (xy 379.522641 -37.215366)
			(xy 379.508478 -37.165015) (xy 379.501326 -37.113201) (xy 379.500892 -37.087048) (xy 375.700798 -37.087048)
			(xy 375.700798 -38.315138) (xy 380.718058 -38.315138) (xy 380.722129 -38.259516) (xy 380.734255 -38.205079)
			(xy 380.754178 -38.152988) (xy 380.781474 -38.104353) (xy 380.81556 -38.06021) (xy 380.855709 -38.021501)
			(xy 380.901067 -37.98905) (xy 380.950667 -37.963549) (xy 381.003451 -37.945542) (xy 381.058294 -37.935412)
			(xy 381.114028 -37.933375) (xy 381.169465 -37.939475) (xy 381.223422 -37.953581) (xy 381.274751 -37.975393)
			(xy 381.322357 -38.004447) (xy 381.365225 -38.040122) (xy 381.402442 -38.081659) (xy 381.433215 -38.128172)
			(xy 381.456887 -38.178669) (xy 381.472955 -38.232076) (xy 381.481075 -38.287252) (xy 381.481584 -38.315138)
			(xy 381.481075 -38.343024) (xy 381.472955 -38.3982) (xy 381.456887 -38.451607) (xy 381.433215 -38.502104)
			(xy 381.402442 -38.548617) (xy 381.365225 -38.590154) (xy 381.322357 -38.625829) (xy 381.274751 -38.654883)
			(xy 381.223422 -38.676695) (xy 381.169465 -38.690801) (xy 381.114028 -38.696901) (xy 381.058294 -38.694864)
			(xy 381.003451 -38.684734) (xy 380.950667 -38.666727) (xy 380.901067 -38.641226) (xy 380.855709 -38.608775)
			(xy 380.81556 -38.570066) (xy 380.781474 -38.525923) (xy 380.754178 -38.477288) (xy 380.734255 -38.425197)
			(xy 380.722129 -38.37076) (xy 380.718058 -38.315138) (xy 375.700798 -38.315138) (xy 375.700798 -42.430954)
			(xy 375.702068 -42.44213) (xy 375.703123 -42.446352) (xy 375.706447 -42.454392) (xy 375.708672 -42.458132)
			(xy 375.708926 -42.458386) (xy 375.715022 -42.467022) (xy 375.727468 -42.476166) (xy 375.735596 -42.47896)
			(xy 375.76059 -42.487757) (xy 375.808066 -42.511285) (xy 375.85183 -42.541155) (xy 375.891041 -42.576794)
			(xy 375.924943 -42.617515) (xy 375.952884 -42.662535) (xy 375.974328 -42.710988) (xy 375.988862 -42.761942)
			(xy 375.996206 -42.814417) (xy 375.996708 -42.84091) (xy 375.996268 -42.866892) (xy 375.989212 -42.918374)
			(xy 375.975231 -42.968422) (xy 375.954585 -43.016108) (xy 375.927656 -43.06055) (xy 375.894942 -43.100924)
			(xy 375.876312 -43.11904) (xy 375.875296 -43.120056) (xy 375.874788 -43.120564) (xy 375.874534 -43.120818)
			(xy 375.854384 -43.139501) (xy 375.8097 -43.171479) (xy 375.760892 -43.196718) (xy 375.735088 -43.206162)
			(xy 375.73458 -43.206416) (xy 375.723658 -43.21175) (xy 375.7138 -43.219129) (xy 375.701878 -43.240629)
			(xy 375.700798 -43.252898) (xy 375.700798 -43.446954) (xy 375.702068 -43.45813) (xy 375.703123 -43.462352)
			(xy 375.706447 -43.470392) (xy 375.708672 -43.474132) (xy 375.708926 -43.474386) (xy 375.715022 -43.483022)
			(xy 375.727468 -43.492166) (xy 375.735596 -43.49496) (xy 375.76059 -43.503757) (xy 375.808066 -43.527285)
			(xy 375.85183 -43.557155) (xy 375.891041 -43.592794) (xy 375.924943 -43.633515) (xy 375.952884 -43.678535)
			(xy 375.974328 -43.726988) (xy 375.988862 -43.777942) (xy 375.996206 -43.830417) (xy 375.996708 -43.85691)
			(xy 375.996268 -43.882892) (xy 375.989212 -43.934374) (xy 375.975231 -43.984422) (xy 375.954585 -44.032108)
			(xy 375.927656 -44.07655) (xy 375.894942 -44.116924) (xy 375.876312 -44.13504) (xy 375.875296 -44.136056)
			(xy 375.874788 -44.136564) (xy 375.874534 -44.136818) (xy 375.854384 -44.155501) (xy 375.8097 -44.187479)
			(xy 375.760892 -44.212718) (xy 375.735088 -44.222162) (xy 375.73458 -44.222416) (xy 375.723658 -44.22775)
			(xy 375.7138 -44.235129) (xy 375.701878 -44.256629) (xy 375.700798 -44.268898) (xy 375.700798 -44.462954)
			(xy 375.702068 -44.47413) (xy 375.703123 -44.478352) (xy 375.706447 -44.486392) (xy 375.708672 -44.490132)
			(xy 375.708926 -44.490386) (xy 375.715022 -44.499022) (xy 375.727468 -44.508166) (xy 375.735596 -44.51096)
			(xy 375.76059 -44.519757) (xy 375.808066 -44.543285) (xy 375.85183 -44.573155) (xy 375.891041 -44.608794)
			(xy 375.924943 -44.649515) (xy 375.952884 -44.694535) (xy 375.974328 -44.742988) (xy 375.988862 -44.793942)
			(xy 375.996206 -44.846417) (xy 375.996708 -44.87291) (xy 375.996268 -44.898892) (xy 375.989212 -44.950374)
			(xy 375.975231 -45.000422) (xy 375.954585 -45.048108) (xy 375.927656 -45.09255) (xy 375.894942 -45.132924)
			(xy 375.876312 -45.15104) (xy 375.875296 -45.152056) (xy 375.874788 -45.152564) (xy 375.874534 -45.152818)
			(xy 375.854384 -45.171501) (xy 375.8097 -45.203479) (xy 375.760892 -45.228718) (xy 375.735088 -45.238162)
			(xy 375.73458 -45.238416) (xy 375.723658 -45.24375) (xy 375.7138 -45.251129) (xy 375.701878 -45.272629)
			(xy 375.700798 -45.284898) (xy 375.700798 -45.478954) (xy 375.702068 -45.49013) (xy 375.703123 -45.494352)
			(xy 375.706447 -45.502392) (xy 375.708672 -45.506132) (xy 375.708926 -45.506386) (xy 375.715022 -45.515022)
			(xy 375.727468 -45.524166) (xy 375.735596 -45.52696) (xy 375.76059 -45.535757) (xy 375.808066 -45.559285)
			(xy 375.85183 -45.589155) (xy 375.891041 -45.624794) (xy 375.924943 -45.665515) (xy 375.952884 -45.710535)
			(xy 375.974328 -45.758988) (xy 375.988862 -45.809942) (xy 375.996206 -45.862417) (xy 375.996708 -45.88891)
			(xy 375.996268 -45.914892) (xy 375.989212 -45.966374) (xy 375.975231 -46.016422) (xy 375.954585 -46.064108)
			(xy 375.927656 -46.10855) (xy 375.894942 -46.148924) (xy 375.876312 -46.16704) (xy 375.875296 -46.168056)
			(xy 375.874788 -46.168564) (xy 375.874534 -46.168818) (xy 375.854384 -46.187501) (xy 375.8097 -46.219479)
			(xy 375.760892 -46.244718) (xy 375.735088 -46.254162) (xy 375.73458 -46.254416) (xy 375.723658 -46.25975)
			(xy 375.7138 -46.267129) (xy 375.701878 -46.288629) (xy 375.700798 -46.300898) (xy 375.700798 -47.02302)
			(xy 375.701099 -47.030512) (xy 375.705479 -47.044845) (xy 375.709434 -47.051214) (xy 375.711466 -47.054008)
			(xy 375.714122 -47.05738) (xy 375.720381 -47.063252) (xy 375.723912 -47.065692) (xy 375.730262 -47.069756)
			(xy 375.738898 -47.072042) (xy 375.765876 -47.079479) (xy 375.817462 -47.10117) (xy 375.865324 -47.130166)
			(xy 375.908436 -47.165843) (xy 375.945874 -47.207437) (xy 375.976832 -47.254054) (xy 376.000647 -47.304693)
			(xy 376.016808 -47.358269) (xy 376.024968 -47.413632) (xy 376.02541 -47.441612) (xy 376.024968 -47.467624)
			(xy 376.017897 -47.519167) (xy 376.003887 -47.56927) (xy 375.983198 -47.617004) (xy 375.956215 -47.661485)
			(xy 375.923438 -47.701886) (xy 375.90476 -47.719996) (xy 375.903998 -47.720758) (xy 375.880462 -47.742588)
			(xy 375.827491 -47.778841) (xy 375.769197 -47.805712) (xy 375.73839 -47.814738) (xy 375.73585 -47.8155)
			(xy 375.725896 -47.819344) (xy 375.710082 -47.833631) (xy 375.701423 -47.853104) (xy 375.700798 -47.86376)
			(xy 375.700798 -48.526954) (xy 375.702068 -48.53813) (xy 375.703123 -48.542352) (xy 375.706447 -48.550392)
			(xy 375.708672 -48.554132) (xy 375.708926 -48.554386) (xy 375.715022 -48.563022) (xy 375.727468 -48.572166)
			(xy 375.735596 -48.57496) (xy 375.76059 -48.583757) (xy 375.808066 -48.607285) (xy 375.85183 -48.637155)
			(xy 375.891041 -48.672794) (xy 375.924943 -48.713515) (xy 375.952884 -48.758535) (xy 375.974328 -48.806988)
			(xy 375.988862 -48.857942) (xy 375.996206 -48.910417) (xy 375.996708 -48.93691) (xy 375.996268 -48.962892)
			(xy 375.989212 -49.014374) (xy 375.975231 -49.064422) (xy 375.954585 -49.112108) (xy 375.927656 -49.15655)
			(xy 375.894942 -49.196924) (xy 375.876312 -49.21504) (xy 375.875296 -49.216056) (xy 375.874788 -49.216564)
			(xy 375.874534 -49.216818) (xy 375.854384 -49.235501) (xy 375.8097 -49.267479) (xy 375.760892 -49.292718)
			(xy 375.735088 -49.302162) (xy 375.73458 -49.302416) (xy 375.723658 -49.30775) (xy 375.7138 -49.315129)
			(xy 375.701878 -49.336629) (xy 375.700798 -49.348898) (xy 375.700798 -49.542954) (xy 375.702068 -49.55413)
			(xy 375.703123 -49.558352) (xy 375.706447 -49.566392) (xy 375.708672 -49.570132) (xy 375.708926 -49.570386)
			(xy 375.715022 -49.579022) (xy 375.727468 -49.588166) (xy 375.735596 -49.59096) (xy 375.76059 -49.599757)
			(xy 375.765015 -49.60195) (xy 376.591082 -49.60195) (xy 376.591082 -49.54745) (xy 376.598837 -49.493506)
			(xy 376.614191 -49.441214) (xy 376.636829 -49.39164) (xy 376.666292 -49.345792) (xy 376.70198 -49.304603)
			(xy 376.743166 -49.268911) (xy 376.789012 -49.239445) (xy 376.838584 -49.216802) (xy 376.890875 -49.201444)
			(xy 376.944819 -49.193684) (xy 376.972068 -49.193196) (xy 376.999438 -49.193682) (xy 377.053616 -49.201495)
			(xy 377.106119 -49.21698) (xy 377.155866 -49.239817) (xy 377.201834 -49.269537) (xy 377.222766 -49.287176)
			(xy 377.22302 -49.28743) (xy 377.230094 -49.293034) (xy 377.247021 -49.299269) (xy 377.25604 -49.299622)
			(xy 377.323096 -49.299622) (xy 377.332112 -49.299258) (xy 377.349029 -49.293015) (xy 377.356116 -49.28743)
			(xy 377.356116 -49.287176) (xy 377.35637 -49.287176) (xy 377.377303 -49.269535) (xy 377.423271 -49.239811)
			(xy 377.473017 -49.216965) (xy 377.525519 -49.201469) (xy 377.579697 -49.19364) (xy 377.634439 -49.19364)
			(xy 377.688617 -49.201469) (xy 377.741119 -49.216965) (xy 377.790865 -49.239811) (xy 377.836833 -49.269535)
			(xy 377.857766 -49.287176) (xy 377.85802 -49.28743) (xy 377.865094 -49.293034) (xy 377.882021 -49.299269)
			(xy 377.89104 -49.299622) (xy 377.958096 -49.299622) (xy 377.967112 -49.299258) (xy 377.984029 -49.293015)
			(xy 377.991116 -49.28743) (xy 377.991116 -49.287176) (xy 377.99137 -49.287176) (xy 378.012299 -49.269534)
			(xy 378.058273 -49.239823) (xy 378.108022 -49.216988) (xy 378.160523 -49.201498) (xy 378.214699 -49.19367)
			(xy 378.242068 -49.193196) (xy 378.268383 -49.193619) (xy 378.320514 -49.200863) (xy 378.371157 -49.215191)
			(xy 378.419356 -49.236332) (xy 378.464199 -49.263886) (xy 378.504836 -49.297331) (xy 378.522992 -49.316386)
			(xy 378.530517 -49.323784) (xy 378.549794 -49.332311) (xy 378.56033 -49.332896) (xy 378.635006 -49.332896)
			(xy 378.645558 -49.332385) (xy 378.664853 -49.323837) (xy 378.672344 -49.316386) (xy 378.690482 -49.297313)
			(xy 378.731116 -49.263858) (xy 378.77596 -49.236302) (xy 378.824164 -49.215167) (xy 378.874815 -49.200853)
			(xy 378.926951 -49.193632) (xy 378.953268 -49.193196) (xy 378.980523 -49.193649) (xy 379.034478 -49.201403)
			(xy 379.08678 -49.216756) (xy 379.136364 -49.239397) (xy 379.182222 -49.268864) (xy 379.223419 -49.304558)
			(xy 379.259117 -49.345752) (xy 379.288588 -49.391607) (xy 379.311233 -49.44119) (xy 379.326591 -49.493491)
			(xy 379.334349 -49.547445) (xy 379.334349 -49.601955) (xy 379.326591 -49.655909) (xy 379.311233 -49.70821)
			(xy 379.288588 -49.757793) (xy 379.259117 -49.803648) (xy 379.223419 -49.844842) (xy 379.182222 -49.880536)
			(xy 379.136364 -49.910003) (xy 379.08678 -49.932644) (xy 379.034478 -49.947997) (xy 378.980523 -49.955751)
			(xy 378.953268 -49.956212) (xy 378.926953 -49.955762) (xy 378.874824 -49.948523) (xy 378.824181 -49.9342)
			(xy 378.775983 -49.913065) (xy 378.73114 -49.885516) (xy 378.6905 -49.852075) (xy 378.672344 -49.833022)
			(xy 378.664805 -49.825641) (xy 378.645538 -49.817104) (xy 378.635006 -49.816512) (xy 378.56033 -49.816512)
			(xy 378.54978 -49.81704) (xy 378.530485 -49.825576) (xy 378.522992 -49.833022) (xy 378.504838 -49.852079)
			(xy 378.464207 -49.885535) (xy 378.419366 -49.913093) (xy 378.371166 -49.934231) (xy 378.320518 -49.948548)
			(xy 378.268384 -49.955773) (xy 378.242068 -49.956212) (xy 378.214697 -49.955762) (xy 378.160518 -49.94794)
			(xy 378.108014 -49.932447) (xy 378.058268 -49.909602) (xy 378.012301 -49.879874) (xy 377.99137 -49.862232)
			(xy 377.991116 -49.861978) (xy 377.984031 -49.85639) (xy 377.967113 -49.850145) (xy 377.958096 -49.849786)
			(xy 377.89104 -49.849786) (xy 377.882025 -49.850165) (xy 377.865108 -49.856398) (xy 377.85802 -49.861978)
			(xy 377.85802 -49.862232) (xy 377.857766 -49.862232) (xy 377.836833 -49.879873) (xy 377.790865 -49.909597)
			(xy 377.741119 -49.932443) (xy 377.688617 -49.947939) (xy 377.634439 -49.955768) (xy 377.579697 -49.955768)
			(xy 377.525519 -49.947939) (xy 377.473017 -49.932443) (xy 377.423271 -49.909597) (xy 377.377303 -49.879873)
			(xy 377.35637 -49.862232) (xy 377.356116 -49.861978) (xy 377.349031 -49.85639) (xy 377.332113 -49.850145)
			(xy 377.323096 -49.849786) (xy 377.25604 -49.849786) (xy 377.247025 -49.850165) (xy 377.230108 -49.856398)
			(xy 377.22302 -49.861978) (xy 377.22302 -49.862232) (xy 377.222766 -49.862232) (xy 377.201824 -49.879859)
			(xy 377.155853 -49.909571) (xy 377.106108 -49.932409) (xy 377.05361 -49.947903) (xy 376.999436 -49.955736)
			(xy 376.972068 -49.956212) (xy 376.944819 -49.955716) (xy 376.890875 -49.947956) (xy 376.838584 -49.932598)
			(xy 376.789012 -49.909955) (xy 376.743166 -49.880489) (xy 376.70198 -49.844797) (xy 376.666292 -49.803608)
			(xy 376.636829 -49.75776) (xy 376.614191 -49.708186) (xy 376.598837 -49.655894) (xy 376.591082 -49.60195)
			(xy 375.765015 -49.60195) (xy 375.808066 -49.623285) (xy 375.85183 -49.653155) (xy 375.891041 -49.688794)
			(xy 375.924943 -49.729515) (xy 375.952884 -49.774535) (xy 375.974328 -49.822988) (xy 375.988862 -49.873942)
			(xy 375.996206 -49.926417) (xy 375.996708 -49.95291) (xy 375.996268 -49.978892) (xy 375.989212 -50.030374)
			(xy 375.975231 -50.080422) (xy 375.954585 -50.128108) (xy 375.927656 -50.17255) (xy 375.894942 -50.212924)
			(xy 375.876312 -50.23104) (xy 375.875296 -50.232056) (xy 375.874788 -50.232564) (xy 375.874534 -50.232818)
			(xy 375.854384 -50.251501) (xy 375.8097 -50.283479) (xy 375.760892 -50.308718) (xy 375.735088 -50.318162)
			(xy 375.73458 -50.318416) (xy 375.723658 -50.32375) (xy 375.7138 -50.331129) (xy 375.701878 -50.352629)
			(xy 375.700798 -50.364898) (xy 375.700798 -50.60696) (xy 375.701164 -50.614995) (xy 375.706216 -50.630256)
			(xy 375.710704 -50.636932) (xy 375.715276 -50.643282) (xy 375.727976 -50.652426) (xy 375.736612 -50.65522)
			(xy 375.762169 -50.663657) (xy 375.810799 -50.686713) (xy 375.855708 -50.716372) (xy 375.896005 -50.752047)
			(xy 375.93089 -50.793029) (xy 375.95967 -50.838506) (xy 375.981776 -50.887576) (xy 375.996769 -50.939264)
			(xy 376.00435 -50.992547) (xy 376.004836 -51.019456) (xy 376.004397 -51.045469) (xy 375.997332 -51.097014)
			(xy 375.983326 -51.14712) (xy 375.962639 -51.194858) (xy 375.935656 -51.23934) (xy 375.902877 -51.279742)
			(xy 375.884186 -51.29784) (xy 375.883932 -51.298094) (xy 375.877328 -51.304444) (xy 375.87682 -51.304952)
			(xy 375.856289 -51.323239) (xy 375.810945 -51.354333) (xy 375.761608 -51.378597) (xy 375.735596 -51.387502)
			(xy 375.731736 -51.388827) (xy 375.724461 -51.392527) (xy 375.721118 -51.394868) (xy 375.715276 -51.399186)
			(xy 375.709688 -51.406806) (xy 375.705583 -51.413259) (xy 375.701064 -51.427864) (xy 375.700798 -51.435508)
			(xy 375.700798 -51.62296) (xy 375.700875 -51.62717) (xy 375.702273 -51.635472) (xy 375.703592 -51.63947)
			(xy 375.736358 -51.670966) (xy 375.747026 -51.674522) (xy 375.771772 -51.683466) (xy 375.782826 -51.689052)
			(xy 376.555477 -51.689052) (xy 376.555477 -51.634548) (xy 376.563234 -51.5806) (xy 376.57859 -51.528304)
			(xy 376.601231 -51.478727) (xy 376.630698 -51.432876) (xy 376.666391 -51.391685) (xy 376.707582 -51.355994)
			(xy 376.753434 -51.326528) (xy 376.803012 -51.303887) (xy 376.855308 -51.288532) (xy 376.909256 -51.280777)
			(xy 376.936508 -51.280314) (xy 376.963879 -51.280772) (xy 377.018058 -51.288591) (xy 377.070561 -51.304082)
			(xy 377.120308 -51.326926) (xy 377.166275 -51.356652) (xy 377.187206 -51.374294) (xy 377.18746 -51.374548)
			(xy 377.19455 -51.38013) (xy 377.211464 -51.386378) (xy 377.22048 -51.38674) (xy 377.287536 -51.38674)
			(xy 377.296556 -51.386413) (xy 377.313474 -51.380146) (xy 377.320556 -51.374548) (xy 377.320556 -51.374294)
			(xy 377.32081 -51.374294) (xy 377.341727 -51.356636) (xy 377.387704 -51.326927) (xy 377.437455 -51.304095)
			(xy 377.489959 -51.288608) (xy 377.544138 -51.280785) (xy 377.571508 -51.280314) (xy 377.589851 -51.280542)
			(xy 377.626364 -51.284108) (xy 377.644406 -51.287426) (xy 377.655039 -51.289001) (xy 377.675956 -51.284146)
			(xy 377.684792 -51.278028) (xy 377.75388 -51.225704) (xy 377.764294 -51.206908) (xy 377.765056 -51.195986)
			(xy 377.767944 -51.167701) (xy 377.780982 -51.112363) (xy 377.802079 -51.05957) (xy 377.83077 -51.010487)
			(xy 377.866419 -50.966199) (xy 377.886976 -50.946558) (xy 377.894395 -50.939051) (xy 377.90291 -50.91976)
			(xy 377.903486 -50.90922) (xy 377.903486 -50.834544) (xy 377.902951 -50.823995) (xy 377.89442 -50.804699)
			(xy 377.886976 -50.797206) (xy 377.867926 -50.779045) (xy 377.834469 -50.738416) (xy 377.80691 -50.693577)
			(xy 377.785771 -50.645377) (xy 377.771452 -50.594731) (xy 377.764226 -50.542598) (xy 377.763786 -50.516282)
			(xy 377.764272 -50.489031) (xy 377.772028 -50.435083) (xy 377.787383 -50.382788) (xy 377.810025 -50.333211)
			(xy 377.839491 -50.287361) (xy 377.875182 -50.24617) (xy 377.916373 -50.210479) (xy 377.962223 -50.181013)
			(xy 378.0118 -50.158371) (xy 378.064095 -50.143016) (xy 378.118043 -50.13526) (xy 378.172545 -50.13526)
			(xy 378.226493 -50.143016) (xy 378.278788 -50.158371) (xy 378.328365 -50.181013) (xy 378.374215 -50.210479)
			(xy 378.415406 -50.24617) (xy 378.451097 -50.287361) (xy 378.480563 -50.333211) (xy 378.503205 -50.382788)
			(xy 378.51856 -50.435083) (xy 378.526316 -50.489031) (xy 378.526802 -50.516282) (xy 378.526322 -50.542596)
			(xy 378.51909 -50.594723) (xy 378.504773 -50.645366) (xy 378.483643 -50.693565) (xy 378.456099 -50.738409)
			(xy 378.422663 -50.779049) (xy 378.403612 -50.797206) (xy 378.396208 -50.804725) (xy 378.387684 -50.824007)
			(xy 378.387102 -50.834544) (xy 378.387102 -50.90922) (xy 378.38766 -50.919766) (xy 378.396175 -50.939062)
			(xy 378.403612 -50.946558) (xy 378.422691 -50.96469) (xy 378.456146 -51.005325) (xy 378.483701 -51.05017)
			(xy 378.504835 -51.098376) (xy 378.519148 -51.149027) (xy 378.526367 -51.201165) (xy 378.526802 -51.227482)
			(xy 378.526328 -51.254735) (xy 378.518573 -51.308686) (xy 378.503219 -51.360984) (xy 378.480578 -51.410564)
			(xy 378.451112 -51.456418) (xy 378.415419 -51.497611) (xy 378.374227 -51.533304) (xy 378.328375 -51.562773)
			(xy 378.278795 -51.585415) (xy 378.226497 -51.600771) (xy 378.172547 -51.608527) (xy 378.145294 -51.60899)
			(xy 378.126951 -51.608762) (xy 378.090438 -51.605196) (xy 378.072396 -51.601878) (xy 378.061762 -51.600323)
			(xy 378.040849 -51.605167) (xy 378.03201 -51.611276) (xy 377.962922 -51.6636) (xy 377.952508 -51.682396)
			(xy 377.951746 -51.693318) (xy 377.94886 -51.721577) (xy 377.935827 -51.776863) (xy 377.914741 -51.829607)
			(xy 377.886069 -51.878641) (xy 377.850444 -51.922882) (xy 377.808654 -51.961353) (xy 377.761621 -51.993202)
			(xy 377.710387 -52.017727) (xy 377.656083 -52.034385) (xy 377.599909 -52.042807) (xy 377.571508 -52.04333)
			(xy 377.544137 -52.042876) (xy 377.489957 -52.035058) (xy 377.437453 -52.019567) (xy 377.387706 -51.996722)
			(xy 377.341741 -51.966994) (xy 377.32081 -51.94935) (xy 377.320556 -51.949096) (xy 377.313458 -51.943526)
			(xy 377.29655 -51.93727) (xy 377.287536 -51.936904) (xy 377.22048 -51.936904) (xy 377.211462 -51.937251)
			(xy 377.194545 -51.943505) (xy 377.18746 -51.949096) (xy 377.18746 -51.94935) (xy 377.187206 -51.94935)
			(xy 377.166276 -51.966992) (xy 377.120303 -51.996705) (xy 377.070556 -52.019541) (xy 377.018054 -52.035031)
			(xy 376.963877 -52.042858) (xy 376.936508 -52.04333) (xy 376.909256 -52.042823) (xy 376.855308 -52.035068)
			(xy 376.803012 -52.019713) (xy 376.753434 -51.997072) (xy 376.707582 -51.967606) (xy 376.666391 -51.931915)
			(xy 376.630698 -51.890724) (xy 376.601231 -51.844873) (xy 376.57859 -51.795296) (xy 376.563234 -51.743)
			(xy 376.555477 -51.689052) (xy 375.782826 -51.689052) (xy 375.818735 -51.707198) (xy 375.861989 -51.73716)
			(xy 375.900716 -51.772782) (xy 375.934179 -51.813389) (xy 375.961743 -51.85821) (xy 375.982885 -51.906394)
			(xy 375.997204 -51.957027) (xy 376.004429 -52.009147) (xy 376.004836 -52.035456) (xy 376.004397 -52.061469)
			(xy 375.997332 -52.113014) (xy 375.983326 -52.16312) (xy 375.962639 -52.210858) (xy 375.935656 -52.25534)
			(xy 375.902877 -52.295742) (xy 375.884186 -52.31384) (xy 375.883932 -52.314094) (xy 375.879614 -52.318158)
			(xy 375.872352 -52.325659) (xy 375.8641 -52.344812) (xy 375.863612 -52.355242) (xy 375.863612 -52.564153)
			(xy 378.12723 -52.564153) (xy 378.12723 -52.509647) (xy 378.134986 -52.455696) (xy 378.150341 -52.403398)
			(xy 378.172982 -52.353817) (xy 378.202449 -52.307963) (xy 378.23814 -52.266769) (xy 378.279331 -52.231073)
			(xy 378.325182 -52.201602) (xy 378.37476 -52.178955) (xy 378.427057 -52.163595) (xy 378.481007 -52.155833)
			(xy 378.50826 -52.155344) (xy 378.53563 -52.155823) (xy 378.589809 -52.163636) (xy 378.642312 -52.179121)
			(xy 378.692059 -52.201961) (xy 378.738026 -52.231683) (xy 378.758958 -52.249324) (xy 378.759212 -52.249578)
			(xy 378.766284 -52.255185) (xy 378.783212 -52.261417) (xy 378.792232 -52.26177) (xy 378.859288 -52.26177)
			(xy 378.868305 -52.261414) (xy 378.885222 -52.255166) (xy 378.892308 -52.249578) (xy 378.892308 -52.249324)
			(xy 378.892562 -52.249324) (xy 378.913501 -52.231693) (xy 378.959471 -52.201979) (xy 379.009217 -52.179141)
			(xy 379.061716 -52.163648) (xy 379.115891 -52.155819) (xy 379.14326 -52.155344) (xy 379.170511 -52.1559)
			(xy 379.22446 -52.163652) (xy 379.276756 -52.179002) (xy 379.326335 -52.20164) (xy 379.372187 -52.231103)
			(xy 379.413379 -52.266792) (xy 379.449073 -52.307981) (xy 379.478541 -52.35383) (xy 379.501184 -52.403407)
			(xy 379.51654 -52.455701) (xy 379.524297 -52.509649) (xy 379.524297 -52.564151) (xy 379.51654 -52.618099)
			(xy 379.501184 -52.670393) (xy 379.478541 -52.71997) (xy 379.449073 -52.765819) (xy 379.413379 -52.807008)
			(xy 379.372187 -52.842697) (xy 379.326335 -52.87216) (xy 379.276756 -52.894798) (xy 379.22446 -52.910148)
			(xy 379.170511 -52.9179) (xy 379.14326 -52.91836) (xy 379.115891 -52.917869) (xy 379.061712 -52.910058)
			(xy 379.009209 -52.894576) (xy 378.959462 -52.871739) (xy 378.913494 -52.842019) (xy 378.892562 -52.82438)
			(xy 378.892308 -52.824126) (xy 378.88523 -52.818528) (xy 378.868306 -52.81229) (xy 378.859288 -52.811934)
			(xy 378.792232 -52.811934) (xy 378.783216 -52.812299) (xy 378.766298 -52.81854) (xy 378.759212 -52.824126)
			(xy 378.759212 -52.82438) (xy 378.758958 -52.82438) (xy 378.738012 -52.842002) (xy 378.692044 -52.871717)
			(xy 378.6423 -52.894557) (xy 378.589802 -52.910052) (xy 378.535628 -52.917884) (xy 378.50826 -52.91836)
			(xy 378.481007 -52.917967) (xy 378.427057 -52.910205) (xy 378.37476 -52.894845) (xy 378.325182 -52.872198)
			(xy 378.279331 -52.842727) (xy 378.23814 -52.807031) (xy 378.202449 -52.765837) (xy 378.172982 -52.719983)
			(xy 378.150341 -52.670402) (xy 378.134986 -52.618104) (xy 378.12723 -52.564153) (xy 375.863612 -52.564153)
			(xy 375.863612 -52.731924) (xy 375.86416 -52.742524) (xy 375.872692 -52.761935) (xy 375.880122 -52.769516)
			(xy 375.899397 -52.78765) (xy 375.933253 -52.828323) (xy 375.961154 -52.873291) (xy 375.982561 -52.921689)
			(xy 375.997063 -52.972583) (xy 376.004381 -53.024996) (xy 376.004836 -53.051456) (xy 376.004397 -53.077469)
			(xy 375.997332 -53.129014) (xy 375.983326 -53.17912) (xy 375.962639 -53.226858) (xy 375.935656 -53.27134)
			(xy 375.902877 -53.311742) (xy 375.884186 -53.32984) (xy 375.883932 -53.330094) (xy 375.879614 -53.334158)
			(xy 375.872352 -53.341659) (xy 375.8641 -53.360812) (xy 375.863612 -53.371242) (xy 375.863612 -53.747924)
			(xy 375.86416 -53.758524) (xy 375.872692 -53.777935) (xy 375.880122 -53.785516) (xy 375.899397 -53.80365)
			(xy 375.933253 -53.844323) (xy 375.961154 -53.889291) (xy 375.982561 -53.937689) (xy 375.997063 -53.988583)
			(xy 376.004381 -54.040996) (xy 376.004836 -54.067456) (xy 376.004397 -54.093469) (xy 375.997332 -54.145014)
			(xy 375.983326 -54.19512) (xy 375.964352 -54.238906) (xy 382.68605 -54.238906) (xy 382.690121 -54.183284)
			(xy 382.702247 -54.128847) (xy 382.72217 -54.076756) (xy 382.749466 -54.028121) (xy 382.783552 -53.983978)
			(xy 382.823701 -53.945269) (xy 382.869059 -53.912818) (xy 382.918659 -53.887317) (xy 382.971443 -53.86931)
			(xy 383.026286 -53.85918) (xy 383.08202 -53.857143) (xy 383.137457 -53.863243) (xy 383.191414 -53.877349)
			(xy 383.242743 -53.899161) (xy 383.290349 -53.928215) (xy 383.333217 -53.96389) (xy 383.370434 -54.005427)
			(xy 383.401207 -54.05194) (xy 383.424879 -54.102437) (xy 383.440947 -54.155844) (xy 383.449067 -54.21102)
			(xy 383.449576 -54.238906) (xy 383.449067 -54.266792) (xy 383.440947 -54.321968) (xy 383.424879 -54.375375)
			(xy 383.401207 -54.425872) (xy 383.370434 -54.472385) (xy 383.333217 -54.513922) (xy 383.290349 -54.549597)
			(xy 383.242743 -54.578651) (xy 383.191414 -54.600463) (xy 383.137457 -54.614569) (xy 383.08202 -54.620669)
			(xy 383.026286 -54.618632) (xy 382.971443 -54.608502) (xy 382.918659 -54.590495) (xy 382.869059 -54.564994)
			(xy 382.823701 -54.532543) (xy 382.783552 -54.493834) (xy 382.749466 -54.449691) (xy 382.72217 -54.401056)
			(xy 382.702247 -54.348965) (xy 382.690121 -54.294528) (xy 382.68605 -54.238906) (xy 375.964352 -54.238906)
			(xy 375.962639 -54.242858) (xy 375.935656 -54.28734) (xy 375.902877 -54.327742) (xy 375.884186 -54.34584)
			(xy 375.883932 -54.346094) (xy 375.879614 -54.350158) (xy 375.872352 -54.357659) (xy 375.8641 -54.376812)
			(xy 375.863612 -54.387242) (xy 375.863612 -54.763924) (xy 375.86416 -54.774524) (xy 375.872692 -54.793935)
			(xy 375.880122 -54.801516) (xy 375.899397 -54.81965) (xy 375.933253 -54.860323) (xy 375.961154 -54.905291)
			(xy 375.982561 -54.953689) (xy 375.992637 -54.989051) (xy 378.201168 -54.989051) (xy 378.201168 -54.934549)
			(xy 378.208924 -54.880602) (xy 378.224278 -54.828308) (xy 378.246918 -54.778732) (xy 378.276382 -54.732881)
			(xy 378.312072 -54.691691) (xy 378.35326 -54.655998) (xy 378.399109 -54.62653) (xy 378.448684 -54.603887)
			(xy 378.500977 -54.588529) (xy 378.554923 -54.58077) (xy 378.582174 -54.580282) (xy 378.610265 -54.580797)
			(xy 378.665841 -54.589021) (xy 378.71961 -54.605308) (xy 378.770407 -54.629308) (xy 378.817134 -54.660499)
			(xy 378.85878 -54.698208) (xy 378.894443 -54.741619) (xy 378.909326 -54.765448) (xy 378.91466 -54.774338)
			(xy 378.931678 -54.78653) (xy 379.024896 -54.80685) (xy 379.04547 -54.802532) (xy 379.054106 -54.79669)
			(xy 379.078166 -54.780684) (xy 379.130099 -54.755343) (xy 379.185258 -54.738119) (xy 379.242383 -54.729406)
			(xy 379.271276 -54.728872) (xy 379.298527 -54.729378) (xy 379.352476 -54.737131) (xy 379.404772 -54.752483)
			(xy 379.45435 -54.775121) (xy 379.500203 -54.804585) (xy 379.541395 -54.840274) (xy 379.577089 -54.881462)
			(xy 379.606558 -54.927311) (xy 379.629202 -54.976887) (xy 379.64456 -55.029181) (xy 379.652319 -55.083129)
			(xy 379.652784 -55.11038) (xy 379.65231 -55.13775) (xy 379.644495 -55.191929) (xy 379.629008 -55.244432)
			(xy 379.606168 -55.294179) (xy 379.576445 -55.340146) (xy 379.558804 -55.361078) (xy 379.55855 -55.361332)
			(xy 379.55298 -55.36843) (xy 379.546724 -55.385338) (xy 379.546358 -55.394352) (xy 379.546358 -55.461408)
			(xy 379.546699 -55.470427) (xy 379.552956 -55.487344) (xy 379.55855 -55.494428) (xy 379.558804 -55.494428)
			(xy 379.558804 -55.494682) (xy 379.576424 -55.515631) (xy 379.606147 -55.561597) (xy 379.628992 -55.611341)
			(xy 379.644488 -55.66384) (xy 379.652318 -55.718016) (xy 379.65232 -55.772754) (xy 379.644495 -55.826931)
			(xy 379.629002 -55.879431) (xy 379.606162 -55.929177) (xy 379.576442 -55.975145) (xy 379.558804 -55.996078)
			(xy 379.55855 -55.996332) (xy 379.55298 -56.00343) (xy 379.546724 -56.020338) (xy 379.546358 -56.029352)
			(xy 379.546358 -56.096408) (xy 379.546699 -56.105427) (xy 379.552956 -56.122344) (xy 379.55855 -56.129428)
			(xy 379.558804 -56.129428) (xy 379.558804 -56.129682) (xy 379.576449 -56.15061) (xy 379.60616 -56.196584)
			(xy 379.628994 -56.246332) (xy 379.644484 -56.298834) (xy 379.652311 -56.353011) (xy 379.652784 -56.38038)
			(xy 379.652298 -56.407631) (xy 379.644542 -56.461579) (xy 379.629187 -56.513874) (xy 379.606545 -56.563451)
			(xy 379.577079 -56.609301) (xy 379.541388 -56.650492) (xy 379.500197 -56.686183) (xy 379.454347 -56.715649)
			(xy 379.40477 -56.738291) (xy 379.352475 -56.753646) (xy 379.298527 -56.761402) (xy 379.244025 -56.761402)
			(xy 379.190077 -56.753646) (xy 379.137782 -56.738291) (xy 379.088205 -56.715649) (xy 379.042355 -56.686183)
			(xy 379.001164 -56.650492) (xy 378.965473 -56.609301) (xy 378.936007 -56.563451) (xy 378.913365 -56.513874)
			(xy 378.89801 -56.461579) (xy 378.890254 -56.407631) (xy 378.889768 -56.38038) (xy 378.890206 -56.353009)
			(xy 378.898028 -56.298828) (xy 378.913523 -56.246324) (xy 378.936371 -56.196577) (xy 378.966103 -56.150612)
			(xy 378.983748 -56.129682) (xy 378.984002 -56.129428) (xy 378.989583 -56.122338) (xy 378.995833 -56.105424)
			(xy 378.996194 -56.096408) (xy 378.996194 -56.029352) (xy 378.995813 -56.020338) (xy 378.989582 -56.00342)
			(xy 378.984002 -55.996332) (xy 378.983748 -55.996332) (xy 378.983748 -55.996078) (xy 378.966087 -55.975162)
			(xy 378.936361 -55.929191) (xy 378.913516 -55.879443) (xy 378.89802 -55.826938) (xy 378.890193 -55.772757)
			(xy 378.890195 -55.718013) (xy 378.898027 -55.663833) (xy 378.913526 -55.611329) (xy 378.936376 -55.561582)
			(xy 378.966105 -55.515614) (xy 378.983748 -55.494682) (xy 378.984002 -55.494428) (xy 378.989583 -55.487338)
			(xy 378.995833 -55.470424) (xy 378.996194 -55.461408) (xy 378.996194 -55.394352) (xy 378.995813 -55.385338)
			(xy 378.989582 -55.36842) (xy 378.984002 -55.361332) (xy 378.983748 -55.360824) (xy 378.972801 -55.348092)
			(xy 378.952962 -55.320999) (xy 378.944124 -55.306722) (xy 378.93879 -55.297832) (xy 378.921772 -55.28564)
			(xy 378.828554 -55.26532) (xy 378.80798 -55.269638) (xy 378.799344 -55.27548) (xy 378.775268 -55.291461)
			(xy 378.723341 -55.316809) (xy 378.668187 -55.33404) (xy 378.611066 -55.342761) (xy 378.582174 -55.343298)
			(xy 378.554923 -55.34283) (xy 378.500977 -55.335071) (xy 378.448684 -55.319713) (xy 378.399109 -55.29707)
			(xy 378.35326 -55.267602) (xy 378.312072 -55.231909) (xy 378.276382 -55.190719) (xy 378.246918 -55.144868)
			(xy 378.224278 -55.095292) (xy 378.208924 -55.042998) (xy 378.201168 -54.989051) (xy 375.992637 -54.989051)
			(xy 375.997063 -55.004583) (xy 376.004381 -55.056996) (xy 376.004836 -55.083456) (xy 376.004397 -55.109469)
			(xy 375.997332 -55.161014) (xy 375.983326 -55.21112) (xy 375.962639 -55.258858) (xy 375.935656 -55.30334)
			(xy 375.902877 -55.343742) (xy 375.884186 -55.36184) (xy 375.883932 -55.362094) (xy 375.879614 -55.366158)
			(xy 375.872352 -55.373659) (xy 375.8641 -55.392812) (xy 375.863612 -55.403242) (xy 375.863612 -55.420851)
			(xy 376.524768 -55.420851) (xy 376.524768 -55.366349) (xy 376.532524 -55.312402) (xy 376.547878 -55.260108)
			(xy 376.570518 -55.210532) (xy 376.599982 -55.164681) (xy 376.635672 -55.123491) (xy 376.67686 -55.087798)
			(xy 376.722709 -55.05833) (xy 376.772284 -55.035687) (xy 376.824577 -55.020329) (xy 376.878523 -55.01257)
			(xy 376.905774 -55.012082) (xy 376.932087 -55.012572) (xy 376.984214 -55.019803) (xy 377.034856 -55.034118)
			(xy 377.083055 -55.055247) (xy 377.127899 -55.082788) (xy 377.16854 -55.116223) (xy 377.186698 -55.135272)
			(xy 377.194222 -55.142671) (xy 377.2135 -55.151198) (xy 377.224036 -55.151782) (xy 377.298712 -55.151782)
			(xy 377.309265 -55.151278) (xy 377.32856 -55.142726) (xy 377.33605 -55.135272) (xy 377.354183 -55.116194)
			(xy 377.394818 -55.08274) (xy 377.439663 -55.055184) (xy 377.487868 -55.03405) (xy 377.53852 -55.019738)
			(xy 377.590657 -55.012518) (xy 377.616974 -55.012082) (xy 377.644227 -55.012564) (xy 377.69818 -55.020317)
			(xy 377.750479 -55.035671) (xy 377.800061 -55.058311) (xy 377.845917 -55.087778) (xy 377.887111 -55.12347)
			(xy 377.922807 -55.164663) (xy 377.952276 -55.210516) (xy 377.97492 -55.260096) (xy 377.990277 -55.312395)
			(xy 377.998035 -55.366347) (xy 377.998035 -55.420853) (xy 377.990277 -55.474805) (xy 377.97492 -55.527104)
			(xy 377.952276 -55.576684) (xy 377.922807 -55.622537) (xy 377.887111 -55.66373) (xy 377.845917 -55.699422)
			(xy 377.800061 -55.728889) (xy 377.750479 -55.751529) (xy 377.69818 -55.766883) (xy 377.644227 -55.774636)
			(xy 377.616974 -55.775098) (xy 377.590659 -55.774649) (xy 377.53853 -55.76741) (xy 377.487887 -55.753088)
			(xy 377.439688 -55.731952) (xy 377.394845 -55.704402) (xy 377.354206 -55.670961) (xy 377.33605 -55.651908)
			(xy 377.328548 -55.644484) (xy 377.309253 -55.635972) (xy 377.298712 -55.635398) (xy 377.224036 -55.635398)
			(xy 377.213487 -55.635934) (xy 377.194192 -55.644464) (xy 377.186698 -55.651908) (xy 377.168538 -55.670959)
			(xy 377.127909 -55.704416) (xy 377.08307 -55.731976) (xy 377.03487 -55.753115) (xy 376.984223 -55.767433)
			(xy 376.93209 -55.774659) (xy 376.905774 -55.775098) (xy 376.878523 -55.77463) (xy 376.824577 -55.766871)
			(xy 376.772284 -55.751513) (xy 376.722709 -55.72887) (xy 376.67686 -55.699402) (xy 376.635672 -55.663709)
			(xy 376.599982 -55.622519) (xy 376.570518 -55.576668) (xy 376.547878 -55.527092) (xy 376.532524 -55.474798)
			(xy 376.524768 -55.420851) (xy 375.863612 -55.420851) (xy 375.863612 -56.033924) (xy 375.86416 -56.044524)
			(xy 375.872692 -56.063935) (xy 375.880122 -56.071516) (xy 375.899397 -56.08965) (xy 375.933253 -56.130323)
			(xy 375.961154 -56.175291) (xy 375.982561 -56.223689) (xy 375.997063 -56.274583) (xy 376.004381 -56.326996)
			(xy 376.004836 -56.353456) (xy 376.004397 -56.379469) (xy 375.997332 -56.431014) (xy 375.983326 -56.48112)
			(xy 375.962639 -56.528858) (xy 375.935656 -56.57334) (xy 375.902877 -56.613742) (xy 375.884186 -56.63184)
			(xy 375.883932 -56.632094) (xy 375.879614 -56.636158) (xy 375.872352 -56.643659) (xy 375.8641 -56.662812)
			(xy 375.863612 -56.673242) (xy 375.863612 -57.48528) (xy 378.906022 -57.48528) (xy 378.910093 -57.429658)
			(xy 378.922219 -57.375221) (xy 378.942142 -57.32313) (xy 378.969438 -57.274495) (xy 379.003524 -57.230352)
			(xy 379.043673 -57.191643) (xy 379.089031 -57.159192) (xy 379.138631 -57.133691) (xy 379.191415 -57.115684)
			(xy 379.246258 -57.105554) (xy 379.301992 -57.103517) (xy 379.357429 -57.109617) (xy 379.411386 -57.123723)
			(xy 379.462715 -57.145535) (xy 379.510321 -57.174589) (xy 379.553189 -57.210264) (xy 379.590406 -57.251801)
			(xy 379.621179 -57.298314) (xy 379.644851 -57.348811) (xy 379.660919 -57.402218) (xy 379.669039 -57.457394)
			(xy 379.669548 -57.48528) (xy 379.669039 -57.513166) (xy 379.660919 -57.568342) (xy 379.644851 -57.621749)
			(xy 379.621179 -57.672246) (xy 379.590406 -57.718759) (xy 379.553189 -57.760296) (xy 379.510321 -57.795971)
			(xy 379.462715 -57.825025) (xy 379.411386 -57.846837) (xy 379.357429 -57.860943) (xy 379.301992 -57.867043)
			(xy 379.246258 -57.865006) (xy 379.191415 -57.854876) (xy 379.138631 -57.836869) (xy 379.089031 -57.811368)
			(xy 379.043673 -57.778917) (xy 379.003524 -57.740208) (xy 378.969438 -57.696065) (xy 378.942142 -57.64743)
			(xy 378.922219 -57.595339) (xy 378.910093 -57.540902) (xy 378.906022 -57.48528) (xy 375.863612 -57.48528)
			(xy 375.863612 -58.076084) (xy 379.658116 -58.076084) (xy 379.662187 -58.020462) (xy 379.674313 -57.966025)
			(xy 379.694236 -57.913934) (xy 379.721532 -57.865299) (xy 379.755618 -57.821156) (xy 379.795767 -57.782447)
			(xy 379.841125 -57.749996) (xy 379.890725 -57.724495) (xy 379.943509 -57.706488) (xy 379.998352 -57.696358)
			(xy 380.054086 -57.694321) (xy 380.109523 -57.700421) (xy 380.16348 -57.714527) (xy 380.214809 -57.736339)
			(xy 380.262415 -57.765393) (xy 380.305283 -57.801068) (xy 380.3425 -57.842605) (xy 380.358836 -57.867296)
			(xy 381.942846 -57.867296) (xy 381.946919 -57.811637) (xy 381.959054 -57.757164) (xy 381.97899 -57.705038)
			(xy 382.006304 -57.65637) (xy 382.040412 -57.612198) (xy 382.080589 -57.573463) (xy 382.125977 -57.540991)
			(xy 382.175609 -57.515473) (xy 382.228429 -57.497454) (xy 382.283308 -57.487317) (xy 382.339079 -57.485279)
			(xy 382.394553 -57.491382) (xy 382.448546 -57.505498) (xy 382.499909 -57.527325) (xy 382.547547 -57.556398)
			(xy 382.590443 -57.592097) (xy 382.627685 -57.633661) (xy 382.658479 -57.680205) (xy 382.682167 -57.730736)
			(xy 382.698245 -57.784178) (xy 382.706371 -57.839392) (xy 382.70688 -57.867296) (xy 382.706371 -57.8952)
			(xy 382.698245 -57.950414) (xy 382.682167 -58.003856) (xy 382.658479 -58.054387) (xy 382.627685 -58.100931)
			(xy 382.590443 -58.142495) (xy 382.547547 -58.178194) (xy 382.499909 -58.207267) (xy 382.448546 -58.229094)
			(xy 382.394553 -58.24321) (xy 382.339079 -58.249313) (xy 382.283308 -58.247275) (xy 382.228429 -58.237138)
			(xy 382.175609 -58.219119) (xy 382.125977 -58.193601) (xy 382.080589 -58.161129) (xy 382.040412 -58.122394)
			(xy 382.006304 -58.078222) (xy 381.97899 -58.029554) (xy 381.959054 -57.977428) (xy 381.946919 -57.922955)
			(xy 381.942846 -57.867296) (xy 380.358836 -57.867296) (xy 380.373273 -57.889118) (xy 380.396945 -57.939615)
			(xy 380.413013 -57.993022) (xy 380.421133 -58.048198) (xy 380.421642 -58.076084) (xy 380.421133 -58.10397)
			(xy 380.413013 -58.159146) (xy 380.396945 -58.212553) (xy 380.373273 -58.26305) (xy 380.3425 -58.309563)
			(xy 380.305283 -58.3511) (xy 380.262415 -58.386775) (xy 380.214809 -58.415829) (xy 380.16348 -58.437641)
			(xy 380.109523 -58.451747) (xy 380.054086 -58.457847) (xy 379.998352 -58.45581) (xy 379.943509 -58.44568)
			(xy 379.890725 -58.427673) (xy 379.841125 -58.402172) (xy 379.795767 -58.369721) (xy 379.755618 -58.331012)
			(xy 379.721532 -58.286869) (xy 379.694236 -58.238234) (xy 379.674313 -58.186143) (xy 379.662187 -58.131706)
			(xy 379.658116 -58.076084) (xy 375.863612 -58.076084) (xy 375.863612 -58.561224) (xy 380.86233 -58.561224)
			(xy 380.866401 -58.505602) (xy 380.878527 -58.451165) (xy 380.89845 -58.399074) (xy 380.925746 -58.350439)
			(xy 380.959832 -58.306296) (xy 380.999981 -58.267587) (xy 381.045339 -58.235136) (xy 381.094939 -58.209635)
			(xy 381.147723 -58.191628) (xy 381.202566 -58.181498) (xy 381.2583 -58.179461) (xy 381.313737 -58.185561)
			(xy 381.367694 -58.199667) (xy 381.419023 -58.221479) (xy 381.466629 -58.250533) (xy 381.509497 -58.286208)
			(xy 381.546714 -58.327745) (xy 381.577487 -58.374258) (xy 381.601159 -58.424755) (xy 381.608669 -58.449718)
			(xy 383.10896 -58.449718) (xy 383.113031 -58.394096) (xy 383.125157 -58.339659) (xy 383.14508 -58.287568)
			(xy 383.172376 -58.238933) (xy 383.206462 -58.19479) (xy 383.246611 -58.156081) (xy 383.291969 -58.12363)
			(xy 383.341569 -58.098129) (xy 383.394353 -58.080122) (xy 383.449196 -58.069992) (xy 383.50493 -58.067955)
			(xy 383.560367 -58.074055) (xy 383.614324 -58.088161) (xy 383.665653 -58.109973) (xy 383.713259 -58.139027)
			(xy 383.756127 -58.174702) (xy 383.793344 -58.216239) (xy 383.824117 -58.262752) (xy 383.847789 -58.313249)
			(xy 383.863857 -58.366656) (xy 383.871977 -58.421832) (xy 383.872486 -58.449718) (xy 383.871977 -58.477604)
			(xy 383.863857 -58.53278) (xy 383.847789 -58.586187) (xy 383.824117 -58.636684) (xy 383.793344 -58.683197)
			(xy 383.756127 -58.724734) (xy 383.713259 -58.760409) (xy 383.665653 -58.789463) (xy 383.614324 -58.811275)
			(xy 383.560367 -58.825381) (xy 383.50493 -58.831481) (xy 383.449196 -58.829444) (xy 383.394353 -58.819314)
			(xy 383.341569 -58.801307) (xy 383.291969 -58.775806) (xy 383.246611 -58.743355) (xy 383.206462 -58.704646)
			(xy 383.172376 -58.660503) (xy 383.14508 -58.611868) (xy 383.125157 -58.559777) (xy 383.113031 -58.50534)
			(xy 383.10896 -58.449718) (xy 381.608669 -58.449718) (xy 381.617227 -58.478162) (xy 381.625347 -58.533338)
			(xy 381.625856 -58.561224) (xy 381.625347 -58.58911) (xy 381.617227 -58.644286) (xy 381.601159 -58.697693)
			(xy 381.577487 -58.74819) (xy 381.546714 -58.794703) (xy 381.509497 -58.83624) (xy 381.466629 -58.871915)
			(xy 381.419023 -58.900969) (xy 381.367694 -58.922781) (xy 381.313737 -58.936887) (xy 381.2583 -58.942987)
			(xy 381.202566 -58.94095) (xy 381.147723 -58.93082) (xy 381.094939 -58.912813) (xy 381.045339 -58.887312)
			(xy 380.999981 -58.854861) (xy 380.959832 -58.816152) (xy 380.925746 -58.772009) (xy 380.89845 -58.723374)
			(xy 380.878527 -58.671283) (xy 380.866401 -58.616846) (xy 380.86233 -58.561224) (xy 375.863612 -58.561224)
			(xy 375.863612 -59.974734) (xy 379.3871 -59.974734) (xy 379.387532 -59.947907) (xy 379.395052 -59.894783)
			(xy 379.409936 -59.843234) (xy 379.431889 -59.794277) (xy 379.46048 -59.748875) (xy 379.495145 -59.707923)
			(xy 379.535202 -59.672227) (xy 379.55728 -59.65698) (xy 379.56885 -59.648765) (xy 379.587261 -59.627186)
			(xy 379.599019 -59.601373) (xy 379.603216 -59.573319) (xy 379.599526 -59.545195) (xy 379.588235 -59.519174)
			(xy 379.570215 -59.497267) (xy 379.558804 -59.488832) (xy 379.537353 -59.473471) (xy 379.498439 -59.437846)
			(xy 379.464806 -59.397199) (xy 379.437094 -59.352305) (xy 379.415832 -59.304021) (xy 379.401427 -59.253267)
			(xy 379.394152 -59.201013) (xy 379.393704 -59.174634) (xy 379.39419 -59.147383) (xy 379.401946 -59.093435)
			(xy 379.417301 -59.04114) (xy 379.439943 -58.991563) (xy 379.469409 -58.945713) (xy 379.5051 -58.904522)
			(xy 379.546291 -58.868831) (xy 379.592141 -58.839365) (xy 379.641718 -58.816723) (xy 379.694013 -58.801368)
			(xy 379.747961 -58.793612) (xy 379.802463 -58.793612) (xy 379.856411 -58.801368) (xy 379.908706 -58.816723)
			(xy 379.958283 -58.839365) (xy 380.004133 -58.868831) (xy 380.045324 -58.904522) (xy 380.081015 -58.945713)
			(xy 380.110481 -58.991563) (xy 380.133123 -59.04114) (xy 380.148478 -59.093435) (xy 380.156234 -59.147383)
			(xy 380.15672 -59.174634) (xy 380.156255 -59.20146) (xy 380.14874 -59.254582) (xy 380.133861 -59.30613)
			(xy 380.111913 -59.355087) (xy 380.083327 -59.400489) (xy 380.048667 -59.441442) (xy 380.008615 -59.47714)
			(xy 379.98654 -59.492388) (xy 379.975008 -59.500647) (xy 379.956612 -59.522221) (xy 379.944862 -59.548023)
			(xy 379.940665 -59.576063) (xy 379.944346 -59.604175) (xy 379.95562 -59.630189) (xy 379.973617 -59.652096)
			(xy 379.985016 -59.660536) (xy 380.006503 -59.675848) (xy 380.045415 -59.711482) (xy 380.079045 -59.752138)
			(xy 380.106753 -59.79704) (xy 380.128008 -59.845332) (xy 380.142406 -59.896092) (xy 380.149672 -59.948353)
			(xy 380.150116 -59.974734) (xy 380.14963 -60.001985) (xy 380.141874 -60.055933) (xy 380.126519 -60.108228)
			(xy 380.103877 -60.157805) (xy 380.074411 -60.203655) (xy 380.03872 -60.244846) (xy 379.997529 -60.280537)
			(xy 379.951679 -60.310003) (xy 379.902102 -60.332645) (xy 379.849807 -60.348) (xy 379.795859 -60.355756)
			(xy 379.741357 -60.355756) (xy 379.687409 -60.348) (xy 379.635114 -60.332645) (xy 379.585537 -60.310003)
			(xy 379.539687 -60.280537) (xy 379.498496 -60.244846) (xy 379.462805 -60.203655) (xy 379.433339 -60.157805)
			(xy 379.410697 -60.108228) (xy 379.395342 -60.055933) (xy 379.387586 -60.001985) (xy 379.3871 -59.974734)
			(xy 375.863612 -59.974734) (xy 375.863612 -60.601606) (xy 378.633226 -60.601606) (xy 378.637297 -60.545984)
			(xy 378.649423 -60.491547) (xy 378.669346 -60.439456) (xy 378.696642 -60.390821) (xy 378.730728 -60.346678)
			(xy 378.770877 -60.307969) (xy 378.816235 -60.275518) (xy 378.865835 -60.250017) (xy 378.918619 -60.23201)
			(xy 378.973462 -60.22188) (xy 379.029196 -60.219843) (xy 379.084633 -60.225943) (xy 379.13859 -60.240049)
			(xy 379.189919 -60.261861) (xy 379.237525 -60.290915) (xy 379.280393 -60.32659) (xy 379.31761 -60.368127)
			(xy 379.348383 -60.41464) (xy 379.372055 -60.465137) (xy 379.388123 -60.518544) (xy 379.396243 -60.57372)
			(xy 379.396752 -60.601606) (xy 379.396288 -60.627006) (xy 381.021334 -60.627006) (xy 381.025405 -60.571384)
			(xy 381.037531 -60.516947) (xy 381.057454 -60.464856) (xy 381.08475 -60.416221) (xy 381.118836 -60.372078)
			(xy 381.158985 -60.333369) (xy 381.204343 -60.300918) (xy 381.253943 -60.275417) (xy 381.306727 -60.25741)
			(xy 381.36157 -60.24728) (xy 381.417304 -60.245243) (xy 381.472741 -60.251343) (xy 381.526698 -60.265449)
			(xy 381.578027 -60.287261) (xy 381.625633 -60.316315) (xy 381.668501 -60.35199) (xy 381.705718 -60.393527)
			(xy 381.736491 -60.44004) (xy 381.760163 -60.490537) (xy 381.776231 -60.543944) (xy 381.784351 -60.59912)
			(xy 381.78486 -60.627006) (xy 381.784744 -60.633356) (xy 383.113024 -60.633356) (xy 383.117095 -60.577734)
			(xy 383.129221 -60.523297) (xy 383.149144 -60.471206) (xy 383.17644 -60.422571) (xy 383.210526 -60.378428)
			(xy 383.250675 -60.339719) (xy 383.296033 -60.307268) (xy 383.345633 -60.281767) (xy 383.398417 -60.26376)
			(xy 383.45326 -60.25363) (xy 383.508994 -60.251593) (xy 383.564431 -60.257693) (xy 383.618388 -60.271799)
			(xy 383.669717 -60.293611) (xy 383.717323 -60.322665) (xy 383.760191 -60.35834) (xy 383.797408 -60.399877)
			(xy 383.828181 -60.44639) (xy 383.851853 -60.496887) (xy 383.867921 -60.550294) (xy 383.876041 -60.60547)
			(xy 383.87655 -60.633356) (xy 383.876041 -60.661242) (xy 383.867921 -60.716418) (xy 383.851853 -60.769825)
			(xy 383.828181 -60.820322) (xy 383.797408 -60.866835) (xy 383.760191 -60.908372) (xy 383.717323 -60.944047)
			(xy 383.669717 -60.973101) (xy 383.618388 -60.994913) (xy 383.564431 -61.009019) (xy 383.508994 -61.015119)
			(xy 383.45326 -61.013082) (xy 383.398417 -61.002952) (xy 383.345633 -60.984945) (xy 383.296033 -60.959444)
			(xy 383.250675 -60.926993) (xy 383.210526 -60.888284) (xy 383.17644 -60.844141) (xy 383.149144 -60.795506)
			(xy 383.129221 -60.743415) (xy 383.117095 -60.688978) (xy 383.113024 -60.633356) (xy 381.784744 -60.633356)
			(xy 381.784351 -60.654892) (xy 381.776231 -60.710068) (xy 381.760163 -60.763475) (xy 381.736491 -60.813972)
			(xy 381.705718 -60.860485) (xy 381.668501 -60.902022) (xy 381.625633 -60.937697) (xy 381.578027 -60.966751)
			(xy 381.526698 -60.988563) (xy 381.472741 -61.002669) (xy 381.417304 -61.008769) (xy 381.36157 -61.006732)
			(xy 381.306727 -60.996602) (xy 381.253943 -60.978595) (xy 381.204343 -60.953094) (xy 381.158985 -60.920643)
			(xy 381.118836 -60.881934) (xy 381.08475 -60.837791) (xy 381.057454 -60.789156) (xy 381.037531 -60.737065)
			(xy 381.025405 -60.682628) (xy 381.021334 -60.627006) (xy 379.396288 -60.627006) (xy 379.396243 -60.629492)
			(xy 379.388123 -60.684668) (xy 379.372055 -60.738075) (xy 379.348383 -60.788572) (xy 379.31761 -60.835085)
			(xy 379.280393 -60.876622) (xy 379.237525 -60.912297) (xy 379.189919 -60.941351) (xy 379.13859 -60.963163)
			(xy 379.084633 -60.977269) (xy 379.029196 -60.983369) (xy 378.973462 -60.981332) (xy 378.918619 -60.971202)
			(xy 378.865835 -60.953195) (xy 378.816235 -60.927694) (xy 378.770877 -60.895243) (xy 378.730728 -60.856534)
			(xy 378.696642 -60.812391) (xy 378.669346 -60.763756) (xy 378.649423 -60.711665) (xy 378.637297 -60.657228)
			(xy 378.633226 -60.601606) (xy 375.863612 -60.601606) (xy 375.863612 -61.495686) (xy 375.864051 -61.505749)
			(xy 375.871789 -61.52433) (xy 375.878598 -61.531754) (xy 375.908824 -61.56198) (xy 375.91311 -61.566)
			(xy 375.923116 -61.572156) (xy 375.928636 -61.574172) (xy 375.933462 -61.575442) (xy 375.9454 -61.574934)
			(xy 375.961148 -61.57468) (xy 375.961656 -61.57468) (xy 378.484638 -61.57468) (xy 378.518674 -61.576458)
			(xy 378.523246 -61.576712) (xy 379.32233 -61.576712)
		)
		(stroke
			(width 0)
			(type solid)
		)
		(fill yes)
		(layer "In9.Cu")
		(net "P3V3_SSD13")
	)
	(gr_poly
		(pts
			(xy 370.884196 -253.986792) (xy 370.894075 -253.986336) (xy 370.912378 -253.978897) (xy 370.919756 -253.972314)
			(xy 370.92001 -253.97206) (xy 372.802912 -252.089158) (xy 372.810308 -252.082307) (xy 372.828907 -252.074568)
			(xy 372.83898 -252.074172) (xy 389.10768 -252.074172) (xy 389.117552 -252.0737) (xy 389.135832 -252.066238)
			(xy 389.14324 -252.059694) (xy 389.143494 -252.05944) (xy 390.144762 -251.058172) (xy 390.14527 -251.057664)
			(xy 390.151853 -251.050283) (xy 390.159307 -251.031984) (xy 390.159748 -251.022104) (xy 390.159748 -245.632224)
			(xy 390.15931 -245.622161) (xy 390.15157 -245.603582) (xy 390.144762 -245.596156) (xy 389.704072 -245.155466)
			(xy 389.696675 -245.148617) (xy 389.678076 -245.140882) (xy 389.668004 -245.14048) (xy 382.965198 -245.14048)
			(xy 382.953662 -245.141022) (xy 382.932889 -245.151063) (xy 382.92532 -245.159784) (xy 382.876298 -245.22176)
			(xy 382.869948 -245.23192) (xy 382.866392 -245.242588) (xy 382.863852 -245.254018) (xy 382.866646 -245.265448)
			(xy 382.871626 -245.287464) (xy 382.876975 -245.332286) (xy 382.877314 -245.354856) (xy 382.876853 -245.382128)
			(xy 382.869096 -245.436117) (xy 382.853733 -245.488452) (xy 382.831077 -245.538068) (xy 382.80159 -245.583954)
			(xy 382.765872 -245.625175) (xy 382.72465 -245.660893) (xy 382.678764 -245.690379) (xy 382.629148 -245.713035)
			(xy 382.576813 -245.728397) (xy 382.522824 -245.736154) (xy 382.495552 -245.736618) (xy 382.467191 -245.736104)
			(xy 382.411091 -245.72772) (xy 382.35685 -245.711129) (xy 382.305659 -245.686696) (xy 382.258647 -245.654958)
			(xy 382.216847 -245.616614) (xy 382.18118 -245.572509) (xy 382.152431 -245.523612) (xy 382.131231 -245.471)
			(xy 382.118049 -245.415831) (xy 382.11506 -245.387622) (xy 382.11506 -245.386606) (xy 382.114044 -245.378224)
			(xy 382.11379 -245.373144) (xy 382.11379 -245.37289) (xy 382.11379 -245.359682) (xy 382.11379 -245.355618)
			(xy 382.11379 -245.354602) (xy 382.114305 -245.326895) (xy 382.122355 -245.272069) (xy 382.138241 -245.21898)
			(xy 382.161632 -245.168745) (xy 382.192035 -245.122415) (xy 382.210056 -245.101364) (xy 382.216152 -245.094506)
			(xy 382.22936 -245.061486) (xy 382.22936 -245.051834) (xy 382.229614 -245.031514) (xy 382.229532 -245.025454)
			(xy 382.226837 -245.013641) (xy 382.22428 -245.008146) (xy 382.219708 -244.999256) (xy 379.90399 -242.683538)
			(xy 379.89383 -242.677188) (xy 379.887734 -242.67541) (xy 379.862843 -242.667124) (xy 379.815426 -242.644679)
			(xy 379.771529 -242.615954) (xy 379.731977 -242.581489) (xy 379.697517 -242.541933) (xy 379.668797 -242.498032)
			(xy 379.646358 -242.450613) (xy 379.638052 -242.425728) (xy 379.636274 -242.419632) (xy 379.629924 -242.409472)
			(xy 379.081538 -241.861086) (xy 379.07469 -241.853689) (xy 379.066954 -241.83509) (xy 379.066552 -241.825018)
			(xy 379.066552 -227.775262) (xy 379.066298 -227.772722) (xy 379.06579 -227.764086) (xy 379.058678 -227.748084)
			(xy 379.00483 -227.691188) (xy 379.001407 -227.687682) (xy 378.993476 -227.681928) (xy 378.989082 -227.679758)
			(xy 378.980446 -227.675948) (xy 378.970794 -227.675186) (xy 378.943417 -227.67306) (xy 378.889643 -227.661938)
			(xy 378.838021 -227.643221) (xy 378.789615 -227.617295) (xy 378.745426 -227.584697) (xy 378.706369 -227.5461)
			(xy 378.673249 -227.502301) (xy 378.64675 -227.454206) (xy 378.627422 -227.402809) (xy 378.615663 -227.349172)
			(xy 378.611716 -227.294402) (xy 378.615662 -227.239633) (xy 378.627421 -227.185995) (xy 378.646748 -227.134598)
			(xy 378.673246 -227.086503) (xy 378.706365 -227.042704) (xy 378.745423 -227.004106) (xy 378.789611 -226.971507)
			(xy 378.838016 -226.945581) (xy 378.889639 -226.926863) (xy 378.943412 -226.91574) (xy 378.970794 -226.913694)
			(xy 378.980446 -226.912932) (xy 378.989082 -226.909122) (xy 378.993381 -226.90697) (xy 379.001179 -226.901348)
			(xy 379.004576 -226.897946) (xy 379.05817 -226.841812) (xy 379.065282 -226.826318) (xy 379.066044 -226.817682)
			(xy 379.066552 -226.813618) (xy 379.066552 -222.807784) (xy 379.065902 -222.795807) (xy 379.055024 -222.774467)
			(xy 379.045724 -222.76689) (xy 378.969524 -222.711264) (xy 378.945902 -222.7072) (xy 378.934218 -222.71101)
			(xy 378.906177 -222.719301) (xy 378.848392 -222.728234) (xy 378.819156 -222.72879) (xy 378.791908 -222.728301)
			(xy 378.737968 -222.72054) (xy 378.685681 -222.705181) (xy 378.636112 -222.682539) (xy 378.590269 -222.653073)
			(xy 378.549086 -222.617383) (xy 378.513401 -222.576196) (xy 378.48394 -222.53035) (xy 378.461303 -222.480778)
			(xy 378.445951 -222.428489) (xy 378.438196 -222.374548) (xy 378.438196 -222.320052) (xy 378.445951 -222.266111)
			(xy 378.461303 -222.213822) (xy 378.48394 -222.16425) (xy 378.513401 -222.118404) (xy 378.549086 -222.077217)
			(xy 378.590269 -222.041527) (xy 378.636112 -222.012061) (xy 378.685681 -221.989419) (xy 378.737968 -221.97406)
			(xy 378.791908 -221.966299) (xy 378.819156 -221.965774) (xy 378.848394 -221.966302) (xy 378.906186 -221.975225)
			(xy 378.934218 -221.983554) (xy 378.945902 -221.987364) (xy 378.969778 -221.9833) (xy 379.045724 -221.927674)
			(xy 379.054983 -221.920069) (xy 379.065836 -221.898741) (xy 379.066552 -221.88678) (xy 379.066552 -221.478856)
			(xy 379.058932 -221.46006) (xy 379.051566 -221.452948) (xy 378.081032 -220.482414) (xy 378.07363 -220.475577)
			(xy 378.055032 -220.467865) (xy 378.044964 -220.467428) (xy 375.053352 -220.467428) (xy 375.048053 -220.467563)
			(xy 375.037681 -220.469733) (xy 375.032778 -220.471746) (xy 375.03227 -220.472) (xy 375.023482 -220.476381)
			(xy 375.00984 -220.49048) (xy 375.002496 -220.508672) (xy 375.002044 -220.518482) (xy 375.002044 -220.51899)
			(xy 375.002044 -220.523308) (xy 375.002044 -220.524578) (xy 375.00154 -220.551836) (xy 374.993749 -220.605792)
			(xy 374.978362 -220.658091) (xy 374.955691 -220.707669) (xy 374.926198 -220.753518) (xy 374.890483 -220.794705)
			(xy 374.849272 -220.830393) (xy 374.803404 -220.859855) (xy 374.75381 -220.882493) (xy 374.701501 -220.897845)
			(xy 374.64754 -220.9056) (xy 374.593024 -220.9056) (xy 374.539063 -220.897845) (xy 374.486754 -220.882493)
			(xy 374.43716 -220.859855) (xy 374.391292 -220.830393) (xy 374.350081 -220.794705) (xy 374.314366 -220.753518)
			(xy 374.284873 -220.707669) (xy 374.262202 -220.658091) (xy 374.246815 -220.605792) (xy 374.239024 -220.551836)
			(xy 374.23852 -220.524578) (xy 374.23852 -220.523308) (xy 374.23852 -220.51899) (xy 374.23852 -220.518228)
			(xy 374.238105 -220.508202) (xy 374.230441 -220.489672) (xy 374.216269 -220.475486) (xy 374.197746 -220.467804)
			(xy 374.18772 -220.467428) (xy 372.722394 -220.467428) (xy 372.694708 -220.466412) (xy 372.692422 -220.466158)
			(xy 371.549422 -220.466158) (xy 371.539705 -220.466584) (xy 371.521662 -220.473798) (xy 371.507592 -220.487203)
			(xy 371.503194 -220.495876) (xy 371.503194 -220.49613) (xy 371.491475 -220.520858) (xy 371.46201 -220.566967)
			(xy 371.426266 -220.608399) (xy 371.384975 -220.644306) (xy 371.338983 -220.673953) (xy 371.28923 -220.696733)
			(xy 371.236735 -220.712179) (xy 371.182574 -220.719976) (xy 371.155214 -220.720412) (xy 371.127987 -220.719929)
			(xy 371.074087 -220.712191) (xy 371.021834 -220.696869) (xy 370.97229 -220.674276) (xy 370.92646 -220.644869)
			(xy 370.885276 -220.609246) (xy 370.849574 -220.568131) (xy 370.820078 -220.522358) (xy 370.797389 -220.472857)
			(xy 370.781966 -220.420634) (xy 370.777516 -220.393768) (xy 370.776246 -220.38564) (xy 370.76888 -220.370908)
			(xy 367.923572 -217.5256) (xy 367.916718 -217.518205) (xy 367.908972 -217.499606) (xy 367.908586 -217.489532)
			(xy 367.908586 -214.896192) (xy 367.908161 -214.886123) (xy 367.900443 -214.867522) (xy 367.8936 -214.860124)
			(xy 367.880138 -214.846662) (xy 367.873026 -214.843106) (xy 367.848289 -214.829972) (xy 367.802615 -214.797558)
			(xy 367.762171 -214.758816) (xy 367.727824 -214.714577) (xy 367.700314 -214.665793) (xy 367.68023 -214.613512)
			(xy 367.668004 -214.558856) (xy 367.6639 -214.503) (xy 367.668004 -214.447144) (xy 367.68023 -214.392488)
			(xy 367.700314 -214.340207) (xy 367.727824 -214.291423) (xy 367.762171 -214.247184) (xy 367.802615 -214.208442)
			(xy 367.848289 -214.176028) (xy 367.873026 -214.162894) (xy 367.880138 -214.159338) (xy 367.903506 -214.13597)
			(xy 367.905853 -214.130748) (xy 367.908425 -214.119595) (xy 367.908586 -214.113872) (xy 367.908586 -212.445854)
			(xy 367.908118 -212.43561) (xy 367.900121 -212.416746) (xy 367.893092 -212.409278) (xy 367.867184 -212.384132)
			(xy 367.840514 -212.358478) (xy 367.833167 -212.351985) (xy 367.815004 -212.344645) (xy 367.805208 -212.344254)
			(xy 367.803176 -212.344254) (xy 367.792 -212.344508) (xy 367.791746 -212.344508) (xy 367.764507 -212.344005)
			(xy 367.710586 -212.336219) (xy 367.658322 -212.320842) (xy 367.608777 -212.298186) (xy 367.562958 -212.268713)
			(xy 367.521798 -212.233022) (xy 367.486134 -212.191838) (xy 367.456692 -212.146) (xy 367.434069 -212.09644)
			(xy 367.418727 -212.044165) (xy 367.410977 -211.99024) (xy 367.410977 -211.93576) (xy 367.418727 -211.881835)
			(xy 367.434069 -211.82956) (xy 367.456692 -211.78) (xy 367.486134 -211.734162) (xy 367.521798 -211.692978)
			(xy 367.562958 -211.657287) (xy 367.608777 -211.627814) (xy 367.658322 -211.605158) (xy 367.710586 -211.589781)
			(xy 367.764507 -211.581995) (xy 367.791746 -211.581492) (xy 367.792254 -211.581492) (xy 367.802922 -211.581746)
			(xy 367.8047 -211.581746) (xy 367.81462 -211.58138) (xy 367.833057 -211.574073) (xy 367.840514 -211.567522)
			(xy 367.89233 -211.517484) (xy 367.900204 -211.507578) (xy 367.900966 -211.506308) (xy 367.904465 -211.500201)
			(xy 367.908326 -211.486672) (xy 367.908586 -211.479638) (xy 367.908586 -208.30032) (xy 367.908188 -208.291119)
			(xy 367.901707 -208.273895) (xy 367.889595 -208.260038) (xy 367.881662 -208.255362) (xy 367.809018 -208.217008)
			(xy 367.803433 -208.214275) (xy 367.791358 -208.211319) (xy 367.785142 -208.211166) (xy 367.77422 -208.211166)
			(xy 367.770614 -208.211227) (xy 367.763474 -208.212244) (xy 367.759996 -208.213198) (xy 367.750344 -208.215992)
			(xy 367.743232 -208.220818) (xy 367.720156 -208.234959) (xy 367.670857 -208.257289) (xy 367.618895 -208.272418)
			(xy 367.565314 -208.280042) (xy 367.538254 -208.280508) (xy 367.537492 -208.280508) (xy 367.527123 -208.280492)
			(xy 367.506411 -208.279473) (xy 367.49609 -208.278476) (xy 367.477802 -208.275682) (xy 367.451266 -208.270965)
			(xy 367.399774 -208.255044) (xy 367.351035 -208.232036) (xy 367.306019 -208.202398) (xy 367.265621 -208.166721)
			(xy 367.230646 -208.125714) (xy 367.201788 -208.080193) (xy 367.179624 -208.031065) (xy 367.164593 -207.979307)
			(xy 367.156995 -207.925948) (xy 367.156492 -207.899) (xy 367.156996 -207.871264) (xy 367.165041 -207.816377)
			(xy 367.180945 -207.763232) (xy 367.204375 -207.71295) (xy 367.234837 -207.666589) (xy 367.271688 -207.625125)
			(xy 367.314153 -207.589432) (xy 367.361338 -207.560262) (xy 367.412248 -207.53823) (xy 367.465812 -207.523799)
			(xy 367.493296 -207.520032) (xy 367.507266 -207.518508) (xy 367.515648 -207.518) (xy 367.51768 -207.518)
			(xy 367.537746 -207.517238) (xy 367.538254 -207.517238) (xy 367.566422 -207.517787) (xy 367.622135 -207.526147)
			(xy 367.676019 -207.542589) (xy 367.726909 -207.566758) (xy 367.750598 -207.582008) (xy 367.762282 -207.589882)
			(xy 367.790222 -207.591406) (xy 367.877852 -207.54467) (xy 367.887472 -207.539771) (xy 367.901908 -207.523755)
			(xy 367.905792 -207.513682) (xy 367.908586 -207.505554) (xy 367.908586 -206.26832) (xy 367.908188 -206.259119)
			(xy 367.901707 -206.241895) (xy 367.889595 -206.228038) (xy 367.881662 -206.223362) (xy 367.809018 -206.185008)
			(xy 367.803433 -206.182275) (xy 367.791358 -206.179319) (xy 367.785142 -206.179166) (xy 367.77422 -206.179166)
			(xy 367.770614 -206.179227) (xy 367.763474 -206.180244) (xy 367.759996 -206.181198) (xy 367.750344 -206.183992)
			(xy 367.743232 -206.188818) (xy 367.720156 -206.202959) (xy 367.670857 -206.225289) (xy 367.618895 -206.240418)
			(xy 367.565314 -206.248042) (xy 367.538254 -206.248508) (xy 367.537492 -206.248508) (xy 367.527123 -206.248492)
			(xy 367.506411 -206.247473) (xy 367.49609 -206.246476) (xy 367.477802 -206.243682) (xy 367.451266 -206.238965)
			(xy 367.399774 -206.223044) (xy 367.351035 -206.200036) (xy 367.306019 -206.170398) (xy 367.265621 -206.134721)
			(xy 367.230646 -206.093714) (xy 367.201788 -206.048193) (xy 367.179624 -205.999065) (xy 367.164593 -205.947307)
			(xy 367.156995 -205.893948) (xy 367.156492 -205.867) (xy 367.156996 -205.839264) (xy 367.165041 -205.784377)
			(xy 367.180945 -205.731232) (xy 367.204375 -205.68095) (xy 367.234837 -205.634589) (xy 367.271688 -205.593125)
			(xy 367.314153 -205.557432) (xy 367.361338 -205.528262) (xy 367.412248 -205.50623) (xy 367.465812 -205.491799)
			(xy 367.493296 -205.488032) (xy 367.507266 -205.486508) (xy 367.515648 -205.486) (xy 367.51768 -205.486)
			(xy 367.537746 -205.485238) (xy 367.538254 -205.485238) (xy 367.566422 -205.485787) (xy 367.622135 -205.494147)
			(xy 367.676019 -205.510589) (xy 367.726909 -205.534758) (xy 367.750598 -205.550008) (xy 367.762282 -205.557882)
			(xy 367.790222 -205.559406) (xy 367.877852 -205.51267) (xy 367.887472 -205.507771) (xy 367.901908 -205.491755)
			(xy 367.905792 -205.481682) (xy 367.908586 -205.473554) (xy 367.908586 -197.663054) (xy 367.907891 -197.650317)
			(xy 367.895767 -197.627911) (xy 367.885472 -197.620382) (xy 367.849658 -197.597014) (xy 367.84915 -197.597014)
			(xy 367.81486 -197.574408) (xy 367.804309 -197.568213) (xy 367.780025 -197.565575) (xy 367.768378 -197.569328)
			(xy 367.756694 -197.5739) (xy 367.756186 -197.574154) (xy 367.733165 -197.583152) (xy 367.685386 -197.59581)
			(xy 367.636374 -197.602196) (xy 367.61166 -197.602602) (xy 367.60404 -197.602602) (xy 367.57585 -197.601551)
			(xy 367.520225 -197.592171) (xy 367.466588 -197.574704) (xy 367.416106 -197.549531) (xy 367.369881 -197.5172)
			(xy 367.328919 -197.478416) (xy 367.294114 -197.434023) (xy 367.266224 -197.38499) (xy 367.245857 -197.332386)
			(xy 367.233456 -197.277356) (xy 367.229292 -197.2211) (xy 367.233456 -197.164844) (xy 367.245857 -197.109814)
			(xy 367.266224 -197.057209) (xy 367.294114 -197.008177) (xy 367.32892 -196.963784) (xy 367.369881 -196.925)
			(xy 367.416107 -196.892669) (xy 367.466588 -196.867496) (xy 367.520226 -196.850029) (xy 367.57585 -196.840649)
			(xy 367.60404 -196.839586) (xy 367.611914 -196.839586) (xy 367.638333 -196.840055) (xy 367.690662 -196.847382)
			(xy 367.741481 -196.861853) (xy 367.765838 -196.872098) (xy 367.777776 -196.877432) (xy 367.803176 -196.8754)
			(xy 367.84915 -196.845428) (xy 367.849658 -196.845174) (xy 367.884964 -196.822314) (xy 367.889553 -196.819227)
			(xy 367.897379 -196.811414) (xy 367.900458 -196.80682) (xy 367.902535 -196.803503) (xy 367.90573 -196.796358)
			(xy 367.906808 -196.792596) (xy 367.908586 -196.785738) (xy 367.908586 -195.140834) (xy 367.90815 -195.130769)
			(xy 367.900418 -195.112184) (xy 367.8936 -195.104766) (xy 365.23422 -192.445386) (xy 365.226821 -192.438543)
			(xy 365.208222 -192.430824) (xy 365.198152 -192.4304) (xy 364.611666 -192.4304) (xy 364.602712 -192.43075)
			(xy 364.585892 -192.436901) (xy 364.572201 -192.448445) (xy 364.56747 -192.456054) (xy 364.553818 -192.479114)
			(xy 364.521047 -192.521513) (xy 364.482664 -192.558909) (xy 364.439424 -192.590563) (xy 364.392179 -192.615854)
			(xy 364.34186 -192.634284) (xy 364.289456 -192.645488) (xy 364.236 -192.649248) (xy 364.182544 -192.645488)
			(xy 364.13014 -192.634284) (xy 364.079821 -192.615854) (xy 364.032576 -192.590563) (xy 363.989336 -192.558909)
			(xy 363.950953 -192.521513) (xy 363.918182 -192.479114) (xy 363.90453 -192.456054) (xy 363.899797 -192.448446)
			(xy 363.886116 -192.436892) (xy 363.869289 -192.430768) (xy 363.860334 -192.4304) (xy 362.623862 -192.4304)
			(xy 362.60659 -192.437004) (xy 362.599478 -192.443354) (xy 362.5977 -192.445132) (xy 362.596176 -192.446148)
			(xy 362.581698 -192.459864) (xy 362.568998 -192.459102) (xy 362.53674 -192.477136) (xy 362.52785 -192.483232)
			(xy 362.522516 -192.487804) (xy 362.516928 -192.49644) (xy 362.501558 -192.51768) (xy 362.465932 -192.556143)
			(xy 362.425377 -192.589369) (xy 362.380657 -192.616733) (xy 362.332613 -192.63772) (xy 362.282148 -192.651934)
			(xy 362.230214 -192.659109) (xy 362.204 -192.659508) (xy 362.186951 -192.659326) (xy 362.15299 -192.656272)
			(xy 362.136182 -192.653412) (xy 362.123736 -192.651126) (xy 362.100114 -192.658492) (xy 361.805474 -192.953132)
			(xy 361.798625 -192.960529) (xy 361.79089 -192.979128) (xy 361.790488 -192.9892) (xy 361.790488 -194.691)
			(xy 362.075982 -194.691) (xy 362.080053 -194.635378) (xy 362.092179 -194.580941) (xy 362.112102 -194.52885)
			(xy 362.139398 -194.480215) (xy 362.173484 -194.436072) (xy 362.213633 -194.397363) (xy 362.258991 -194.364912)
			(xy 362.308591 -194.339411) (xy 362.361375 -194.321404) (xy 362.416218 -194.311274) (xy 362.471952 -194.309237)
			(xy 362.527389 -194.315337) (xy 362.581346 -194.329443) (xy 362.632675 -194.351255) (xy 362.680281 -194.380309)
			(xy 362.723149 -194.415984) (xy 362.741979 -194.437) (xy 364.107982 -194.437) (xy 364.112053 -194.381378)
			(xy 364.124179 -194.326941) (xy 364.144102 -194.27485) (xy 364.171398 -194.226215) (xy 364.205484 -194.182072)
			(xy 364.245633 -194.143363) (xy 364.290991 -194.110912) (xy 364.340591 -194.085411) (xy 364.393375 -194.067404)
			(xy 364.448218 -194.057274) (xy 364.503952 -194.055237) (xy 364.559389 -194.061337) (xy 364.613346 -194.075443)
			(xy 364.664675 -194.097255) (xy 364.712281 -194.126309) (xy 364.755149 -194.161984) (xy 364.792366 -194.203521)
			(xy 364.823139 -194.250034) (xy 364.846811 -194.300531) (xy 364.862879 -194.353938) (xy 364.870999 -194.409114)
			(xy 364.871508 -194.437) (xy 364.870999 -194.464886) (xy 364.862879 -194.520062) (xy 364.846811 -194.573469)
			(xy 364.823139 -194.623966) (xy 364.792366 -194.670479) (xy 364.755149 -194.712016) (xy 364.712281 -194.747691)
			(xy 364.664675 -194.776745) (xy 364.613346 -194.798557) (xy 364.559389 -194.812663) (xy 364.503952 -194.818763)
			(xy 364.448218 -194.816726) (xy 364.393375 -194.806596) (xy 364.340591 -194.788589) (xy 364.290991 -194.763088)
			(xy 364.245633 -194.730637) (xy 364.205484 -194.691928) (xy 364.171398 -194.647785) (xy 364.144102 -194.59915)
			(xy 364.124179 -194.547059) (xy 364.112053 -194.492622) (xy 364.107982 -194.437) (xy 362.741979 -194.437)
			(xy 362.760366 -194.457521) (xy 362.791139 -194.504034) (xy 362.814811 -194.554531) (xy 362.830879 -194.607938)
			(xy 362.838999 -194.663114) (xy 362.839508 -194.691) (xy 362.838999 -194.718886) (xy 362.830879 -194.774062)
			(xy 362.814811 -194.827469) (xy 362.791139 -194.877966) (xy 362.760366 -194.924479) (xy 362.723149 -194.966016)
			(xy 362.680281 -195.001691) (xy 362.632675 -195.030745) (xy 362.581346 -195.052557) (xy 362.527389 -195.066663)
			(xy 362.471952 -195.072763) (xy 362.416218 -195.070726) (xy 362.361375 -195.060596) (xy 362.308591 -195.042589)
			(xy 362.258991 -195.017088) (xy 362.213633 -194.984637) (xy 362.173484 -194.945928) (xy 362.139398 -194.901785)
			(xy 362.112102 -194.85315) (xy 362.092179 -194.801059) (xy 362.080053 -194.746622) (xy 362.075982 -194.691)
			(xy 361.790488 -194.691) (xy 361.790488 -195.707) (xy 362.075982 -195.707) (xy 362.080053 -195.651378)
			(xy 362.092179 -195.596941) (xy 362.112102 -195.54485) (xy 362.139398 -195.496215) (xy 362.173484 -195.452072)
			(xy 362.213633 -195.413363) (xy 362.258991 -195.380912) (xy 362.308591 -195.355411) (xy 362.361375 -195.337404)
			(xy 362.416218 -195.327274) (xy 362.471952 -195.325237) (xy 362.527389 -195.331337) (xy 362.581346 -195.345443)
			(xy 362.632675 -195.367255) (xy 362.680281 -195.396309) (xy 362.723149 -195.431984) (xy 362.760366 -195.473521)
			(xy 362.791139 -195.520034) (xy 362.814811 -195.570531) (xy 362.830879 -195.623938) (xy 362.838999 -195.679114)
			(xy 362.839508 -195.707) (xy 364.107982 -195.707) (xy 364.112053 -195.651378) (xy 364.124179 -195.596941)
			(xy 364.144102 -195.54485) (xy 364.171398 -195.496215) (xy 364.205484 -195.452072) (xy 364.245633 -195.413363)
			(xy 364.290991 -195.380912) (xy 364.340591 -195.355411) (xy 364.393375 -195.337404) (xy 364.448218 -195.327274)
			(xy 364.503952 -195.325237) (xy 364.559389 -195.331337) (xy 364.613346 -195.345443) (xy 364.664675 -195.367255)
			(xy 364.712281 -195.396309) (xy 364.755149 -195.431984) (xy 364.792366 -195.473521) (xy 364.823139 -195.520034)
			(xy 364.846811 -195.570531) (xy 364.862879 -195.623938) (xy 364.870999 -195.679114) (xy 364.871508 -195.707)
			(xy 366.901982 -195.707) (xy 366.906053 -195.651378) (xy 366.918179 -195.596941) (xy 366.938102 -195.54485)
			(xy 366.965398 -195.496215) (xy 366.999484 -195.452072) (xy 367.039633 -195.413363) (xy 367.084991 -195.380912)
			(xy 367.134591 -195.355411) (xy 367.187375 -195.337404) (xy 367.242218 -195.327274) (xy 367.297952 -195.325237)
			(xy 367.353389 -195.331337) (xy 367.407346 -195.345443) (xy 367.458675 -195.367255) (xy 367.506281 -195.396309)
			(xy 367.549149 -195.431984) (xy 367.586366 -195.473521) (xy 367.617139 -195.520034) (xy 367.640811 -195.570531)
			(xy 367.656879 -195.623938) (xy 367.664999 -195.679114) (xy 367.665508 -195.707) (xy 367.664999 -195.734886)
			(xy 367.656879 -195.790062) (xy 367.640811 -195.843469) (xy 367.617139 -195.893966) (xy 367.586366 -195.940479)
			(xy 367.549149 -195.982016) (xy 367.506281 -196.017691) (xy 367.458675 -196.046745) (xy 367.407346 -196.068557)
			(xy 367.353389 -196.082663) (xy 367.297952 -196.088763) (xy 367.242218 -196.086726) (xy 367.187375 -196.076596)
			(xy 367.134591 -196.058589) (xy 367.084991 -196.033088) (xy 367.039633 -196.000637) (xy 366.999484 -195.961928)
			(xy 366.965398 -195.917785) (xy 366.938102 -195.86915) (xy 366.918179 -195.817059) (xy 366.906053 -195.762622)
			(xy 366.901982 -195.707) (xy 364.871508 -195.707) (xy 364.870999 -195.734886) (xy 364.862879 -195.790062)
			(xy 364.846811 -195.843469) (xy 364.823139 -195.893966) (xy 364.792366 -195.940479) (xy 364.755149 -195.982016)
			(xy 364.712281 -196.017691) (xy 364.664675 -196.046745) (xy 364.613346 -196.068557) (xy 364.559389 -196.082663)
			(xy 364.503952 -196.088763) (xy 364.448218 -196.086726) (xy 364.393375 -196.076596) (xy 364.340591 -196.058589)
			(xy 364.290991 -196.033088) (xy 364.245633 -196.000637) (xy 364.205484 -195.961928) (xy 364.171398 -195.917785)
			(xy 364.144102 -195.86915) (xy 364.124179 -195.817059) (xy 364.112053 -195.762622) (xy 364.107982 -195.707)
			(xy 362.839508 -195.707) (xy 362.838999 -195.734886) (xy 362.830879 -195.790062) (xy 362.814811 -195.843469)
			(xy 362.791139 -195.893966) (xy 362.760366 -195.940479) (xy 362.723149 -195.982016) (xy 362.680281 -196.017691)
			(xy 362.632675 -196.046745) (xy 362.581346 -196.068557) (xy 362.527389 -196.082663) (xy 362.471952 -196.088763)
			(xy 362.416218 -196.086726) (xy 362.361375 -196.076596) (xy 362.308591 -196.058589) (xy 362.258991 -196.033088)
			(xy 362.213633 -196.000637) (xy 362.173484 -195.961928) (xy 362.139398 -195.917785) (xy 362.112102 -195.86915)
			(xy 362.092179 -195.817059) (xy 362.080053 -195.762622) (xy 362.075982 -195.707) (xy 361.790488 -195.707)
			(xy 361.790488 -196.723) (xy 362.075982 -196.723) (xy 362.080053 -196.667378) (xy 362.092179 -196.612941)
			(xy 362.112102 -196.56085) (xy 362.139398 -196.512215) (xy 362.173484 -196.468072) (xy 362.213633 -196.429363)
			(xy 362.258991 -196.396912) (xy 362.308591 -196.371411) (xy 362.361375 -196.353404) (xy 362.416218 -196.343274)
			(xy 362.471952 -196.341237) (xy 362.527389 -196.347337) (xy 362.581346 -196.361443) (xy 362.632675 -196.383255)
			(xy 362.680281 -196.412309) (xy 362.723149 -196.447984) (xy 362.760366 -196.489521) (xy 362.791139 -196.536034)
			(xy 362.814811 -196.586531) (xy 362.830879 -196.639938) (xy 362.838999 -196.695114) (xy 362.839508 -196.723)
			(xy 362.838999 -196.750886) (xy 362.830879 -196.806062) (xy 362.814811 -196.859469) (xy 362.791139 -196.909966)
			(xy 362.760366 -196.956479) (xy 362.723149 -196.998016) (xy 362.680281 -197.033691) (xy 362.632675 -197.062745)
			(xy 362.581346 -197.084557) (xy 362.527389 -197.098663) (xy 362.471952 -197.104763) (xy 362.416218 -197.102726)
			(xy 362.361375 -197.092596) (xy 362.308591 -197.074589) (xy 362.258991 -197.049088) (xy 362.213633 -197.016637)
			(xy 362.173484 -196.977928) (xy 362.139398 -196.933785) (xy 362.112102 -196.88515) (xy 362.092179 -196.833059)
			(xy 362.080053 -196.778622) (xy 362.075982 -196.723) (xy 361.790488 -196.723) (xy 361.790488 -198.585836)
			(xy 362.075982 -198.585836) (xy 362.080053 -198.530214) (xy 362.092179 -198.475777) (xy 362.112102 -198.423686)
			(xy 362.139398 -198.375051) (xy 362.173484 -198.330908) (xy 362.213633 -198.292199) (xy 362.258991 -198.259748)
			(xy 362.308591 -198.234247) (xy 362.361375 -198.21624) (xy 362.416218 -198.20611) (xy 362.471952 -198.204073)
			(xy 362.527389 -198.210173) (xy 362.581346 -198.224279) (xy 362.632675 -198.246091) (xy 362.680281 -198.275145)
			(xy 362.723149 -198.31082) (xy 362.760366 -198.352357) (xy 362.791139 -198.39887) (xy 362.814811 -198.449367)
			(xy 362.830879 -198.502774) (xy 362.838999 -198.55795) (xy 362.839508 -198.585836) (xy 362.838999 -198.613722)
			(xy 362.830879 -198.668898) (xy 362.814811 -198.722305) (xy 362.791139 -198.772802) (xy 362.760366 -198.819315)
			(xy 362.723149 -198.860852) (xy 362.680281 -198.896527) (xy 362.632675 -198.925581) (xy 362.581346 -198.947393)
			(xy 362.527389 -198.961499) (xy 362.471952 -198.967599) (xy 362.416218 -198.965562) (xy 362.361375 -198.955432)
			(xy 362.308591 -198.937425) (xy 362.258991 -198.911924) (xy 362.213633 -198.879473) (xy 362.173484 -198.840764)
			(xy 362.139398 -198.796621) (xy 362.112102 -198.747986) (xy 362.092179 -198.695895) (xy 362.080053 -198.641458)
			(xy 362.075982 -198.585836) (xy 361.790488 -198.585836) (xy 361.790488 -200.787) (xy 362.075982 -200.787)
			(xy 362.080053 -200.731378) (xy 362.092179 -200.676941) (xy 362.112102 -200.62485) (xy 362.139398 -200.576215)
			(xy 362.173484 -200.532072) (xy 362.213633 -200.493363) (xy 362.258991 -200.460912) (xy 362.308591 -200.435411)
			(xy 362.361375 -200.417404) (xy 362.416218 -200.407274) (xy 362.471952 -200.405237) (xy 362.527389 -200.411337)
			(xy 362.581346 -200.425443) (xy 362.632675 -200.447255) (xy 362.680281 -200.476309) (xy 362.723149 -200.511984)
			(xy 362.760366 -200.553521) (xy 362.791139 -200.600034) (xy 362.814811 -200.650531) (xy 362.830879 -200.703938)
			(xy 362.838999 -200.759114) (xy 362.839508 -200.787) (xy 362.838999 -200.814886) (xy 362.830879 -200.870062)
			(xy 362.814811 -200.923469) (xy 362.791139 -200.973966) (xy 362.760366 -201.020479) (xy 362.723149 -201.062016)
			(xy 362.680281 -201.097691) (xy 362.632675 -201.126745) (xy 362.581346 -201.148557) (xy 362.527389 -201.162663)
			(xy 362.471952 -201.168763) (xy 362.416218 -201.166726) (xy 362.361375 -201.156596) (xy 362.308591 -201.138589)
			(xy 362.258991 -201.113088) (xy 362.213633 -201.080637) (xy 362.173484 -201.041928) (xy 362.139398 -200.997785)
			(xy 362.112102 -200.94915) (xy 362.092179 -200.897059) (xy 362.080053 -200.842622) (xy 362.075982 -200.787)
			(xy 361.790488 -200.787) (xy 361.790488 -201.803) (xy 362.075982 -201.803) (xy 362.080053 -201.747378)
			(xy 362.092179 -201.692941) (xy 362.112102 -201.64085) (xy 362.139398 -201.592215) (xy 362.173484 -201.548072)
			(xy 362.213633 -201.509363) (xy 362.258991 -201.476912) (xy 362.308591 -201.451411) (xy 362.361375 -201.433404)
			(xy 362.416218 -201.423274) (xy 362.471952 -201.421237) (xy 362.527389 -201.427337) (xy 362.581346 -201.441443)
			(xy 362.632675 -201.463255) (xy 362.680281 -201.492309) (xy 362.723149 -201.527984) (xy 362.760366 -201.569521)
			(xy 362.791139 -201.616034) (xy 362.814811 -201.666531) (xy 362.830879 -201.719938) (xy 362.838999 -201.775114)
			(xy 362.839508 -201.803) (xy 366.139982 -201.803) (xy 366.144053 -201.747378) (xy 366.156179 -201.692941)
			(xy 366.176102 -201.64085) (xy 366.203398 -201.592215) (xy 366.237484 -201.548072) (xy 366.277633 -201.509363)
			(xy 366.322991 -201.476912) (xy 366.372591 -201.451411) (xy 366.425375 -201.433404) (xy 366.480218 -201.423274)
			(xy 366.535952 -201.421237) (xy 366.591389 -201.427337) (xy 366.645346 -201.441443) (xy 366.696675 -201.463255)
			(xy 366.744281 -201.492309) (xy 366.787149 -201.527984) (xy 366.824366 -201.569521) (xy 366.855139 -201.616034)
			(xy 366.878811 -201.666531) (xy 366.894879 -201.719938) (xy 366.902999 -201.775114) (xy 366.903508 -201.803)
			(xy 366.902999 -201.830886) (xy 366.894879 -201.886062) (xy 366.878811 -201.939469) (xy 366.855139 -201.989966)
			(xy 366.824366 -202.036479) (xy 366.787149 -202.078016) (xy 366.744281 -202.113691) (xy 366.696675 -202.142745)
			(xy 366.645346 -202.164557) (xy 366.591389 -202.178663) (xy 366.535952 -202.184763) (xy 366.480218 -202.182726)
			(xy 366.425375 -202.172596) (xy 366.372591 -202.154589) (xy 366.322991 -202.129088) (xy 366.277633 -202.096637)
			(xy 366.237484 -202.057928) (xy 366.203398 -202.013785) (xy 366.176102 -201.96515) (xy 366.156179 -201.913059)
			(xy 366.144053 -201.858622) (xy 366.139982 -201.803) (xy 362.839508 -201.803) (xy 362.838999 -201.830886)
			(xy 362.830879 -201.886062) (xy 362.814811 -201.939469) (xy 362.791139 -201.989966) (xy 362.760366 -202.036479)
			(xy 362.723149 -202.078016) (xy 362.680281 -202.113691) (xy 362.632675 -202.142745) (xy 362.581346 -202.164557)
			(xy 362.527389 -202.178663) (xy 362.471952 -202.184763) (xy 362.416218 -202.182726) (xy 362.361375 -202.172596)
			(xy 362.308591 -202.154589) (xy 362.258991 -202.129088) (xy 362.213633 -202.096637) (xy 362.173484 -202.057928)
			(xy 362.139398 -202.013785) (xy 362.112102 -201.96515) (xy 362.092179 -201.913059) (xy 362.080053 -201.858622)
			(xy 362.075982 -201.803) (xy 361.790488 -201.803) (xy 361.790488 -202.819) (xy 366.139982 -202.819)
			(xy 366.144053 -202.763378) (xy 366.156179 -202.708941) (xy 366.176102 -202.65685) (xy 366.203398 -202.608215)
			(xy 366.237484 -202.564072) (xy 366.277633 -202.525363) (xy 366.322991 -202.492912) (xy 366.372591 -202.467411)
			(xy 366.425375 -202.449404) (xy 366.480218 -202.439274) (xy 366.535952 -202.437237) (xy 366.591389 -202.443337)
			(xy 366.645346 -202.457443) (xy 366.696675 -202.479255) (xy 366.744281 -202.508309) (xy 366.787149 -202.543984)
			(xy 366.824366 -202.585521) (xy 366.855139 -202.632034) (xy 366.878811 -202.682531) (xy 366.894879 -202.735938)
			(xy 366.902999 -202.791114) (xy 366.903508 -202.819) (xy 366.902999 -202.846886) (xy 366.894879 -202.902062)
			(xy 366.878811 -202.955469) (xy 366.855139 -203.005966) (xy 366.824366 -203.052479) (xy 366.787149 -203.094016)
			(xy 366.744281 -203.129691) (xy 366.696675 -203.158745) (xy 366.645346 -203.180557) (xy 366.591389 -203.194663)
			(xy 366.535952 -203.200763) (xy 366.480218 -203.198726) (xy 366.425375 -203.188596) (xy 366.372591 -203.170589)
			(xy 366.322991 -203.145088) (xy 366.277633 -203.112637) (xy 366.237484 -203.073928) (xy 366.203398 -203.029785)
			(xy 366.176102 -202.98115) (xy 366.156179 -202.929059) (xy 366.144053 -202.874622) (xy 366.139982 -202.819)
			(xy 361.790488 -202.819) (xy 361.790488 -203.835) (xy 362.075982 -203.835) (xy 362.080053 -203.779378)
			(xy 362.092179 -203.724941) (xy 362.112102 -203.67285) (xy 362.139398 -203.624215) (xy 362.173484 -203.580072)
			(xy 362.213633 -203.541363) (xy 362.258991 -203.508912) (xy 362.308591 -203.483411) (xy 362.361375 -203.465404)
			(xy 362.416218 -203.455274) (xy 362.471952 -203.453237) (xy 362.527389 -203.459337) (xy 362.581346 -203.473443)
			(xy 362.632675 -203.495255) (xy 362.680281 -203.524309) (xy 362.723149 -203.559984) (xy 362.760366 -203.601521)
			(xy 362.791139 -203.648034) (xy 362.814811 -203.698531) (xy 362.830879 -203.751938) (xy 362.838999 -203.807114)
			(xy 362.839508 -203.835) (xy 364.107982 -203.835) (xy 364.112053 -203.779378) (xy 364.124179 -203.724941)
			(xy 364.144102 -203.67285) (xy 364.171398 -203.624215) (xy 364.205484 -203.580072) (xy 364.245633 -203.541363)
			(xy 364.290991 -203.508912) (xy 364.340591 -203.483411) (xy 364.393375 -203.465404) (xy 364.448218 -203.455274)
			(xy 364.503952 -203.453237) (xy 364.559389 -203.459337) (xy 364.613346 -203.473443) (xy 364.664675 -203.495255)
			(xy 364.712281 -203.524309) (xy 364.755149 -203.559984) (xy 364.792366 -203.601521) (xy 364.823139 -203.648034)
			(xy 364.846811 -203.698531) (xy 364.862879 -203.751938) (xy 364.870999 -203.807114) (xy 364.871508 -203.835)
			(xy 364.870999 -203.862886) (xy 364.862879 -203.918062) (xy 364.846811 -203.971469) (xy 364.823139 -204.021966)
			(xy 364.792366 -204.068479) (xy 364.755149 -204.110016) (xy 364.712281 -204.145691) (xy 364.664675 -204.174745)
			(xy 364.613346 -204.196557) (xy 364.559389 -204.210663) (xy 364.503952 -204.216763) (xy 364.448218 -204.214726)
			(xy 364.393375 -204.204596) (xy 364.340591 -204.186589) (xy 364.290991 -204.161088) (xy 364.245633 -204.128637)
			(xy 364.205484 -204.089928) (xy 364.171398 -204.045785) (xy 364.144102 -203.99715) (xy 364.124179 -203.945059)
			(xy 364.112053 -203.890622) (xy 364.107982 -203.835) (xy 362.839508 -203.835) (xy 362.838999 -203.862886)
			(xy 362.830879 -203.918062) (xy 362.814811 -203.971469) (xy 362.791139 -204.021966) (xy 362.760366 -204.068479)
			(xy 362.723149 -204.110016) (xy 362.680281 -204.145691) (xy 362.632675 -204.174745) (xy 362.581346 -204.196557)
			(xy 362.527389 -204.210663) (xy 362.471952 -204.216763) (xy 362.416218 -204.214726) (xy 362.361375 -204.204596)
			(xy 362.308591 -204.186589) (xy 362.258991 -204.161088) (xy 362.213633 -204.128637) (xy 362.173484 -204.089928)
			(xy 362.139398 -204.045785) (xy 362.112102 -203.99715) (xy 362.092179 -203.945059) (xy 362.080053 -203.890622)
			(xy 362.075982 -203.835) (xy 361.790488 -203.835) (xy 361.790488 -205.867) (xy 362.075982 -205.867)
			(xy 362.080053 -205.811378) (xy 362.092179 -205.756941) (xy 362.112102 -205.70485) (xy 362.139398 -205.656215)
			(xy 362.173484 -205.612072) (xy 362.213633 -205.573363) (xy 362.258991 -205.540912) (xy 362.308591 -205.515411)
			(xy 362.361375 -205.497404) (xy 362.416218 -205.487274) (xy 362.471952 -205.485237) (xy 362.527389 -205.491337)
			(xy 362.581346 -205.505443) (xy 362.632675 -205.527255) (xy 362.680281 -205.556309) (xy 362.723149 -205.591984)
			(xy 362.741979 -205.613) (xy 364.107982 -205.613) (xy 364.112053 -205.557378) (xy 364.124179 -205.502941)
			(xy 364.144102 -205.45085) (xy 364.171398 -205.402215) (xy 364.205484 -205.358072) (xy 364.245633 -205.319363)
			(xy 364.290991 -205.286912) (xy 364.340591 -205.261411) (xy 364.393375 -205.243404) (xy 364.448218 -205.233274)
			(xy 364.503952 -205.231237) (xy 364.559389 -205.237337) (xy 364.613346 -205.251443) (xy 364.664675 -205.273255)
			(xy 364.712281 -205.302309) (xy 364.755149 -205.337984) (xy 364.792366 -205.379521) (xy 364.823139 -205.426034)
			(xy 364.846811 -205.476531) (xy 364.862879 -205.529938) (xy 364.870999 -205.585114) (xy 364.871508 -205.613)
			(xy 364.870999 -205.640886) (xy 364.862879 -205.696062) (xy 364.846811 -205.749469) (xy 364.823139 -205.799966)
			(xy 364.792366 -205.846479) (xy 364.755149 -205.888016) (xy 364.712281 -205.923691) (xy 364.664675 -205.952745)
			(xy 364.613346 -205.974557) (xy 364.559389 -205.988663) (xy 364.503952 -205.994763) (xy 364.448218 -205.992726)
			(xy 364.393375 -205.982596) (xy 364.340591 -205.964589) (xy 364.290991 -205.939088) (xy 364.245633 -205.906637)
			(xy 364.205484 -205.867928) (xy 364.171398 -205.823785) (xy 364.144102 -205.77515) (xy 364.124179 -205.723059)
			(xy 364.112053 -205.668622) (xy 364.107982 -205.613) (xy 362.741979 -205.613) (xy 362.760366 -205.633521)
			(xy 362.791139 -205.680034) (xy 362.814811 -205.730531) (xy 362.830879 -205.783938) (xy 362.838999 -205.839114)
			(xy 362.839508 -205.867) (xy 362.838999 -205.894886) (xy 362.830879 -205.950062) (xy 362.814811 -206.003469)
			(xy 362.791139 -206.053966) (xy 362.760366 -206.100479) (xy 362.723149 -206.142016) (xy 362.680281 -206.177691)
			(xy 362.632675 -206.206745) (xy 362.581346 -206.228557) (xy 362.527389 -206.242663) (xy 362.471952 -206.248763)
			(xy 362.416218 -206.246726) (xy 362.361375 -206.236596) (xy 362.308591 -206.218589) (xy 362.258991 -206.193088)
			(xy 362.213633 -206.160637) (xy 362.173484 -206.121928) (xy 362.139398 -206.077785) (xy 362.112102 -206.02915)
			(xy 362.092179 -205.977059) (xy 362.080053 -205.922622) (xy 362.075982 -205.867) (xy 361.790488 -205.867)
			(xy 361.790488 -206.883) (xy 362.075982 -206.883) (xy 362.080053 -206.827378) (xy 362.092179 -206.772941)
			(xy 362.112102 -206.72085) (xy 362.139398 -206.672215) (xy 362.173484 -206.628072) (xy 362.213633 -206.589363)
			(xy 362.258991 -206.556912) (xy 362.308591 -206.531411) (xy 362.361375 -206.513404) (xy 362.416218 -206.503274)
			(xy 362.471952 -206.501237) (xy 362.527389 -206.507337) (xy 362.581346 -206.521443) (xy 362.632675 -206.543255)
			(xy 362.680281 -206.572309) (xy 362.723149 -206.607984) (xy 362.760366 -206.649521) (xy 362.791139 -206.696034)
			(xy 362.814811 -206.746531) (xy 362.830879 -206.799938) (xy 362.838999 -206.855114) (xy 362.839508 -206.883)
			(xy 364.107982 -206.883) (xy 364.112053 -206.827378) (xy 364.124179 -206.772941) (xy 364.144102 -206.72085)
			(xy 364.171398 -206.672215) (xy 364.205484 -206.628072) (xy 364.245633 -206.589363) (xy 364.290991 -206.556912)
			(xy 364.340591 -206.531411) (xy 364.393375 -206.513404) (xy 364.448218 -206.503274) (xy 364.503952 -206.501237)
			(xy 364.559389 -206.507337) (xy 364.613346 -206.521443) (xy 364.664675 -206.543255) (xy 364.712281 -206.572309)
			(xy 364.755149 -206.607984) (xy 364.792366 -206.649521) (xy 364.823139 -206.696034) (xy 364.846811 -206.746531)
			(xy 364.862879 -206.799938) (xy 364.870999 -206.855114) (xy 364.871508 -206.883) (xy 364.870999 -206.910886)
			(xy 364.862879 -206.966062) (xy 364.846811 -207.019469) (xy 364.823139 -207.069966) (xy 364.792366 -207.116479)
			(xy 364.755149 -207.158016) (xy 364.712281 -207.193691) (xy 364.664675 -207.222745) (xy 364.613346 -207.244557)
			(xy 364.559389 -207.258663) (xy 364.503952 -207.264763) (xy 364.448218 -207.262726) (xy 364.393375 -207.252596)
			(xy 364.340591 -207.234589) (xy 364.290991 -207.209088) (xy 364.245633 -207.176637) (xy 364.205484 -207.137928)
			(xy 364.171398 -207.093785) (xy 364.144102 -207.04515) (xy 364.124179 -206.993059) (xy 364.112053 -206.938622)
			(xy 364.107982 -206.883) (xy 362.839508 -206.883) (xy 362.838999 -206.910886) (xy 362.830879 -206.966062)
			(xy 362.814811 -207.019469) (xy 362.791139 -207.069966) (xy 362.760366 -207.116479) (xy 362.723149 -207.158016)
			(xy 362.680281 -207.193691) (xy 362.632675 -207.222745) (xy 362.581346 -207.244557) (xy 362.527389 -207.258663)
			(xy 362.471952 -207.264763) (xy 362.416218 -207.262726) (xy 362.361375 -207.252596) (xy 362.308591 -207.234589)
			(xy 362.258991 -207.209088) (xy 362.213633 -207.176637) (xy 362.173484 -207.137928) (xy 362.139398 -207.093785)
			(xy 362.112102 -207.04515) (xy 362.092179 -206.993059) (xy 362.080053 -206.938622) (xy 362.075982 -206.883)
			(xy 361.790488 -206.883) (xy 361.790488 -207.899) (xy 362.075982 -207.899) (xy 362.080053 -207.843378)
			(xy 362.092179 -207.788941) (xy 362.112102 -207.73685) (xy 362.139398 -207.688215) (xy 362.173484 -207.644072)
			(xy 362.213633 -207.605363) (xy 362.258991 -207.572912) (xy 362.308591 -207.547411) (xy 362.361375 -207.529404)
			(xy 362.416218 -207.519274) (xy 362.471952 -207.517237) (xy 362.527389 -207.523337) (xy 362.581346 -207.537443)
			(xy 362.632675 -207.559255) (xy 362.680281 -207.588309) (xy 362.723149 -207.623984) (xy 362.760366 -207.665521)
			(xy 362.791139 -207.712034) (xy 362.814811 -207.762531) (xy 362.830879 -207.815938) (xy 362.838999 -207.871114)
			(xy 362.839508 -207.899) (xy 364.107982 -207.899) (xy 364.112053 -207.843378) (xy 364.124179 -207.788941)
			(xy 364.144102 -207.73685) (xy 364.171398 -207.688215) (xy 364.205484 -207.644072) (xy 364.245633 -207.605363)
			(xy 364.290991 -207.572912) (xy 364.340591 -207.547411) (xy 364.393375 -207.529404) (xy 364.448218 -207.519274)
			(xy 364.503952 -207.517237) (xy 364.559389 -207.523337) (xy 364.613346 -207.537443) (xy 364.664675 -207.559255)
			(xy 364.712281 -207.588309) (xy 364.755149 -207.623984) (xy 364.792366 -207.665521) (xy 364.823139 -207.712034)
			(xy 364.846811 -207.762531) (xy 364.862879 -207.815938) (xy 364.870999 -207.871114) (xy 364.871508 -207.899)
			(xy 364.870999 -207.926886) (xy 364.862879 -207.982062) (xy 364.846811 -208.035469) (xy 364.823139 -208.085966)
			(xy 364.792366 -208.132479) (xy 364.755149 -208.174016) (xy 364.712281 -208.209691) (xy 364.664675 -208.238745)
			(xy 364.613346 -208.260557) (xy 364.559389 -208.274663) (xy 364.503952 -208.280763) (xy 364.448218 -208.278726)
			(xy 364.393375 -208.268596) (xy 364.340591 -208.250589) (xy 364.290991 -208.225088) (xy 364.245633 -208.192637)
			(xy 364.205484 -208.153928) (xy 364.171398 -208.109785) (xy 364.144102 -208.06115) (xy 364.124179 -208.009059)
			(xy 364.112053 -207.954622) (xy 364.107982 -207.899) (xy 362.839508 -207.899) (xy 362.838999 -207.926886)
			(xy 362.830879 -207.982062) (xy 362.814811 -208.035469) (xy 362.791139 -208.085966) (xy 362.760366 -208.132479)
			(xy 362.723149 -208.174016) (xy 362.680281 -208.209691) (xy 362.632675 -208.238745) (xy 362.581346 -208.260557)
			(xy 362.527389 -208.274663) (xy 362.471952 -208.280763) (xy 362.416218 -208.278726) (xy 362.361375 -208.268596)
			(xy 362.308591 -208.250589) (xy 362.258991 -208.225088) (xy 362.213633 -208.192637) (xy 362.173484 -208.153928)
			(xy 362.139398 -208.109785) (xy 362.112102 -208.06115) (xy 362.092179 -208.009059) (xy 362.080053 -207.954622)
			(xy 362.075982 -207.899) (xy 361.790488 -207.899) (xy 361.790488 -209.931) (xy 362.075982 -209.931)
			(xy 362.080053 -209.875378) (xy 362.092179 -209.820941) (xy 362.112102 -209.76885) (xy 362.139398 -209.720215)
			(xy 362.173484 -209.676072) (xy 362.213633 -209.637363) (xy 362.258991 -209.604912) (xy 362.308591 -209.579411)
			(xy 362.361375 -209.561404) (xy 362.416218 -209.551274) (xy 362.471952 -209.549237) (xy 362.527389 -209.555337)
			(xy 362.581346 -209.569443) (xy 362.632675 -209.591255) (xy 362.680281 -209.620309) (xy 362.723149 -209.655984)
			(xy 362.741979 -209.677) (xy 364.107982 -209.677) (xy 364.112053 -209.621378) (xy 364.124179 -209.566941)
			(xy 364.144102 -209.51485) (xy 364.171398 -209.466215) (xy 364.205484 -209.422072) (xy 364.245633 -209.383363)
			(xy 364.290991 -209.350912) (xy 364.340591 -209.325411) (xy 364.393375 -209.307404) (xy 364.448218 -209.297274)
			(xy 364.503952 -209.295237) (xy 364.559389 -209.301337) (xy 364.613346 -209.315443) (xy 364.664675 -209.337255)
			(xy 364.712281 -209.366309) (xy 364.755149 -209.401984) (xy 364.792366 -209.443521) (xy 364.823139 -209.490034)
			(xy 364.846811 -209.540531) (xy 364.862879 -209.593938) (xy 364.870999 -209.649114) (xy 364.871508 -209.677)
			(xy 364.870999 -209.704886) (xy 364.862879 -209.760062) (xy 364.846811 -209.813469) (xy 364.823139 -209.863966)
			(xy 364.792366 -209.910479) (xy 364.755149 -209.952016) (xy 364.712281 -209.987691) (xy 364.664675 -210.016745)
			(xy 364.613346 -210.038557) (xy 364.559389 -210.052663) (xy 364.503952 -210.058763) (xy 364.448218 -210.056726)
			(xy 364.393375 -210.046596) (xy 364.340591 -210.028589) (xy 364.290991 -210.003088) (xy 364.245633 -209.970637)
			(xy 364.205484 -209.931928) (xy 364.171398 -209.887785) (xy 364.144102 -209.83915) (xy 364.124179 -209.787059)
			(xy 364.112053 -209.732622) (xy 364.107982 -209.677) (xy 362.741979 -209.677) (xy 362.760366 -209.697521)
			(xy 362.791139 -209.744034) (xy 362.814811 -209.794531) (xy 362.830879 -209.847938) (xy 362.838999 -209.903114)
			(xy 362.839508 -209.931) (xy 362.838999 -209.958886) (xy 362.830879 -210.014062) (xy 362.814811 -210.067469)
			(xy 362.791139 -210.117966) (xy 362.760366 -210.164479) (xy 362.723149 -210.206016) (xy 362.680281 -210.241691)
			(xy 362.632675 -210.270745) (xy 362.581346 -210.292557) (xy 362.527389 -210.306663) (xy 362.471952 -210.312763)
			(xy 362.416218 -210.310726) (xy 362.361375 -210.300596) (xy 362.308591 -210.282589) (xy 362.258991 -210.257088)
			(xy 362.213633 -210.224637) (xy 362.173484 -210.185928) (xy 362.139398 -210.141785) (xy 362.112102 -210.09315)
			(xy 362.092179 -210.041059) (xy 362.080053 -209.986622) (xy 362.075982 -209.931) (xy 361.790488 -209.931)
			(xy 361.790488 -210.947) (xy 362.075982 -210.947) (xy 362.080053 -210.891378) (xy 362.092179 -210.836941)
			(xy 362.112102 -210.78485) (xy 362.139398 -210.736215) (xy 362.173484 -210.692072) (xy 362.213633 -210.653363)
			(xy 362.258991 -210.620912) (xy 362.308591 -210.595411) (xy 362.361375 -210.577404) (xy 362.416218 -210.567274)
			(xy 362.471952 -210.565237) (xy 362.527389 -210.571337) (xy 362.581346 -210.585443) (xy 362.632675 -210.607255)
			(xy 362.680281 -210.636309) (xy 362.723149 -210.671984) (xy 362.760366 -210.713521) (xy 362.791139 -210.760034)
			(xy 362.814811 -210.810531) (xy 362.830879 -210.863938) (xy 362.838999 -210.919114) (xy 362.839508 -210.947)
			(xy 364.101632 -210.947) (xy 364.105703 -210.891378) (xy 364.117829 -210.836941) (xy 364.137752 -210.78485)
			(xy 364.165048 -210.736215) (xy 364.199134 -210.692072) (xy 364.239283 -210.653363) (xy 364.284641 -210.620912)
			(xy 364.334241 -210.595411) (xy 364.387025 -210.577404) (xy 364.441868 -210.567274) (xy 364.497602 -210.565237)
			(xy 364.553039 -210.571337) (xy 364.606996 -210.585443) (xy 364.658325 -210.607255) (xy 364.705931 -210.636309)
			(xy 364.748799 -210.671984) (xy 364.786016 -210.713521) (xy 364.816789 -210.760034) (xy 364.840461 -210.810531)
			(xy 364.856529 -210.863938) (xy 364.864649 -210.919114) (xy 364.865158 -210.947) (xy 364.864649 -210.974886)
			(xy 364.856529 -211.030062) (xy 364.840461 -211.083469) (xy 364.816789 -211.133966) (xy 364.786016 -211.180479)
			(xy 364.748799 -211.222016) (xy 364.705931 -211.257691) (xy 364.658325 -211.286745) (xy 364.606996 -211.308557)
			(xy 364.553039 -211.322663) (xy 364.497602 -211.328763) (xy 364.441868 -211.326726) (xy 364.387025 -211.316596)
			(xy 364.334241 -211.298589) (xy 364.284641 -211.273088) (xy 364.239283 -211.240637) (xy 364.199134 -211.201928)
			(xy 364.165048 -211.157785) (xy 364.137752 -211.10915) (xy 364.117829 -211.057059) (xy 364.105703 -211.002622)
			(xy 364.101632 -210.947) (xy 362.839508 -210.947) (xy 362.838999 -210.974886) (xy 362.830879 -211.030062)
			(xy 362.814811 -211.083469) (xy 362.791139 -211.133966) (xy 362.760366 -211.180479) (xy 362.723149 -211.222016)
			(xy 362.680281 -211.257691) (xy 362.632675 -211.286745) (xy 362.581346 -211.308557) (xy 362.527389 -211.322663)
			(xy 362.471952 -211.328763) (xy 362.416218 -211.326726) (xy 362.361375 -211.316596) (xy 362.308591 -211.298589)
			(xy 362.258991 -211.273088) (xy 362.213633 -211.240637) (xy 362.173484 -211.201928) (xy 362.139398 -211.157785)
			(xy 362.112102 -211.10915) (xy 362.092179 -211.057059) (xy 362.080053 -211.002622) (xy 362.075982 -210.947)
			(xy 361.790488 -210.947) (xy 361.790488 -211.963) (xy 362.075982 -211.963) (xy 362.080053 -211.907378)
			(xy 362.092179 -211.852941) (xy 362.112102 -211.80085) (xy 362.139398 -211.752215) (xy 362.173484 -211.708072)
			(xy 362.213633 -211.669363) (xy 362.258991 -211.636912) (xy 362.308591 -211.611411) (xy 362.361375 -211.593404)
			(xy 362.416218 -211.583274) (xy 362.471952 -211.581237) (xy 362.527389 -211.587337) (xy 362.581346 -211.601443)
			(xy 362.632675 -211.623255) (xy 362.680281 -211.652309) (xy 362.723149 -211.687984) (xy 362.760366 -211.729521)
			(xy 362.791139 -211.776034) (xy 362.814811 -211.826531) (xy 362.830879 -211.879938) (xy 362.838999 -211.935114)
			(xy 362.839508 -211.963) (xy 364.107982 -211.963) (xy 364.112053 -211.907378) (xy 364.124179 -211.852941)
			(xy 364.144102 -211.80085) (xy 364.171398 -211.752215) (xy 364.205484 -211.708072) (xy 364.245633 -211.669363)
			(xy 364.290991 -211.636912) (xy 364.340591 -211.611411) (xy 364.393375 -211.593404) (xy 364.448218 -211.583274)
			(xy 364.503952 -211.581237) (xy 364.559389 -211.587337) (xy 364.613346 -211.601443) (xy 364.664675 -211.623255)
			(xy 364.712281 -211.652309) (xy 364.755149 -211.687984) (xy 364.792366 -211.729521) (xy 364.823139 -211.776034)
			(xy 364.846811 -211.826531) (xy 364.862879 -211.879938) (xy 364.870999 -211.935114) (xy 364.871508 -211.963)
			(xy 364.870999 -211.990886) (xy 364.862879 -212.046062) (xy 364.846811 -212.099469) (xy 364.823139 -212.149966)
			(xy 364.792366 -212.196479) (xy 364.755149 -212.238016) (xy 364.712281 -212.273691) (xy 364.664675 -212.302745)
			(xy 364.613346 -212.324557) (xy 364.559389 -212.338663) (xy 364.503952 -212.344763) (xy 364.448218 -212.342726)
			(xy 364.393375 -212.332596) (xy 364.340591 -212.314589) (xy 364.290991 -212.289088) (xy 364.245633 -212.256637)
			(xy 364.205484 -212.217928) (xy 364.171398 -212.173785) (xy 364.144102 -212.12515) (xy 364.124179 -212.073059)
			(xy 364.112053 -212.018622) (xy 364.107982 -211.963) (xy 362.839508 -211.963) (xy 362.838999 -211.990886)
			(xy 362.830879 -212.046062) (xy 362.814811 -212.099469) (xy 362.791139 -212.149966) (xy 362.760366 -212.196479)
			(xy 362.723149 -212.238016) (xy 362.680281 -212.273691) (xy 362.632675 -212.302745) (xy 362.581346 -212.324557)
			(xy 362.527389 -212.338663) (xy 362.471952 -212.344763) (xy 362.416218 -212.342726) (xy 362.361375 -212.332596)
			(xy 362.308591 -212.314589) (xy 362.258991 -212.289088) (xy 362.213633 -212.256637) (xy 362.173484 -212.217928)
			(xy 362.139398 -212.173785) (xy 362.112102 -212.12515) (xy 362.092179 -212.073059) (xy 362.080053 -212.018622)
			(xy 362.075982 -211.963) (xy 361.790488 -211.963) (xy 361.790488 -212.979) (xy 362.075982 -212.979)
			(xy 362.080053 -212.923378) (xy 362.092179 -212.868941) (xy 362.112102 -212.81685) (xy 362.139398 -212.768215)
			(xy 362.173484 -212.724072) (xy 362.213633 -212.685363) (xy 362.258991 -212.652912) (xy 362.308591 -212.627411)
			(xy 362.361375 -212.609404) (xy 362.416218 -212.599274) (xy 362.471952 -212.597237) (xy 362.527389 -212.603337)
			(xy 362.581346 -212.617443) (xy 362.632675 -212.639255) (xy 362.680281 -212.668309) (xy 362.723149 -212.703984)
			(xy 362.760366 -212.745521) (xy 362.791139 -212.792034) (xy 362.814811 -212.842531) (xy 362.830879 -212.895938)
			(xy 362.838999 -212.951114) (xy 362.839508 -212.979) (xy 366.139982 -212.979) (xy 366.144053 -212.923378)
			(xy 366.156179 -212.868941) (xy 366.176102 -212.81685) (xy 366.203398 -212.768215) (xy 366.237484 -212.724072)
			(xy 366.277633 -212.685363) (xy 366.322991 -212.652912) (xy 366.372591 -212.627411) (xy 366.425375 -212.609404)
			(xy 366.480218 -212.599274) (xy 366.535952 -212.597237) (xy 366.591389 -212.603337) (xy 366.645346 -212.617443)
			(xy 366.696675 -212.639255) (xy 366.744281 -212.668309) (xy 366.787149 -212.703984) (xy 366.824366 -212.745521)
			(xy 366.855139 -212.792034) (xy 366.878811 -212.842531) (xy 366.894879 -212.895938) (xy 366.902999 -212.951114)
			(xy 366.903508 -212.979) (xy 366.902999 -213.006886) (xy 366.894879 -213.062062) (xy 366.878811 -213.115469)
			(xy 366.855139 -213.165966) (xy 366.824366 -213.212479) (xy 366.787149 -213.254016) (xy 366.744281 -213.289691)
			(xy 366.696675 -213.318745) (xy 366.645346 -213.340557) (xy 366.591389 -213.354663) (xy 366.535952 -213.360763)
			(xy 366.480218 -213.358726) (xy 366.425375 -213.348596) (xy 366.372591 -213.330589) (xy 366.322991 -213.305088)
			(xy 366.277633 -213.272637) (xy 366.237484 -213.233928) (xy 366.203398 -213.189785) (xy 366.176102 -213.14115)
			(xy 366.156179 -213.089059) (xy 366.144053 -213.034622) (xy 366.139982 -212.979) (xy 362.839508 -212.979)
			(xy 362.838999 -213.006886) (xy 362.830879 -213.062062) (xy 362.814811 -213.115469) (xy 362.791139 -213.165966)
			(xy 362.760366 -213.212479) (xy 362.723149 -213.254016) (xy 362.680281 -213.289691) (xy 362.632675 -213.318745)
			(xy 362.581346 -213.340557) (xy 362.527389 -213.354663) (xy 362.471952 -213.360763) (xy 362.416218 -213.358726)
			(xy 362.361375 -213.348596) (xy 362.308591 -213.330589) (xy 362.258991 -213.305088) (xy 362.213633 -213.272637)
			(xy 362.173484 -213.233928) (xy 362.139398 -213.189785) (xy 362.112102 -213.14115) (xy 362.092179 -213.089059)
			(xy 362.080053 -213.034622) (xy 362.075982 -212.979) (xy 361.790488 -212.979) (xy 361.790488 -213.995)
			(xy 362.075982 -213.995) (xy 362.080053 -213.939378) (xy 362.092179 -213.884941) (xy 362.112102 -213.83285)
			(xy 362.139398 -213.784215) (xy 362.173484 -213.740072) (xy 362.213633 -213.701363) (xy 362.258991 -213.668912)
			(xy 362.308591 -213.643411) (xy 362.361375 -213.625404) (xy 362.416218 -213.615274) (xy 362.471952 -213.613237)
			(xy 362.527389 -213.619337) (xy 362.581346 -213.633443) (xy 362.632675 -213.655255) (xy 362.680281 -213.684309)
			(xy 362.723149 -213.719984) (xy 362.760366 -213.761521) (xy 362.791139 -213.808034) (xy 362.814811 -213.858531)
			(xy 362.830879 -213.911938) (xy 362.838999 -213.967114) (xy 362.839508 -213.995) (xy 366.139982 -213.995)
			(xy 366.144053 -213.939378) (xy 366.156179 -213.884941) (xy 366.176102 -213.83285) (xy 366.203398 -213.784215)
			(xy 366.237484 -213.740072) (xy 366.277633 -213.701363) (xy 366.322991 -213.668912) (xy 366.372591 -213.643411)
			(xy 366.425375 -213.625404) (xy 366.480218 -213.615274) (xy 366.535952 -213.613237) (xy 366.591389 -213.619337)
			(xy 366.645346 -213.633443) (xy 366.696675 -213.655255) (xy 366.744281 -213.684309) (xy 366.787149 -213.719984)
			(xy 366.824366 -213.761521) (xy 366.855139 -213.808034) (xy 366.878811 -213.858531) (xy 366.894879 -213.911938)
			(xy 366.902999 -213.967114) (xy 366.903508 -213.995) (xy 366.902999 -214.022886) (xy 366.894879 -214.078062)
			(xy 366.878811 -214.131469) (xy 366.855139 -214.181966) (xy 366.824366 -214.228479) (xy 366.787149 -214.270016)
			(xy 366.744281 -214.305691) (xy 366.696675 -214.334745) (xy 366.645346 -214.356557) (xy 366.591389 -214.370663)
			(xy 366.535952 -214.376763) (xy 366.480218 -214.374726) (xy 366.425375 -214.364596) (xy 366.372591 -214.346589)
			(xy 366.322991 -214.321088) (xy 366.277633 -214.288637) (xy 366.237484 -214.249928) (xy 366.203398 -214.205785)
			(xy 366.176102 -214.15715) (xy 366.156179 -214.105059) (xy 366.144053 -214.050622) (xy 366.139982 -213.995)
			(xy 362.839508 -213.995) (xy 362.838999 -214.022886) (xy 362.830879 -214.078062) (xy 362.814811 -214.131469)
			(xy 362.791139 -214.181966) (xy 362.760366 -214.228479) (xy 362.723149 -214.270016) (xy 362.680281 -214.305691)
			(xy 362.632675 -214.334745) (xy 362.581346 -214.356557) (xy 362.527389 -214.370663) (xy 362.471952 -214.376763)
			(xy 362.416218 -214.374726) (xy 362.361375 -214.364596) (xy 362.308591 -214.346589) (xy 362.258991 -214.321088)
			(xy 362.213633 -214.288637) (xy 362.173484 -214.249928) (xy 362.139398 -214.205785) (xy 362.112102 -214.15715)
			(xy 362.092179 -214.105059) (xy 362.080053 -214.050622) (xy 362.075982 -213.995) (xy 361.790488 -213.995)
			(xy 361.790488 -215.011) (xy 362.075982 -215.011) (xy 362.080053 -214.955378) (xy 362.092179 -214.900941)
			(xy 362.112102 -214.84885) (xy 362.139398 -214.800215) (xy 362.173484 -214.756072) (xy 362.213633 -214.717363)
			(xy 362.258991 -214.684912) (xy 362.308591 -214.659411) (xy 362.361375 -214.641404) (xy 362.416218 -214.631274)
			(xy 362.471952 -214.629237) (xy 362.527389 -214.635337) (xy 362.581346 -214.649443) (xy 362.632675 -214.671255)
			(xy 362.680281 -214.700309) (xy 362.723149 -214.735984) (xy 362.760366 -214.777521) (xy 362.791139 -214.824034)
			(xy 362.814811 -214.874531) (xy 362.830879 -214.927938) (xy 362.838999 -214.983114) (xy 362.839508 -215.011)
			(xy 364.107982 -215.011) (xy 364.112053 -214.955378) (xy 364.124179 -214.900941) (xy 364.144102 -214.84885)
			(xy 364.171398 -214.800215) (xy 364.205484 -214.756072) (xy 364.245633 -214.717363) (xy 364.290991 -214.684912)
			(xy 364.340591 -214.659411) (xy 364.393375 -214.641404) (xy 364.448218 -214.631274) (xy 364.503952 -214.629237)
			(xy 364.559389 -214.635337) (xy 364.613346 -214.649443) (xy 364.664675 -214.671255) (xy 364.712281 -214.700309)
			(xy 364.755149 -214.735984) (xy 364.792366 -214.777521) (xy 364.823139 -214.824034) (xy 364.846811 -214.874531)
			(xy 364.862879 -214.927938) (xy 364.870999 -214.983114) (xy 364.871508 -215.011) (xy 364.870999 -215.038886)
			(xy 364.862879 -215.094062) (xy 364.846811 -215.147469) (xy 364.823139 -215.197966) (xy 364.792366 -215.244479)
			(xy 364.755149 -215.286016) (xy 364.712281 -215.321691) (xy 364.664675 -215.350745) (xy 364.613346 -215.372557)
			(xy 364.559389 -215.386663) (xy 364.503952 -215.392763) (xy 364.448218 -215.390726) (xy 364.393375 -215.380596)
			(xy 364.340591 -215.362589) (xy 364.290991 -215.337088) (xy 364.245633 -215.304637) (xy 364.205484 -215.265928)
			(xy 364.171398 -215.221785) (xy 364.144102 -215.17315) (xy 364.124179 -215.121059) (xy 364.112053 -215.066622)
			(xy 364.107982 -215.011) (xy 362.839508 -215.011) (xy 362.838999 -215.038886) (xy 362.830879 -215.094062)
			(xy 362.814811 -215.147469) (xy 362.791139 -215.197966) (xy 362.760366 -215.244479) (xy 362.723149 -215.286016)
			(xy 362.680281 -215.321691) (xy 362.632675 -215.350745) (xy 362.581346 -215.372557) (xy 362.527389 -215.386663)
			(xy 362.471952 -215.392763) (xy 362.416218 -215.390726) (xy 362.361375 -215.380596) (xy 362.308591 -215.362589)
			(xy 362.258991 -215.337088) (xy 362.213633 -215.304637) (xy 362.173484 -215.265928) (xy 362.139398 -215.221785)
			(xy 362.112102 -215.17315) (xy 362.092179 -215.121059) (xy 362.080053 -215.066622) (xy 362.075982 -215.011)
			(xy 361.790488 -215.011) (xy 361.790488 -216.926668) (xy 364.16183 -216.926668) (xy 364.165901 -216.871046)
			(xy 364.178027 -216.816609) (xy 364.19795 -216.764518) (xy 364.225246 -216.715883) (xy 364.259332 -216.67174)
			(xy 364.299481 -216.633031) (xy 364.344839 -216.60058) (xy 364.394439 -216.575079) (xy 364.447223 -216.557072)
			(xy 364.502066 -216.546942) (xy 364.5578 -216.544905) (xy 364.613237 -216.551005) (xy 364.667194 -216.565111)
			(xy 364.718523 -216.586923) (xy 364.766129 -216.615977) (xy 364.808997 -216.651652) (xy 364.846214 -216.693189)
			(xy 364.876987 -216.739702) (xy 364.900659 -216.790199) (xy 364.916727 -216.843606) (xy 364.924847 -216.898782)
			(xy 364.925356 -216.926668) (xy 364.924847 -216.954554) (xy 364.916727 -217.00973) (xy 364.900659 -217.063137)
			(xy 364.876987 -217.113634) (xy 364.846214 -217.160147) (xy 364.808997 -217.201684) (xy 364.766129 -217.237359)
			(xy 364.718523 -217.266413) (xy 364.667194 -217.288225) (xy 364.613237 -217.302331) (xy 364.5578 -217.308431)
			(xy 364.502066 -217.306394) (xy 364.447223 -217.296264) (xy 364.394439 -217.278257) (xy 364.344839 -217.252756)
			(xy 364.299481 -217.220305) (xy 364.259332 -217.181596) (xy 364.225246 -217.137453) (xy 364.19795 -217.088818)
			(xy 364.178027 -217.036727) (xy 364.165901 -216.98229) (xy 364.16183 -216.926668) (xy 361.790488 -216.926668)
			(xy 361.790488 -219.5576) (xy 367.594386 -219.5576) (xy 367.598457 -219.501978) (xy 367.610583 -219.447541)
			(xy 367.630506 -219.39545) (xy 367.657802 -219.346815) (xy 367.691888 -219.302672) (xy 367.732037 -219.263963)
			(xy 367.777395 -219.231512) (xy 367.826995 -219.206011) (xy 367.879779 -219.188004) (xy 367.934622 -219.177874)
			(xy 367.990356 -219.175837) (xy 368.045793 -219.181937) (xy 368.09975 -219.196043) (xy 368.151079 -219.217855)
			(xy 368.198685 -219.246909) (xy 368.241553 -219.282584) (xy 368.27877 -219.324121) (xy 368.309543 -219.370634)
			(xy 368.333215 -219.421131) (xy 368.349283 -219.474538) (xy 368.357403 -219.529714) (xy 368.357912 -219.5576)
			(xy 368.357403 -219.585486) (xy 368.349283 -219.640662) (xy 368.333215 -219.694069) (xy 368.309543 -219.744566)
			(xy 368.27877 -219.791079) (xy 368.241553 -219.832616) (xy 368.198685 -219.868291) (xy 368.151079 -219.897345)
			(xy 368.09975 -219.919157) (xy 368.045793 -219.933263) (xy 367.990356 -219.939363) (xy 367.934622 -219.937326)
			(xy 367.879779 -219.927196) (xy 367.826995 -219.909189) (xy 367.777395 -219.883688) (xy 367.732037 -219.851237)
			(xy 367.691888 -219.812528) (xy 367.657802 -219.768385) (xy 367.630506 -219.71975) (xy 367.610583 -219.667659)
			(xy 367.598457 -219.613222) (xy 367.594386 -219.5576) (xy 361.790488 -219.5576) (xy 361.790488 -220.378782)
			(xy 364.917734 -220.378782) (xy 364.921805 -220.32316) (xy 364.933931 -220.268723) (xy 364.953854 -220.216632)
			(xy 364.98115 -220.167997) (xy 365.015236 -220.123854) (xy 365.055385 -220.085145) (xy 365.100743 -220.052694)
			(xy 365.150343 -220.027193) (xy 365.203127 -220.009186) (xy 365.25797 -219.999056) (xy 365.313704 -219.997019)
			(xy 365.369141 -220.003119) (xy 365.423098 -220.017225) (xy 365.474427 -220.039037) (xy 365.522033 -220.068091)
			(xy 365.564901 -220.103766) (xy 365.602118 -220.145303) (xy 365.632891 -220.191816) (xy 365.656563 -220.242313)
			(xy 365.672631 -220.29572) (xy 365.680751 -220.350896) (xy 365.68126 -220.378782) (xy 365.680751 -220.406668)
			(xy 365.672631 -220.461844) (xy 365.656563 -220.515251) (xy 365.632891 -220.565748) (xy 365.602118 -220.612261)
			(xy 365.564901 -220.653798) (xy 365.522033 -220.689473) (xy 365.474427 -220.718527) (xy 365.423098 -220.740339)
			(xy 365.369141 -220.754445) (xy 365.313704 -220.760545) (xy 365.25797 -220.758508) (xy 365.203127 -220.748378)
			(xy 365.150343 -220.730371) (xy 365.100743 -220.70487) (xy 365.055385 -220.672419) (xy 365.015236 -220.63371)
			(xy 364.98115 -220.589567) (xy 364.953854 -220.540932) (xy 364.933931 -220.488841) (xy 364.921805 -220.434404)
			(xy 364.917734 -220.378782) (xy 361.790488 -220.378782) (xy 361.790488 -220.84665) (xy 364.12881 -220.84665)
			(xy 364.132881 -220.791028) (xy 364.145007 -220.736591) (xy 364.16493 -220.6845) (xy 364.192226 -220.635865)
			(xy 364.226312 -220.591722) (xy 364.266461 -220.553013) (xy 364.311819 -220.520562) (xy 364.361419 -220.495061)
			(xy 364.414203 -220.477054) (xy 364.469046 -220.466924) (xy 364.52478 -220.464887) (xy 364.580217 -220.470987)
			(xy 364.634174 -220.485093) (xy 364.685503 -220.506905) (xy 364.733109 -220.535959) (xy 364.775977 -220.571634)
			(xy 364.813194 -220.613171) (xy 364.843967 -220.659684) (xy 364.867639 -220.710181) (xy 364.883707 -220.763588)
			(xy 364.891827 -220.818764) (xy 364.892336 -220.84665) (xy 364.891827 -220.874536) (xy 364.883707 -220.929712)
			(xy 364.867639 -220.983119) (xy 364.843967 -221.033616) (xy 364.813194 -221.080129) (xy 364.775977 -221.121666)
			(xy 364.733109 -221.157341) (xy 364.685503 -221.186395) (xy 364.634174 -221.208207) (xy 364.580217 -221.222313)
			(xy 364.52478 -221.228413) (xy 364.469046 -221.226376) (xy 364.414203 -221.216246) (xy 364.361419 -221.198239)
			(xy 364.311819 -221.172738) (xy 364.266461 -221.140287) (xy 364.226312 -221.101578) (xy 364.192226 -221.057435)
			(xy 364.16493 -221.0088) (xy 364.145007 -220.956709) (xy 364.132881 -220.902272) (xy 364.12881 -220.84665)
			(xy 361.790488 -220.84665) (xy 361.790488 -221.332806) (xy 370.740684 -221.332806) (xy 370.744755 -221.277184)
			(xy 370.756881 -221.222747) (xy 370.776804 -221.170656) (xy 370.8041 -221.122021) (xy 370.838186 -221.077878)
			(xy 370.878335 -221.039169) (xy 370.923693 -221.006718) (xy 370.973293 -220.981217) (xy 371.026077 -220.96321)
			(xy 371.08092 -220.95308) (xy 371.136654 -220.951043) (xy 371.192091 -220.957143) (xy 371.246048 -220.971249)
			(xy 371.297377 -220.993061) (xy 371.344983 -221.022115) (xy 371.387851 -221.05779) (xy 371.425068 -221.099327)
			(xy 371.455841 -221.14584) (xy 371.479513 -221.196337) (xy 371.495581 -221.249744) (xy 371.503701 -221.30492)
			(xy 371.50421 -221.332806) (xy 371.503701 -221.360692) (xy 371.495581 -221.415868) (xy 371.479513 -221.469275)
			(xy 371.455841 -221.519772) (xy 371.425068 -221.566285) (xy 371.387851 -221.607822) (xy 371.344983 -221.643497)
			(xy 371.297377 -221.672551) (xy 371.246048 -221.694363) (xy 371.220255 -221.701106) (xy 377.605034 -221.701106)
			(xy 377.609105 -221.645484) (xy 377.621231 -221.591047) (xy 377.641154 -221.538956) (xy 377.66845 -221.490321)
			(xy 377.702536 -221.446178) (xy 377.742685 -221.407469) (xy 377.788043 -221.375018) (xy 377.837643 -221.349517)
			(xy 377.890427 -221.33151) (xy 377.94527 -221.32138) (xy 378.001004 -221.319343) (xy 378.056441 -221.325443)
			(xy 378.110398 -221.339549) (xy 378.161727 -221.361361) (xy 378.209333 -221.390415) (xy 378.252201 -221.42609)
			(xy 378.289418 -221.467627) (xy 378.320191 -221.51414) (xy 378.343863 -221.564637) (xy 378.359931 -221.618044)
			(xy 378.368051 -221.67322) (xy 378.36856 -221.701106) (xy 378.368051 -221.728992) (xy 378.359931 -221.784168)
			(xy 378.343863 -221.837575) (xy 378.320191 -221.888072) (xy 378.289418 -221.934585) (xy 378.252201 -221.976122)
			(xy 378.209333 -222.011797) (xy 378.161727 -222.040851) (xy 378.110398 -222.062663) (xy 378.056441 -222.076769)
			(xy 378.001004 -222.082869) (xy 377.94527 -222.080832) (xy 377.890427 -222.070702) (xy 377.837643 -222.052695)
			(xy 377.788043 -222.027194) (xy 377.742685 -221.994743) (xy 377.702536 -221.956034) (xy 377.66845 -221.911891)
			(xy 377.641154 -221.863256) (xy 377.621231 -221.811165) (xy 377.609105 -221.756728) (xy 377.605034 -221.701106)
			(xy 371.220255 -221.701106) (xy 371.192091 -221.708469) (xy 371.136654 -221.714569) (xy 371.08092 -221.712532)
			(xy 371.026077 -221.702402) (xy 370.973293 -221.684395) (xy 370.923693 -221.658894) (xy 370.878335 -221.626443)
			(xy 370.838186 -221.587734) (xy 370.8041 -221.543591) (xy 370.776804 -221.494956) (xy 370.756881 -221.442865)
			(xy 370.744755 -221.388428) (xy 370.740684 -221.332806) (xy 361.790488 -221.332806) (xy 361.790488 -222.172276)
			(xy 364.118904 -222.172276) (xy 364.122975 -222.116654) (xy 364.135101 -222.062217) (xy 364.155024 -222.010126)
			(xy 364.18232 -221.961491) (xy 364.216406 -221.917348) (xy 364.256555 -221.878639) (xy 364.301913 -221.846188)
			(xy 364.351513 -221.820687) (xy 364.404297 -221.80268) (xy 364.45914 -221.79255) (xy 364.514874 -221.790513)
			(xy 364.570311 -221.796613) (xy 364.624268 -221.810719) (xy 364.675597 -221.832531) (xy 364.723203 -221.861585)
			(xy 364.766071 -221.89726) (xy 364.803288 -221.938797) (xy 364.82906 -221.977751) (xy 365.351289 -221.977751)
			(xy 365.351289 -221.923249) (xy 365.359046 -221.869302) (xy 365.374401 -221.817007) (xy 365.397043 -221.767431)
			(xy 365.426509 -221.721581) (xy 365.462201 -221.680392) (xy 365.503392 -221.644701) (xy 365.549243 -221.615236)
			(xy 365.59882 -221.592596) (xy 365.651115 -221.577243) (xy 365.705063 -221.569488) (xy 365.732314 -221.569026)
			(xy 365.762003 -221.56956) (xy 365.820664 -221.578762) (xy 365.87719 -221.596941) (xy 365.930218 -221.623658)
			(xy 365.978466 -221.658268) (xy 366.020769 -221.699935) (xy 366.038892 -221.723458) (xy 366.047737 -221.734577)
			(xy 366.070265 -221.751868) (xy 366.096687 -221.762278) (xy 366.124954 -221.765) (xy 366.152877 -221.759822)
			(xy 366.17829 -221.747146) (xy 366.199223 -221.727955) (xy 366.20704 -221.716092) (xy 366.222014 -221.692618)
			(xy 366.257716 -221.649893) (xy 366.299245 -221.612808) (xy 366.345722 -221.582149) (xy 366.396159 -221.558568)
			(xy 366.449488 -221.542564) (xy 366.504575 -221.534478) (xy 366.532414 -221.533974) (xy 366.559663 -221.534497)
			(xy 366.613607 -221.542255) (xy 366.665897 -221.557611) (xy 366.71547 -221.580251) (xy 366.761317 -221.609717)
			(xy 366.802503 -221.645406) (xy 366.838192 -221.686594) (xy 366.867655 -221.732442) (xy 366.890294 -221.782016)
			(xy 366.905648 -221.834307) (xy 366.913404 -221.888251) (xy 366.913404 -221.942749) (xy 366.905648 -221.996693)
			(xy 366.890294 -222.048984) (xy 366.867655 -222.098558) (xy 366.838192 -222.144406) (xy 366.802503 -222.185594)
			(xy 366.761317 -222.221283) (xy 366.71547 -222.250749) (xy 366.665897 -222.273389) (xy 366.613607 -222.288745)
			(xy 366.559663 -222.296503) (xy 366.532414 -222.29699) (xy 366.502726 -222.296429) (xy 366.444067 -222.287232)
			(xy 366.387541 -222.269058) (xy 366.334514 -222.242346) (xy 366.286265 -222.207741) (xy 366.24396 -222.166078)
			(xy 366.225836 -222.142558) (xy 366.216959 -222.131465) (xy 366.19444 -222.114171) (xy 366.168025 -222.103757)
			(xy 366.139762 -222.101032) (xy 366.111844 -222.106205) (xy 366.086434 -222.118876) (xy 366.065504 -222.138063)
			(xy 366.057688 -222.149924) (xy 366.042665 -222.173366) (xy 366.006975 -222.216095) (xy 365.965455 -222.253186)
			(xy 365.918987 -222.283849) (xy 365.868556 -222.307436) (xy 365.815234 -222.323445) (xy 365.760151 -222.331536)
			(xy 365.732314 -222.332042) (xy 365.705063 -222.331512) (xy 365.651115 -222.323757) (xy 365.59882 -222.308404)
			(xy 365.549243 -222.285764) (xy 365.503392 -222.256299) (xy 365.462201 -222.220608) (xy 365.426509 -222.179419)
			(xy 365.397043 -222.133569) (xy 365.374401 -222.083993) (xy 365.359046 -222.031698) (xy 365.351289 -221.977751)
			(xy 364.82906 -221.977751) (xy 364.834061 -221.98531) (xy 364.857733 -222.035807) (xy 364.873801 -222.089214)
			(xy 364.881921 -222.14439) (xy 364.88243 -222.172276) (xy 364.881921 -222.200162) (xy 364.873801 -222.255338)
			(xy 364.857733 -222.308745) (xy 364.834061 -222.359242) (xy 364.803288 -222.405755) (xy 364.766071 -222.447292)
			(xy 364.723203 -222.482967) (xy 364.675597 -222.512021) (xy 364.624268 -222.533833) (xy 364.570311 -222.547939)
			(xy 364.514874 -222.554039) (xy 364.45914 -222.552002) (xy 364.404297 -222.541872) (xy 364.351513 -222.523865)
			(xy 364.301913 -222.498364) (xy 364.256555 -222.465913) (xy 364.216406 -222.427204) (xy 364.18232 -222.383061)
			(xy 364.155024 -222.334426) (xy 364.135101 -222.282335) (xy 364.122975 -222.227898) (xy 364.118904 -222.172276)
			(xy 361.790488 -222.172276) (xy 361.790488 -222.976186) (xy 371.142768 -222.976186) (xy 371.143322 -222.94727)
			(xy 371.15204 -222.890099) (xy 371.169289 -222.8349) (xy 371.194674 -222.782938) (xy 371.227613 -222.735403)
			(xy 371.26735 -222.693386) (xy 371.289834 -222.675196) (xy 371.298639 -222.667587) (xy 371.308822 -222.646687)
			(xy 371.309392 -222.635064) (xy 371.309392 -222.555308) (xy 371.308837 -222.543678) (xy 371.298659 -222.522768)
			(xy 371.289834 -222.515176) (xy 371.267346 -222.49699) (xy 371.22761 -222.45497) (xy 371.19467 -222.407435)
			(xy 371.169282 -222.355472) (xy 371.152027 -222.300273) (xy 371.143301 -222.243102) (xy 371.142768 -222.214186)
			(xy 371.143254 -222.186935) (xy 371.15101 -222.132987) (xy 371.166365 -222.080692) (xy 371.189007 -222.031115)
			(xy 371.218473 -221.985265) (xy 371.254164 -221.944074) (xy 371.295355 -221.908383) (xy 371.341205 -221.878917)
			(xy 371.390782 -221.856275) (xy 371.443077 -221.84092) (xy 371.497025 -221.833164) (xy 371.551527 -221.833164)
			(xy 371.605475 -221.84092) (xy 371.65777 -221.856275) (xy 371.707347 -221.878917) (xy 371.753197 -221.908383)
			(xy 371.794388 -221.944074) (xy 371.830079 -221.985265) (xy 371.859545 -222.031115) (xy 371.882187 -222.080692)
			(xy 371.897542 -222.132987) (xy 371.905298 -222.186935) (xy 371.905784 -222.214186) (xy 371.905262 -222.243103)
			(xy 371.896534 -222.300274) (xy 371.879277 -222.355473) (xy 371.853887 -222.407435) (xy 371.820944 -222.454969)
			(xy 371.781203 -222.496986) (xy 371.758718 -222.515176) (xy 371.749918 -222.522789) (xy 371.739734 -222.543686)
			(xy 371.73916 -222.555308) (xy 371.73916 -222.635064) (xy 371.739656 -222.646702) (xy 371.749873 -222.667612)
			(xy 371.758718 -222.675196) (xy 371.781203 -222.693385) (xy 371.820938 -222.735405) (xy 371.853876 -222.782941)
			(xy 371.879264 -222.834903) (xy 371.89652 -222.8901) (xy 371.905249 -222.94727) (xy 371.905784 -222.976186)
			(xy 371.905298 -223.003437) (xy 371.897542 -223.057385) (xy 371.885585 -223.098106) (xy 377.605034 -223.098106)
			(xy 377.609105 -223.042484) (xy 377.621231 -222.988047) (xy 377.641154 -222.935956) (xy 377.66845 -222.887321)
			(xy 377.702536 -222.843178) (xy 377.742685 -222.804469) (xy 377.788043 -222.772018) (xy 377.837643 -222.746517)
			(xy 377.890427 -222.72851) (xy 377.94527 -222.71838) (xy 378.001004 -222.716343) (xy 378.056441 -222.722443)
			(xy 378.110398 -222.736549) (xy 378.161727 -222.758361) (xy 378.209333 -222.787415) (xy 378.252201 -222.82309)
			(xy 378.289418 -222.864627) (xy 378.320191 -222.91114) (xy 378.343863 -222.961637) (xy 378.359931 -223.015044)
			(xy 378.368051 -223.07022) (xy 378.36856 -223.098106) (xy 378.368051 -223.125992) (xy 378.359931 -223.181168)
			(xy 378.343863 -223.234575) (xy 378.320191 -223.285072) (xy 378.289418 -223.331585) (xy 378.252201 -223.373122)
			(xy 378.209333 -223.408797) (xy 378.161727 -223.437851) (xy 378.110398 -223.459663) (xy 378.056441 -223.473769)
			(xy 378.001004 -223.479869) (xy 377.94527 -223.477832) (xy 377.890427 -223.467702) (xy 377.837643 -223.449695)
			(xy 377.788043 -223.424194) (xy 377.742685 -223.391743) (xy 377.702536 -223.353034) (xy 377.66845 -223.308891)
			(xy 377.641154 -223.260256) (xy 377.621231 -223.208165) (xy 377.609105 -223.153728) (xy 377.605034 -223.098106)
			(xy 371.885585 -223.098106) (xy 371.882187 -223.10968) (xy 371.859545 -223.159257) (xy 371.830079 -223.205107)
			(xy 371.794388 -223.246298) (xy 371.753197 -223.281989) (xy 371.707347 -223.311455) (xy 371.65777 -223.334097)
			(xy 371.605475 -223.349452) (xy 371.551527 -223.357208) (xy 371.497025 -223.357208) (xy 371.443077 -223.349452)
			(xy 371.390782 -223.334097) (xy 371.341205 -223.311455) (xy 371.295355 -223.281989) (xy 371.254164 -223.246298)
			(xy 371.218473 -223.205107) (xy 371.189007 -223.159257) (xy 371.166365 -223.10968) (xy 371.15101 -223.057385)
			(xy 371.143254 -223.003437) (xy 371.142768 -222.976186) (xy 361.790488 -222.976186) (xy 361.790488 -223.537018)
			(xy 364.794544 -223.537018) (xy 364.798615 -223.481396) (xy 364.810741 -223.426959) (xy 364.830664 -223.374868)
			(xy 364.85796 -223.326233) (xy 364.892046 -223.28209) (xy 364.932195 -223.243381) (xy 364.977553 -223.21093)
			(xy 365.027153 -223.185429) (xy 365.079937 -223.167422) (xy 365.13478 -223.157292) (xy 365.190514 -223.155255)
			(xy 365.245951 -223.161355) (xy 365.299908 -223.175461) (xy 365.351237 -223.197273) (xy 365.398843 -223.226327)
			(xy 365.441711 -223.262002) (xy 365.478928 -223.303539) (xy 365.509701 -223.350052) (xy 365.533373 -223.400549)
			(xy 365.549441 -223.453956) (xy 365.557561 -223.509132) (xy 365.55807 -223.537018) (xy 365.557561 -223.564904)
			(xy 365.549441 -223.62008) (xy 365.533373 -223.673487) (xy 365.509701 -223.723984) (xy 365.478928 -223.770497)
			(xy 365.441711 -223.812034) (xy 365.398843 -223.847709) (xy 365.351237 -223.876763) (xy 365.299908 -223.898575)
			(xy 365.245951 -223.912681) (xy 365.190514 -223.918781) (xy 365.13478 -223.916744) (xy 365.079937 -223.906614)
			(xy 365.027153 -223.888607) (xy 364.977553 -223.863106) (xy 364.932195 -223.830655) (xy 364.892046 -223.791946)
			(xy 364.85796 -223.747803) (xy 364.830664 -223.699168) (xy 364.810741 -223.647077) (xy 364.798615 -223.59264)
			(xy 364.794544 -223.537018) (xy 361.790488 -223.537018) (xy 361.790488 -225.04019) (xy 370.57787 -225.04019)
			(xy 370.581941 -224.984568) (xy 370.594067 -224.930131) (xy 370.61399 -224.87804) (xy 370.641286 -224.829405)
			(xy 370.675372 -224.785262) (xy 370.715521 -224.746553) (xy 370.760879 -224.714102) (xy 370.810479 -224.688601)
			(xy 370.863263 -224.670594) (xy 370.918106 -224.660464) (xy 370.97384 -224.658427) (xy 371.029277 -224.664527)
			(xy 371.083234 -224.678633) (xy 371.134563 -224.700445) (xy 371.182169 -224.729499) (xy 371.225037 -224.765174)
			(xy 371.262254 -224.806711) (xy 371.293027 -224.853224) (xy 371.316699 -224.903721) (xy 371.332767 -224.957128)
			(xy 371.338337 -224.994978) (xy 376.095512 -224.994978) (xy 376.099583 -224.939356) (xy 376.111709 -224.884919)
			(xy 376.131632 -224.832828) (xy 376.158928 -224.784193) (xy 376.193014 -224.74005) (xy 376.233163 -224.701341)
			(xy 376.278521 -224.66889) (xy 376.328121 -224.643389) (xy 376.380905 -224.625382) (xy 376.435748 -224.615252)
			(xy 376.491482 -224.613215) (xy 376.546919 -224.619315) (xy 376.600876 -224.633421) (xy 376.652205 -224.655233)
			(xy 376.699811 -224.684287) (xy 376.742679 -224.719962) (xy 376.779896 -224.761499) (xy 376.810669 -224.808012)
			(xy 376.834341 -224.858509) (xy 376.850409 -224.911916) (xy 376.858529 -224.967092) (xy 376.859038 -224.994978)
			(xy 376.858529 -225.022864) (xy 376.850409 -225.07804) (xy 376.834341 -225.131447) (xy 376.810669 -225.181944)
			(xy 376.779896 -225.228457) (xy 376.742679 -225.269994) (xy 376.699811 -225.305669) (xy 376.652205 -225.334723)
			(xy 376.600876 -225.356535) (xy 376.546919 -225.370641) (xy 376.491482 -225.376741) (xy 376.435748 -225.374704)
			(xy 376.380905 -225.364574) (xy 376.328121 -225.346567) (xy 376.278521 -225.321066) (xy 376.233163 -225.288615)
			(xy 376.193014 -225.249906) (xy 376.158928 -225.205763) (xy 376.131632 -225.157128) (xy 376.111709 -225.105037)
			(xy 376.099583 -225.0506) (xy 376.095512 -224.994978) (xy 371.338337 -224.994978) (xy 371.340887 -225.012304)
			(xy 371.341396 -225.04019) (xy 371.340887 -225.068076) (xy 371.332767 -225.123252) (xy 371.316699 -225.176659)
			(xy 371.293027 -225.227156) (xy 371.262254 -225.273669) (xy 371.225037 -225.315206) (xy 371.182169 -225.350881)
			(xy 371.134563 -225.379935) (xy 371.083234 -225.401747) (xy 371.029277 -225.415853) (xy 370.97384 -225.421953)
			(xy 370.918106 -225.419916) (xy 370.863263 -225.409786) (xy 370.810479 -225.391779) (xy 370.760879 -225.366278)
			(xy 370.715521 -225.333827) (xy 370.675372 -225.295118) (xy 370.641286 -225.250975) (xy 370.61399 -225.20234)
			(xy 370.594067 -225.150249) (xy 370.581941 -225.095812) (xy 370.57787 -225.04019) (xy 361.790488 -225.04019)
			(xy 361.790488 -225.560382) (xy 368.588796 -225.560382) (xy 368.592867 -225.50476) (xy 368.604993 -225.450323)
			(xy 368.624916 -225.398232) (xy 368.652212 -225.349597) (xy 368.686298 -225.305454) (xy 368.726447 -225.266745)
			(xy 368.771805 -225.234294) (xy 368.821405 -225.208793) (xy 368.874189 -225.190786) (xy 368.929032 -225.180656)
			(xy 368.984766 -225.178619) (xy 369.040203 -225.184719) (xy 369.09416 -225.198825) (xy 369.145489 -225.220637)
			(xy 369.193095 -225.249691) (xy 369.235963 -225.285366) (xy 369.27318 -225.326903) (xy 369.303953 -225.373416)
			(xy 369.327625 -225.423913) (xy 369.343693 -225.47732) (xy 369.351813 -225.532496) (xy 369.352322 -225.560382)
			(xy 369.351813 -225.588268) (xy 369.343693 -225.643444) (xy 369.327625 -225.696851) (xy 369.304559 -225.746056)
			(xy 369.751354 -225.746056) (xy 369.755425 -225.690434) (xy 369.767551 -225.635997) (xy 369.787474 -225.583906)
			(xy 369.81477 -225.535271) (xy 369.848856 -225.491128) (xy 369.889005 -225.452419) (xy 369.934363 -225.419968)
			(xy 369.983963 -225.394467) (xy 370.036747 -225.37646) (xy 370.09159 -225.36633) (xy 370.147324 -225.364293)
			(xy 370.202761 -225.370393) (xy 370.256718 -225.384499) (xy 370.308047 -225.406311) (xy 370.355653 -225.435365)
			(xy 370.398521 -225.47104) (xy 370.435738 -225.512577) (xy 370.466511 -225.55909) (xy 370.490183 -225.609587)
			(xy 370.506251 -225.662994) (xy 370.514371 -225.71817) (xy 370.51488 -225.746056) (xy 370.514371 -225.773942)
			(xy 370.506251 -225.829118) (xy 370.490183 -225.882525) (xy 370.466511 -225.933022) (xy 370.435738 -225.979535)
			(xy 370.398521 -226.021072) (xy 370.355653 -226.056747) (xy 370.308047 -226.085801) (xy 370.256718 -226.107613)
			(xy 370.202761 -226.121719) (xy 370.147324 -226.127819) (xy 370.09159 -226.125782) (xy 370.036747 -226.115652)
			(xy 369.983963 -226.097645) (xy 369.934363 -226.072144) (xy 369.889005 -226.039693) (xy 369.848856 -226.000984)
			(xy 369.81477 -225.956841) (xy 369.787474 -225.908206) (xy 369.767551 -225.856115) (xy 369.755425 -225.801678)
			(xy 369.751354 -225.746056) (xy 369.304559 -225.746056) (xy 369.303953 -225.747348) (xy 369.27318 -225.793861)
			(xy 369.235963 -225.835398) (xy 369.193095 -225.871073) (xy 369.145489 -225.900127) (xy 369.09416 -225.921939)
			(xy 369.040203 -225.936045) (xy 368.984766 -225.942145) (xy 368.929032 -225.940108) (xy 368.874189 -225.929978)
			(xy 368.821405 -225.911971) (xy 368.771805 -225.88647) (xy 368.726447 -225.854019) (xy 368.686298 -225.81531)
			(xy 368.652212 -225.771167) (xy 368.624916 -225.722532) (xy 368.604993 -225.670441) (xy 368.592867 -225.616004)
			(xy 368.588796 -225.560382) (xy 361.790488 -225.560382) (xy 361.790488 -226.557078) (xy 365.688624 -226.557078)
			(xy 365.692695 -226.501456) (xy 365.704821 -226.447019) (xy 365.724744 -226.394928) (xy 365.75204 -226.346293)
			(xy 365.786126 -226.30215) (xy 365.826275 -226.263441) (xy 365.871633 -226.23099) (xy 365.921233 -226.205489)
			(xy 365.974017 -226.187482) (xy 366.02886 -226.177352) (xy 366.084594 -226.175315) (xy 366.140031 -226.181415)
			(xy 366.193988 -226.195521) (xy 366.245317 -226.217333) (xy 366.292923 -226.246387) (xy 366.335791 -226.282062)
			(xy 366.373008 -226.323599) (xy 366.403781 -226.370112) (xy 366.427453 -226.420609) (xy 366.443521 -226.474016)
			(xy 366.451641 -226.529192) (xy 366.45183 -226.539552) (xy 366.7412 -226.539552) (xy 366.745271 -226.48393)
			(xy 366.757397 -226.429493) (xy 366.77732 -226.377402) (xy 366.804616 -226.328767) (xy 366.838702 -226.284624)
			(xy 366.878851 -226.245915) (xy 366.924209 -226.213464) (xy 366.973809 -226.187963) (xy 367.026593 -226.169956)
			(xy 367.081436 -226.159826) (xy 367.13717 -226.157789) (xy 367.192607 -226.163889) (xy 367.246564 -226.177995)
			(xy 367.297893 -226.199807) (xy 367.345499 -226.228861) (xy 367.388367 -226.264536) (xy 367.425584 -226.306073)
			(xy 367.456357 -226.352586) (xy 367.480029 -226.403083) (xy 367.496097 -226.45649) (xy 367.504217 -226.511666)
			(xy 367.504726 -226.539552) (xy 367.504217 -226.567438) (xy 367.496097 -226.622614) (xy 367.480029 -226.676021)
			(xy 367.461487 -226.715574) (xy 367.68227 -226.715574) (xy 367.686341 -226.659952) (xy 367.698467 -226.605515)
			(xy 367.71839 -226.553424) (xy 367.745686 -226.504789) (xy 367.779772 -226.460646) (xy 367.819921 -226.421937)
			(xy 367.865279 -226.389486) (xy 367.914879 -226.363985) (xy 367.967663 -226.345978) (xy 368.022506 -226.335848)
			(xy 368.07824 -226.333811) (xy 368.133677 -226.339911) (xy 368.187634 -226.354017) (xy 368.238963 -226.375829)
			(xy 368.286569 -226.404883) (xy 368.329437 -226.440558) (xy 368.366654 -226.482095) (xy 368.397427 -226.528608)
			(xy 368.421099 -226.579105) (xy 368.437167 -226.632512) (xy 368.445287 -226.687688) (xy 368.445796 -226.715574)
			(xy 368.445287 -226.74346) (xy 368.437167 -226.798636) (xy 368.421099 -226.852043) (xy 368.397427 -226.90254)
			(xy 368.366654 -226.949053) (xy 368.329437 -226.99059) (xy 368.286569 -227.026265) (xy 368.238963 -227.055319)
			(xy 368.187634 -227.077131) (xy 368.133677 -227.091237) (xy 368.07824 -227.097337) (xy 368.022506 -227.0953)
			(xy 367.967663 -227.08517) (xy 367.914879 -227.067163) (xy 367.865279 -227.041662) (xy 367.819921 -227.009211)
			(xy 367.779772 -226.970502) (xy 367.745686 -226.926359) (xy 367.71839 -226.877724) (xy 367.698467 -226.825633)
			(xy 367.686341 -226.771196) (xy 367.68227 -226.715574) (xy 367.461487 -226.715574) (xy 367.456357 -226.726518)
			(xy 367.425584 -226.773031) (xy 367.388367 -226.814568) (xy 367.345499 -226.850243) (xy 367.297893 -226.879297)
			(xy 367.246564 -226.901109) (xy 367.192607 -226.915215) (xy 367.13717 -226.921315) (xy 367.081436 -226.919278)
			(xy 367.026593 -226.909148) (xy 366.973809 -226.891141) (xy 366.924209 -226.86564) (xy 366.878851 -226.833189)
			(xy 366.838702 -226.79448) (xy 366.804616 -226.750337) (xy 366.77732 -226.701702) (xy 366.757397 -226.649611)
			(xy 366.745271 -226.595174) (xy 366.7412 -226.539552) (xy 366.45183 -226.539552) (xy 366.45215 -226.557078)
			(xy 366.451641 -226.584964) (xy 366.443521 -226.64014) (xy 366.427453 -226.693547) (xy 366.403781 -226.744044)
			(xy 366.373008 -226.790557) (xy 366.335791 -226.832094) (xy 366.292923 -226.867769) (xy 366.245317 -226.896823)
			(xy 366.193988 -226.918635) (xy 366.140031 -226.932741) (xy 366.084594 -226.938841) (xy 366.02886 -226.936804)
			(xy 365.974017 -226.926674) (xy 365.921233 -226.908667) (xy 365.871633 -226.883166) (xy 365.826275 -226.850715)
			(xy 365.786126 -226.812006) (xy 365.75204 -226.767863) (xy 365.724744 -226.719228) (xy 365.704821 -226.667137)
			(xy 365.692695 -226.6127) (xy 365.688624 -226.557078) (xy 361.790488 -226.557078) (xy 361.790488 -227.965)
			(xy 364.181134 -227.965) (xy 364.185205 -227.909378) (xy 364.197331 -227.854941) (xy 364.217254 -227.80285)
			(xy 364.24455 -227.754215) (xy 364.278636 -227.710072) (xy 364.318785 -227.671363) (xy 364.364143 -227.638912)
			(xy 364.413743 -227.613411) (xy 364.466527 -227.595404) (xy 364.52137 -227.585274) (xy 364.577104 -227.583237)
			(xy 364.632541 -227.589337) (xy 364.686498 -227.603443) (xy 364.737827 -227.625255) (xy 364.785433 -227.654309)
			(xy 364.828301 -227.689984) (xy 364.865518 -227.731521) (xy 364.896291 -227.778034) (xy 364.919963 -227.828531)
			(xy 364.936031 -227.881938) (xy 364.944151 -227.937114) (xy 364.94466 -227.965) (xy 364.944151 -227.992886)
			(xy 364.936031 -228.048062) (xy 364.919963 -228.101469) (xy 364.896291 -228.151966) (xy 364.865518 -228.198479)
			(xy 364.832566 -228.235256) (xy 365.150144 -228.235256) (xy 365.154215 -228.179634) (xy 365.166341 -228.125197)
			(xy 365.186264 -228.073106) (xy 365.21356 -228.024471) (xy 365.247646 -227.980328) (xy 365.287795 -227.941619)
			(xy 365.333153 -227.909168) (xy 365.382753 -227.883667) (xy 365.435537 -227.86566) (xy 365.49038 -227.85553)
			(xy 365.546114 -227.853493) (xy 365.601551 -227.859593) (xy 365.655508 -227.873699) (xy 365.706837 -227.895511)
			(xy 365.754443 -227.924565) (xy 365.797311 -227.96024) (xy 365.834528 -228.001777) (xy 365.865301 -228.04829)
			(xy 365.888973 -228.098787) (xy 365.905041 -228.152194) (xy 365.913161 -228.20737) (xy 365.91367 -228.235256)
			(xy 365.913161 -228.263142) (xy 365.905041 -228.318318) (xy 365.896254 -228.347524) (xy 366.198656 -228.347524)
			(xy 366.202727 -228.291902) (xy 366.214853 -228.237465) (xy 366.234776 -228.185374) (xy 366.262072 -228.136739)
			(xy 366.296158 -228.092596) (xy 366.336307 -228.053887) (xy 366.381665 -228.021436) (xy 366.431265 -227.995935)
			(xy 366.484049 -227.977928) (xy 366.538892 -227.967798) (xy 366.594626 -227.965761) (xy 366.650063 -227.971861)
			(xy 366.70402 -227.985967) (xy 366.755349 -228.007779) (xy 366.802955 -228.036833) (xy 366.845823 -228.072508)
			(xy 366.88304 -228.114045) (xy 366.913813 -228.160558) (xy 366.937485 -228.211055) (xy 366.945301 -228.237034)
			(xy 367.222276 -228.237034) (xy 367.226347 -228.181412) (xy 367.238473 -228.126975) (xy 367.258396 -228.074884)
			(xy 367.285692 -228.026249) (xy 367.319778 -227.982106) (xy 367.359927 -227.943397) (xy 367.405285 -227.910946)
			(xy 367.454885 -227.885445) (xy 367.507669 -227.867438) (xy 367.562512 -227.857308) (xy 367.618246 -227.855271)
			(xy 367.673683 -227.861371) (xy 367.72764 -227.875477) (xy 367.778969 -227.897289) (xy 367.826575 -227.926343)
			(xy 367.869443 -227.962018) (xy 367.90666 -228.003555) (xy 367.937433 -228.050068) (xy 367.961105 -228.100565)
			(xy 367.977173 -228.153972) (xy 367.985293 -228.209148) (xy 367.9857 -228.231446) (xy 368.244626 -228.231446)
			(xy 368.248697 -228.175824) (xy 368.260823 -228.121387) (xy 368.280746 -228.069296) (xy 368.308042 -228.020661)
			(xy 368.342128 -227.976518) (xy 368.382277 -227.937809) (xy 368.427635 -227.905358) (xy 368.477235 -227.879857)
			(xy 368.530019 -227.86185) (xy 368.584862 -227.85172) (xy 368.640596 -227.849683) (xy 368.696033 -227.855783)
			(xy 368.74999 -227.869889) (xy 368.801319 -227.891701) (xy 368.848925 -227.920755) (xy 368.8792 -227.94595)
			(xy 373.85828 -227.94595) (xy 373.862351 -227.890328) (xy 373.874477 -227.835891) (xy 373.8944 -227.7838)
			(xy 373.921696 -227.735165) (xy 373.955782 -227.691022) (xy 373.995931 -227.652313) (xy 374.041289 -227.619862)
			(xy 374.090889 -227.594361) (xy 374.143673 -227.576354) (xy 374.198516 -227.566224) (xy 374.25425 -227.564187)
			(xy 374.309687 -227.570287) (xy 374.363644 -227.584393) (xy 374.414973 -227.606205) (xy 374.462579 -227.635259)
			(xy 374.505447 -227.670934) (xy 374.542664 -227.712471) (xy 374.573437 -227.758984) (xy 374.597109 -227.809481)
			(xy 374.613177 -227.862888) (xy 374.621297 -227.918064) (xy 374.621806 -227.94595) (xy 374.621297 -227.973836)
			(xy 374.613177 -228.029012) (xy 374.597109 -228.082419) (xy 374.573437 -228.132916) (xy 374.542664 -228.179429)
			(xy 374.505447 -228.220966) (xy 374.462579 -228.256641) (xy 374.414973 -228.285695) (xy 374.363644 -228.307507)
			(xy 374.309687 -228.321613) (xy 374.25425 -228.327713) (xy 374.198516 -228.325676) (xy 374.143673 -228.315546)
			(xy 374.090889 -228.297539) (xy 374.041289 -228.272038) (xy 373.995931 -228.239587) (xy 373.955782 -228.200878)
			(xy 373.921696 -228.156735) (xy 373.8944 -228.1081) (xy 373.874477 -228.056009) (xy 373.862351 -228.001572)
			(xy 373.85828 -227.94595) (xy 368.8792 -227.94595) (xy 368.891793 -227.95643) (xy 368.92901 -227.997967)
			(xy 368.959783 -228.04448) (xy 368.983455 -228.094977) (xy 368.999523 -228.148384) (xy 369.007643 -228.20356)
			(xy 369.008152 -228.231446) (xy 369.007643 -228.259332) (xy 368.999523 -228.314508) (xy 368.983455 -228.367915)
			(xy 368.966818 -228.403404) (xy 370.310662 -228.403404) (xy 370.314733 -228.347782) (xy 370.326859 -228.293345)
			(xy 370.346782 -228.241254) (xy 370.374078 -228.192619) (xy 370.408164 -228.148476) (xy 370.448313 -228.109767)
			(xy 370.493671 -228.077316) (xy 370.543271 -228.051815) (xy 370.596055 -228.033808) (xy 370.650898 -228.023678)
			(xy 370.706632 -228.021641) (xy 370.762069 -228.027741) (xy 370.816026 -228.041847) (xy 370.867355 -228.063659)
			(xy 370.914961 -228.092713) (xy 370.957829 -228.128388) (xy 370.995046 -228.169925) (xy 371.025819 -228.216438)
			(xy 371.049491 -228.266935) (xy 371.065559 -228.320342) (xy 371.073679 -228.375518) (xy 371.074188 -228.403404)
			(xy 371.073679 -228.43129) (xy 371.065559 -228.486466) (xy 371.049491 -228.539873) (xy 371.025819 -228.59037)
			(xy 370.995046 -228.636883) (xy 370.957829 -228.67842) (xy 370.914961 -228.714095) (xy 370.867355 -228.743149)
			(xy 370.816026 -228.764961) (xy 370.762069 -228.779067) (xy 370.706632 -228.785167) (xy 370.650898 -228.78313)
			(xy 370.596055 -228.773) (xy 370.543271 -228.754993) (xy 370.493671 -228.729492) (xy 370.448313 -228.697041)
			(xy 370.408164 -228.658332) (xy 370.374078 -228.614189) (xy 370.346782 -228.565554) (xy 370.326859 -228.513463)
			(xy 370.314733 -228.459026) (xy 370.310662 -228.403404) (xy 368.966818 -228.403404) (xy 368.959783 -228.418412)
			(xy 368.92901 -228.464925) (xy 368.891793 -228.506462) (xy 368.848925 -228.542137) (xy 368.801319 -228.571191)
			(xy 368.74999 -228.593003) (xy 368.696033 -228.607109) (xy 368.640596 -228.613209) (xy 368.584862 -228.611172)
			(xy 368.530019 -228.601042) (xy 368.477235 -228.583035) (xy 368.427635 -228.557534) (xy 368.382277 -228.525083)
			(xy 368.342128 -228.486374) (xy 368.308042 -228.442231) (xy 368.280746 -228.393596) (xy 368.260823 -228.341505)
			(xy 368.248697 -228.287068) (xy 368.244626 -228.231446) (xy 367.9857 -228.231446) (xy 367.985802 -228.237034)
			(xy 367.985293 -228.26492) (xy 367.977173 -228.320096) (xy 367.961105 -228.373503) (xy 367.937433 -228.424)
			(xy 367.90666 -228.470513) (xy 367.869443 -228.51205) (xy 367.826575 -228.547725) (xy 367.778969 -228.576779)
			(xy 367.72764 -228.598591) (xy 367.673683 -228.612697) (xy 367.618246 -228.618797) (xy 367.562512 -228.61676)
			(xy 367.507669 -228.60663) (xy 367.454885 -228.588623) (xy 367.405285 -228.563122) (xy 367.359927 -228.530671)
			(xy 367.319778 -228.491962) (xy 367.285692 -228.447819) (xy 367.258396 -228.399184) (xy 367.238473 -228.347093)
			(xy 367.226347 -228.292656) (xy 367.222276 -228.237034) (xy 366.945301 -228.237034) (xy 366.953553 -228.264462)
			(xy 366.961673 -228.319638) (xy 366.962182 -228.347524) (xy 366.961673 -228.37541) (xy 366.953553 -228.430586)
			(xy 366.937485 -228.483993) (xy 366.913813 -228.53449) (xy 366.88304 -228.581003) (xy 366.845823 -228.62254)
			(xy 366.802955 -228.658215) (xy 366.755349 -228.687269) (xy 366.70402 -228.709081) (xy 366.650063 -228.723187)
			(xy 366.594626 -228.729287) (xy 366.538892 -228.72725) (xy 366.484049 -228.71712) (xy 366.431265 -228.699113)
			(xy 366.381665 -228.673612) (xy 366.336307 -228.641161) (xy 366.296158 -228.602452) (xy 366.262072 -228.558309)
			(xy 366.234776 -228.509674) (xy 366.214853 -228.457583) (xy 366.202727 -228.403146) (xy 366.198656 -228.347524)
			(xy 365.896254 -228.347524) (xy 365.888973 -228.371725) (xy 365.865301 -228.422222) (xy 365.834528 -228.468735)
			(xy 365.797311 -228.510272) (xy 365.754443 -228.545947) (xy 365.706837 -228.575001) (xy 365.655508 -228.596813)
			(xy 365.601551 -228.610919) (xy 365.546114 -228.617019) (xy 365.49038 -228.614982) (xy 365.435537 -228.604852)
			(xy 365.382753 -228.586845) (xy 365.333153 -228.561344) (xy 365.287795 -228.528893) (xy 365.247646 -228.490184)
			(xy 365.21356 -228.446041) (xy 365.186264 -228.397406) (xy 365.166341 -228.345315) (xy 365.154215 -228.290878)
			(xy 365.150144 -228.235256) (xy 364.832566 -228.235256) (xy 364.828301 -228.240016) (xy 364.785433 -228.275691)
			(xy 364.737827 -228.304745) (xy 364.686498 -228.326557) (xy 364.632541 -228.340663) (xy 364.577104 -228.346763)
			(xy 364.52137 -228.344726) (xy 364.466527 -228.334596) (xy 364.413743 -228.316589) (xy 364.364143 -228.291088)
			(xy 364.318785 -228.258637) (xy 364.278636 -228.219928) (xy 364.24455 -228.175785) (xy 364.217254 -228.12715)
			(xy 364.197331 -228.075059) (xy 364.185205 -228.020622) (xy 364.181134 -227.965) (xy 361.790488 -227.965)
			(xy 361.790488 -228.27488) (xy 361.81157 -228.302058) (xy 361.828334 -228.30663) (xy 361.832652 -228.307646)
			(xy 361.843066 -228.310694) (xy 361.868531 -228.319222) (xy 361.916966 -228.34242) (xy 361.961674 -228.372172)
			(xy 362.001776 -228.407891) (xy 362.036481 -228.448874) (xy 362.065105 -228.494312) (xy 362.087084 -228.543312)
			(xy 362.101986 -228.594906) (xy 362.109516 -228.648079) (xy 362.11002 -228.67493) (xy 362.109523 -228.70265)
			(xy 362.101503 -228.757506) (xy 362.085636 -228.810626) (xy 362.062255 -228.860894) (xy 362.031852 -228.907253)
			(xy 361.995066 -228.94873) (xy 361.952669 -228.984452) (xy 361.905553 -229.013668) (xy 361.854708 -229.035766)
			(xy 361.82808 -229.043484) (xy 361.811316 -229.048056) (xy 361.790488 -229.075234) (xy 361.790488 -229.684326)
			(xy 361.79056 -229.688334) (xy 361.791842 -229.696245) (xy 361.793028 -229.700074) (xy 361.800394 -229.722426)
			(xy 361.804458 -229.728268) (xy 361.816758 -229.746665) (xy 361.837515 -229.78575) (xy 361.84586 -229.806246)
			(xy 361.856894 -229.836421) (xy 361.869843 -229.899346) (xy 361.871429 -229.94493) (xy 371.092982 -229.94493)
			(xy 371.097053 -229.889308) (xy 371.109179 -229.834871) (xy 371.129102 -229.78278) (xy 371.156398 -229.734145)
			(xy 371.190484 -229.690002) (xy 371.230633 -229.651293) (xy 371.275991 -229.618842) (xy 371.325591 -229.593341)
			(xy 371.378375 -229.575334) (xy 371.433218 -229.565204) (xy 371.488952 -229.563167) (xy 371.544389 -229.569267)
			(xy 371.598346 -229.583373) (xy 371.649675 -229.605185) (xy 371.697281 -229.634239) (xy 371.740149 -229.669914)
			(xy 371.777366 -229.711451) (xy 371.808139 -229.757964) (xy 371.831811 -229.808461) (xy 371.847879 -229.861868)
			(xy 371.855999 -229.917044) (xy 371.856508 -229.94493) (xy 371.855999 -229.972816) (xy 371.847879 -230.027992)
			(xy 371.831811 -230.081399) (xy 371.808139 -230.131896) (xy 371.777366 -230.178409) (xy 371.740149 -230.219946)
			(xy 371.697281 -230.255621) (xy 371.649675 -230.284675) (xy 371.598346 -230.306487) (xy 371.544389 -230.320593)
			(xy 371.488952 -230.326693) (xy 371.433218 -230.324656) (xy 371.378375 -230.314526) (xy 371.325591 -230.296519)
			(xy 371.275991 -230.271018) (xy 371.230633 -230.238567) (xy 371.190484 -230.199858) (xy 371.156398 -230.155715)
			(xy 371.129102 -230.10708) (xy 371.109179 -230.054989) (xy 371.097053 -230.000552) (xy 371.092982 -229.94493)
			(xy 361.871429 -229.94493) (xy 361.872077 -229.963551) (xy 361.868466 -229.995476) (xy 361.863894 -230.022654)
			(xy 361.858459 -230.046904) (xy 361.842133 -230.093841) (xy 361.819841 -230.138256) (xy 361.806236 -230.159052)
			(xy 361.806236 -230.159306) (xy 361.804204 -230.162354) (xy 361.799378 -230.172514) (xy 361.796838 -230.178356)
			(xy 361.793282 -230.189024) (xy 361.791994 -230.193031) (xy 361.790581 -230.201327) (xy 361.790488 -230.205534)
			(xy 361.790488 -230.779066) (xy 362.598968 -230.779066) (xy 362.603039 -230.723444) (xy 362.615165 -230.669007)
			(xy 362.635088 -230.616916) (xy 362.662384 -230.568281) (xy 362.69647 -230.524138) (xy 362.736619 -230.485429)
			(xy 362.781977 -230.452978) (xy 362.831577 -230.427477) (xy 362.884361 -230.40947) (xy 362.939204 -230.39934)
			(xy 362.994938 -230.397303) (xy 363.050375 -230.403403) (xy 363.104332 -230.417509) (xy 363.155661 -230.439321)
			(xy 363.203267 -230.468375) (xy 363.246135 -230.50405) (xy 363.283352 -230.545587) (xy 363.314125 -230.5921)
			(xy 363.337797 -230.642597) (xy 363.353865 -230.696004) (xy 363.361985 -230.75118) (xy 363.362494 -230.779066)
			(xy 363.361985 -230.806952) (xy 363.353865 -230.862128) (xy 363.337797 -230.915535) (xy 363.314125 -230.966032)
			(xy 363.283352 -231.012545) (xy 363.246135 -231.054082) (xy 363.203267 -231.089757) (xy 363.155661 -231.118811)
			(xy 363.104332 -231.140623) (xy 363.050375 -231.154729) (xy 362.994938 -231.160829) (xy 362.939204 -231.158792)
			(xy 362.884361 -231.148662) (xy 362.831577 -231.130655) (xy 362.781977 -231.105154) (xy 362.736619 -231.072703)
			(xy 362.69647 -231.033994) (xy 362.662384 -230.989851) (xy 362.635088 -230.941216) (xy 362.615165 -230.889125)
			(xy 362.603039 -230.834688) (xy 362.598968 -230.779066) (xy 361.790488 -230.779066) (xy 361.790488 -230.86187)
			(xy 361.790488 -230.863902) (xy 361.791646 -230.876474) (xy 361.804429 -230.898211) (xy 361.814872 -230.905304)
			(xy 361.821476 -230.908606) (xy 361.907074 -230.945182) (xy 361.915801 -230.948468) (xy 361.934418 -230.949234)
			(xy 361.943396 -230.946706) (xy 361.954318 -230.942896) (xy 361.975973 -230.92186) (xy 362.024688 -230.886204)
			(xy 362.078405 -230.858654) (xy 362.135787 -230.839897) (xy 362.195405 -230.830399) (xy 362.22559 -230.829866)
			(xy 362.252845 -230.830328) (xy 362.306801 -230.838085) (xy 362.359104 -230.853441) (xy 362.408688 -230.876084)
			(xy 362.454546 -230.905554) (xy 362.495743 -230.94125) (xy 362.53144 -230.982446) (xy 362.560911 -231.028303)
			(xy 362.583556 -231.077887) (xy 362.598913 -231.130189) (xy 362.606671 -231.184145) (xy 362.606671 -231.238655)
			(xy 362.598913 -231.292611) (xy 362.583556 -231.344913) (xy 362.560911 -231.394497) (xy 362.53144 -231.440354)
			(xy 362.495743 -231.48155) (xy 362.454546 -231.517246) (xy 362.408688 -231.546716) (xy 362.359104 -231.569359)
			(xy 362.306801 -231.584715) (xy 362.252845 -231.592472) (xy 362.22559 -231.592882) (xy 362.196508 -231.592336)
			(xy 362.139017 -231.583512) (xy 362.08353 -231.566069) (xy 362.031331 -231.540412) (xy 361.983627 -231.507134)
			(xy 361.962192 -231.487472) (xy 361.958088 -231.483732) (xy 361.948609 -231.477954) (xy 361.943396 -231.476042)
			(xy 361.934428 -231.47345) (xy 361.915792 -231.474229) (xy 361.907074 -231.477566) (xy 361.821476 -231.514142)
			(xy 361.814872 -231.517444) (xy 361.804446 -231.524558) (xy 361.79165 -231.546278) (xy 361.790488 -231.558846)
			(xy 361.790488 -232.353104) (xy 375.625614 -232.353104) (xy 375.626121 -232.325718) (xy 375.633966 -232.271511)
			(xy 375.649481 -232.218983) (xy 375.672348 -232.169213) (xy 375.702097 -232.123224) (xy 375.738116 -232.081961)
			(xy 375.779664 -232.046273) (xy 375.825889 -232.016892) (xy 375.87584 -231.994423) (xy 375.92849 -231.979326)
			(xy 375.95556 -231.975152) (xy 375.969387 -231.972791) (xy 375.995105 -231.961626) (xy 376.016814 -231.943883)
			(xy 376.032874 -231.920902) (xy 376.042072 -231.894417) (xy 376.043715 -231.866428) (xy 376.037678 -231.839049)
			(xy 376.024417 -231.814346) (xy 376.014996 -231.803956) (xy 375.995022 -231.782467) (xy 375.961191 -231.734539)
			(xy 375.935092 -231.681999) (xy 375.91734 -231.626085) (xy 375.908351 -231.568112) (xy 375.907808 -231.53878)
			(xy 375.908294 -231.511529) (xy 375.91605 -231.457581) (xy 375.931405 -231.405286) (xy 375.954047 -231.355709)
			(xy 375.983513 -231.309859) (xy 376.019204 -231.268668) (xy 376.060395 -231.232977) (xy 376.106245 -231.203511)
			(xy 376.155822 -231.180869) (xy 376.208117 -231.165514) (xy 376.262065 -231.157758) (xy 376.316567 -231.157758)
			(xy 376.370515 -231.165514) (xy 376.42281 -231.180869) (xy 376.472387 -231.203511) (xy 376.518237 -231.232977)
			(xy 376.559428 -231.268668) (xy 376.595119 -231.309859) (xy 376.624585 -231.355709) (xy 376.647227 -231.405286)
			(xy 376.662582 -231.457581) (xy 376.670338 -231.511529) (xy 376.670824 -231.53878) (xy 376.670356 -231.566168)
			(xy 376.662511 -231.620379) (xy 376.646995 -231.672911) (xy 376.624125 -231.722685) (xy 376.594373 -231.768676)
			(xy 376.558349 -231.809939) (xy 376.516795 -231.845627) (xy 376.470564 -231.875006) (xy 376.420607 -231.897471)
			(xy 376.367951 -231.912561) (xy 376.340878 -231.916732) (xy 376.327059 -231.919137) (xy 376.30134 -231.930292)
			(xy 376.27963 -231.948026) (xy 376.263568 -231.971002) (xy 376.254368 -231.997482) (xy 376.252724 -232.025467)
			(xy 376.25876 -232.052842) (xy 376.272021 -232.07754) (xy 376.281442 -232.087928) (xy 376.301462 -232.109375)
			(xy 376.335285 -232.157315) (xy 376.361375 -232.209866) (xy 376.379117 -232.265789) (xy 376.388093 -232.323769)
			(xy 376.38863 -232.353104) (xy 376.388144 -232.380355) (xy 376.380388 -232.434303) (xy 376.365033 -232.486598)
			(xy 376.342391 -232.536175) (xy 376.312925 -232.582025) (xy 376.277234 -232.623216) (xy 376.236043 -232.658907)
			(xy 376.190193 -232.688373) (xy 376.140616 -232.711015) (xy 376.088321 -232.72637) (xy 376.034373 -232.734126)
			(xy 375.979871 -232.734126) (xy 375.925923 -232.72637) (xy 375.873628 -232.711015) (xy 375.824051 -232.688373)
			(xy 375.778201 -232.658907) (xy 375.73701 -232.623216) (xy 375.701319 -232.582025) (xy 375.671853 -232.536175)
			(xy 375.649211 -232.486598) (xy 375.633856 -232.434303) (xy 375.6261 -232.380355) (xy 375.625614 -232.353104)
			(xy 361.790488 -232.353104) (xy 361.790488 -233.853245) (xy 373.234028 -233.853245) (xy 373.234028 -233.798755)
			(xy 373.241782 -233.744818) (xy 373.257133 -233.692535) (xy 373.279767 -233.642967) (xy 373.309225 -233.597125)
			(xy 373.344906 -233.555942) (xy 373.386085 -233.520255) (xy 373.431923 -233.490791) (xy 373.481488 -233.46815)
			(xy 373.53377 -233.452793) (xy 373.587705 -233.445032) (xy 373.61495 -233.444542) (xy 373.641554 -233.44501)
			(xy 373.694247 -233.452386) (xy 373.745403 -233.467016) (xy 373.794028 -233.488615) (xy 373.839179 -233.516764)
			(xy 373.879978 -233.550916) (xy 373.915633 -233.590408) (xy 373.930926 -233.612182) (xy 373.93926 -233.623662)
			(xy 373.961004 -233.641866) (xy 373.986917 -233.653384) (xy 374.015 -233.657324) (xy 374.043083 -233.653384)
			(xy 374.068996 -233.641866) (xy 374.09074 -233.623662) (xy 374.099074 -233.612182) (xy 374.114386 -233.590424)
			(xy 374.150048 -233.550943) (xy 374.190848 -233.516798) (xy 374.235995 -233.48865) (xy 374.284614 -233.467045)
			(xy 374.335762 -233.452403) (xy 374.388449 -233.445007) (xy 374.41505 -233.444542) (xy 374.442309 -233.444902)
			(xy 374.496272 -233.452654) (xy 374.548583 -233.468007) (xy 374.598176 -233.49065) (xy 374.644041 -233.520121)
			(xy 374.685246 -233.555819) (xy 374.720949 -233.597018) (xy 374.750426 -233.64288) (xy 374.773075 -233.69247)
			(xy 374.788436 -233.744779) (xy 374.796195 -233.798741) (xy 374.796195 -233.853259) (xy 374.788436 -233.907221)
			(xy 374.786166 -233.91495) (xy 377.335032 -233.91495) (xy 377.339103 -233.859328) (xy 377.351229 -233.804891)
			(xy 377.371152 -233.7528) (xy 377.398448 -233.704165) (xy 377.432534 -233.660022) (xy 377.472683 -233.621313)
			(xy 377.518041 -233.588862) (xy 377.567641 -233.563361) (xy 377.620425 -233.545354) (xy 377.675268 -233.535224)
			(xy 377.731002 -233.533187) (xy 377.786439 -233.539287) (xy 377.840396 -233.553393) (xy 377.891725 -233.575205)
			(xy 377.939331 -233.604259) (xy 377.982199 -233.639934) (xy 378.019416 -233.681471) (xy 378.050189 -233.727984)
			(xy 378.073861 -233.778481) (xy 378.089929 -233.831888) (xy 378.098049 -233.887064) (xy 378.098558 -233.91495)
			(xy 378.098049 -233.942836) (xy 378.089929 -233.998012) (xy 378.073861 -234.051419) (xy 378.050189 -234.101916)
			(xy 378.019416 -234.148429) (xy 377.982199 -234.189966) (xy 377.939331 -234.225641) (xy 377.891725 -234.254695)
			(xy 377.840396 -234.276507) (xy 377.786439 -234.290613) (xy 377.731002 -234.296713) (xy 377.675268 -234.294676)
			(xy 377.620425 -234.284546) (xy 377.567641 -234.266539) (xy 377.518041 -234.241038) (xy 377.472683 -234.208587)
			(xy 377.432534 -234.169878) (xy 377.398448 -234.125735) (xy 377.371152 -234.0771) (xy 377.351229 -234.025009)
			(xy 377.339103 -233.970572) (xy 377.335032 -233.91495) (xy 374.786166 -233.91495) (xy 374.773075 -233.95953)
			(xy 374.750426 -234.00912) (xy 374.720949 -234.054982) (xy 374.685246 -234.096181) (xy 374.644041 -234.131879)
			(xy 374.598176 -234.16135) (xy 374.548583 -234.183992) (xy 374.496272 -234.199346) (xy 374.442309 -234.207098)
			(xy 374.41505 -234.207558) (xy 374.388446 -234.20709) (xy 374.335753 -234.199714) (xy 374.284597 -234.185084)
			(xy 374.235972 -234.163485) (xy 374.190821 -234.135336) (xy 374.150022 -234.101184) (xy 374.114367 -234.061692)
			(xy 374.099074 -234.039918) (xy 374.09074 -234.028438) (xy 374.068996 -234.010234) (xy 374.043083 -233.998716)
			(xy 374.015 -233.994776) (xy 373.986917 -233.998716) (xy 373.961004 -234.010234) (xy 373.93926 -234.028438)
			(xy 373.930926 -234.039918) (xy 373.915614 -234.061676) (xy 373.879952 -234.101157) (xy 373.839152 -234.135302)
			(xy 373.794005 -234.16345) (xy 373.745386 -234.185055) (xy 373.694238 -234.199697) (xy 373.641551 -234.207093)
			(xy 373.61495 -234.207558) (xy 373.587705 -234.206968) (xy 373.53377 -234.199207) (xy 373.481488 -234.18385)
			(xy 373.431923 -234.161209) (xy 373.386085 -234.131745) (xy 373.344906 -234.096058) (xy 373.309225 -234.054875)
			(xy 373.279767 -234.009033) (xy 373.257133 -233.959465) (xy 373.241782 -233.907182) (xy 373.234028 -233.853245)
			(xy 361.790488 -233.853245) (xy 361.790488 -234.811062) (xy 377.376942 -234.811062) (xy 377.381013 -234.75544)
			(xy 377.393139 -234.701003) (xy 377.413062 -234.648912) (xy 377.440358 -234.600277) (xy 377.474444 -234.556134)
			(xy 377.514593 -234.517425) (xy 377.559951 -234.484974) (xy 377.609551 -234.459473) (xy 377.662335 -234.441466)
			(xy 377.717178 -234.431336) (xy 377.772912 -234.429299) (xy 377.828349 -234.435399) (xy 377.882306 -234.449505)
			(xy 377.933635 -234.471317) (xy 377.981241 -234.500371) (xy 378.024109 -234.536046) (xy 378.061326 -234.577583)
			(xy 378.092099 -234.624096) (xy 378.115771 -234.674593) (xy 378.131839 -234.728) (xy 378.139959 -234.783176)
			(xy 378.140468 -234.811062) (xy 378.139959 -234.838948) (xy 378.131839 -234.894124) (xy 378.115771 -234.947531)
			(xy 378.092099 -234.998028) (xy 378.061326 -235.044541) (xy 378.024109 -235.086078) (xy 377.981241 -235.121753)
			(xy 377.933635 -235.150807) (xy 377.882306 -235.172619) (xy 377.828349 -235.186725) (xy 377.772912 -235.192825)
			(xy 377.717178 -235.190788) (xy 377.662335 -235.180658) (xy 377.609551 -235.162651) (xy 377.559951 -235.13715)
			(xy 377.514593 -235.104699) (xy 377.474444 -235.06599) (xy 377.440358 -235.021847) (xy 377.413062 -234.973212)
			(xy 377.393139 -234.921121) (xy 377.381013 -234.866684) (xy 377.376942 -234.811062) (xy 361.790488 -234.811062)
			(xy 361.790488 -235.458) (xy 366.90757 -235.458) (xy 366.911641 -235.402378) (xy 366.923767 -235.347941)
			(xy 366.94369 -235.29585) (xy 366.970986 -235.247215) (xy 367.005072 -235.203072) (xy 367.045221 -235.164363)
			(xy 367.090579 -235.131912) (xy 367.140179 -235.106411) (xy 367.192963 -235.088404) (xy 367.247806 -235.078274)
			(xy 367.30354 -235.076237) (xy 367.358977 -235.082337) (xy 367.412934 -235.096443) (xy 367.464263 -235.118255)
			(xy 367.511869 -235.147309) (xy 367.554737 -235.182984) (xy 367.591954 -235.224521) (xy 367.622727 -235.271034)
			(xy 367.646399 -235.321531) (xy 367.662467 -235.374938) (xy 367.670587 -235.430114) (xy 367.671096 -235.458)
			(xy 367.670587 -235.485886) (xy 367.66258 -235.540296) (xy 376.763278 -235.540296) (xy 376.767349 -235.484674)
			(xy 376.779475 -235.430237) (xy 376.799398 -235.378146) (xy 376.826694 -235.329511) (xy 376.86078 -235.285368)
			(xy 376.900929 -235.246659) (xy 376.946287 -235.214208) (xy 376.995887 -235.188707) (xy 377.048671 -235.1707)
			(xy 377.103514 -235.16057) (xy 377.159248 -235.158533) (xy 377.214685 -235.164633) (xy 377.268642 -235.178739)
			(xy 377.319971 -235.200551) (xy 377.367577 -235.229605) (xy 377.410445 -235.26528) (xy 377.447662 -235.306817)
			(xy 377.478435 -235.35333) (xy 377.502107 -235.403827) (xy 377.518175 -235.457234) (xy 377.526295 -235.51241)
			(xy 377.526804 -235.540296) (xy 377.526295 -235.568182) (xy 377.518175 -235.623358) (xy 377.502107 -235.676765)
			(xy 377.478435 -235.727262) (xy 377.447662 -235.773775) (xy 377.410445 -235.815312) (xy 377.367577 -235.850987)
			(xy 377.319971 -235.880041) (xy 377.268642 -235.901853) (xy 377.214685 -235.915959) (xy 377.159248 -235.922059)
			(xy 377.103514 -235.920022) (xy 377.048671 -235.909892) (xy 376.995887 -235.891885) (xy 376.946287 -235.866384)
			(xy 376.900929 -235.833933) (xy 376.86078 -235.795224) (xy 376.826694 -235.751081) (xy 376.799398 -235.702446)
			(xy 376.779475 -235.650355) (xy 376.767349 -235.595918) (xy 376.763278 -235.540296) (xy 367.66258 -235.540296)
			(xy 367.662467 -235.541062) (xy 367.646399 -235.594469) (xy 367.622727 -235.644966) (xy 367.591954 -235.691479)
			(xy 367.554737 -235.733016) (xy 367.511869 -235.768691) (xy 367.464263 -235.797745) (xy 367.412934 -235.819557)
			(xy 367.358977 -235.833663) (xy 367.30354 -235.839763) (xy 367.247806 -235.837726) (xy 367.192963 -235.827596)
			(xy 367.140179 -235.809589) (xy 367.090579 -235.784088) (xy 367.045221 -235.751637) (xy 367.005072 -235.712928)
			(xy 366.970986 -235.668785) (xy 366.94369 -235.62015) (xy 366.923767 -235.568059) (xy 366.911641 -235.513622)
			(xy 366.90757 -235.458) (xy 361.790488 -235.458) (xy 361.790488 -236.689392) (xy 368.173252 -236.689392)
			(xy 368.177323 -236.63377) (xy 368.189449 -236.579333) (xy 368.209372 -236.527242) (xy 368.236668 -236.478607)
			(xy 368.270754 -236.434464) (xy 368.310903 -236.395755) (xy 368.356261 -236.363304) (xy 368.405861 -236.337803)
			(xy 368.458645 -236.319796) (xy 368.513488 -236.309666) (xy 368.569222 -236.307629) (xy 368.624659 -236.313729)
			(xy 368.678616 -236.327835) (xy 368.729945 -236.349647) (xy 368.777551 -236.378701) (xy 368.820419 -236.414376)
			(xy 368.857636 -236.455913) (xy 368.888409 -236.502426) (xy 368.912081 -236.552923) (xy 368.921297 -236.583555)
			(xy 376.280851 -236.583555) (xy 376.280851 -236.529045) (xy 376.288609 -236.475091) (xy 376.303967 -236.42279)
			(xy 376.326613 -236.373207) (xy 376.356084 -236.327352) (xy 376.391782 -236.286158) (xy 376.432979 -236.250464)
			(xy 376.478837 -236.220996) (xy 376.528422 -236.198355) (xy 376.580724 -236.183002) (xy 376.634679 -236.175249)
			(xy 376.661934 -236.174788) (xy 376.688833 -236.175297) (xy 376.7421 -236.182847) (xy 376.793777 -236.197806)
			(xy 376.84284 -236.219877) (xy 376.888315 -236.248623) (xy 376.9293 -236.283474) (xy 376.964982 -236.323737)
			(xy 376.994652 -236.368614) (xy 377.017723 -236.417215) (xy 377.02617 -236.442758) (xy 377.029787 -236.452808)
			(xy 377.043854 -236.468855) (xy 377.053348 -236.473746) (xy 377.132342 -236.509814) (xy 377.153678 -236.510068)
			(xy 377.163838 -236.505496) (xy 377.188006 -236.495391) (xy 377.238415 -236.481146) (xy 377.290301 -236.473942)
			(xy 377.316492 -236.473492) (xy 377.317 -236.473492) (xy 377.344251 -236.473978) (xy 377.398199 -236.481734)
			(xy 377.450494 -236.497089) (xy 377.500071 -236.519731) (xy 377.545921 -236.549197) (xy 377.587112 -236.584888)
			(xy 377.622803 -236.626079) (xy 377.652269 -236.671929) (xy 377.674911 -236.721506) (xy 377.690266 -236.773801)
			(xy 377.698022 -236.827749) (xy 377.698022 -236.882251) (xy 377.690266 -236.936199) (xy 377.674911 -236.988494)
			(xy 377.652269 -237.038071) (xy 377.622803 -237.083921) (xy 377.587112 -237.125112) (xy 377.545921 -237.160803)
			(xy 377.500071 -237.190269) (xy 377.450494 -237.212911) (xy 377.398199 -237.228266) (xy 377.344251 -237.236022)
			(xy 377.317 -237.236508) (xy 377.290099 -237.236061) (xy 377.236829 -237.228502) (xy 377.18515 -237.213534)
			(xy 377.136087 -237.191454) (xy 377.090612 -237.1627) (xy 377.049628 -237.127843) (xy 377.013948 -237.087573)
			(xy 376.984279 -237.04269) (xy 376.96121 -236.994083) (xy 376.952764 -236.968538) (xy 376.949176 -236.958475)
			(xy 376.935089 -236.942434) (xy 376.925586 -236.93755) (xy 376.846592 -236.901482) (xy 376.825256 -236.901228)
			(xy 376.815096 -236.9058) (xy 376.790924 -236.915894) (xy 376.740517 -236.930143) (xy 376.688633 -236.937352)
			(xy 376.662442 -236.937804) (xy 376.661934 -236.937804) (xy 376.634679 -236.937351) (xy 376.580724 -236.929598)
			(xy 376.528422 -236.914245) (xy 376.478837 -236.891604) (xy 376.432979 -236.862136) (xy 376.391782 -236.826442)
			(xy 376.356084 -236.785248) (xy 376.326613 -236.739393) (xy 376.303967 -236.68981) (xy 376.288609 -236.637509)
			(xy 376.280851 -236.583555) (xy 368.921297 -236.583555) (xy 368.928149 -236.60633) (xy 368.936269 -236.661506)
			(xy 368.936778 -236.689392) (xy 368.936269 -236.717278) (xy 368.928149 -236.772454) (xy 368.912081 -236.825861)
			(xy 368.888409 -236.876358) (xy 368.857636 -236.922871) (xy 368.820419 -236.964408) (xy 368.777551 -237.000083)
			(xy 368.729945 -237.029137) (xy 368.678616 -237.050949) (xy 368.624659 -237.065055) (xy 368.569222 -237.071155)
			(xy 368.513488 -237.069118) (xy 368.458645 -237.058988) (xy 368.405861 -237.040981) (xy 368.356261 -237.01548)
			(xy 368.310903 -236.983029) (xy 368.270754 -236.94432) (xy 368.236668 -236.900177) (xy 368.209372 -236.851542)
			(xy 368.189449 -236.799451) (xy 368.177323 -236.745014) (xy 368.173252 -236.689392) (xy 361.790488 -236.689392)
			(xy 361.790488 -237.459012) (xy 361.791001 -237.469431) (xy 361.799274 -237.48856) (xy 361.80649 -237.496096)
			(xy 361.860846 -237.546896) (xy 361.868086 -237.553135) (xy 361.885841 -237.560167) (xy 361.89539 -237.560612)
			(xy 361.902756 -237.560612) (xy 361.923838 -237.55985) (xy 361.95109 -237.560338) (xy 362.00504 -237.5681)
			(xy 362.057336 -237.58346) (xy 362.106914 -237.606106) (xy 362.152765 -237.635577) (xy 362.193955 -237.671272)
			(xy 362.229646 -237.712466) (xy 362.259112 -237.75832) (xy 362.281753 -237.8079) (xy 362.297108 -237.860197)
			(xy 362.304864 -237.914147) (xy 362.304864 -237.968653) (xy 362.297108 -238.022603) (xy 362.281753 -238.0749)
			(xy 362.259112 -238.12448) (xy 362.229646 -238.170334) (xy 362.193955 -238.211528) (xy 362.152765 -238.247223)
			(xy 362.106914 -238.276694) (xy 362.057336 -238.29934) (xy 362.00504 -238.3147) (xy 361.95109 -238.322462)
			(xy 361.923838 -238.322866) (xy 361.8992 -238.322104) (xy 361.898438 -238.322104) (xy 361.888255 -238.322044)
			(xy 361.86913 -238.32899) (xy 361.861354 -238.335566) (xy 361.806744 -238.386366) (xy 361.799408 -238.393837)
			(xy 361.791006 -238.412992) (xy 361.790488 -238.42345) (xy 361.790488 -238.529575) (xy 362.217476 -238.529575)
			(xy 362.225229 -238.475627) (xy 362.24058 -238.423333) (xy 362.263216 -238.373755) (xy 362.292679 -238.327903)
			(xy 362.328366 -238.286711) (xy 362.369552 -238.251017) (xy 362.415399 -238.221547) (xy 362.464973 -238.198902)
			(xy 362.517266 -238.183542) (xy 362.571211 -238.17578) (xy 362.598462 -238.175292) (xy 362.598716 -238.175292)
			(xy 362.623383 -238.175699) (xy 362.672305 -238.182064) (xy 362.696252 -238.187992) (xy 362.710593 -238.191246)
			(xy 362.739972 -238.19035) (xy 362.767881 -238.181131) (xy 362.792012 -238.16435) (xy 362.81037 -238.141395)
			(xy 362.821436 -238.114165) (xy 362.824295 -238.084911) (xy 362.821982 -238.07039) (xy 362.818676 -238.052346)
			(xy 362.815113 -238.015834) (xy 362.81487 -237.997492) (xy 362.815364 -237.97024) (xy 362.823122 -237.916289)
			(xy 362.838479 -237.863993) (xy 362.861122 -237.814414) (xy 362.890591 -237.768562) (xy 362.926285 -237.727371)
			(xy 362.967479 -237.691679) (xy 363.013332 -237.662212) (xy 363.062912 -237.639572) (xy 363.11521 -237.624218)
			(xy 363.16916 -237.616462) (xy 363.223665 -237.616464) (xy 363.277615 -237.624223) (xy 363.329912 -237.639581)
			(xy 363.37949 -237.662225) (xy 363.425342 -237.691694) (xy 363.466532 -237.727389) (xy 363.480925 -237.744)
			(xy 364.239046 -237.744) (xy 364.243117 -237.688378) (xy 364.255243 -237.633941) (xy 364.275166 -237.58185)
			(xy 364.302462 -237.533215) (xy 364.336548 -237.489072) (xy 364.376697 -237.450363) (xy 364.422055 -237.417912)
			(xy 364.471655 -237.392411) (xy 364.524439 -237.374404) (xy 364.579282 -237.364274) (xy 364.635016 -237.362237)
			(xy 364.690453 -237.368337) (xy 364.74441 -237.382443) (xy 364.795739 -237.404255) (xy 364.843345 -237.433309)
			(xy 364.886213 -237.468984) (xy 364.92343 -237.510521) (xy 364.954203 -237.557034) (xy 364.977875 -237.607531)
			(xy 364.993943 -237.660938) (xy 365.002063 -237.716114) (xy 365.002572 -237.744) (xy 365.002317 -237.75797)
			(xy 370.937534 -237.75797) (xy 370.941605 -237.702348) (xy 370.953731 -237.647911) (xy 370.973654 -237.59582)
			(xy 371.00095 -237.547185) (xy 371.035036 -237.503042) (xy 371.075185 -237.464333) (xy 371.120543 -237.431882)
			(xy 371.170143 -237.406381) (xy 371.222927 -237.388374) (xy 371.27777 -237.378244) (xy 371.333504 -237.376207)
			(xy 371.388941 -237.382307) (xy 371.442898 -237.396413) (xy 371.494227 -237.418225) (xy 371.541833 -237.447279)
			(xy 371.584701 -237.482954) (xy 371.621918 -237.524491) (xy 371.652691 -237.571004) (xy 371.676363 -237.621501)
			(xy 371.692431 -237.674908) (xy 371.700551 -237.730084) (xy 371.70106 -237.75797) (xy 371.700551 -237.785856)
			(xy 371.692431 -237.841032) (xy 371.676363 -237.894439) (xy 371.652691 -237.944936) (xy 371.621918 -237.991449)
			(xy 371.584701 -238.032986) (xy 371.541833 -238.068661) (xy 371.494227 -238.097715) (xy 371.442898 -238.119527)
			(xy 371.388941 -238.133633) (xy 371.333504 -238.139733) (xy 371.27777 -238.137696) (xy 371.222927 -238.127566)
			(xy 371.170143 -238.109559) (xy 371.120543 -238.084058) (xy 371.075185 -238.051607) (xy 371.035036 -238.012898)
			(xy 371.00095 -237.968755) (xy 370.973654 -237.92012) (xy 370.953731 -237.868029) (xy 370.941605 -237.813592)
			(xy 370.937534 -237.75797) (xy 365.002317 -237.75797) (xy 365.002063 -237.771886) (xy 364.993943 -237.827062)
			(xy 364.977875 -237.880469) (xy 364.954203 -237.930966) (xy 364.92343 -237.977479) (xy 364.886213 -238.019016)
			(xy 364.843345 -238.054691) (xy 364.795739 -238.083745) (xy 364.74441 -238.105557) (xy 364.690453 -238.119663)
			(xy 364.635016 -238.125763) (xy 364.579282 -238.123726) (xy 364.524439 -238.113596) (xy 364.471655 -238.095589)
			(xy 364.422055 -238.070088) (xy 364.376697 -238.037637) (xy 364.336548 -237.998928) (xy 364.302462 -237.954785)
			(xy 364.275166 -237.90615) (xy 364.255243 -237.854059) (xy 364.243117 -237.799622) (xy 364.239046 -237.744)
			(xy 363.480925 -237.744) (xy 363.502224 -237.768582) (xy 363.53169 -237.814436) (xy 363.55433 -237.864016)
			(xy 363.569683 -237.916314) (xy 363.577438 -237.970265) (xy 363.577435 -238.02477) (xy 363.569676 -238.07872)
			(xy 363.554318 -238.131016) (xy 363.531673 -238.180594) (xy 363.502203 -238.226445) (xy 363.466508 -238.267636)
			(xy 363.425314 -238.303327) (xy 363.37946 -238.332792) (xy 363.329879 -238.355431) (xy 363.277581 -238.370784)
			(xy 363.223631 -238.378538) (xy 363.196378 -238.379) (xy 363.196124 -238.379) (xy 363.171457 -238.378605)
			(xy 363.122535 -238.372231) (xy 363.098588 -238.3663) (xy 363.084259 -238.36299) (xy 363.054875 -238.3639)
			(xy 363.026964 -238.373132) (xy 363.002833 -238.389922) (xy 362.984475 -238.412884) (xy 362.973408 -238.440119)
			(xy 362.971784 -238.456724) (xy 366.509044 -238.456724) (xy 366.513115 -238.401102) (xy 366.525241 -238.346665)
			(xy 366.545164 -238.294574) (xy 366.57246 -238.245939) (xy 366.606546 -238.201796) (xy 366.646695 -238.163087)
			(xy 366.692053 -238.130636) (xy 366.741653 -238.105135) (xy 366.794437 -238.087128) (xy 366.84928 -238.076998)
			(xy 366.905014 -238.074961) (xy 366.960451 -238.081061) (xy 367.014408 -238.095167) (xy 367.065737 -238.116979)
			(xy 367.113343 -238.146033) (xy 367.156211 -238.181708) (xy 367.193428 -238.223245) (xy 367.224201 -238.269758)
			(xy 367.247873 -238.320255) (xy 367.263941 -238.373662) (xy 367.272061 -238.428838) (xy 367.27257 -238.456724)
			(xy 367.272061 -238.48461) (xy 367.263941 -238.539786) (xy 367.249346 -238.588296) (xy 376.382278 -238.588296)
			(xy 376.386349 -238.532674) (xy 376.398475 -238.478237) (xy 376.418398 -238.426146) (xy 376.445694 -238.377511)
			(xy 376.47978 -238.333368) (xy 376.519929 -238.294659) (xy 376.565287 -238.262208) (xy 376.614887 -238.236707)
			(xy 376.667671 -238.2187) (xy 376.722514 -238.20857) (xy 376.778248 -238.206533) (xy 376.833685 -238.212633)
			(xy 376.887642 -238.226739) (xy 376.938971 -238.248551) (xy 376.986577 -238.277605) (xy 377.029445 -238.31328)
			(xy 377.066662 -238.354817) (xy 377.097435 -238.40133) (xy 377.121107 -238.451827) (xy 377.137175 -238.505234)
			(xy 377.145295 -238.56041) (xy 377.145804 -238.588296) (xy 377.145295 -238.616182) (xy 377.137175 -238.671358)
			(xy 377.121107 -238.724765) (xy 377.097435 -238.775262) (xy 377.066662 -238.821775) (xy 377.029445 -238.863312)
			(xy 376.986577 -238.898987) (xy 376.938971 -238.928041) (xy 376.887642 -238.949853) (xy 376.833685 -238.963959)
			(xy 376.778248 -238.970059) (xy 376.722514 -238.968022) (xy 376.667671 -238.957892) (xy 376.614887 -238.939885)
			(xy 376.565287 -238.914384) (xy 376.519929 -238.881933) (xy 376.47978 -238.843224) (xy 376.445694 -238.799081)
			(xy 376.418398 -238.750446) (xy 376.398475 -238.698355) (xy 376.386349 -238.643918) (xy 376.382278 -238.588296)
			(xy 367.249346 -238.588296) (xy 367.247873 -238.593193) (xy 367.224201 -238.64369) (xy 367.193428 -238.690203)
			(xy 367.156211 -238.73174) (xy 367.113343 -238.767415) (xy 367.065737 -238.796469) (xy 367.014408 -238.818281)
			(xy 366.960451 -238.832387) (xy 366.905014 -238.838487) (xy 366.84928 -238.83645) (xy 366.794437 -238.82632)
			(xy 366.741653 -238.808313) (xy 366.692053 -238.782812) (xy 366.646695 -238.750361) (xy 366.606546 -238.711652)
			(xy 366.57246 -238.667509) (xy 366.545164 -238.618874) (xy 366.525241 -238.566783) (xy 366.513115 -238.512346)
			(xy 366.509044 -238.456724) (xy 362.971784 -238.456724) (xy 362.970546 -238.469378) (xy 362.972858 -238.483902)
			(xy 362.976163 -238.501946) (xy 362.979726 -238.538458) (xy 362.97997 -238.5568) (xy 362.979522 -238.584051)
			(xy 362.971766 -238.637997) (xy 362.956412 -238.690291) (xy 362.933771 -238.739867) (xy 362.904306 -238.785717)
			(xy 362.868616 -238.826907) (xy 362.827427 -238.862599) (xy 362.781579 -238.892065) (xy 362.732003 -238.914707)
			(xy 362.67971 -238.930063) (xy 362.625763 -238.937821) (xy 362.571262 -238.937823) (xy 362.517315 -238.930069)
			(xy 362.465021 -238.914716) (xy 362.415444 -238.892077) (xy 362.369593 -238.862614) (xy 362.328402 -238.826925)
			(xy 362.292709 -238.785738) (xy 362.263241 -238.73989) (xy 362.240597 -238.690315) (xy 362.225239 -238.638022)
			(xy 362.21748 -238.584076) (xy 362.217476 -238.529575) (xy 361.790488 -238.529575) (xy 361.790488 -239.647984)
			(xy 375.566178 -239.647984) (xy 375.566664 -239.620733) (xy 375.57442 -239.566785) (xy 375.589775 -239.51449)
			(xy 375.612417 -239.464913) (xy 375.641883 -239.419063) (xy 375.677574 -239.377872) (xy 375.718765 -239.342181)
			(xy 375.764615 -239.312715) (xy 375.814192 -239.290073) (xy 375.866487 -239.274718) (xy 375.920435 -239.266962)
			(xy 375.974937 -239.266962) (xy 376.028885 -239.274718) (xy 376.08118 -239.290073) (xy 376.130757 -239.312715)
			(xy 376.176607 -239.342181) (xy 376.217798 -239.377872) (xy 376.253489 -239.419063) (xy 376.282955 -239.464913)
			(xy 376.305597 -239.51449) (xy 376.320952 -239.566785) (xy 376.328708 -239.620733) (xy 376.329194 -239.647984)
			(xy 376.328649 -239.677596) (xy 376.3195 -239.736109) (xy 376.314854 -239.7506) (xy 376.833892 -239.7506)
			(xy 376.834378 -239.723349) (xy 376.842134 -239.669401) (xy 376.857489 -239.617106) (xy 376.880131 -239.567529)
			(xy 376.909597 -239.521679) (xy 376.945288 -239.480488) (xy 376.986479 -239.444797) (xy 377.032329 -239.415331)
			(xy 377.081906 -239.392689) (xy 377.134201 -239.377334) (xy 377.188149 -239.369578) (xy 377.242651 -239.369578)
			(xy 377.296599 -239.377334) (xy 377.348894 -239.392689) (xy 377.398471 -239.415331) (xy 377.444321 -239.444797)
			(xy 377.485512 -239.480488) (xy 377.521203 -239.521679) (xy 377.550669 -239.567529) (xy 377.573311 -239.617106)
			(xy 377.588666 -239.669401) (xy 377.596422 -239.723349) (xy 377.596908 -239.7506) (xy 377.596442 -239.776633)
			(xy 377.589357 -239.828214) (xy 377.575331 -239.878355) (xy 377.554625 -239.926127) (xy 377.527622 -239.970643)
			(xy 377.511564 -239.991138) (xy 377.502985 -240.002322) (xy 377.491821 -240.028194) (xy 377.488158 -240.056133)
			(xy 377.492276 -240.084009) (xy 377.503862 -240.109696) (xy 377.52203 -240.131235) (xy 377.545397 -240.146984)
			(xy 377.572179 -240.155741) (xy 377.58624 -240.156746) (xy 377.612762 -240.158226) (xy 377.66503 -240.167703)
			(xy 377.715479 -240.184337) (xy 377.763133 -240.207808) (xy 377.807071 -240.237661) (xy 377.846444 -240.273319)
			(xy 377.880491 -240.314094) (xy 377.908554 -240.359197) (xy 377.930089 -240.407756) (xy 377.944682 -240.458833)
			(xy 377.95205 -240.51144) (xy 377.952508 -240.538) (xy 377.952022 -240.565251) (xy 377.944266 -240.619199)
			(xy 377.928911 -240.671494) (xy 377.906269 -240.721071) (xy 377.876803 -240.766921) (xy 377.841112 -240.808112)
			(xy 377.799921 -240.843803) (xy 377.754071 -240.873269) (xy 377.704494 -240.895911) (xy 377.652199 -240.911266)
			(xy 377.598251 -240.919022) (xy 377.543749 -240.919022) (xy 377.489801 -240.911266) (xy 377.437506 -240.895911)
			(xy 377.387929 -240.873269) (xy 377.342079 -240.843803) (xy 377.300888 -240.808112) (xy 377.265197 -240.766921)
			(xy 377.235731 -240.721071) (xy 377.213089 -240.671494) (xy 377.197734 -240.619199) (xy 377.189978 -240.565251)
			(xy 377.189492 -240.538) (xy 377.189958 -240.511967) (xy 377.197043 -240.460386) (xy 377.211069 -240.410245)
			(xy 377.231775 -240.362473) (xy 377.258778 -240.317957) (xy 377.274836 -240.297462) (xy 377.283415 -240.286278)
			(xy 377.294579 -240.260406) (xy 377.298242 -240.232467) (xy 377.294124 -240.204591) (xy 377.282538 -240.178904)
			(xy 377.26437 -240.157365) (xy 377.241003 -240.141616) (xy 377.214221 -240.132859) (xy 377.20016 -240.131854)
			(xy 377.173638 -240.130374) (xy 377.12137 -240.120897) (xy 377.070921 -240.104263) (xy 377.023267 -240.080792)
			(xy 376.979329 -240.050939) (xy 376.939956 -240.015281) (xy 376.905909 -239.974506) (xy 376.877846 -239.929403)
			(xy 376.856311 -239.880844) (xy 376.841718 -239.829767) (xy 376.83435 -239.77716) (xy 376.833892 -239.7506)
			(xy 376.314854 -239.7506) (xy 376.301419 -239.792505) (xy 376.274839 -239.845429) (xy 376.240401 -239.89361)
			(xy 376.198931 -239.935891) (xy 376.151425 -239.971256) (xy 376.125486 -239.98555) (xy 376.113296 -239.99239)
			(xy 376.092985 -240.011581) (xy 376.078637 -240.035561) (xy 376.071328 -240.062532) (xy 376.071605 -240.090474)
			(xy 376.079448 -240.117295) (xy 376.094268 -240.140985) (xy 376.114956 -240.15977) (xy 376.127264 -240.166398)
			(xy 376.150661 -240.178638) (xy 376.194185 -240.208533) (xy 376.233167 -240.244148) (xy 376.266861 -240.284802)
			(xy 376.294624 -240.329715) (xy 376.315924 -240.37803) (xy 376.330354 -240.428822) (xy 376.337637 -240.481119)
			(xy 376.338084 -240.50752) (xy 376.337598 -240.534771) (xy 376.329842 -240.588719) (xy 376.314487 -240.641014)
			(xy 376.291845 -240.690591) (xy 376.262379 -240.736441) (xy 376.226688 -240.777632) (xy 376.185497 -240.813323)
			(xy 376.139647 -240.842789) (xy 376.09007 -240.865431) (xy 376.037775 -240.880786) (xy 375.983827 -240.888542)
			(xy 375.929325 -240.888542) (xy 375.875377 -240.880786) (xy 375.823082 -240.865431) (xy 375.773505 -240.842789)
			(xy 375.727655 -240.813323) (xy 375.686464 -240.777632) (xy 375.650773 -240.736441) (xy 375.621307 -240.690591)
			(xy 375.598665 -240.641014) (xy 375.58331 -240.588719) (xy 375.575554 -240.534771) (xy 375.575068 -240.50752)
			(xy 375.575583 -240.477907) (xy 375.584733 -240.419391) (xy 375.602818 -240.362993) (xy 375.629401 -240.310067)
			(xy 375.663845 -240.261885) (xy 375.705321 -240.219606) (xy 375.752833 -240.184245) (xy 375.778776 -240.169954)
			(xy 375.790956 -240.163103) (xy 375.811255 -240.143908) (xy 375.825593 -240.119932) (xy 375.832897 -240.092966)
			(xy 375.83262 -240.065031) (xy 375.824784 -240.038216) (xy 375.809974 -240.014527) (xy 375.789299 -239.995739)
			(xy 375.776998 -239.989106) (xy 375.753594 -239.97688) (xy 375.710072 -239.946981) (xy 375.671091 -239.911363)
			(xy 375.637398 -239.870707) (xy 375.609637 -239.825792) (xy 375.588337 -239.777476) (xy 375.573908 -239.726683)
			(xy 375.566625 -239.674385) (xy 375.566178 -239.647984) (xy 361.790488 -239.647984) (xy 361.790488 -241.15776)
			(xy 367.44478 -241.15776) (xy 367.448851 -241.102138) (xy 367.460977 -241.047701) (xy 367.4809 -240.99561)
			(xy 367.508196 -240.946975) (xy 367.542282 -240.902832) (xy 367.582431 -240.864123) (xy 367.627789 -240.831672)
			(xy 367.677389 -240.806171) (xy 367.730173 -240.788164) (xy 367.785016 -240.778034) (xy 367.84075 -240.775997)
			(xy 367.896187 -240.782097) (xy 367.950144 -240.796203) (xy 368.001473 -240.818015) (xy 368.049079 -240.847069)
			(xy 368.091947 -240.882744) (xy 368.129164 -240.924281) (xy 368.159937 -240.970794) (xy 368.183609 -241.021291)
			(xy 368.199677 -241.074698) (xy 368.207797 -241.129874) (xy 368.208306 -241.15776) (xy 368.207797 -241.185646)
			(xy 368.199677 -241.240822) (xy 368.183609 -241.294229) (xy 368.18138 -241.298984) (xy 371.174008 -241.298984)
			(xy 371.178079 -241.243362) (xy 371.190205 -241.188925) (xy 371.210128 -241.136834) (xy 371.237424 -241.088199)
			(xy 371.27151 -241.044056) (xy 371.311659 -241.005347) (xy 371.357017 -240.972896) (xy 371.406617 -240.947395)
			(xy 371.459401 -240.929388) (xy 371.514244 -240.919258) (xy 371.569978 -240.917221) (xy 371.625415 -240.923321)
			(xy 371.679372 -240.937427) (xy 371.730701 -240.959239) (xy 371.778307 -240.988293) (xy 371.821175 -241.023968)
			(xy 371.858392 -241.065505) (xy 371.889165 -241.112018) (xy 371.905131 -241.146076) (xy 374.102628 -241.146076)
			(xy 374.106699 -241.090454) (xy 374.118825 -241.036017) (xy 374.138748 -240.983926) (xy 374.166044 -240.935291)
			(xy 374.20013 -240.891148) (xy 374.240279 -240.852439) (xy 374.285637 -240.819988) (xy 374.335237 -240.794487)
			(xy 374.388021 -240.77648) (xy 374.442864 -240.76635) (xy 374.498598 -240.764313) (xy 374.554035 -240.770413)
			(xy 374.607992 -240.784519) (xy 374.659321 -240.806331) (xy 374.706927 -240.835385) (xy 374.749795 -240.87106)
			(xy 374.787012 -240.912597) (xy 374.817785 -240.95911) (xy 374.841457 -241.009607) (xy 374.857525 -241.063014)
			(xy 374.865645 -241.11819) (xy 374.866154 -241.146076) (xy 374.865645 -241.173962) (xy 374.857525 -241.229138)
			(xy 374.841457 -241.282545) (xy 374.817785 -241.333042) (xy 374.787012 -241.379555) (xy 374.749795 -241.421092)
			(xy 374.706927 -241.456767) (xy 374.659321 -241.485821) (xy 374.607992 -241.507633) (xy 374.554035 -241.521739)
			(xy 374.498598 -241.527839) (xy 374.442864 -241.525802) (xy 374.388021 -241.515672) (xy 374.335237 -241.497665)
			(xy 374.285637 -241.472164) (xy 374.240279 -241.439713) (xy 374.20013 -241.401004) (xy 374.166044 -241.356861)
			(xy 374.138748 -241.308226) (xy 374.118825 -241.256135) (xy 374.106699 -241.201698) (xy 374.102628 -241.146076)
			(xy 371.905131 -241.146076) (xy 371.912837 -241.162515) (xy 371.928905 -241.215922) (xy 371.937025 -241.271098)
			(xy 371.937534 -241.298984) (xy 371.937025 -241.32687) (xy 371.928905 -241.382046) (xy 371.912837 -241.435453)
			(xy 371.889165 -241.48595) (xy 371.858392 -241.532463) (xy 371.821175 -241.574) (xy 371.778307 -241.609675)
			(xy 371.730701 -241.638729) (xy 371.679372 -241.660541) (xy 371.625415 -241.674647) (xy 371.569978 -241.680747)
			(xy 371.514244 -241.67871) (xy 371.459401 -241.66858) (xy 371.406617 -241.650573) (xy 371.357017 -241.625072)
			(xy 371.311659 -241.592621) (xy 371.27151 -241.553912) (xy 371.237424 -241.509769) (xy 371.210128 -241.461134)
			(xy 371.190205 -241.409043) (xy 371.178079 -241.354606) (xy 371.174008 -241.298984) (xy 368.18138 -241.298984)
			(xy 368.159937 -241.344726) (xy 368.129164 -241.391239) (xy 368.091947 -241.432776) (xy 368.049079 -241.468451)
			(xy 368.001473 -241.497505) (xy 367.950144 -241.519317) (xy 367.896187 -241.533423) (xy 367.84075 -241.539523)
			(xy 367.785016 -241.537486) (xy 367.730173 -241.527356) (xy 367.677389 -241.509349) (xy 367.627789 -241.483848)
			(xy 367.582431 -241.451397) (xy 367.542282 -241.412688) (xy 367.508196 -241.368545) (xy 367.4809 -241.31991)
			(xy 367.460977 -241.267819) (xy 367.448851 -241.213382) (xy 367.44478 -241.15776) (xy 361.790488 -241.15776)
			(xy 361.790488 -241.862356) (xy 375.643138 -241.862356) (xy 375.647209 -241.806734) (xy 375.659335 -241.752297)
			(xy 375.679258 -241.700206) (xy 375.706554 -241.651571) (xy 375.74064 -241.607428) (xy 375.780789 -241.568719)
			(xy 375.826147 -241.536268) (xy 375.875747 -241.510767) (xy 375.928531 -241.49276) (xy 375.983374 -241.48263)
			(xy 376.039108 -241.480593) (xy 376.094545 -241.486693) (xy 376.148502 -241.500799) (xy 376.199831 -241.522611)
			(xy 376.247437 -241.551665) (xy 376.290305 -241.58734) (xy 376.327522 -241.628877) (xy 376.358295 -241.67539)
			(xy 376.381967 -241.725887) (xy 376.398035 -241.779294) (xy 376.402708 -241.811048) (xy 377.376942 -241.811048)
			(xy 377.381013 -241.755426) (xy 377.393139 -241.700989) (xy 377.413062 -241.648898) (xy 377.440358 -241.600263)
			(xy 377.474444 -241.55612) (xy 377.514593 -241.517411) (xy 377.559951 -241.48496) (xy 377.609551 -241.459459)
			(xy 377.662335 -241.441452) (xy 377.717178 -241.431322) (xy 377.772912 -241.429285) (xy 377.828349 -241.435385)
			(xy 377.882306 -241.449491) (xy 377.933635 -241.471303) (xy 377.981241 -241.500357) (xy 378.024109 -241.536032)
			(xy 378.061326 -241.577569) (xy 378.092099 -241.624082) (xy 378.115771 -241.674579) (xy 378.131839 -241.727986)
			(xy 378.139959 -241.783162) (xy 378.140468 -241.811048) (xy 378.139959 -241.838934) (xy 378.131839 -241.89411)
			(xy 378.115771 -241.947517) (xy 378.092099 -241.998014) (xy 378.061326 -242.044527) (xy 378.024109 -242.086064)
			(xy 377.981241 -242.121739) (xy 377.933635 -242.150793) (xy 377.882306 -242.172605) (xy 377.828349 -242.186711)
			(xy 377.772912 -242.192811) (xy 377.717178 -242.190774) (xy 377.662335 -242.180644) (xy 377.609551 -242.162637)
			(xy 377.559951 -242.137136) (xy 377.514593 -242.104685) (xy 377.474444 -242.065976) (xy 377.440358 -242.021833)
			(xy 377.413062 -241.973198) (xy 377.393139 -241.921107) (xy 377.381013 -241.86667) (xy 377.376942 -241.811048)
			(xy 376.402708 -241.811048) (xy 376.406155 -241.83447) (xy 376.406664 -241.862356) (xy 376.406155 -241.890242)
			(xy 376.398035 -241.945418) (xy 376.381967 -241.998825) (xy 376.358295 -242.049322) (xy 376.327522 -242.095835)
			(xy 376.290305 -242.137372) (xy 376.247437 -242.173047) (xy 376.199831 -242.202101) (xy 376.148502 -242.223913)
			(xy 376.094545 -242.238019) (xy 376.039108 -242.244119) (xy 375.983374 -242.242082) (xy 375.928531 -242.231952)
			(xy 375.875747 -242.213945) (xy 375.826147 -242.188444) (xy 375.780789 -242.155993) (xy 375.74064 -242.117284)
			(xy 375.706554 -242.073141) (xy 375.679258 -242.024506) (xy 375.659335 -241.972415) (xy 375.647209 -241.917978)
			(xy 375.643138 -241.862356) (xy 361.790488 -241.862356) (xy 361.790488 -243.251482) (xy 365.131856 -243.251482)
			(xy 365.135927 -243.19586) (xy 365.148053 -243.141423) (xy 365.167976 -243.089332) (xy 365.195272 -243.040697)
			(xy 365.229358 -242.996554) (xy 365.269507 -242.957845) (xy 365.314865 -242.925394) (xy 365.364465 -242.899893)
			(xy 365.417249 -242.881886) (xy 365.472092 -242.871756) (xy 365.527826 -242.869719) (xy 365.583263 -242.875819)
			(xy 365.63722 -242.889925) (xy 365.688549 -242.911737) (xy 365.736155 -242.940791) (xy 365.779023 -242.976466)
			(xy 365.81624 -243.018003) (xy 365.847013 -243.064516) (xy 365.870685 -243.115013) (xy 365.886753 -243.16842)
			(xy 365.894873 -243.223596) (xy 365.895382 -243.251482) (xy 365.894873 -243.279368) (xy 365.886753 -243.334544)
			(xy 365.870685 -243.387951) (xy 365.847013 -243.438448) (xy 365.81624 -243.484961) (xy 365.779023 -243.526498)
			(xy 365.736155 -243.562173) (xy 365.688549 -243.591227) (xy 365.63722 -243.613039) (xy 365.583263 -243.627145)
			(xy 365.527826 -243.633245) (xy 365.472092 -243.631208) (xy 365.417249 -243.621078) (xy 365.364465 -243.603071)
			(xy 365.314865 -243.57757) (xy 365.269507 -243.545119) (xy 365.229358 -243.50641) (xy 365.195272 -243.462267)
			(xy 365.167976 -243.413632) (xy 365.148053 -243.361541) (xy 365.135927 -243.307104) (xy 365.131856 -243.251482)
			(xy 361.790488 -243.251482) (xy 361.790488 -243.913152) (xy 370.00129 -243.913152) (xy 370.005361 -243.85753)
			(xy 370.017487 -243.803093) (xy 370.03741 -243.751002) (xy 370.064706 -243.702367) (xy 370.098792 -243.658224)
			(xy 370.138941 -243.619515) (xy 370.184299 -243.587064) (xy 370.233899 -243.561563) (xy 370.286683 -243.543556)
			(xy 370.341526 -243.533426) (xy 370.39726 -243.531389) (xy 370.452697 -243.537489) (xy 370.506654 -243.551595)
			(xy 370.557983 -243.573407) (xy 370.605589 -243.602461) (xy 370.648457 -243.638136) (xy 370.685674 -243.679673)
			(xy 370.716447 -243.726186) (xy 370.740119 -243.776683) (xy 370.756187 -243.83009) (xy 370.764307 -243.885266)
			(xy 370.764816 -243.913152) (xy 370.764399 -243.936012) (xy 370.966492 -243.936012) (xy 370.966992 -243.909945)
			(xy 370.974097 -243.858297) (xy 370.988163 -243.808095) (xy 371.008928 -243.760274) (xy 371.036006 -243.715723)
			(xy 371.068893 -243.67527) (xy 371.106979 -243.639668) (xy 371.149554 -243.609579) (xy 371.172486 -243.597176)
			(xy 371.184593 -243.590351) (xy 371.204888 -243.571382) (xy 371.219316 -243.547643) (xy 371.226807 -243.520893)
			(xy 371.226808 -243.493113) (xy 371.219318 -243.466362) (xy 371.204891 -243.442622) (xy 371.184597 -243.423652)
			(xy 371.172486 -243.416836) (xy 371.14956 -243.404416) (xy 371.106966 -243.374344) (xy 371.068863 -243.338753)
			(xy 371.035961 -243.298305) (xy 371.008872 -243.253755) (xy 370.988101 -243.205931) (xy 370.974036 -243.155724)
			(xy 370.966936 -243.10407) (xy 370.966492 -243.078) (xy 370.966978 -243.050749) (xy 370.974734 -242.996801)
			(xy 370.990089 -242.944506) (xy 371.012731 -242.894929) (xy 371.042197 -242.849079) (xy 371.077888 -242.807888)
			(xy 371.119079 -242.772197) (xy 371.164929 -242.742731) (xy 371.214506 -242.720089) (xy 371.266801 -242.704734)
			(xy 371.320749 -242.696978) (xy 371.375251 -242.696978) (xy 371.429199 -242.704734) (xy 371.481494 -242.720089)
			(xy 371.531071 -242.742731) (xy 371.576921 -242.772197) (xy 371.618112 -242.807888) (xy 371.653803 -242.849079)
			(xy 371.683269 -242.894929) (xy 371.705911 -242.944506) (xy 371.721266 -242.996801) (xy 371.729022 -243.050749)
			(xy 371.729508 -243.078) (xy 371.729018 -243.104068) (xy 371.721911 -243.155716) (xy 371.707844 -243.205918)
			(xy 371.687077 -243.253739) (xy 371.659998 -243.29829) (xy 371.627109 -243.338742) (xy 371.589023 -243.374344)
			(xy 371.546447 -243.404434) (xy 371.523514 -243.416836) (xy 371.511396 -243.423644) (xy 371.491101 -243.442616)
			(xy 371.476672 -243.466358) (xy 371.469181 -243.493112) (xy 371.469182 -243.520894) (xy 371.476675 -243.547647)
			(xy 371.491104 -243.571389) (xy 371.511401 -243.590359) (xy 371.523514 -243.597176) (xy 371.546445 -243.609587)
			(xy 371.589039 -243.63966) (xy 371.627142 -243.675253) (xy 371.660044 -243.715702) (xy 371.687132 -243.760253)
			(xy 371.707902 -243.808079) (xy 371.721967 -243.858286) (xy 371.729064 -243.909942) (xy 371.729508 -243.936012)
			(xy 371.729022 -243.963263) (xy 371.721266 -244.017211) (xy 371.705911 -244.069506) (xy 371.683269 -244.119083)
			(xy 371.653803 -244.164933) (xy 371.618112 -244.206124) (xy 371.576921 -244.241815) (xy 371.531071 -244.271281)
			(xy 371.481494 -244.293923) (xy 371.429199 -244.309278) (xy 371.375251 -244.317034) (xy 371.320749 -244.317034)
			(xy 371.266801 -244.309278) (xy 371.214506 -244.293923) (xy 371.164929 -244.271281) (xy 371.119079 -244.241815)
			(xy 371.077888 -244.206124) (xy 371.042197 -244.164933) (xy 371.012731 -244.119083) (xy 370.990089 -244.069506)
			(xy 370.974734 -244.017211) (xy 370.966978 -243.963263) (xy 370.966492 -243.936012) (xy 370.764399 -243.936012)
			(xy 370.764307 -243.941038) (xy 370.756187 -243.996214) (xy 370.740119 -244.049621) (xy 370.716447 -244.100118)
			(xy 370.685674 -244.146631) (xy 370.648457 -244.188168) (xy 370.605589 -244.223843) (xy 370.557983 -244.252897)
			(xy 370.506654 -244.274709) (xy 370.452697 -244.288815) (xy 370.39726 -244.294915) (xy 370.341526 -244.292878)
			(xy 370.286683 -244.282748) (xy 370.233899 -244.264741) (xy 370.184299 -244.23924) (xy 370.138941 -244.206789)
			(xy 370.098792 -244.16808) (xy 370.064706 -244.123937) (xy 370.03741 -244.075302) (xy 370.017487 -244.023211)
			(xy 370.005361 -243.968774) (xy 370.00129 -243.913152) (xy 361.790488 -243.913152) (xy 361.790488 -244.324886)
			(xy 376.196096 -244.324886) (xy 376.200167 -244.269264) (xy 376.212293 -244.214827) (xy 376.232216 -244.162736)
			(xy 376.259512 -244.114101) (xy 376.293598 -244.069958) (xy 376.333747 -244.031249) (xy 376.379105 -243.998798)
			(xy 376.428705 -243.973297) (xy 376.481489 -243.95529) (xy 376.536332 -243.94516) (xy 376.592066 -243.943123)
			(xy 376.647503 -243.949223) (xy 376.70146 -243.963329) (xy 376.752789 -243.985141) (xy 376.800395 -244.014195)
			(xy 376.843263 -244.04987) (xy 376.88048 -244.091407) (xy 376.882196 -244.094) (xy 379.875032 -244.094)
			(xy 379.879103 -244.038378) (xy 379.891229 -243.983941) (xy 379.911152 -243.93185) (xy 379.938448 -243.883215)
			(xy 379.972534 -243.839072) (xy 380.012683 -243.800363) (xy 380.058041 -243.767912) (xy 380.107641 -243.742411)
			(xy 380.160425 -243.724404) (xy 380.215268 -243.714274) (xy 380.271002 -243.712237) (xy 380.326439 -243.718337)
			(xy 380.380396 -243.732443) (xy 380.431725 -243.754255) (xy 380.479331 -243.783309) (xy 380.522199 -243.818984)
			(xy 380.559416 -243.860521) (xy 380.590189 -243.907034) (xy 380.613861 -243.957531) (xy 380.629929 -244.010938)
			(xy 380.638049 -244.066114) (xy 380.638558 -244.094) (xy 380.638049 -244.121886) (xy 380.629929 -244.177062)
			(xy 380.613861 -244.230469) (xy 380.590189 -244.280966) (xy 380.559416 -244.327479) (xy 380.522199 -244.369016)
			(xy 380.479331 -244.404691) (xy 380.431725 -244.433745) (xy 380.380396 -244.455557) (xy 380.326439 -244.469663)
			(xy 380.271002 -244.475763) (xy 380.215268 -244.473726) (xy 380.160425 -244.463596) (xy 380.107641 -244.445589)
			(xy 380.058041 -244.420088) (xy 380.012683 -244.387637) (xy 379.972534 -244.348928) (xy 379.938448 -244.304785)
			(xy 379.911152 -244.25615) (xy 379.891229 -244.204059) (xy 379.879103 -244.149622) (xy 379.875032 -244.094)
			(xy 376.882196 -244.094) (xy 376.911253 -244.13792) (xy 376.934925 -244.188417) (xy 376.950993 -244.241824)
			(xy 376.959113 -244.297) (xy 376.959622 -244.324886) (xy 376.959113 -244.352772) (xy 376.950993 -244.407948)
			(xy 376.934925 -244.461355) (xy 376.911253 -244.511852) (xy 376.88048 -244.558365) (xy 376.843263 -244.599902)
			(xy 376.800395 -244.635577) (xy 376.752789 -244.664631) (xy 376.70146 -244.686443) (xy 376.647503 -244.700549)
			(xy 376.592066 -244.706649) (xy 376.536332 -244.704612) (xy 376.481489 -244.694482) (xy 376.428705 -244.676475)
			(xy 376.379105 -244.650974) (xy 376.333747 -244.618523) (xy 376.293598 -244.579814) (xy 376.259512 -244.535671)
			(xy 376.232216 -244.487036) (xy 376.212293 -244.434945) (xy 376.200167 -244.380508) (xy 376.196096 -244.324886)
			(xy 361.790488 -244.324886) (xy 361.790488 -245.294952) (xy 362.197089 -245.294952) (xy 362.197089 -245.240448)
			(xy 362.204847 -245.186498) (xy 362.220204 -245.134201) (xy 362.242847 -245.084623) (xy 362.272316 -245.038772)
			(xy 362.308011 -244.997582) (xy 362.349205 -244.961891) (xy 362.39506 -244.932427) (xy 362.444641 -244.909789)
			(xy 362.496939 -244.894438) (xy 362.55089 -244.886686) (xy 362.578142 -244.886226) (xy 362.607177 -244.886779)
			(xy 362.66458 -244.895559) (xy 362.719988 -244.912941) (xy 362.77212 -244.938522) (xy 362.819772 -244.971711)
			(xy 362.86184 -245.011741) (xy 362.897353 -245.057687) (xy 362.911898 -245.082822) (xy 362.918994 -245.094665)
			(xy 362.938396 -245.114293) (xy 362.962348 -245.128003) (xy 362.989098 -245.134794) (xy 363.01669 -245.134168)
			(xy 363.043105 -245.12617) (xy 363.06641 -245.111387) (xy 363.084902 -245.0909) (xy 363.091476 -245.078758)
			(xy 363.103729 -245.055302) (xy 363.133622 -245.011638) (xy 363.169261 -244.972523) (xy 363.209963 -244.938707)
			(xy 363.254946 -244.910838) (xy 363.303348 -244.889452) (xy 363.354241 -244.874958) (xy 363.406648 -244.867634)
			(xy 363.433106 -244.867176) (xy 363.460356 -244.867695) (xy 363.514301 -244.875452) (xy 363.566592 -244.890807)
			(xy 363.616167 -244.913447) (xy 363.626771 -244.920262) (xy 370.624352 -244.920262) (xy 370.628423 -244.86464)
			(xy 370.640549 -244.810203) (xy 370.660472 -244.758112) (xy 370.687768 -244.709477) (xy 370.721854 -244.665334)
			(xy 370.762003 -244.626625) (xy 370.807361 -244.594174) (xy 370.856961 -244.568673) (xy 370.909745 -244.550666)
			(xy 370.964588 -244.540536) (xy 371.020322 -244.538499) (xy 371.075759 -244.544599) (xy 371.129716 -244.558705)
			(xy 371.181045 -244.580517) (xy 371.228651 -244.609571) (xy 371.271519 -244.645246) (xy 371.308736 -244.686783)
			(xy 371.339509 -244.733296) (xy 371.363181 -244.783793) (xy 371.379249 -244.8372) (xy 371.387369 -244.892376)
			(xy 371.387878 -244.920262) (xy 371.387369 -244.948148) (xy 371.379249 -245.003324) (xy 371.363181 -245.056731)
			(xy 371.339509 -245.107228) (xy 371.308736 -245.153741) (xy 371.271519 -245.195278) (xy 371.228651 -245.230953)
			(xy 371.181045 -245.260007) (xy 371.129716 -245.281819) (xy 371.075759 -245.295925) (xy 371.020322 -245.302025)
			(xy 370.964588 -245.299988) (xy 370.909745 -245.289858) (xy 370.856961 -245.271851) (xy 370.807361 -245.24635)
			(xy 370.762003 -245.213899) (xy 370.721854 -245.17519) (xy 370.687768 -245.131047) (xy 370.660472 -245.082412)
			(xy 370.640549 -245.030321) (xy 370.628423 -244.975884) (xy 370.624352 -244.920262) (xy 363.626771 -244.920262)
			(xy 363.662014 -244.942912) (xy 363.703202 -244.978602) (xy 363.738891 -245.01979) (xy 363.768356 -245.065639)
			(xy 363.790996 -245.115213) (xy 363.80635 -245.167505) (xy 363.814106 -245.22145) (xy 363.814106 -245.27595)
			(xy 363.80635 -245.329895) (xy 363.790996 -245.382187) (xy 363.768356 -245.431761) (xy 363.738891 -245.47761)
			(xy 363.703202 -245.518798) (xy 363.673139 -245.544848) (xy 369.93398 -245.544848) (xy 369.938051 -245.489226)
			(xy 369.950177 -245.434789) (xy 369.9701 -245.382698) (xy 369.997396 -245.334063) (xy 370.031482 -245.28992)
			(xy 370.071631 -245.251211) (xy 370.116989 -245.21876) (xy 370.166589 -245.193259) (xy 370.219373 -245.175252)
			(xy 370.274216 -245.165122) (xy 370.32995 -245.163085) (xy 370.385387 -245.169185) (xy 370.439344 -245.183291)
			(xy 370.490673 -245.205103) (xy 370.538279 -245.234157) (xy 370.581147 -245.269832) (xy 370.618364 -245.311369)
			(xy 370.649137 -245.357882) (xy 370.655339 -245.371112) (xy 376.10618 -245.371112) (xy 376.110251 -245.31549)
			(xy 376.122377 -245.261053) (xy 376.1423 -245.208962) (xy 376.169596 -245.160327) (xy 376.203682 -245.116184)
			(xy 376.243831 -245.077475) (xy 376.289189 -245.045024) (xy 376.338789 -245.019523) (xy 376.391573 -245.001516)
			(xy 376.446416 -244.991386) (xy 376.50215 -244.989349) (xy 376.557587 -244.995449) (xy 376.611544 -245.009555)
			(xy 376.662873 -245.031367) (xy 376.710479 -245.060421) (xy 376.753347 -245.096096) (xy 376.790564 -245.137633)
			(xy 376.821337 -245.184146) (xy 376.845009 -245.234643) (xy 376.861077 -245.28805) (xy 376.869197 -245.343226)
			(xy 376.869576 -245.364) (xy 380.973582 -245.364) (xy 380.977653 -245.308378) (xy 380.989779 -245.253941)
			(xy 381.009702 -245.20185) (xy 381.036998 -245.153215) (xy 381.071084 -245.109072) (xy 381.111233 -245.070363)
			(xy 381.156591 -245.037912) (xy 381.206191 -245.012411) (xy 381.258975 -244.994404) (xy 381.313818 -244.984274)
			(xy 381.369552 -244.982237) (xy 381.424989 -244.988337) (xy 381.478946 -245.002443) (xy 381.530275 -245.024255)
			(xy 381.577881 -245.053309) (xy 381.620749 -245.088984) (xy 381.657966 -245.130521) (xy 381.688739 -245.177034)
			(xy 381.712411 -245.227531) (xy 381.728479 -245.280938) (xy 381.736599 -245.336114) (xy 381.737108 -245.364)
			(xy 381.736599 -245.391886) (xy 381.728479 -245.447062) (xy 381.712411 -245.500469) (xy 381.688739 -245.550966)
			(xy 381.657966 -245.597479) (xy 381.620749 -245.639016) (xy 381.577881 -245.674691) (xy 381.530275 -245.703745)
			(xy 381.478946 -245.725557) (xy 381.424989 -245.739663) (xy 381.369552 -245.745763) (xy 381.313818 -245.743726)
			(xy 381.258975 -245.733596) (xy 381.206191 -245.715589) (xy 381.156591 -245.690088) (xy 381.111233 -245.657637)
			(xy 381.071084 -245.618928) (xy 381.036998 -245.574785) (xy 381.009702 -245.52615) (xy 380.989779 -245.474059)
			(xy 380.977653 -245.419622) (xy 380.973582 -245.364) (xy 376.869576 -245.364) (xy 376.869706 -245.371112)
			(xy 376.869197 -245.398998) (xy 376.861077 -245.454174) (xy 376.845009 -245.507581) (xy 376.821337 -245.558078)
			(xy 376.790564 -245.604591) (xy 376.753347 -245.646128) (xy 376.710479 -245.681803) (xy 376.662873 -245.710857)
			(xy 376.611544 -245.732669) (xy 376.557587 -245.746775) (xy 376.50215 -245.752875) (xy 376.446416 -245.750838)
			(xy 376.391573 -245.740708) (xy 376.338789 -245.722701) (xy 376.289189 -245.6972) (xy 376.243831 -245.664749)
			(xy 376.203682 -245.62604) (xy 376.169596 -245.581897) (xy 376.1423 -245.533262) (xy 376.122377 -245.481171)
			(xy 376.110251 -245.426734) (xy 376.10618 -245.371112) (xy 370.655339 -245.371112) (xy 370.672809 -245.408379)
			(xy 370.688877 -245.461786) (xy 370.696997 -245.516962) (xy 370.697506 -245.544848) (xy 370.696997 -245.572734)
			(xy 370.688877 -245.62791) (xy 370.672809 -245.681317) (xy 370.649137 -245.731814) (xy 370.618364 -245.778327)
			(xy 370.581147 -245.819864) (xy 370.538279 -245.855539) (xy 370.490673 -245.884593) (xy 370.439344 -245.906405)
			(xy 370.385387 -245.920511) (xy 370.32995 -245.926611) (xy 370.274216 -245.924574) (xy 370.219373 -245.914444)
			(xy 370.166589 -245.896437) (xy 370.116989 -245.870936) (xy 370.071631 -245.838485) (xy 370.031482 -245.799776)
			(xy 369.997396 -245.755633) (xy 369.9701 -245.706998) (xy 369.950177 -245.654907) (xy 369.938051 -245.60047)
			(xy 369.93398 -245.544848) (xy 363.673139 -245.544848) (xy 363.662014 -245.554488) (xy 363.616167 -245.583953)
			(xy 363.566592 -245.606593) (xy 363.514301 -245.621948) (xy 363.460356 -245.629705) (xy 363.433106 -245.630192)
			(xy 363.40407 -245.629672) (xy 363.346666 -245.620884) (xy 363.291258 -245.603496) (xy 363.239126 -245.577909)
			(xy 363.191475 -245.544715) (xy 363.149407 -245.504681) (xy 363.113894 -245.458733) (xy 363.09935 -245.433596)
			(xy 363.092187 -245.421795) (xy 363.072799 -245.402168) (xy 363.048859 -245.388455) (xy 363.02212 -245.38166)
			(xy 362.994538 -245.38228) (xy 362.968131 -245.39027) (xy 362.944832 -245.405044) (xy 362.926345 -245.425523)
			(xy 362.919772 -245.43766) (xy 362.907566 -245.461142) (xy 362.877666 -245.504806) (xy 362.84202 -245.54392)
			(xy 362.801311 -245.577734) (xy 362.756321 -245.605599) (xy 362.707913 -245.626982) (xy 362.657014 -245.64147)
			(xy 362.604602 -245.648788) (xy 362.578142 -245.649242) (xy 362.55089 -245.648714) (xy 362.496939 -245.640962)
			(xy 362.444641 -245.625611) (xy 362.39506 -245.602973) (xy 362.349205 -245.573509) (xy 362.308011 -245.537818)
			(xy 362.272316 -245.496628) (xy 362.242847 -245.450777) (xy 362.220204 -245.401199) (xy 362.204847 -245.348902)
			(xy 362.197089 -245.294952) (xy 361.790488 -245.294952) (xy 361.790488 -246.38) (xy 375.333766 -246.38)
			(xy 375.337837 -246.324378) (xy 375.349963 -246.269941) (xy 375.369886 -246.21785) (xy 375.397182 -246.169215)
			(xy 375.431268 -246.125072) (xy 375.471417 -246.086363) (xy 375.516775 -246.053912) (xy 375.566375 -246.028411)
			(xy 375.619159 -246.010404) (xy 375.674002 -246.000274) (xy 375.729736 -245.998237) (xy 375.785173 -246.004337)
			(xy 375.83913 -246.018443) (xy 375.890459 -246.040255) (xy 375.92233 -246.059706) (xy 384.173982 -246.059706)
			(xy 384.178053 -246.004084) (xy 384.190179 -245.949647) (xy 384.210102 -245.897556) (xy 384.237398 -245.848921)
			(xy 384.271484 -245.804778) (xy 384.311633 -245.766069) (xy 384.356991 -245.733618) (xy 384.406591 -245.708117)
			(xy 384.459375 -245.69011) (xy 384.514218 -245.67998) (xy 384.569952 -245.677943) (xy 384.625389 -245.684043)
			(xy 384.679346 -245.698149) (xy 384.730675 -245.719961) (xy 384.778281 -245.749015) (xy 384.821149 -245.78469)
			(xy 384.858366 -245.826227) (xy 384.889139 -245.87274) (xy 384.912811 -245.923237) (xy 384.928879 -245.976644)
			(xy 384.936999 -246.03182) (xy 384.937508 -246.059706) (xy 384.936999 -246.087592) (xy 384.928879 -246.142768)
			(xy 384.912811 -246.196175) (xy 384.889139 -246.246672) (xy 384.858366 -246.293185) (xy 384.821149 -246.334722)
			(xy 384.778281 -246.370397) (xy 384.730675 -246.399451) (xy 384.679346 -246.421263) (xy 384.625389 -246.435369)
			(xy 384.569952 -246.441469) (xy 384.514218 -246.439432) (xy 384.459375 -246.429302) (xy 384.406591 -246.411295)
			(xy 384.356991 -246.385794) (xy 384.311633 -246.353343) (xy 384.271484 -246.314634) (xy 384.237398 -246.270491)
			(xy 384.210102 -246.221856) (xy 384.190179 -246.169765) (xy 384.178053 -246.115328) (xy 384.173982 -246.059706)
			(xy 375.92233 -246.059706) (xy 375.938065 -246.069309) (xy 375.980933 -246.104984) (xy 376.01815 -246.146521)
			(xy 376.048923 -246.193034) (xy 376.072595 -246.243531) (xy 376.088663 -246.296938) (xy 376.096783 -246.352114)
			(xy 376.097292 -246.38) (xy 376.096783 -246.407886) (xy 376.088663 -246.463062) (xy 376.072595 -246.516469)
			(xy 376.048923 -246.566966) (xy 376.01815 -246.613479) (xy 375.980933 -246.655016) (xy 375.938065 -246.690691)
			(xy 375.890459 -246.719745) (xy 375.83913 -246.741557) (xy 375.785173 -246.755663) (xy 375.729736 -246.761763)
			(xy 375.674002 -246.759726) (xy 375.619159 -246.749596) (xy 375.566375 -246.731589) (xy 375.516775 -246.706088)
			(xy 375.471417 -246.673637) (xy 375.431268 -246.634928) (xy 375.397182 -246.590785) (xy 375.369886 -246.54215)
			(xy 375.349963 -246.490059) (xy 375.337837 -246.435622) (xy 375.333766 -246.38) (xy 361.790488 -246.38)
			(xy 361.790488 -247.441974) (xy 372.616982 -247.441974) (xy 372.621053 -247.386352) (xy 372.633179 -247.331915)
			(xy 372.653102 -247.279824) (xy 372.680398 -247.231189) (xy 372.714484 -247.187046) (xy 372.754633 -247.148337)
			(xy 372.799991 -247.115886) (xy 372.849591 -247.090385) (xy 372.902375 -247.072378) (xy 372.957218 -247.062248)
			(xy 373.012952 -247.060211) (xy 373.068389 -247.066311) (xy 373.122346 -247.080417) (xy 373.173675 -247.102229)
			(xy 373.221281 -247.131283) (xy 373.264149 -247.166958) (xy 373.301366 -247.208495) (xy 373.332139 -247.255008)
			(xy 373.355811 -247.305505) (xy 373.371879 -247.358912) (xy 373.379999 -247.414088) (xy 373.380508 -247.441974)
			(xy 373.379999 -247.46986) (xy 373.371879 -247.525036) (xy 373.355811 -247.578443) (xy 373.332139 -247.62894)
			(xy 373.307451 -247.666256) (xy 375.643138 -247.666256) (xy 375.647209 -247.610634) (xy 375.659335 -247.556197)
			(xy 375.679258 -247.504106) (xy 375.706554 -247.455471) (xy 375.74064 -247.411328) (xy 375.780789 -247.372619)
			(xy 375.826147 -247.340168) (xy 375.875747 -247.314667) (xy 375.928531 -247.29666) (xy 375.983374 -247.28653)
			(xy 376.039108 -247.284493) (xy 376.094545 -247.290593) (xy 376.148502 -247.304699) (xy 376.199831 -247.326511)
			(xy 376.247437 -247.355565) (xy 376.26123 -247.367044) (xy 376.865386 -247.367044) (xy 376.869457 -247.311422)
			(xy 376.881583 -247.256985) (xy 376.901506 -247.204894) (xy 376.928802 -247.156259) (xy 376.962888 -247.112116)
			(xy 377.003037 -247.073407) (xy 377.048395 -247.040956) (xy 377.097995 -247.015455) (xy 377.150779 -246.997448)
			(xy 377.205622 -246.987318) (xy 377.261356 -246.985281) (xy 377.316793 -246.991381) (xy 377.37075 -247.005487)
			(xy 377.393136 -247.015) (xy 377.950982 -247.015) (xy 377.955053 -246.959378) (xy 377.967179 -246.904941)
			(xy 377.987102 -246.85285) (xy 378.014398 -246.804215) (xy 378.048484 -246.760072) (xy 378.088633 -246.721363)
			(xy 378.133991 -246.688912) (xy 378.183591 -246.663411) (xy 378.236375 -246.645404) (xy 378.291218 -246.635274)
			(xy 378.346952 -246.633237) (xy 378.402389 -246.639337) (xy 378.456346 -246.653443) (xy 378.507675 -246.675255)
			(xy 378.555281 -246.704309) (xy 378.598149 -246.739984) (xy 378.635366 -246.781521) (xy 378.666139 -246.828034)
			(xy 378.689811 -246.878531) (xy 378.705879 -246.931938) (xy 378.713999 -246.987114) (xy 378.714508 -247.015)
			(xy 379.474982 -247.015) (xy 379.479053 -246.959378) (xy 379.491179 -246.904941) (xy 379.511102 -246.85285)
			(xy 379.538398 -246.804215) (xy 379.572484 -246.760072) (xy 379.612633 -246.721363) (xy 379.657991 -246.688912)
			(xy 379.707591 -246.663411) (xy 379.760375 -246.645404) (xy 379.815218 -246.635274) (xy 379.870952 -246.633237)
			(xy 379.926389 -246.639337) (xy 379.980346 -246.653443) (xy 380.031675 -246.675255) (xy 380.079281 -246.704309)
			(xy 380.122149 -246.739984) (xy 380.159366 -246.781521) (xy 380.190139 -246.828034) (xy 380.213811 -246.878531)
			(xy 380.229879 -246.931938) (xy 380.237999 -246.987114) (xy 380.238508 -247.015) (xy 380.237999 -247.042886)
			(xy 380.229879 -247.098062) (xy 380.213811 -247.151469) (xy 380.190139 -247.201966) (xy 380.159366 -247.248479)
			(xy 380.122149 -247.290016) (xy 380.079281 -247.325691) (xy 380.072286 -247.32996) (xy 383.345942 -247.32996)
			(xy 383.350013 -247.274338) (xy 383.362139 -247.219901) (xy 383.382062 -247.16781) (xy 383.409358 -247.119175)
			(xy 383.443444 -247.075032) (xy 383.483593 -247.036323) (xy 383.528951 -247.003872) (xy 383.578551 -246.978371)
			(xy 383.631335 -246.960364) (xy 383.686178 -246.950234) (xy 383.741912 -246.948197) (xy 383.797349 -246.954297)
			(xy 383.851306 -246.968403) (xy 383.902635 -246.990215) (xy 383.950241 -247.019269) (xy 383.993109 -247.054944)
			(xy 384.030326 -247.096481) (xy 384.061099 -247.142994) (xy 384.084771 -247.193491) (xy 384.100839 -247.246898)
			(xy 384.108959 -247.302074) (xy 384.109468 -247.32996) (xy 384.108959 -247.357846) (xy 384.100839 -247.413022)
			(xy 384.084771 -247.466429) (xy 384.079327 -247.478042) (xy 386.969762 -247.478042) (xy 386.970356 -247.449365)
			(xy 386.978948 -247.392658) (xy 386.995932 -247.337876) (xy 387.020923 -247.286253) (xy 387.053359 -247.238952)
			(xy 387.092509 -247.197038) (xy 387.137492 -247.161456) (xy 387.187293 -247.133007) (xy 387.213856 -247.122188)
			(xy 387.226556 -247.117362) (xy 387.24332 -247.09628) (xy 387.261608 -246.982488) (xy 387.251956 -246.957342)
			(xy 387.241288 -246.948706) (xy 387.219753 -246.930495) (xy 387.181785 -246.888795) (xy 387.150376 -246.841955)
			(xy 387.126213 -246.790998) (xy 387.109822 -246.737036) (xy 387.101563 -246.681248) (xy 387.10108 -246.65305)
			(xy 387.101622 -246.623751) (xy 387.110564 -246.565839) (xy 387.128261 -246.509977) (xy 387.154295 -246.45748)
			(xy 387.188055 -246.409584) (xy 387.208014 -246.388128) (xy 387.214618 -246.38127) (xy 387.221984 -246.363744)
			(xy 387.224016 -246.275606) (xy 387.217666 -246.257826) (xy 387.211316 -246.250714) (xy 387.19355 -246.22972)
			(xy 387.163594 -246.183599) (xy 387.140567 -246.133655) (xy 387.124946 -246.080925) (xy 387.117054 -246.026498)
			(xy 387.116574 -245.999) (xy 387.11706 -245.971749) (xy 387.124816 -245.917801) (xy 387.140171 -245.865506)
			(xy 387.162813 -245.815929) (xy 387.192279 -245.770079) (xy 387.22797 -245.728888) (xy 387.269161 -245.693197)
			(xy 387.315011 -245.663731) (xy 387.364588 -245.641089) (xy 387.416883 -245.625734) (xy 387.470831 -245.617978)
			(xy 387.525333 -245.617978) (xy 387.579281 -245.625734) (xy 387.631576 -245.641089) (xy 387.681153 -245.663731)
			(xy 387.727003 -245.693197) (xy 387.768194 -245.728888) (xy 387.803885 -245.770079) (xy 387.833351 -245.815929)
			(xy 387.855993 -245.865506) (xy 387.871348 -245.917801) (xy 387.879104 -245.971749) (xy 387.87959 -245.999)
			(xy 387.879088 -246.028301) (xy 387.870137 -246.086215) (xy 387.852432 -246.142078) (xy 387.826388 -246.194574)
			(xy 387.792619 -246.242468) (xy 387.772656 -246.263922) (xy 387.766052 -246.27078) (xy 387.758686 -246.288306)
			(xy 387.756654 -246.376444) (xy 387.763004 -246.394224) (xy 387.769354 -246.401336) (xy 387.787139 -246.422314)
			(xy 387.817093 -246.46844) (xy 387.840117 -246.518387) (xy 387.855733 -246.571121) (xy 387.86362 -246.625551)
			(xy 387.864096 -246.65305) (xy 387.863608 -246.681731) (xy 387.855001 -246.738444) (xy 387.838003 -246.79323)
			(xy 387.812996 -246.844855) (xy 387.780546 -246.892156) (xy 387.741381 -246.934068) (xy 387.696385 -246.969646)
			(xy 387.646571 -246.998089) (xy 387.620002 -247.008904) (xy 387.607302 -247.01373) (xy 387.590538 -247.034812)
			(xy 387.57225 -247.148604) (xy 387.581902 -247.17375) (xy 387.59257 -247.182386) (xy 387.614092 -247.200611)
			(xy 387.652064 -247.242307) (xy 387.683475 -247.289144) (xy 387.707641 -247.340098) (xy 387.724033 -247.394058)
			(xy 387.732295 -247.449844) (xy 387.732778 -247.478042) (xy 387.732292 -247.505293) (xy 387.724536 -247.559241)
			(xy 387.709181 -247.611536) (xy 387.686539 -247.661113) (xy 387.657073 -247.706963) (xy 387.621382 -247.748154)
			(xy 387.580191 -247.783845) (xy 387.534341 -247.813311) (xy 387.484764 -247.835953) (xy 387.432469 -247.851308)
			(xy 387.378521 -247.859064) (xy 387.324019 -247.859064) (xy 387.270071 -247.851308) (xy 387.217776 -247.835953)
			(xy 387.168199 -247.813311) (xy 387.122349 -247.783845) (xy 387.081158 -247.748154) (xy 387.045467 -247.706963)
			(xy 387.016001 -247.661113) (xy 386.993359 -247.611536) (xy 386.978004 -247.559241) (xy 386.970248 -247.505293)
			(xy 386.969762 -247.478042) (xy 384.079327 -247.478042) (xy 384.061099 -247.516926) (xy 384.030326 -247.563439)
			(xy 383.993109 -247.604976) (xy 383.950241 -247.640651) (xy 383.902635 -247.669705) (xy 383.851306 -247.691517)
			(xy 383.797349 -247.705623) (xy 383.741912 -247.711723) (xy 383.686178 -247.709686) (xy 383.631335 -247.699556)
			(xy 383.578551 -247.681549) (xy 383.528951 -247.656048) (xy 383.483593 -247.623597) (xy 383.443444 -247.584888)
			(xy 383.409358 -247.540745) (xy 383.382062 -247.49211) (xy 383.362139 -247.440019) (xy 383.350013 -247.385582)
			(xy 383.345942 -247.32996) (xy 380.072286 -247.32996) (xy 380.031675 -247.354745) (xy 379.980346 -247.376557)
			(xy 379.926389 -247.390663) (xy 379.870952 -247.396763) (xy 379.815218 -247.394726) (xy 379.760375 -247.384596)
			(xy 379.707591 -247.366589) (xy 379.657991 -247.341088) (xy 379.612633 -247.308637) (xy 379.572484 -247.269928)
			(xy 379.538398 -247.225785) (xy 379.511102 -247.17715) (xy 379.491179 -247.125059) (xy 379.479053 -247.070622)
			(xy 379.474982 -247.015) (xy 378.714508 -247.015) (xy 378.713999 -247.042886) (xy 378.705879 -247.098062)
			(xy 378.689811 -247.151469) (xy 378.666139 -247.201966) (xy 378.635366 -247.248479) (xy 378.598149 -247.290016)
			(xy 378.555281 -247.325691) (xy 378.507675 -247.354745) (xy 378.456346 -247.376557) (xy 378.402389 -247.390663)
			(xy 378.346952 -247.396763) (xy 378.291218 -247.394726) (xy 378.236375 -247.384596) (xy 378.183591 -247.366589)
			(xy 378.133991 -247.341088) (xy 378.088633 -247.308637) (xy 378.048484 -247.269928) (xy 378.014398 -247.225785)
			(xy 377.987102 -247.17715) (xy 377.967179 -247.125059) (xy 377.955053 -247.070622) (xy 377.950982 -247.015)
			(xy 377.393136 -247.015) (xy 377.422079 -247.027299) (xy 377.469685 -247.056353) (xy 377.512553 -247.092028)
			(xy 377.54977 -247.133565) (xy 377.580543 -247.180078) (xy 377.604215 -247.230575) (xy 377.620283 -247.283982)
			(xy 377.628403 -247.339158) (xy 377.628912 -247.367044) (xy 377.628403 -247.39493) (xy 377.620283 -247.450106)
			(xy 377.604215 -247.503513) (xy 377.580543 -247.55401) (xy 377.57518 -247.562116) (xy 378.728222 -247.562116)
			(xy 378.732293 -247.506494) (xy 378.744419 -247.452057) (xy 378.764342 -247.399966) (xy 378.791638 -247.351331)
			(xy 378.825724 -247.307188) (xy 378.865873 -247.268479) (xy 378.911231 -247.236028) (xy 378.960831 -247.210527)
			(xy 379.013615 -247.19252) (xy 379.068458 -247.18239) (xy 379.124192 -247.180353) (xy 379.179629 -247.186453)
			(xy 379.233586 -247.200559) (xy 379.284915 -247.222371) (xy 379.332521 -247.251425) (xy 379.375389 -247.2871)
			(xy 379.412606 -247.328637) (xy 379.443379 -247.37515) (xy 379.467051 -247.425647) (xy 379.483119 -247.479054)
			(xy 379.491239 -247.53423) (xy 379.491748 -247.562116) (xy 379.491239 -247.590002) (xy 379.483119 -247.645178)
			(xy 379.467051 -247.698585) (xy 379.443379 -247.749082) (xy 379.434487 -247.762522) (xy 380.357124 -247.762522)
			(xy 380.361195 -247.7069) (xy 380.373321 -247.652463) (xy 380.393244 -247.600372) (xy 380.42054 -247.551737)
			(xy 380.454626 -247.507594) (xy 380.494775 -247.468885) (xy 380.540133 -247.436434) (xy 380.589733 -247.410933)
			(xy 380.642517 -247.392926) (xy 380.69736 -247.382796) (xy 380.753094 -247.380759) (xy 380.808531 -247.386859)
			(xy 380.862488 -247.400965) (xy 380.913817 -247.422777) (xy 380.961423 -247.451831) (xy 381.004291 -247.487506)
			(xy 381.041508 -247.529043) (xy 381.072281 -247.575556) (xy 381.095953 -247.626053) (xy 381.112021 -247.67946)
			(xy 381.120141 -247.734636) (xy 381.12065 -247.762522) (xy 381.120141 -247.790408) (xy 381.112021 -247.845584)
			(xy 381.095953 -247.898991) (xy 381.072281 -247.949488) (xy 381.041508 -247.996001) (xy 381.004291 -248.037538)
			(xy 380.961423 -248.073213) (xy 380.913817 -248.102267) (xy 380.862488 -248.124079) (xy 380.808531 -248.138185)
			(xy 380.753094 -248.144285) (xy 380.69736 -248.142248) (xy 380.642517 -248.132118) (xy 380.589733 -248.114111)
			(xy 380.540133 -248.08861) (xy 380.494775 -248.056159) (xy 380.454626 -248.01745) (xy 380.42054 -247.973307)
			(xy 380.393244 -247.924672) (xy 380.373321 -247.872581) (xy 380.361195 -247.818144) (xy 380.357124 -247.762522)
			(xy 379.434487 -247.762522) (xy 379.412606 -247.795595) (xy 379.375389 -247.837132) (xy 379.332521 -247.872807)
			(xy 379.284915 -247.901861) (xy 379.233586 -247.923673) (xy 379.179629 -247.937779) (xy 379.124192 -247.943879)
			(xy 379.068458 -247.941842) (xy 379.013615 -247.931712) (xy 378.960831 -247.913705) (xy 378.911231 -247.888204)
			(xy 378.865873 -247.855753) (xy 378.825724 -247.817044) (xy 378.791638 -247.772901) (xy 378.764342 -247.724266)
			(xy 378.744419 -247.672175) (xy 378.732293 -247.617738) (xy 378.728222 -247.562116) (xy 377.57518 -247.562116)
			(xy 377.54977 -247.600523) (xy 377.512553 -247.64206) (xy 377.469685 -247.677735) (xy 377.422079 -247.706789)
			(xy 377.37075 -247.728601) (xy 377.316793 -247.742707) (xy 377.261356 -247.748807) (xy 377.205622 -247.74677)
			(xy 377.150779 -247.73664) (xy 377.097995 -247.718633) (xy 377.048395 -247.693132) (xy 377.003037 -247.660681)
			(xy 376.962888 -247.621972) (xy 376.928802 -247.577829) (xy 376.901506 -247.529194) (xy 376.881583 -247.477103)
			(xy 376.869457 -247.422666) (xy 376.865386 -247.367044) (xy 376.26123 -247.367044) (xy 376.290305 -247.39124)
			(xy 376.327522 -247.432777) (xy 376.358295 -247.47929) (xy 376.381967 -247.529787) (xy 376.398035 -247.583194)
			(xy 376.406155 -247.63837) (xy 376.406664 -247.666256) (xy 376.406155 -247.694142) (xy 376.398035 -247.749318)
			(xy 376.381967 -247.802725) (xy 376.358295 -247.853222) (xy 376.327522 -247.899735) (xy 376.290305 -247.941272)
			(xy 376.247437 -247.976947) (xy 376.199831 -248.006001) (xy 376.148502 -248.027813) (xy 376.094545 -248.041919)
			(xy 376.039108 -248.048019) (xy 375.983374 -248.045982) (xy 375.928531 -248.035852) (xy 375.875747 -248.017845)
			(xy 375.826147 -247.992344) (xy 375.780789 -247.959893) (xy 375.74064 -247.921184) (xy 375.706554 -247.877041)
			(xy 375.679258 -247.828406) (xy 375.659335 -247.776315) (xy 375.647209 -247.721878) (xy 375.643138 -247.666256)
			(xy 373.307451 -247.666256) (xy 373.301366 -247.675453) (xy 373.264149 -247.71699) (xy 373.221281 -247.752665)
			(xy 373.173675 -247.781719) (xy 373.122346 -247.803531) (xy 373.068389 -247.817637) (xy 373.012952 -247.823737)
			(xy 372.957218 -247.8217) (xy 372.902375 -247.81157) (xy 372.849591 -247.793563) (xy 372.799991 -247.768062)
			(xy 372.754633 -247.735611) (xy 372.714484 -247.696902) (xy 372.680398 -247.652759) (xy 372.653102 -247.604124)
			(xy 372.633179 -247.552033) (xy 372.621053 -247.497596) (xy 372.616982 -247.441974) (xy 361.790488 -247.441974)
			(xy 361.790488 -248.012712) (xy 361.790913 -248.022782) (xy 361.798629 -248.041384) (xy 361.805474 -248.04878)
			(xy 362.42498 -248.668286) (xy 365.238538 -248.668286) (xy 365.239084 -248.639586) (xy 365.247657 -248.58283)
			(xy 365.264638 -248.528) (xy 365.289643 -248.476333) (xy 365.322108 -248.428997) (xy 365.361299 -248.387059)
			(xy 365.406332 -248.351468) (xy 365.456189 -248.323026) (xy 365.509746 -248.302376) (xy 365.565792 -248.289984)
			(xy 365.594392 -248.28754) (xy 365.606343 -248.286023) (xy 365.627013 -248.273718) (xy 365.634016 -248.263918)
			(xy 365.684054 -248.184162) (xy 365.68634 -248.160286) (xy 365.681768 -248.148856) (xy 365.673234 -248.126389)
			(xy 365.661245 -248.079849) (xy 365.655206 -248.03217) (xy 365.654844 -248.00814) (xy 365.654844 -248.007886)
			(xy 365.65533 -247.980635) (xy 365.663086 -247.926687) (xy 365.678441 -247.874392) (xy 365.701083 -247.824815)
			(xy 365.730549 -247.778965) (xy 365.76624 -247.737774) (xy 365.807431 -247.702083) (xy 365.853281 -247.672617)
			(xy 365.902858 -247.649975) (xy 365.955153 -247.63462) (xy 366.009101 -247.626864) (xy 366.063603 -247.626864)
			(xy 366.117551 -247.63462) (xy 366.169846 -247.649975) (xy 366.219423 -247.672617) (xy 366.265273 -247.702083)
			(xy 366.306464 -247.737774) (xy 366.342155 -247.778965) (xy 366.371621 -247.824815) (xy 366.394263 -247.874392)
			(xy 366.409618 -247.926687) (xy 366.416472 -247.974358) (xy 369.78539 -247.974358) (xy 369.789461 -247.918736)
			(xy 369.801587 -247.864299) (xy 369.82151 -247.812208) (xy 369.848806 -247.763573) (xy 369.882892 -247.71943)
			(xy 369.923041 -247.680721) (xy 369.968399 -247.64827) (xy 370.017999 -247.622769) (xy 370.070783 -247.604762)
			(xy 370.125626 -247.594632) (xy 370.18136 -247.592595) (xy 370.236797 -247.598695) (xy 370.290754 -247.612801)
			(xy 370.342083 -247.634613) (xy 370.389689 -247.663667) (xy 370.432557 -247.699342) (xy 370.469774 -247.740879)
			(xy 370.500547 -247.787392) (xy 370.524219 -247.837889) (xy 370.540287 -247.891296) (xy 370.548407 -247.946472)
			(xy 370.548916 -247.974358) (xy 370.548407 -248.002244) (xy 370.540287 -248.05742) (xy 370.524219 -248.110827)
			(xy 370.500547 -248.161324) (xy 370.469774 -248.207837) (xy 370.432557 -248.249374) (xy 370.389689 -248.285049)
			(xy 370.342083 -248.314103) (xy 370.328681 -248.319798) (xy 385.663184 -248.319798) (xy 385.667255 -248.264176)
			(xy 385.679381 -248.209739) (xy 385.699304 -248.157648) (xy 385.7266 -248.109013) (xy 385.760686 -248.06487)
			(xy 385.800835 -248.026161) (xy 385.846193 -247.99371) (xy 385.895793 -247.968209) (xy 385.948577 -247.950202)
			(xy 386.00342 -247.940072) (xy 386.059154 -247.938035) (xy 386.114591 -247.944135) (xy 386.168548 -247.958241)
			(xy 386.219877 -247.980053) (xy 386.267483 -248.009107) (xy 386.310351 -248.044782) (xy 386.347568 -248.086319)
			(xy 386.378341 -248.132832) (xy 386.402013 -248.183329) (xy 386.418081 -248.236736) (xy 386.426201 -248.291912)
			(xy 386.42671 -248.319798) (xy 386.426201 -248.347684) (xy 386.418081 -248.40286) (xy 386.402013 -248.456267)
			(xy 386.378341 -248.506764) (xy 386.347568 -248.553277) (xy 386.310351 -248.594814) (xy 386.267483 -248.630489)
			(xy 386.219877 -248.659543) (xy 386.168548 -248.681355) (xy 386.114591 -248.695461) (xy 386.059154 -248.701561)
			(xy 386.00342 -248.699524) (xy 385.948577 -248.689394) (xy 385.895793 -248.671387) (xy 385.846193 -248.645886)
			(xy 385.800835 -248.613435) (xy 385.760686 -248.574726) (xy 385.7266 -248.530583) (xy 385.699304 -248.481948)
			(xy 385.679381 -248.429857) (xy 385.667255 -248.37542) (xy 385.663184 -248.319798) (xy 370.328681 -248.319798)
			(xy 370.290754 -248.335915) (xy 370.236797 -248.350021) (xy 370.18136 -248.356121) (xy 370.125626 -248.354084)
			(xy 370.070783 -248.343954) (xy 370.017999 -248.325947) (xy 369.968399 -248.300446) (xy 369.923041 -248.267995)
			(xy 369.882892 -248.229286) (xy 369.848806 -248.185143) (xy 369.82151 -248.136508) (xy 369.801587 -248.084417)
			(xy 369.789461 -248.02998) (xy 369.78539 -247.974358) (xy 366.416472 -247.974358) (xy 366.417374 -247.980635)
			(xy 366.41786 -248.007886) (xy 366.41729 -248.036585) (xy 366.408721 -248.09334) (xy 366.391743 -248.14817)
			(xy 366.366741 -248.199837) (xy 366.33428 -248.247174) (xy 366.295091 -248.289112) (xy 366.25006 -248.324703)
			(xy 366.200205 -248.353146) (xy 366.14665 -248.373796) (xy 366.090605 -248.386188) (xy 366.062006 -248.388632)
			(xy 366.050058 -248.390159) (xy 366.029387 -248.402458) (xy 366.022382 -248.412254) (xy 365.972344 -248.49201)
			(xy 365.970058 -248.515886) (xy 365.97463 -248.527316) (xy 365.983155 -248.549786) (xy 365.995148 -248.596324)
			(xy 366.00119 -248.644002) (xy 366.001554 -248.668032) (xy 366.001554 -248.668286) (xy 366.00091 -248.699659)
			(xy 365.990636 -248.761558) (xy 365.970377 -248.820943) (xy 365.956088 -248.84888) (xy 365.952544 -248.855484)
			(xy 372.001286 -248.855484) (xy 372.005357 -248.799862) (xy 372.017483 -248.745425) (xy 372.037406 -248.693334)
			(xy 372.064702 -248.644699) (xy 372.098788 -248.600556) (xy 372.138937 -248.561847) (xy 372.184295 -248.529396)
			(xy 372.233895 -248.503895) (xy 372.286679 -248.485888) (xy 372.341522 -248.475758) (xy 372.397256 -248.473721)
			(xy 372.452693 -248.479821) (xy 372.50665 -248.493927) (xy 372.557979 -248.515739) (xy 372.605585 -248.544793)
			(xy 372.648453 -248.580468) (xy 372.68567 -248.622005) (xy 372.716443 -248.668518) (xy 372.740115 -248.719015)
			(xy 372.756183 -248.772422) (xy 372.764303 -248.827598) (xy 372.764812 -248.855484) (xy 372.764303 -248.88337)
			(xy 372.756183 -248.938546) (xy 372.740289 -248.991374) (xy 386.705346 -248.991374) (xy 386.709417 -248.935752)
			(xy 386.721543 -248.881315) (xy 386.741466 -248.829224) (xy 386.768762 -248.780589) (xy 386.802848 -248.736446)
			(xy 386.842997 -248.697737) (xy 386.888355 -248.665286) (xy 386.937955 -248.639785) (xy 386.990739 -248.621778)
			(xy 387.045582 -248.611648) (xy 387.101316 -248.609611) (xy 387.156753 -248.615711) (xy 387.21071 -248.629817)
			(xy 387.262039 -248.651629) (xy 387.309645 -248.680683) (xy 387.352513 -248.716358) (xy 387.38973 -248.757895)
			(xy 387.420503 -248.804408) (xy 387.444175 -248.854905) (xy 387.460091 -248.907808) (xy 388.388858 -248.907808)
			(xy 388.392929 -248.852186) (xy 388.405055 -248.797749) (xy 388.424978 -248.745658) (xy 388.452274 -248.697023)
			(xy 388.48636 -248.65288) (xy 388.526509 -248.614171) (xy 388.571867 -248.58172) (xy 388.621467 -248.556219)
			(xy 388.674251 -248.538212) (xy 388.729094 -248.528082) (xy 388.784828 -248.526045) (xy 388.840265 -248.532145)
			(xy 388.894222 -248.546251) (xy 388.945551 -248.568063) (xy 388.993157 -248.597117) (xy 389.036025 -248.632792)
			(xy 389.073242 -248.674329) (xy 389.104015 -248.720842) (xy 389.127687 -248.771339) (xy 389.143755 -248.824746)
			(xy 389.151875 -248.879922) (xy 389.152384 -248.907808) (xy 389.151875 -248.935694) (xy 389.143755 -248.99087)
			(xy 389.127687 -249.044277) (xy 389.104015 -249.094774) (xy 389.073242 -249.141287) (xy 389.036025 -249.182824)
			(xy 388.993157 -249.218499) (xy 388.945551 -249.247553) (xy 388.894222 -249.269365) (xy 388.840265 -249.283471)
			(xy 388.784828 -249.289571) (xy 388.729094 -249.287534) (xy 388.674251 -249.277404) (xy 388.621467 -249.259397)
			(xy 388.571867 -249.233896) (xy 388.526509 -249.201445) (xy 388.48636 -249.162736) (xy 388.452274 -249.118593)
			(xy 388.424978 -249.069958) (xy 388.405055 -249.017867) (xy 388.392929 -248.96343) (xy 388.388858 -248.907808)
			(xy 387.460091 -248.907808) (xy 387.460243 -248.908312) (xy 387.468363 -248.963488) (xy 387.468872 -248.991374)
			(xy 387.468363 -249.01926) (xy 387.460243 -249.074436) (xy 387.444175 -249.127843) (xy 387.420503 -249.17834)
			(xy 387.38973 -249.224853) (xy 387.352513 -249.26639) (xy 387.309645 -249.302065) (xy 387.262039 -249.331119)
			(xy 387.21071 -249.352931) (xy 387.156753 -249.367037) (xy 387.101316 -249.373137) (xy 387.045582 -249.3711)
			(xy 386.990739 -249.36097) (xy 386.937955 -249.342963) (xy 386.888355 -249.317462) (xy 386.842997 -249.285011)
			(xy 386.802848 -249.246302) (xy 386.768762 -249.202159) (xy 386.741466 -249.153524) (xy 386.721543 -249.101433)
			(xy 386.709417 -249.046996) (xy 386.705346 -248.991374) (xy 372.740289 -248.991374) (xy 372.740115 -248.991953)
			(xy 372.716443 -249.04245) (xy 372.68567 -249.088963) (xy 372.648453 -249.1305) (xy 372.605585 -249.166175)
			(xy 372.557979 -249.195229) (xy 372.50665 -249.217041) (xy 372.452693 -249.231147) (xy 372.397256 -249.237247)
			(xy 372.341522 -249.23521) (xy 372.286679 -249.22508) (xy 372.233895 -249.207073) (xy 372.184295 -249.181572)
			(xy 372.138937 -249.149121) (xy 372.098788 -249.110412) (xy 372.064702 -249.066269) (xy 372.037406 -249.017634)
			(xy 372.017483 -248.965543) (xy 372.005357 -248.911106) (xy 372.001286 -248.855484) (xy 365.952544 -248.855484)
			(xy 365.9505 -248.859294) (xy 365.949738 -248.882916) (xy 365.992918 -248.978166) (xy 366.011206 -248.993152)
			(xy 366.02289 -248.995946) (xy 366.050582 -249.002858) (xy 366.103705 -249.023723) (xy 366.153124 -249.052271)
			(xy 366.197738 -249.087864) (xy 366.236551 -249.129708) (xy 366.268695 -249.176868) (xy 366.293452 -249.228292)
			(xy 366.310271 -249.28283) (xy 366.318775 -249.339266) (xy 366.319308 -249.367802) (xy 366.318822 -249.395053)
			(xy 366.311066 -249.449001) (xy 366.295711 -249.501296) (xy 366.273069 -249.550873) (xy 366.243603 -249.596723)
			(xy 366.207912 -249.637914) (xy 366.166721 -249.673605) (xy 366.120871 -249.703071) (xy 366.071294 -249.725713)
			(xy 366.018999 -249.741068) (xy 365.965051 -249.748824) (xy 365.910549 -249.748824) (xy 365.856601 -249.741068)
			(xy 365.804306 -249.725713) (xy 365.754729 -249.703071) (xy 365.708879 -249.673605) (xy 365.667688 -249.637914)
			(xy 365.631997 -249.596723) (xy 365.602531 -249.550873) (xy 365.579889 -249.501296) (xy 365.564534 -249.449001)
			(xy 365.556778 -249.395053) (xy 365.556292 -249.367802) (xy 365.556926 -249.336429) (xy 365.567204 -249.274529)
			(xy 365.587466 -249.215144) (xy 365.601758 -249.187208) (xy 365.607346 -249.176794) (xy 365.608108 -249.153172)
			(xy 365.564928 -249.057922) (xy 365.54664 -249.042936) (xy 365.534956 -249.040142) (xy 365.507251 -249.033279)
			(xy 365.454128 -249.012405) (xy 365.404709 -248.98385) (xy 365.360096 -248.948249) (xy 365.321286 -248.9064)
			(xy 365.289144 -248.859234) (xy 365.264388 -248.807806) (xy 365.247572 -248.753263) (xy 365.239069 -248.696824)
			(xy 365.238538 -248.668286) (xy 362.42498 -248.668286) (xy 363.041692 -249.284998) (xy 363.852966 -249.284998)
			(xy 363.857037 -249.229376) (xy 363.869163 -249.174939) (xy 363.889086 -249.122848) (xy 363.916382 -249.074213)
			(xy 363.950468 -249.03007) (xy 363.990617 -248.991361) (xy 364.035975 -248.95891) (xy 364.085575 -248.933409)
			(xy 364.138359 -248.915402) (xy 364.193202 -248.905272) (xy 364.248936 -248.903235) (xy 364.304373 -248.909335)
			(xy 364.35833 -248.923441) (xy 364.409659 -248.945253) (xy 364.457265 -248.974307) (xy 364.500133 -249.009982)
			(xy 364.53735 -249.051519) (xy 364.568123 -249.098032) (xy 364.591795 -249.148529) (xy 364.607863 -249.201936)
			(xy 364.615983 -249.257112) (xy 364.616492 -249.284998) (xy 364.615983 -249.312884) (xy 364.607863 -249.36806)
			(xy 364.591795 -249.421467) (xy 364.568123 -249.471964) (xy 364.53735 -249.518477) (xy 364.500133 -249.560014)
			(xy 364.457265 -249.595689) (xy 364.409659 -249.624743) (xy 364.35833 -249.646555) (xy 364.304373 -249.660661)
			(xy 364.248936 -249.666761) (xy 364.193202 -249.664724) (xy 364.138359 -249.654594) (xy 364.085575 -249.636587)
			(xy 364.035975 -249.611086) (xy 363.990617 -249.578635) (xy 363.950468 -249.539926) (xy 363.916382 -249.495783)
			(xy 363.889086 -249.447148) (xy 363.869163 -249.395057) (xy 363.857037 -249.34062) (xy 363.852966 -249.284998)
			(xy 363.041692 -249.284998) (xy 365.072422 -251.315728) (xy 370.335808 -251.315728) (xy 370.339879 -251.260106)
			(xy 370.352005 -251.205669) (xy 370.371928 -251.153578) (xy 370.399224 -251.104943) (xy 370.43331 -251.0608)
			(xy 370.473459 -251.022091) (xy 370.518817 -250.98964) (xy 370.568417 -250.964139) (xy 370.621201 -250.946132)
			(xy 370.676044 -250.936002) (xy 370.731778 -250.933965) (xy 370.787215 -250.940065) (xy 370.841172 -250.954171)
			(xy 370.892501 -250.975983) (xy 370.940107 -251.005037) (xy 370.982975 -251.040712) (xy 371.020192 -251.082249)
			(xy 371.050965 -251.128762) (xy 371.064907 -251.158502) (xy 372.260366 -251.158502) (xy 372.264437 -251.10288)
			(xy 372.276563 -251.048443) (xy 372.296486 -250.996352) (xy 372.323782 -250.947717) (xy 372.357868 -250.903574)
			(xy 372.398017 -250.864865) (xy 372.443375 -250.832414) (xy 372.492975 -250.806913) (xy 372.545759 -250.788906)
			(xy 372.600602 -250.778776) (xy 372.656336 -250.776739) (xy 372.711773 -250.782839) (xy 372.76573 -250.796945)
			(xy 372.817059 -250.818757) (xy 372.864665 -250.847811) (xy 372.907533 -250.883486) (xy 372.94475 -250.925023)
			(xy 372.975523 -250.971536) (xy 372.999195 -251.022033) (xy 373.015263 -251.07544) (xy 373.023383 -251.130616)
			(xy 373.023892 -251.158502) (xy 373.327166 -251.158502) (xy 373.331237 -251.10288) (xy 373.343363 -251.048443)
			(xy 373.363286 -250.996352) (xy 373.390582 -250.947717) (xy 373.424668 -250.903574) (xy 373.464817 -250.864865)
			(xy 373.510175 -250.832414) (xy 373.559775 -250.806913) (xy 373.612559 -250.788906) (xy 373.667402 -250.778776)
			(xy 373.723136 -250.776739) (xy 373.778573 -250.782839) (xy 373.83253 -250.796945) (xy 373.883859 -250.818757)
			(xy 373.931465 -250.847811) (xy 373.974333 -250.883486) (xy 374.01155 -250.925023) (xy 374.042323 -250.971536)
			(xy 374.065995 -251.022033) (xy 374.082063 -251.07544) (xy 374.090183 -251.130616) (xy 374.090692 -251.158502)
			(xy 374.292366 -251.158502) (xy 374.296437 -251.10288) (xy 374.308563 -251.048443) (xy 374.328486 -250.996352)
			(xy 374.355782 -250.947717) (xy 374.389868 -250.903574) (xy 374.430017 -250.864865) (xy 374.475375 -250.832414)
			(xy 374.524975 -250.806913) (xy 374.577759 -250.788906) (xy 374.632602 -250.778776) (xy 374.688336 -250.776739)
			(xy 374.743773 -250.782839) (xy 374.79773 -250.796945) (xy 374.849059 -250.818757) (xy 374.896665 -250.847811)
			(xy 374.939533 -250.883486) (xy 374.97675 -250.925023) (xy 375.007523 -250.971536) (xy 375.031195 -251.022033)
			(xy 375.047263 -251.07544) (xy 375.055383 -251.130616) (xy 375.055892 -251.158502) (xy 375.308366 -251.158502)
			(xy 375.312437 -251.10288) (xy 375.324563 -251.048443) (xy 375.344486 -250.996352) (xy 375.371782 -250.947717)
			(xy 375.405868 -250.903574) (xy 375.446017 -250.864865) (xy 375.491375 -250.832414) (xy 375.540975 -250.806913)
			(xy 375.593759 -250.788906) (xy 375.648602 -250.778776) (xy 375.704336 -250.776739) (xy 375.759773 -250.782839)
			(xy 375.81373 -250.796945) (xy 375.865059 -250.818757) (xy 375.912665 -250.847811) (xy 375.955533 -250.883486)
			(xy 375.99275 -250.925023) (xy 376.023523 -250.971536) (xy 376.047195 -251.022033) (xy 376.063263 -251.07544)
			(xy 376.071383 -251.130616) (xy 376.071892 -251.158502) (xy 376.324366 -251.158502) (xy 376.328437 -251.10288)
			(xy 376.340563 -251.048443) (xy 376.360486 -250.996352) (xy 376.387782 -250.947717) (xy 376.421868 -250.903574)
			(xy 376.462017 -250.864865) (xy 376.507375 -250.832414) (xy 376.556975 -250.806913) (xy 376.609759 -250.788906)
			(xy 376.664602 -250.778776) (xy 376.720336 -250.776739) (xy 376.775773 -250.782839) (xy 376.82973 -250.796945)
			(xy 376.881059 -250.818757) (xy 376.928665 -250.847811) (xy 376.971533 -250.883486) (xy 377.00875 -250.925023)
			(xy 377.039523 -250.971536) (xy 377.063195 -251.022033) (xy 377.079263 -251.07544) (xy 377.087383 -251.130616)
			(xy 377.087892 -251.158502) (xy 377.340366 -251.158502) (xy 377.344437 -251.10288) (xy 377.356563 -251.048443)
			(xy 377.376486 -250.996352) (xy 377.403782 -250.947717) (xy 377.437868 -250.903574) (xy 377.478017 -250.864865)
			(xy 377.523375 -250.832414) (xy 377.572975 -250.806913) (xy 377.625759 -250.788906) (xy 377.680602 -250.778776)
			(xy 377.736336 -250.776739) (xy 377.791773 -250.782839) (xy 377.84573 -250.796945) (xy 377.897059 -250.818757)
			(xy 377.944665 -250.847811) (xy 377.987533 -250.883486) (xy 378.02475 -250.925023) (xy 378.055523 -250.971536)
			(xy 378.079195 -251.022033) (xy 378.095263 -251.07544) (xy 378.103383 -251.130616) (xy 378.103892 -251.158502)
			(xy 378.356366 -251.158502) (xy 378.360437 -251.10288) (xy 378.372563 -251.048443) (xy 378.392486 -250.996352)
			(xy 378.419782 -250.947717) (xy 378.453868 -250.903574) (xy 378.494017 -250.864865) (xy 378.539375 -250.832414)
			(xy 378.588975 -250.806913) (xy 378.641759 -250.788906) (xy 378.696602 -250.778776) (xy 378.752336 -250.776739)
			(xy 378.807773 -250.782839) (xy 378.86173 -250.796945) (xy 378.913059 -250.818757) (xy 378.960665 -250.847811)
			(xy 379.003533 -250.883486) (xy 379.04075 -250.925023) (xy 379.071523 -250.971536) (xy 379.095195 -251.022033)
			(xy 379.111263 -251.07544) (xy 379.119383 -251.130616) (xy 379.119892 -251.158502) (xy 379.372366 -251.158502)
			(xy 379.376437 -251.10288) (xy 379.388563 -251.048443) (xy 379.408486 -250.996352) (xy 379.435782 -250.947717)
			(xy 379.469868 -250.903574) (xy 379.510017 -250.864865) (xy 379.555375 -250.832414) (xy 379.604975 -250.806913)
			(xy 379.657759 -250.788906) (xy 379.712602 -250.778776) (xy 379.768336 -250.776739) (xy 379.823773 -250.782839)
			(xy 379.87773 -250.796945) (xy 379.929059 -250.818757) (xy 379.976665 -250.847811) (xy 380.019533 -250.883486)
			(xy 380.05675 -250.925023) (xy 380.087523 -250.971536) (xy 380.111195 -251.022033) (xy 380.127263 -251.07544)
			(xy 380.135383 -251.130616) (xy 380.135892 -251.158502) (xy 380.388366 -251.158502) (xy 380.392437 -251.10288)
			(xy 380.404563 -251.048443) (xy 380.424486 -250.996352) (xy 380.451782 -250.947717) (xy 380.485868 -250.903574)
			(xy 380.526017 -250.864865) (xy 380.571375 -250.832414) (xy 380.620975 -250.806913) (xy 380.673759 -250.788906)
			(xy 380.728602 -250.778776) (xy 380.784336 -250.776739) (xy 380.839773 -250.782839) (xy 380.89373 -250.796945)
			(xy 380.945059 -250.818757) (xy 380.992665 -250.847811) (xy 381.035533 -250.883486) (xy 381.07275 -250.925023)
			(xy 381.103523 -250.971536) (xy 381.127195 -251.022033) (xy 381.143263 -251.07544) (xy 381.151383 -251.130616)
			(xy 381.151892 -251.158502) (xy 381.404366 -251.158502) (xy 381.408437 -251.10288) (xy 381.420563 -251.048443)
			(xy 381.440486 -250.996352) (xy 381.467782 -250.947717) (xy 381.501868 -250.903574) (xy 381.542017 -250.864865)
			(xy 381.587375 -250.832414) (xy 381.636975 -250.806913) (xy 381.689759 -250.788906) (xy 381.744602 -250.778776)
			(xy 381.800336 -250.776739) (xy 381.855773 -250.782839) (xy 381.90973 -250.796945) (xy 381.961059 -250.818757)
			(xy 382.008665 -250.847811) (xy 382.051533 -250.883486) (xy 382.08875 -250.925023) (xy 382.119523 -250.971536)
			(xy 382.143195 -251.022033) (xy 382.159263 -251.07544) (xy 382.167383 -251.130616) (xy 382.167892 -251.158502)
			(xy 382.420366 -251.158502) (xy 382.424437 -251.10288) (xy 382.436563 -251.048443) (xy 382.456486 -250.996352)
			(xy 382.483782 -250.947717) (xy 382.517868 -250.903574) (xy 382.558017 -250.864865) (xy 382.603375 -250.832414)
			(xy 382.652975 -250.806913) (xy 382.705759 -250.788906) (xy 382.760602 -250.778776) (xy 382.816336 -250.776739)
			(xy 382.871773 -250.782839) (xy 382.92573 -250.796945) (xy 382.977059 -250.818757) (xy 383.024665 -250.847811)
			(xy 383.067533 -250.883486) (xy 383.10475 -250.925023) (xy 383.135523 -250.971536) (xy 383.159195 -251.022033)
			(xy 383.175263 -251.07544) (xy 383.183383 -251.130616) (xy 383.183892 -251.158502) (xy 383.436366 -251.158502)
			(xy 383.440437 -251.10288) (xy 383.452563 -251.048443) (xy 383.472486 -250.996352) (xy 383.499782 -250.947717)
			(xy 383.533868 -250.903574) (xy 383.574017 -250.864865) (xy 383.619375 -250.832414) (xy 383.668975 -250.806913)
			(xy 383.721759 -250.788906) (xy 383.776602 -250.778776) (xy 383.832336 -250.776739) (xy 383.887773 -250.782839)
			(xy 383.94173 -250.796945) (xy 383.993059 -250.818757) (xy 384.040665 -250.847811) (xy 384.083533 -250.883486)
			(xy 384.12075 -250.925023) (xy 384.151523 -250.971536) (xy 384.175195 -251.022033) (xy 384.191263 -251.07544)
			(xy 384.199383 -251.130616) (xy 384.199892 -251.158502) (xy 384.452366 -251.158502) (xy 384.456437 -251.10288)
			(xy 384.468563 -251.048443) (xy 384.488486 -250.996352) (xy 384.515782 -250.947717) (xy 384.549868 -250.903574)
			(xy 384.590017 -250.864865) (xy 384.635375 -250.832414) (xy 384.684975 -250.806913) (xy 384.737759 -250.788906)
			(xy 384.792602 -250.778776) (xy 384.848336 -250.776739) (xy 384.903773 -250.782839) (xy 384.95773 -250.796945)
			(xy 385.009059 -250.818757) (xy 385.056665 -250.847811) (xy 385.099533 -250.883486) (xy 385.13675 -250.925023)
			(xy 385.167523 -250.971536) (xy 385.191195 -251.022033) (xy 385.207263 -251.07544) (xy 385.215383 -251.130616)
			(xy 385.215892 -251.158502) (xy 385.468366 -251.158502) (xy 385.472437 -251.10288) (xy 385.484563 -251.048443)
			(xy 385.504486 -250.996352) (xy 385.531782 -250.947717) (xy 385.565868 -250.903574) (xy 385.606017 -250.864865)
			(xy 385.651375 -250.832414) (xy 385.700975 -250.806913) (xy 385.753759 -250.788906) (xy 385.808602 -250.778776)
			(xy 385.864336 -250.776739) (xy 385.919773 -250.782839) (xy 385.97373 -250.796945) (xy 386.025059 -250.818757)
			(xy 386.072665 -250.847811) (xy 386.115533 -250.883486) (xy 386.15275 -250.925023) (xy 386.183523 -250.971536)
			(xy 386.207195 -251.022033) (xy 386.223263 -251.07544) (xy 386.231383 -251.130616) (xy 386.231892 -251.158502)
			(xy 386.484366 -251.158502) (xy 386.488437 -251.10288) (xy 386.500563 -251.048443) (xy 386.520486 -250.996352)
			(xy 386.547782 -250.947717) (xy 386.581868 -250.903574) (xy 386.622017 -250.864865) (xy 386.667375 -250.832414)
			(xy 386.716975 -250.806913) (xy 386.769759 -250.788906) (xy 386.824602 -250.778776) (xy 386.880336 -250.776739)
			(xy 386.935773 -250.782839) (xy 386.98973 -250.796945) (xy 387.041059 -250.818757) (xy 387.088665 -250.847811)
			(xy 387.131533 -250.883486) (xy 387.16875 -250.925023) (xy 387.199523 -250.971536) (xy 387.223195 -251.022033)
			(xy 387.239263 -251.07544) (xy 387.247383 -251.130616) (xy 387.247892 -251.158502) (xy 388.516366 -251.158502)
			(xy 388.520437 -251.10288) (xy 388.532563 -251.048443) (xy 388.552486 -250.996352) (xy 388.579782 -250.947717)
			(xy 388.613868 -250.903574) (xy 388.654017 -250.864865) (xy 388.699375 -250.832414) (xy 388.748975 -250.806913)
			(xy 388.801759 -250.788906) (xy 388.856602 -250.778776) (xy 388.912336 -250.776739) (xy 388.967773 -250.782839)
			(xy 389.02173 -250.796945) (xy 389.073059 -250.818757) (xy 389.120665 -250.847811) (xy 389.163533 -250.883486)
			(xy 389.20075 -250.925023) (xy 389.231523 -250.971536) (xy 389.255195 -251.022033) (xy 389.271263 -251.07544)
			(xy 389.279383 -251.130616) (xy 389.279892 -251.158502) (xy 389.279383 -251.186388) (xy 389.271263 -251.241564)
			(xy 389.255195 -251.294971) (xy 389.231523 -251.345468) (xy 389.20075 -251.391981) (xy 389.163533 -251.433518)
			(xy 389.120665 -251.469193) (xy 389.073059 -251.498247) (xy 389.02173 -251.520059) (xy 388.967773 -251.534165)
			(xy 388.912336 -251.540265) (xy 388.856602 -251.538228) (xy 388.801759 -251.528098) (xy 388.748975 -251.510091)
			(xy 388.699375 -251.48459) (xy 388.654017 -251.452139) (xy 388.613868 -251.41343) (xy 388.579782 -251.369287)
			(xy 388.552486 -251.320652) (xy 388.532563 -251.268561) (xy 388.520437 -251.214124) (xy 388.516366 -251.158502)
			(xy 387.247892 -251.158502) (xy 387.247383 -251.186388) (xy 387.239263 -251.241564) (xy 387.223195 -251.294971)
			(xy 387.199523 -251.345468) (xy 387.16875 -251.391981) (xy 387.131533 -251.433518) (xy 387.088665 -251.469193)
			(xy 387.041059 -251.498247) (xy 386.98973 -251.520059) (xy 386.935773 -251.534165) (xy 386.880336 -251.540265)
			(xy 386.824602 -251.538228) (xy 386.769759 -251.528098) (xy 386.716975 -251.510091) (xy 386.667375 -251.48459)
			(xy 386.622017 -251.452139) (xy 386.581868 -251.41343) (xy 386.547782 -251.369287) (xy 386.520486 -251.320652)
			(xy 386.500563 -251.268561) (xy 386.488437 -251.214124) (xy 386.484366 -251.158502) (xy 386.231892 -251.158502)
			(xy 386.231383 -251.186388) (xy 386.223263 -251.241564) (xy 386.207195 -251.294971) (xy 386.183523 -251.345468)
			(xy 386.15275 -251.391981) (xy 386.115533 -251.433518) (xy 386.072665 -251.469193) (xy 386.025059 -251.498247)
			(xy 385.97373 -251.520059) (xy 385.919773 -251.534165) (xy 385.864336 -251.540265) (xy 385.808602 -251.538228)
			(xy 385.753759 -251.528098) (xy 385.700975 -251.510091) (xy 385.651375 -251.48459) (xy 385.606017 -251.452139)
			(xy 385.565868 -251.41343) (xy 385.531782 -251.369287) (xy 385.504486 -251.320652) (xy 385.484563 -251.268561)
			(xy 385.472437 -251.214124) (xy 385.468366 -251.158502) (xy 385.215892 -251.158502) (xy 385.215383 -251.186388)
			(xy 385.207263 -251.241564) (xy 385.191195 -251.294971) (xy 385.167523 -251.345468) (xy 385.13675 -251.391981)
			(xy 385.099533 -251.433518) (xy 385.056665 -251.469193) (xy 385.009059 -251.498247) (xy 384.95773 -251.520059)
			(xy 384.903773 -251.534165) (xy 384.848336 -251.540265) (xy 384.792602 -251.538228) (xy 384.737759 -251.528098)
			(xy 384.684975 -251.510091) (xy 384.635375 -251.48459) (xy 384.590017 -251.452139) (xy 384.549868 -251.41343)
			(xy 384.515782 -251.369287) (xy 384.488486 -251.320652) (xy 384.468563 -251.268561) (xy 384.456437 -251.214124)
			(xy 384.452366 -251.158502) (xy 384.199892 -251.158502) (xy 384.199383 -251.186388) (xy 384.191263 -251.241564)
			(xy 384.175195 -251.294971) (xy 384.151523 -251.345468) (xy 384.12075 -251.391981) (xy 384.083533 -251.433518)
			(xy 384.040665 -251.469193) (xy 383.993059 -251.498247) (xy 383.94173 -251.520059) (xy 383.887773 -251.534165)
			(xy 383.832336 -251.540265) (xy 383.776602 -251.538228) (xy 383.721759 -251.528098) (xy 383.668975 -251.510091)
			(xy 383.619375 -251.48459) (xy 383.574017 -251.452139) (xy 383.533868 -251.41343) (xy 383.499782 -251.369287)
			(xy 383.472486 -251.320652) (xy 383.452563 -251.268561) (xy 383.440437 -251.214124) (xy 383.436366 -251.158502)
			(xy 383.183892 -251.158502) (xy 383.183383 -251.186388) (xy 383.175263 -251.241564) (xy 383.159195 -251.294971)
			(xy 383.135523 -251.345468) (xy 383.10475 -251.391981) (xy 383.067533 -251.433518) (xy 383.024665 -251.469193)
			(xy 382.977059 -251.498247) (xy 382.92573 -251.520059) (xy 382.871773 -251.534165) (xy 382.816336 -251.540265)
			(xy 382.760602 -251.538228) (xy 382.705759 -251.528098) (xy 382.652975 -251.510091) (xy 382.603375 -251.48459)
			(xy 382.558017 -251.452139) (xy 382.517868 -251.41343) (xy 382.483782 -251.369287) (xy 382.456486 -251.320652)
			(xy 382.436563 -251.268561) (xy 382.424437 -251.214124) (xy 382.420366 -251.158502) (xy 382.167892 -251.158502)
			(xy 382.167383 -251.186388) (xy 382.159263 -251.241564) (xy 382.143195 -251.294971) (xy 382.119523 -251.345468)
			(xy 382.08875 -251.391981) (xy 382.051533 -251.433518) (xy 382.008665 -251.469193) (xy 381.961059 -251.498247)
			(xy 381.90973 -251.520059) (xy 381.855773 -251.534165) (xy 381.800336 -251.540265) (xy 381.744602 -251.538228)
			(xy 381.689759 -251.528098) (xy 381.636975 -251.510091) (xy 381.587375 -251.48459) (xy 381.542017 -251.452139)
			(xy 381.501868 -251.41343) (xy 381.467782 -251.369287) (xy 381.440486 -251.320652) (xy 381.420563 -251.268561)
			(xy 381.408437 -251.214124) (xy 381.404366 -251.158502) (xy 381.151892 -251.158502) (xy 381.151383 -251.186388)
			(xy 381.143263 -251.241564) (xy 381.127195 -251.294971) (xy 381.103523 -251.345468) (xy 381.07275 -251.391981)
			(xy 381.035533 -251.433518) (xy 380.992665 -251.469193) (xy 380.945059 -251.498247) (xy 380.89373 -251.520059)
			(xy 380.839773 -251.534165) (xy 380.784336 -251.540265) (xy 380.728602 -251.538228) (xy 380.673759 -251.528098)
			(xy 380.620975 -251.510091) (xy 380.571375 -251.48459) (xy 380.526017 -251.452139) (xy 380.485868 -251.41343)
			(xy 380.451782 -251.369287) (xy 380.424486 -251.320652) (xy 380.404563 -251.268561) (xy 380.392437 -251.214124)
			(xy 380.388366 -251.158502) (xy 380.135892 -251.158502) (xy 380.135383 -251.186388) (xy 380.127263 -251.241564)
			(xy 380.111195 -251.294971) (xy 380.087523 -251.345468) (xy 380.05675 -251.391981) (xy 380.019533 -251.433518)
			(xy 379.976665 -251.469193) (xy 379.929059 -251.498247) (xy 379.87773 -251.520059) (xy 379.823773 -251.534165)
			(xy 379.768336 -251.540265) (xy 379.712602 -251.538228) (xy 379.657759 -251.528098) (xy 379.604975 -251.510091)
			(xy 379.555375 -251.48459) (xy 379.510017 -251.452139) (xy 379.469868 -251.41343) (xy 379.435782 -251.369287)
			(xy 379.408486 -251.320652) (xy 379.388563 -251.268561) (xy 379.376437 -251.214124) (xy 379.372366 -251.158502)
			(xy 379.119892 -251.158502) (xy 379.119383 -251.186388) (xy 379.111263 -251.241564) (xy 379.095195 -251.294971)
			(xy 379.071523 -251.345468) (xy 379.04075 -251.391981) (xy 379.003533 -251.433518) (xy 378.960665 -251.469193)
			(xy 378.913059 -251.498247) (xy 378.86173 -251.520059) (xy 378.807773 -251.534165) (xy 378.752336 -251.540265)
			(xy 378.696602 -251.538228) (xy 378.641759 -251.528098) (xy 378.588975 -251.510091) (xy 378.539375 -251.48459)
			(xy 378.494017 -251.452139) (xy 378.453868 -251.41343) (xy 378.419782 -251.369287) (xy 378.392486 -251.320652)
			(xy 378.372563 -251.268561) (xy 378.360437 -251.214124) (xy 378.356366 -251.158502) (xy 378.103892 -251.158502)
			(xy 378.103383 -251.186388) (xy 378.095263 -251.241564) (xy 378.079195 -251.294971) (xy 378.055523 -251.345468)
			(xy 378.02475 -251.391981) (xy 377.987533 -251.433518) (xy 377.944665 -251.469193) (xy 377.897059 -251.498247)
			(xy 377.84573 -251.520059) (xy 377.791773 -251.534165) (xy 377.736336 -251.540265) (xy 377.680602 -251.538228)
			(xy 377.625759 -251.528098) (xy 377.572975 -251.510091) (xy 377.523375 -251.48459) (xy 377.478017 -251.452139)
			(xy 377.437868 -251.41343) (xy 377.403782 -251.369287) (xy 377.376486 -251.320652) (xy 377.356563 -251.268561)
			(xy 377.344437 -251.214124) (xy 377.340366 -251.158502) (xy 377.087892 -251.158502) (xy 377.087383 -251.186388)
			(xy 377.079263 -251.241564) (xy 377.063195 -251.294971) (xy 377.039523 -251.345468) (xy 377.00875 -251.391981)
			(xy 376.971533 -251.433518) (xy 376.928665 -251.469193) (xy 376.881059 -251.498247) (xy 376.82973 -251.520059)
			(xy 376.775773 -251.534165) (xy 376.720336 -251.540265) (xy 376.664602 -251.538228) (xy 376.609759 -251.528098)
			(xy 376.556975 -251.510091) (xy 376.507375 -251.48459) (xy 376.462017 -251.452139) (xy 376.421868 -251.41343)
			(xy 376.387782 -251.369287) (xy 376.360486 -251.320652) (xy 376.340563 -251.268561) (xy 376.328437 -251.214124)
			(xy 376.324366 -251.158502) (xy 376.071892 -251.158502) (xy 376.071383 -251.186388) (xy 376.063263 -251.241564)
			(xy 376.047195 -251.294971) (xy 376.023523 -251.345468) (xy 375.99275 -251.391981) (xy 375.955533 -251.433518)
			(xy 375.912665 -251.469193) (xy 375.865059 -251.498247) (xy 375.81373 -251.520059) (xy 375.759773 -251.534165)
			(xy 375.704336 -251.540265) (xy 375.648602 -251.538228) (xy 375.593759 -251.528098) (xy 375.540975 -251.510091)
			(xy 375.491375 -251.48459) (xy 375.446017 -251.452139) (xy 375.405868 -251.41343) (xy 375.371782 -251.369287)
			(xy 375.344486 -251.320652) (xy 375.324563 -251.268561) (xy 375.312437 -251.214124) (xy 375.308366 -251.158502)
			(xy 375.055892 -251.158502) (xy 375.055383 -251.186388) (xy 375.047263 -251.241564) (xy 375.031195 -251.294971)
			(xy 375.007523 -251.345468) (xy 374.97675 -251.391981) (xy 374.939533 -251.433518) (xy 374.896665 -251.469193)
			(xy 374.849059 -251.498247) (xy 374.79773 -251.520059) (xy 374.743773 -251.534165) (xy 374.688336 -251.540265)
			(xy 374.632602 -251.538228) (xy 374.577759 -251.528098) (xy 374.524975 -251.510091) (xy 374.475375 -251.48459)
			(xy 374.430017 -251.452139) (xy 374.389868 -251.41343) (xy 374.355782 -251.369287) (xy 374.328486 -251.320652)
			(xy 374.308563 -251.268561) (xy 374.296437 -251.214124) (xy 374.292366 -251.158502) (xy 374.090692 -251.158502)
			(xy 374.090183 -251.186388) (xy 374.082063 -251.241564) (xy 374.065995 -251.294971) (xy 374.042323 -251.345468)
			(xy 374.01155 -251.391981) (xy 373.974333 -251.433518) (xy 373.931465 -251.469193) (xy 373.883859 -251.498247)
			(xy 373.83253 -251.520059) (xy 373.778573 -251.534165) (xy 373.723136 -251.540265) (xy 373.667402 -251.538228)
			(xy 373.612559 -251.528098) (xy 373.559775 -251.510091) (xy 373.510175 -251.48459) (xy 373.464817 -251.452139)
			(xy 373.424668 -251.41343) (xy 373.390582 -251.369287) (xy 373.363286 -251.320652) (xy 373.343363 -251.268561)
			(xy 373.331237 -251.214124) (xy 373.327166 -251.158502) (xy 373.023892 -251.158502) (xy 373.023383 -251.186388)
			(xy 373.015263 -251.241564) (xy 372.999195 -251.294971) (xy 372.975523 -251.345468) (xy 372.94475 -251.391981)
			(xy 372.907533 -251.433518) (xy 372.864665 -251.469193) (xy 372.817059 -251.498247) (xy 372.76573 -251.520059)
			(xy 372.711773 -251.534165) (xy 372.656336 -251.540265) (xy 372.600602 -251.538228) (xy 372.545759 -251.528098)
			(xy 372.492975 -251.510091) (xy 372.443375 -251.48459) (xy 372.398017 -251.452139) (xy 372.357868 -251.41343)
			(xy 372.323782 -251.369287) (xy 372.296486 -251.320652) (xy 372.276563 -251.268561) (xy 372.264437 -251.214124)
			(xy 372.260366 -251.158502) (xy 371.064907 -251.158502) (xy 371.074637 -251.179259) (xy 371.090705 -251.232666)
			(xy 371.098825 -251.287842) (xy 371.099334 -251.315728) (xy 371.098825 -251.343614) (xy 371.090705 -251.39879)
			(xy 371.074637 -251.452197) (xy 371.050965 -251.502694) (xy 371.020192 -251.549207) (xy 370.982975 -251.590744)
			(xy 370.940107 -251.626419) (xy 370.892501 -251.655473) (xy 370.841172 -251.677285) (xy 370.787215 -251.691391)
			(xy 370.731778 -251.697491) (xy 370.676044 -251.695454) (xy 370.621201 -251.685324) (xy 370.568417 -251.667317)
			(xy 370.518817 -251.641816) (xy 370.473459 -251.609365) (xy 370.43331 -251.570656) (xy 370.399224 -251.526513)
			(xy 370.371928 -251.477878) (xy 370.352005 -251.425787) (xy 370.339879 -251.37135) (xy 370.335808 -251.315728)
			(xy 365.072422 -251.315728) (xy 367.7285 -253.971806) (xy 367.729008 -253.972314) (xy 367.736385 -253.978907)
			(xy 367.754684 -253.98638) (xy 367.764568 -253.986792)
		)
		(stroke
			(width 0)
			(type solid)
		)
		(fill yes)
		(layer "In9.Cu")
		(net "P1V8_PEX")
	)
	(gr_poly
		(pts
			(xy 11.078718 -74.3712) (xy 11.088787 -74.370773) (xy 11.107386 -74.363054) (xy 11.114786 -74.356214)
			(xy 11.421618 -74.049382) (xy 11.42847 -74.041986) (xy 11.436211 -74.023387) (xy 11.436604 -74.013314)
			(xy 11.436604 -41.796716) (xy 11.436507 -41.791556) (xy 11.434455 -41.781443) (xy 11.43254 -41.77665)
			(xy 11.420856 -41.749472) (xy 11.41349 -41.74236) (xy 11.393986 -41.722671) (xy 11.360298 -41.678666)
			(xy 11.333331 -41.63025) (xy 11.313654 -41.578441) (xy 11.301679 -41.524331) (xy 11.29766 -41.469057)
			(xy 11.30168 -41.413784) (xy 11.313655 -41.359674) (xy 11.333334 -41.307865) (xy 11.360301 -41.25945)
			(xy 11.39399 -41.215445) (xy 11.41349 -41.195752) (xy 11.420856 -41.18864) (xy 11.43254 -41.161716)
			(xy 11.434432 -41.156917) (xy 11.436484 -41.146807) (xy 11.436604 -41.14165) (xy 11.436604 -38.89629)
			(xy 11.436142 -38.885388) (xy 11.427181 -38.865518) (xy 11.419332 -38.857936) (xy 11.386134 -38.828238)
			(xy 11.324897 -38.763544) (xy 11.270055 -38.693348) (xy 11.2221 -38.618278) (xy 11.181461 -38.539008)
			(xy 11.148504 -38.45625) (xy 11.123525 -38.370744) (xy 11.106746 -38.283259) (xy 11.098319 -38.194579)
			(xy 11.098319 -38.105499) (xy 11.106746 -38.016819) (xy 11.123525 -37.929333) (xy 11.148505 -37.843828)
			(xy 11.181462 -37.761069) (xy 11.222101 -37.681799) (xy 11.270057 -37.60673) (xy 11.324899 -37.536534)
			(xy 11.386136 -37.47184) (xy 11.419332 -37.44214) (xy 11.427167 -37.434553) (xy 11.436109 -37.414682)
			(xy 11.436604 -37.403786) (xy 11.436604 -29.838142) (xy 11.436535 -29.834336) (xy 11.435383 -29.826811)
			(xy 11.434318 -29.823156) (xy 11.428222 -29.80309) (xy 11.424412 -29.797248) (xy 11.409924 -29.773985)
			(xy 11.387042 -29.724187) (xy 11.371521 -29.671628) (xy 11.363681 -29.617388) (xy 11.363683 -29.562585)
			(xy 11.371527 -29.508346) (xy 11.387051 -29.455788) (xy 11.409937 -29.405991) (xy 11.424412 -29.38272)
			(xy 11.428222 -29.376878) (xy 11.434318 -29.356812) (xy 11.43537 -29.353155) (xy 11.436514 -29.345631)
			(xy 11.436604 -29.341826) (xy 11.436604 -28.295092) (xy 11.437029 -28.285023) (xy 11.444746 -28.266421)
			(xy 11.45159 -28.259024) (xy 11.491468 -28.219146) (xy 11.494262 -28.216098) (xy 11.500018 -28.208737)
			(xy 11.506284 -28.19115) (xy 11.506454 -28.181808) (xy 11.504422 -28.097988) (xy 11.495786 -28.079192)
			(xy 11.488166 -28.072334) (xy 11.468887 -28.054178) (xy 11.435027 -28.013459) (xy 11.407127 -27.968446)
			(xy 11.385724 -27.920006) (xy 11.37123 -27.869071) (xy 11.363924 -27.816619) (xy 11.363452 -27.79014)
			(xy 11.363935 -27.762886) (xy 11.371687 -27.708932) (xy 11.387038 -27.65663) (xy 11.409676 -27.607045)
			(xy 11.439141 -27.561187) (xy 11.474832 -27.519988) (xy 11.516023 -27.484289) (xy 11.561875 -27.454815)
			(xy 11.611455 -27.432166) (xy 11.663753 -27.416804) (xy 11.717706 -27.409041) (xy 11.74496 -27.408632)
			(xy 11.771438 -27.409088) (xy 11.823885 -27.416416) (xy 11.874816 -27.430922) (xy 11.923253 -27.452328)
			(xy 11.968267 -27.480223) (xy 12.008994 -27.514072) (xy 12.027154 -27.533346) (xy 12.034012 -27.540966)
			(xy 12.052808 -27.549602) (xy 12.136628 -27.551634) (xy 12.145969 -27.551449) (xy 12.163557 -27.545195)
			(xy 12.170918 -27.539442) (xy 12.172442 -27.538172) (xy 12.48791 -27.222704) (xy 12.495309 -27.215859)
			(xy 12.513907 -27.208127) (xy 12.523978 -27.207718) (xy 16.472916 -27.207718) (xy 16.482923 -27.207228)
			(xy 16.501412 -27.199566) (xy 16.515565 -27.185414) (xy 16.523227 -27.166925) (xy 16.523716 -27.156918)
			(xy 16.523716 -26.479246) (xy 16.523741 -26.46799) (xy 16.524757 -26.445501) (xy 16.525748 -26.434288)
			(xy 16.525748 -26.434034) (xy 16.526934 -26.422342) (xy 16.530363 -26.399088) (xy 16.532606 -26.387552)
			(xy 16.535654 -26.372566) (xy 16.524478 -26.344626) (xy 16.508476 -26.333196) (xy 16.498356 -26.326864)
			(xy 16.474768 -26.323408) (xy 16.463264 -26.326592) (xy 16.45539 -26.329386) (xy 16.452342 -26.33091)
			(xy 16.425602 -26.343735) (xy 16.369137 -26.361861) (xy 16.310544 -26.37101) (xy 16.280892 -26.37155)
			(xy 16.275304 -26.37155) (xy 16.248315 -26.370686) (xy 16.194975 -26.362288) (xy 16.143352 -26.346453)
			(xy 16.094477 -26.323497) (xy 16.049328 -26.293879) (xy 16.008807 -26.25819) (xy 15.973722 -26.217144)
			(xy 15.944776 -26.171561) (xy 15.922547 -26.122352) (xy 15.907479 -26.070499) (xy 15.899873 -26.017041)
			(xy 15.899384 -25.990042) (xy 15.89987 -25.962791) (xy 15.907626 -25.908843) (xy 15.922981 -25.856548)
			(xy 15.945623 -25.806971) (xy 15.975089 -25.761121) (xy 16.01078 -25.71993) (xy 16.051971 -25.684239)
			(xy 16.097821 -25.654773) (xy 16.147398 -25.632131) (xy 16.199693 -25.616776) (xy 16.253641 -25.60902)
			(xy 16.308143 -25.60902) (xy 16.362091 -25.616776) (xy 16.414386 -25.632131) (xy 16.463963 -25.654773)
			(xy 16.509813 -25.684239) (xy 16.551004 -25.71993) (xy 16.586695 -25.761121) (xy 16.616161 -25.806971)
			(xy 16.627616 -25.832054) (xy 18.187922 -25.832054) (xy 18.191993 -25.776432) (xy 18.204119 -25.721995)
			(xy 18.224042 -25.669904) (xy 18.251338 -25.621269) (xy 18.285424 -25.577126) (xy 18.325573 -25.538417)
			(xy 18.370931 -25.505966) (xy 18.420531 -25.480465) (xy 18.473315 -25.462458) (xy 18.528158 -25.452328)
			(xy 18.583892 -25.450291) (xy 18.639329 -25.456391) (xy 18.693286 -25.470497) (xy 18.744615 -25.492309)
			(xy 18.792221 -25.521363) (xy 18.835089 -25.557038) (xy 18.872306 -25.598575) (xy 18.903079 -25.645088)
			(xy 18.926751 -25.695585) (xy 18.942819 -25.748992) (xy 18.950939 -25.804168) (xy 18.951448 -25.832054)
			(xy 18.950939 -25.85994) (xy 18.942819 -25.915116) (xy 18.926751 -25.968523) (xy 18.903079 -26.01902)
			(xy 18.872306 -26.065533) (xy 18.835089 -26.10707) (xy 18.792221 -26.142745) (xy 18.744615 -26.171799)
			(xy 18.693286 -26.193611) (xy 18.639329 -26.207717) (xy 18.583892 -26.213817) (xy 18.528158 -26.21178)
			(xy 18.473315 -26.20165) (xy 18.420531 -26.183643) (xy 18.370931 -26.158142) (xy 18.325573 -26.125691)
			(xy 18.285424 -26.086982) (xy 18.251338 -26.042839) (xy 18.224042 -25.994204) (xy 18.204119 -25.942113)
			(xy 18.191993 -25.887676) (xy 18.187922 -25.832054) (xy 16.627616 -25.832054) (xy 16.638803 -25.856548)
			(xy 16.654158 -25.908843) (xy 16.661914 -25.962791) (xy 16.6624 -25.990042) (xy 16.660876 -26.025348)
			(xy 16.660469 -26.0313) (xy 16.662134 -26.043111) (xy 16.664178 -26.048716) (xy 16.67764 -26.082244)
			(xy 16.679164 -26.083768) (xy 16.681704 -26.0858) (xy 16.697452 -26.096976) (xy 16.727424 -26.097738)
			(xy 16.740632 -26.08961) (xy 16.767865 -26.073434) (xy 16.825836 -26.047907) (xy 16.886767 -26.030599)
			(xy 16.9495 -26.021839) (xy 16.98117 -26.021284) (xy 16.981424 -26.021284) (xy 17.00149 -26.021792)
			(xy 17.011904 -26.0223) (xy 17.043124 -26.024898) (xy 17.104479 -26.037553) (xy 17.163537 -26.058455)
			(xy 17.219193 -26.087212) (xy 17.27041 -26.123288) (xy 17.316231 -26.166009) (xy 17.3558 -26.214578)
			(xy 17.388379 -26.268088) (xy 17.413359 -26.325539) (xy 17.430274 -26.385859) (xy 17.438808 -26.447922)
			(xy 17.439386 -26.479246) (xy 17.439386 -26.727658) (xy 17.439132 -26.727658) (xy 17.439132 -27.163014)
			(xy 17.440727 -27.172145) (xy 17.449446 -27.188487) (xy 17.463353 -27.200722) (xy 17.480672 -27.207289)
			(xy 17.489932 -27.207718) (xy 20.070318 -27.207718) (xy 20.080195 -27.207259) (xy 20.098496 -27.199817)
			(xy 20.105878 -27.19324) (xy 20.106132 -27.192986) (xy 20.406614 -26.892504) (xy 20.412871 -26.886081)
			(xy 20.420935 -26.87008) (xy 20.423043 -26.852286) (xy 20.421346 -26.843482) (xy 20.401534 -26.760424)
			(xy 20.398365 -26.749663) (xy 20.384382 -26.732157) (xy 20.37461 -26.726642) (xy 20.368768 -26.723594)
			(xy 20.365212 -26.722324) (xy 20.340372 -26.71342) (xy 20.293219 -26.689737) (xy 20.249775 -26.659789)
			(xy 20.210867 -26.624144) (xy 20.177237 -26.583482) (xy 20.149526 -26.538578) (xy 20.12826 -26.490286)
			(xy 20.113845 -26.439526) (xy 20.106556 -26.387265) (xy 20.106132 -26.360882) (xy 20.106597 -26.333631)
			(xy 20.114356 -26.279684) (xy 20.129714 -26.227391) (xy 20.152358 -26.177815) (xy 20.181827 -26.131967)
			(xy 20.217521 -26.09078) (xy 20.258714 -26.055092) (xy 20.304566 -26.02563) (xy 20.354145 -26.002994)
			(xy 20.406441 -25.987644) (xy 20.460389 -25.979892) (xy 20.48764 -25.979374) (xy 20.500187 -25.979475)
			(xy 20.525227 -25.981126) (xy 20.537678 -25.982676) (xy 20.5486 -25.9842) (xy 20.569428 -25.97785)
			(xy 20.635214 -25.920192) (xy 20.639195 -25.916527) (xy 20.645608 -25.907814) (xy 20.647914 -25.90292)
			(xy 20.652486 -25.893014) (xy 20.652486 -16.776954) (xy 20.651925 -16.76587) (xy 20.642595 -16.745761)
			(xy 20.625681 -16.731431) (xy 20.615148 -16.727932) (xy 20.614894 -16.727932) (xy 20.503642 -16.697706)
			(xy 20.471892 -16.71066) (xy 20.463256 -16.725646) (xy 20.429835 -16.781914) (xy 20.357047 -16.890695)
			(xy 20.277731 -16.994812) (xy 20.192183 -17.093873) (xy 20.100726 -17.187505) (xy 20.003704 -17.275357)
			(xy 19.90148 -17.357099) (xy 19.794439 -17.432422) (xy 19.682984 -17.501046) (xy 19.567533 -17.56271)
			(xy 19.448521 -17.617184) (xy 19.326394 -17.664262) (xy 19.201612 -17.703769) (xy 19.074643 -17.735555)
			(xy 18.945965 -17.759501) (xy 18.816062 -17.775516) (xy 18.685421 -17.783541) (xy 18.619978 -17.784064)
			(xy 18.555507 -17.783586) (xy 18.426801 -17.775799) (xy 18.298801 -17.760256) (xy 18.171972 -17.737012)
			(xy 18.046778 -17.706153) (xy 17.923675 -17.667791) (xy 17.803114 -17.622066) (xy 17.685533 -17.569146)
			(xy 17.571362 -17.509222) (xy 17.461017 -17.442514) (xy 17.354902 -17.369266) (xy 17.253403 -17.289744)
			(xy 17.15689 -17.204239) (xy 17.065716 -17.113062) (xy 16.980214 -17.016547) (xy 16.900695 -16.915045)
			(xy 16.82745 -16.808927) (xy 16.760746 -16.698581) (xy 16.700826 -16.584408) (xy 16.647909 -16.466825)
			(xy 16.602188 -16.346262) (xy 16.563829 -16.223159) (xy 16.532974 -16.097964) (xy 16.509734 -15.971134)
			(xy 16.494195 -15.843133) (xy 16.486412 -15.714427) (xy 16.48587 -15.649956) (xy 16.486428 -15.581216)
			(xy 16.495296 -15.444022) (xy 16.512974 -15.307683) (xy 16.539388 -15.172765) (xy 16.574428 -15.039825)
			(xy 16.61795 -14.909416) (xy 16.64335 -14.845538) (xy 16.648176 -14.8336) (xy 16.645636 -14.808708)
			(xy 16.59128 -14.727936) (xy 16.58375 -14.717918) (xy 16.561633 -14.706198) (xy 16.549116 -14.705584)
			(xy 14.719808 -14.705584) (xy 14.695678 -14.72057) (xy 14.689074 -14.733524) (xy 14.641576 -14.826996)
			(xy 14.643862 -14.855444) (xy 14.652244 -14.867128) (xy 14.676713 -14.901553) (xy 14.72007 -14.974044)
			(xy 14.756748 -15.050131) (xy 14.786452 -15.129203) (xy 14.808943 -15.21062) (xy 14.824038 -15.293727)
			(xy 14.831617 -15.377853) (xy 14.832076 -15.420086) (xy 14.831528 -15.465817) (xy 14.822645 -15.556848)
			(xy 14.804972 -15.646586) (xy 14.778676 -15.734187) (xy 14.744003 -15.818823) (xy 14.72311 -15.859506)
			(xy 14.717014 -15.870936) (xy 14.717268 -15.896082) (xy 14.769846 -15.993364) (xy 14.790674 -16.00708)
			(xy 14.803628 -16.00835) (xy 14.847523 -16.012895) (xy 14.934297 -16.028988) (xy 15.01924 -16.052932)
			(xy 15.101645 -16.084526) (xy 15.180823 -16.123507) (xy 15.256115 -16.169549) (xy 15.326891 -16.222269)
			(xy 15.392562 -16.281227) (xy 15.45258 -16.345931) (xy 15.506444 -16.415841) (xy 15.553705 -16.490373)
			(xy 15.593968 -16.568907) (xy 15.626898 -16.650787) (xy 15.65222 -16.73533) (xy 15.669722 -16.821831)
			(xy 15.679259 -16.909568) (xy 15.680752 -16.997809) (xy 15.674187 -17.085818) (xy 15.659619 -17.172861)
			(xy 15.63717 -17.258212) (xy 15.607028 -17.341158) (xy 15.569443 -17.421009) (xy 15.52473 -17.497097)
			(xy 15.473261 -17.568788) (xy 15.415465 -17.635484) (xy 15.351825 -17.696629) (xy 15.282872 -17.751712)
			(xy 15.20918 -17.800274) (xy 15.131365 -17.84191) (xy 15.050076 -17.876272) (xy 14.965991 -17.903075)
			(xy 14.879811 -17.922093) (xy 14.792255 -17.933169) (xy 14.704054 -17.936211) (xy 14.615943 -17.931192)
			(xy 14.528658 -17.918155) (xy 14.442926 -17.897208) (xy 14.359463 -17.868527) (xy 14.278965 -17.83235)
			(xy 14.202103 -17.788979) (xy 14.129519 -17.738777) (xy 14.061819 -17.682161) (xy 13.999566 -17.619605)
			(xy 13.943281 -17.551629) (xy 13.893433 -17.478802) (xy 13.850437 -17.40173) (xy 13.814652 -17.321056)
			(xy 13.786378 -17.237455) (xy 13.765849 -17.151622) (xy 13.753237 -17.064274) (xy 13.748648 -16.97614)
			(xy 13.752119 -16.887954) (xy 13.763621 -16.800453) (xy 13.78306 -16.714367) (xy 13.810271 -16.630413)
			(xy 13.845029 -16.549292) (xy 13.865606 -16.510254) (xy 13.871956 -16.498316) (xy 13.871448 -16.471646)
			(xy 13.819886 -16.385032) (xy 13.815081 -16.377667) (xy 13.801523 -16.366486) (xy 13.784985 -16.360546)
			(xy 13.776198 -16.36014) (xy 12.037822 -16.36014) (xy 11.994383 -16.359654) (xy 11.907875 -16.35164)
			(xy 11.822475 -16.335678) (xy 11.738913 -16.311904) (xy 11.657901 -16.280521) (xy 11.58013 -16.241797)
			(xy 11.506264 -16.196062) (xy 11.436933 -16.143706) (xy 11.372729 -16.085177) (xy 11.314199 -16.020973)
			(xy 11.261843 -15.951643) (xy 11.216107 -15.877777) (xy 11.177382 -15.800007) (xy 11.145999 -15.718995)
			(xy 11.122224 -15.635433) (xy 11.106261 -15.550033) (xy 11.098246 -15.463525) (xy 11.097768 -15.420086)
			(xy 11.098219 -15.377859) (xy 11.105774 -15.293744) (xy 11.120839 -15.210645) (xy 11.143292 -15.12923)
			(xy 11.172954 -15.050157) (xy 11.209585 -14.974061) (xy 11.25289 -14.901555) (xy 11.277346 -14.867128)
			(xy 11.285982 -14.855444) (xy 11.288268 -14.82725) (xy 11.241024 -14.733778) (xy 11.237095 -14.72663)
			(xy 11.225566 -14.715102) (xy 11.218418 -14.711172) (xy 11.21791 -14.710918) (xy 11.212583 -14.708461)
			(xy 11.201167 -14.705779) (xy 11.195304 -14.705584) (xy 8.577326 -14.705584) (xy 8.567573 -14.706005)
			(xy 8.549478 -14.713279) (xy 8.535434 -14.726812) (xy 8.531098 -14.735556) (xy 8.486902 -14.833854)
			(xy 8.491474 -14.863318) (xy 8.501634 -14.874748) (xy 8.519759 -14.895838) (xy 8.550345 -14.942277)
			(xy 8.573872 -14.992662) (xy 8.589841 -15.045927) (xy 8.597915 -15.100945) (xy 8.598408 -15.128748)
			(xy 8.597945 -15.156001) (xy 8.590188 -15.209952) (xy 8.574832 -15.26225) (xy 8.55219 -15.311831)
			(xy 8.522722 -15.357684) (xy 8.487028 -15.398877) (xy 8.445836 -15.434571) (xy 8.399982 -15.464039)
			(xy 8.350402 -15.486682) (xy 8.298104 -15.502038) (xy 8.244153 -15.509795) (xy 8.2169 -15.510256)
			(xy 8.189229 -15.509762) (xy 8.134469 -15.501765) (xy 8.081439 -15.485939) (xy 8.031252 -15.462616)
			(xy 7.984962 -15.432285) (xy 7.943542 -15.395583) (xy 7.907859 -15.353281) (xy 7.878664 -15.306267)
			(xy 7.85657 -15.255528) (xy 7.842039 -15.202128) (xy 7.838186 -15.174722) (xy 7.836408 -15.159736)
			(xy 7.834736 -15.134031) (xy 7.837489 -15.082594) (xy 7.847135 -15.031994) (xy 7.863497 -14.98315)
			(xy 7.886279 -14.936951) (xy 7.915066 -14.894234) (xy 7.931912 -14.874748) (xy 7.932166 -14.874494)
			(xy 7.938306 -14.866937) (xy 7.944881 -14.848626) (xy 7.944147 -14.829184) (xy 7.940548 -14.820138)
			(xy 7.902702 -14.735556) (xy 7.898297 -14.726861) (xy 7.884256 -14.713363) (xy 7.86621 -14.706039)
			(xy 7.856474 -14.705584) (xy 6.544564 -14.705584) (xy 6.539484 -14.705838) (xy 6.53923 -14.705838)
			(xy 6.53054 -14.707133) (xy 6.514726 -14.71476) (xy 6.502389 -14.727252) (xy 6.498336 -14.735048)
			(xy 6.453378 -14.83233) (xy 6.457442 -14.86154) (xy 6.467094 -14.87297) (xy 6.48413 -14.893747) (xy 6.51281 -14.93918)
			(xy 6.534833 -14.988186) (xy 6.549764 -15.039798) (xy 6.557306 -15.092994) (xy 6.557772 -15.119858)
			(xy 6.557286 -15.147109) (xy 6.54953 -15.201057) (xy 6.534175 -15.253352) (xy 6.511533 -15.302929)
			(xy 6.482067 -15.348779) (xy 6.446376 -15.38997) (xy 6.405185 -15.425661) (xy 6.359335 -15.455127)
			(xy 6.309758 -15.477769) (xy 6.257463 -15.493124) (xy 6.203515 -15.50088) (xy 6.149013 -15.50088)
			(xy 6.095065 -15.493124) (xy 6.04277 -15.477769) (xy 5.993193 -15.455127) (xy 5.947343 -15.425661)
			(xy 5.906152 -15.38997) (xy 5.870461 -15.348779) (xy 5.840995 -15.302929) (xy 5.818353 -15.253352)
			(xy 5.802998 -15.201057) (xy 5.795242 -15.147109) (xy 5.794756 -15.119858) (xy 5.795211 -15.092993)
			(xy 5.802745 -15.039793) (xy 5.817672 -14.988177) (xy 5.839697 -14.939168) (xy 5.868383 -14.893736)
			(xy 5.885434 -14.87297) (xy 5.895086 -14.86154) (xy 5.89915 -14.83233) (xy 5.854192 -14.735048) (xy 5.848553 -14.724454)
			(xy 5.829742 -14.709601) (xy 5.818124 -14.7066) (xy 5.813044 -14.705584) (xy 1.433322 -14.705584)
			(xy 1.423258 -14.706021) (xy 1.404672 -14.713753) (xy 1.397254 -14.72057) (xy 1.284986 -14.832838)
			(xy 1.27762 -14.83995) (xy 1.27 -14.858746) (xy 1.27 -15.844774) (xy 3.364736 -15.844774) (xy 3.368807 -15.789152)
			(xy 3.380933 -15.734715) (xy 3.400856 -15.682624) (xy 3.428152 -15.633989) (xy 3.462238 -15.589846)
			(xy 3.502387 -15.551137) (xy 3.547745 -15.518686) (xy 3.597345 -15.493185) (xy 3.650129 -15.475178)
			(xy 3.704972 -15.465048) (xy 3.760706 -15.463011) (xy 3.816143 -15.469111) (xy 3.8701 -15.483217)
			(xy 3.921429 -15.505029) (xy 3.969035 -15.534083) (xy 4.011903 -15.569758) (xy 4.04912 -15.611295)
			(xy 4.079893 -15.657808) (xy 4.103565 -15.708305) (xy 4.119633 -15.761712) (xy 4.127753 -15.816888)
			(xy 4.128262 -15.844774) (xy 4.127753 -15.87266) (xy 4.119633 -15.927836) (xy 4.103565 -15.981243)
			(xy 4.079893 -16.03174) (xy 4.04912 -16.078253) (xy 4.011903 -16.11979) (xy 3.992595 -16.135858)
			(xy 5.794246 -16.135858) (xy 5.798317 -16.080236) (xy 5.810443 -16.025799) (xy 5.830366 -15.973708)
			(xy 5.857662 -15.925073) (xy 5.891748 -15.88093) (xy 5.931897 -15.842221) (xy 5.977255 -15.80977)
			(xy 6.026855 -15.784269) (xy 6.079639 -15.766262) (xy 6.134482 -15.756132) (xy 6.190216 -15.754095)
			(xy 6.245653 -15.760195) (xy 6.29961 -15.774301) (xy 6.350939 -15.796113) (xy 6.398545 -15.825167)
			(xy 6.441413 -15.860842) (xy 6.47863 -15.902379) (xy 6.509403 -15.948892) (xy 6.533075 -15.999389)
			(xy 6.549143 -16.052796) (xy 6.557263 -16.107972) (xy 6.557772 -16.135858) (xy 6.55761 -16.144748)
			(xy 7.834882 -16.144748) (xy 7.838953 -16.089126) (xy 7.851079 -16.034689) (xy 7.871002 -15.982598)
			(xy 7.898298 -15.933963) (xy 7.932384 -15.88982) (xy 7.972533 -15.851111) (xy 8.017891 -15.81866)
			(xy 8.067491 -15.793159) (xy 8.120275 -15.775152) (xy 8.175118 -15.765022) (xy 8.230852 -15.762985)
			(xy 8.286289 -15.769085) (xy 8.340246 -15.783191) (xy 8.391575 -15.805003) (xy 8.439181 -15.834057)
			(xy 8.482049 -15.869732) (xy 8.519266 -15.911269) (xy 8.550039 -15.957782) (xy 8.573711 -16.008279)
			(xy 8.589779 -16.061686) (xy 8.597899 -16.116862) (xy 8.598408 -16.144748) (xy 8.597899 -16.172634)
			(xy 8.589779 -16.22781) (xy 8.573711 -16.281217) (xy 8.550039 -16.331714) (xy 8.519266 -16.378227)
			(xy 8.482049 -16.419764) (xy 8.439181 -16.455439) (xy 8.391575 -16.484493) (xy 8.340246 -16.506305)
			(xy 8.286289 -16.520411) (xy 8.230852 -16.526511) (xy 8.175118 -16.524474) (xy 8.120275 -16.514344)
			(xy 8.067491 -16.496337) (xy 8.017891 -16.470836) (xy 7.972533 -16.438385) (xy 7.932384 -16.399676)
			(xy 7.898298 -16.355533) (xy 7.871002 -16.306898) (xy 7.851079 -16.254807) (xy 7.838953 -16.20037)
			(xy 7.834882 -16.144748) (xy 6.55761 -16.144748) (xy 6.557263 -16.163744) (xy 6.549143 -16.21892)
			(xy 6.533075 -16.272327) (xy 6.509403 -16.322824) (xy 6.47863 -16.369337) (xy 6.441413 -16.410874)
			(xy 6.398545 -16.446549) (xy 6.350939 -16.475603) (xy 6.29961 -16.497415) (xy 6.245653 -16.511521)
			(xy 6.190216 -16.517621) (xy 6.134482 -16.515584) (xy 6.079639 -16.505454) (xy 6.026855 -16.487447)
			(xy 5.977255 -16.461946) (xy 5.931897 -16.429495) (xy 5.891748 -16.390786) (xy 5.857662 -16.346643)
			(xy 5.830366 -16.298008) (xy 5.810443 -16.245917) (xy 5.798317 -16.19148) (xy 5.794246 -16.135858)
			(xy 3.992595 -16.135858) (xy 3.969035 -16.155465) (xy 3.921429 -16.184519) (xy 3.8701 -16.206331)
			(xy 3.816143 -16.220437) (xy 3.760706 -16.226537) (xy 3.704972 -16.2245) (xy 3.650129 -16.21437)
			(xy 3.597345 -16.196363) (xy 3.547745 -16.170862) (xy 3.502387 -16.138411) (xy 3.462238 -16.099702)
			(xy 3.428152 -16.055559) (xy 3.400856 -16.006924) (xy 3.380933 -15.954833) (xy 3.368807 -15.900396)
			(xy 3.364736 -15.844774) (xy 1.27 -15.844774) (xy 1.27 -17.151858) (xy 5.794246 -17.151858) (xy 5.798317 -17.096236)
			(xy 5.810443 -17.041799) (xy 5.830366 -16.989708) (xy 5.857662 -16.941073) (xy 5.891748 -16.89693)
			(xy 5.931897 -16.858221) (xy 5.977255 -16.82577) (xy 6.026855 -16.800269) (xy 6.079639 -16.782262)
			(xy 6.134482 -16.772132) (xy 6.190216 -16.770095) (xy 6.245653 -16.776195) (xy 6.29961 -16.790301)
			(xy 6.350939 -16.812113) (xy 6.398545 -16.841167) (xy 6.441413 -16.876842) (xy 6.47863 -16.918379)
			(xy 6.509403 -16.964892) (xy 6.533075 -17.015389) (xy 6.549143 -17.068796) (xy 6.557263 -17.123972)
			(xy 6.557772 -17.151858) (xy 6.55761 -17.160748) (xy 7.834882 -17.160748) (xy 7.838953 -17.105126)
			(xy 7.851079 -17.050689) (xy 7.871002 -16.998598) (xy 7.898298 -16.949963) (xy 7.932384 -16.90582)
			(xy 7.972533 -16.867111) (xy 8.017891 -16.83466) (xy 8.067491 -16.809159) (xy 8.120275 -16.791152)
			(xy 8.175118 -16.781022) (xy 8.230852 -16.778985) (xy 8.286289 -16.785085) (xy 8.340246 -16.799191)
			(xy 8.391575 -16.821003) (xy 8.439181 -16.850057) (xy 8.482049 -16.885732) (xy 8.519266 -16.927269)
			(xy 8.550039 -16.973782) (xy 8.573711 -17.024279) (xy 8.589779 -17.077686) (xy 8.597899 -17.132862)
			(xy 8.598408 -17.160748) (xy 8.597899 -17.188634) (xy 8.589779 -17.24381) (xy 8.573711 -17.297217)
			(xy 8.550039 -17.347714) (xy 8.519266 -17.394227) (xy 8.482049 -17.435764) (xy 8.439181 -17.471439)
			(xy 8.391575 -17.500493) (xy 8.340246 -17.522305) (xy 8.286289 -17.536411) (xy 8.230852 -17.542511)
			(xy 8.175118 -17.540474) (xy 8.120275 -17.530344) (xy 8.067491 -17.512337) (xy 8.017891 -17.486836)
			(xy 7.972533 -17.454385) (xy 7.932384 -17.415676) (xy 7.898298 -17.371533) (xy 7.871002 -17.322898)
			(xy 7.851079 -17.270807) (xy 7.838953 -17.21637) (xy 7.834882 -17.160748) (xy 6.55761 -17.160748)
			(xy 6.557263 -17.179744) (xy 6.549143 -17.23492) (xy 6.533075 -17.288327) (xy 6.509403 -17.338824)
			(xy 6.47863 -17.385337) (xy 6.441413 -17.426874) (xy 6.398545 -17.462549) (xy 6.350939 -17.491603)
			(xy 6.29961 -17.513415) (xy 6.245653 -17.527521) (xy 6.190216 -17.533621) (xy 6.134482 -17.531584)
			(xy 6.079639 -17.521454) (xy 6.026855 -17.503447) (xy 5.977255 -17.477946) (xy 5.931897 -17.445495)
			(xy 5.891748 -17.406786) (xy 5.857662 -17.362643) (xy 5.830366 -17.314008) (xy 5.810443 -17.261917)
			(xy 5.798317 -17.20748) (xy 5.794246 -17.151858) (xy 1.27 -17.151858) (xy 1.27 -18.029174) (xy 1.464816 -18.029174)
			(xy 1.468887 -17.973552) (xy 1.481013 -17.919115) (xy 1.500936 -17.867024) (xy 1.528232 -17.818389)
			(xy 1.562318 -17.774246) (xy 1.602467 -17.735537) (xy 1.647825 -17.703086) (xy 1.697425 -17.677585)
			(xy 1.750209 -17.659578) (xy 1.805052 -17.649448) (xy 1.860786 -17.647411) (xy 1.916223 -17.653511)
			(xy 1.97018 -17.667617) (xy 2.021509 -17.689429) (xy 2.069115 -17.718483) (xy 2.111983 -17.754158)
			(xy 2.1492 -17.795695) (xy 2.179973 -17.842208) (xy 2.203645 -17.892705) (xy 2.219713 -17.946112)
			(xy 2.227833 -18.001288) (xy 2.228342 -18.029174) (xy 2.227833 -18.05706) (xy 2.219713 -18.112236)
			(xy 2.203645 -18.165643) (xy 2.179973 -18.21614) (xy 2.1492 -18.262653) (xy 2.111983 -18.30419) (xy 2.069115 -18.339865)
			(xy 2.021509 -18.368919) (xy 1.97018 -18.390731) (xy 1.916223 -18.404837) (xy 1.860786 -18.410937)
			(xy 1.805052 -18.4089) (xy 1.750209 -18.39877) (xy 1.697425 -18.380763) (xy 1.647825 -18.355262)
			(xy 1.602467 -18.322811) (xy 1.562318 -18.284102) (xy 1.528232 -18.239959) (xy 1.500936 -18.191324)
			(xy 1.481013 -18.139233) (xy 1.468887 -18.084796) (xy 1.464816 -18.029174) (xy 1.27 -18.029174) (xy 1.27 -20.24888)
			(xy 2.414776 -20.24888) (xy 2.418847 -20.193258) (xy 2.430973 -20.138821) (xy 2.450896 -20.08673)
			(xy 2.478192 -20.038095) (xy 2.512278 -19.993952) (xy 2.552427 -19.955243) (xy 2.597785 -19.922792)
			(xy 2.647385 -19.897291) (xy 2.700169 -19.879284) (xy 2.755012 -19.869154) (xy 2.810746 -19.867117)
			(xy 2.866183 -19.873217) (xy 2.92014 -19.887323) (xy 2.971469 -19.909135) (xy 3.019075 -19.938189)
			(xy 3.061943 -19.973864) (xy 3.09916 -20.015401) (xy 3.129933 -20.061914) (xy 3.153605 -20.112411)
			(xy 3.169673 -20.165818) (xy 3.177793 -20.220994) (xy 3.178302 -20.24888) (xy 3.177793 -20.276766)
			(xy 3.169673 -20.331942) (xy 3.153605 -20.385349) (xy 3.129933 -20.435846) (xy 3.09916 -20.482359)
			(xy 3.061943 -20.523896) (xy 3.019075 -20.559571) (xy 2.971469 -20.588625) (xy 2.92014 -20.610437)
			(xy 2.866183 -20.624543) (xy 2.810746 -20.630643) (xy 2.755012 -20.628606) (xy 2.700169 -20.618476)
			(xy 2.647385 -20.600469) (xy 2.597785 -20.574968) (xy 2.552427 -20.542517) (xy 2.512278 -20.503808)
			(xy 2.478192 -20.459665) (xy 2.450896 -20.41103) (xy 2.430973 -20.358939) (xy 2.418847 -20.304502)
			(xy 2.414776 -20.24888) (xy 1.27 -20.24888) (xy 1.27 -20.72005) (xy 5.185422 -20.72005) (xy 5.189392 -20.589916)
			(xy 5.201288 -20.460266) (xy 5.221067 -20.331583) (xy 5.248653 -20.204344) (xy 5.283946 -20.079025)
			(xy 5.326812 -19.956089) (xy 5.377094 -19.835996) (xy 5.434603 -19.719192) (xy 5.499127 -19.60611)
			(xy 5.570424 -19.497173) (xy 5.648229 -19.392785) (xy 5.732254 -19.293334) (xy 5.822186 -19.199191)
			(xy 5.91769 -19.110706) (xy 6.01841 -19.028207) (xy 6.123972 -18.952002) (xy 6.233984 -18.882375)
			(xy 6.348036 -18.819584) (xy 6.465704 -18.763862) (xy 6.58655 -18.715418) (xy 6.710125 -18.674431)
			(xy 6.835968 -18.641054) (xy 6.963613 -18.615411) (xy 7.092583 -18.597597) (xy 7.222399 -18.587679)
			(xy 7.352578 -18.585694) (xy 7.482637 -18.591648) (xy 7.61209 -18.605521) (xy 7.740457 -18.627259)
			(xy 7.86726 -18.656783) (xy 7.992027 -18.693982) (xy 8.114294 -18.738718) (xy 8.233607 -18.790826)
			(xy 8.34952 -18.850109) (xy 8.461605 -18.91635) (xy 8.569442 -18.9893) (xy 8.672631 -19.068688) (xy 8.770789 -19.15422)
			(xy 8.86355 -19.245577) (xy 8.950569 -19.342419) (xy 9.031522 -19.444386) (xy 9.106108 -19.551098)
			(xy 9.174049 -19.662159) (xy 9.235094 -19.777155) (xy 9.289015 -19.895659) (xy 9.33561 -20.01723)
			(xy 9.374708 -20.141415) (xy 9.406162 -20.267753) (xy 9.429856 -20.395774) (xy 9.4457 -20.525) (xy 9.453638 -20.654953)
			(xy 9.454134 -20.72005) (xy 9.453638 -20.785147) (xy 9.4457 -20.9151) (xy 9.429856 -21.044326) (xy 9.406162 -21.172347)
			(xy 9.374708 -21.298685) (xy 9.33561 -21.42287) (xy 9.289015 -21.544441) (xy 9.235094 -21.662945)
			(xy 9.195073 -21.738336) (xy 11.416792 -21.738336) (xy 11.417279 -21.709596) (xy 11.425911 -21.652767)
			(xy 11.44297 -21.597876) (xy 11.468069 -21.546165) (xy 11.500642 -21.498804) (xy 11.519916 -21.477478)
			(xy 11.52652 -21.470366) (xy 11.533632 -21.45284) (xy 11.533632 -21.363432) (xy 11.52652 -21.345906)
			(xy 11.519916 -21.338794) (xy 11.500642 -21.31747) (xy 11.468077 -21.270107) (xy 11.442986 -21.218395)
			(xy 11.425937 -21.163504) (xy 11.417315 -21.106676) (xy 11.417315 -21.049198) (xy 11.425938 -20.992371)
			(xy 11.442988 -20.93748) (xy 11.46808 -20.885768) (xy 11.500645 -20.838405) (xy 11.519916 -20.817078)
			(xy 11.52652 -20.809966) (xy 11.533632 -20.79244) (xy 11.533632 -20.703032) (xy 11.52652 -20.685506)
			(xy 11.519916 -20.678394) (xy 11.500642 -20.65707) (xy 11.468077 -20.609707) (xy 11.442986 -20.557995)
			(xy 11.425937 -20.503104) (xy 11.417315 -20.446276) (xy 11.417315 -20.388798) (xy 11.425938 -20.331971)
			(xy 11.442988 -20.27708) (xy 11.46808 -20.225368) (xy 11.500645 -20.178005) (xy 11.519916 -20.156678)
			(xy 11.52652 -20.149566) (xy 11.533632 -20.13204) (xy 11.533632 -20.042632) (xy 11.52652 -20.025106)
			(xy 11.519916 -20.017994) (xy 11.500642 -19.99667) (xy 11.468077 -19.949307) (xy 11.442986 -19.897595)
			(xy 11.425937 -19.842704) (xy 11.417315 -19.785876) (xy 11.417315 -19.728398) (xy 11.425938 -19.671571)
			(xy 11.442988 -19.61668) (xy 11.46808 -19.564968) (xy 11.500645 -19.517605) (xy 11.519916 -19.496278)
			(xy 11.52652 -19.489166) (xy 11.533632 -19.47164) (xy 11.533632 -19.382232) (xy 11.52652 -19.364706)
			(xy 11.519916 -19.357594) (xy 11.500659 -19.336255) (xy 11.468091 -19.288896) (xy 11.442997 -19.237187)
			(xy 11.425943 -19.182299) (xy 11.417316 -19.125474) (xy 11.416792 -19.096736) (xy 11.417278 -19.069485)
			(xy 11.425034 -19.015537) (xy 11.440389 -18.963242) (xy 11.463031 -18.913665) (xy 11.492497 -18.867815)
			(xy 11.528188 -18.826624) (xy 11.569379 -18.790933) (xy 11.615229 -18.761467) (xy 11.664806 -18.738825)
			(xy 11.717101 -18.72347) (xy 11.771049 -18.715714) (xy 11.825551 -18.715714) (xy 11.879499 -18.72347)
			(xy 11.931794 -18.738825) (xy 11.981371 -18.761467) (xy 12.027221 -18.790933) (xy 12.068412 -18.826624)
			(xy 12.104103 -18.867815) (xy 12.133569 -18.913665) (xy 12.156211 -18.963242) (xy 12.171566 -19.015537)
			(xy 12.179322 -19.069485) (xy 12.179808 -19.096736) (xy 12.179304 -19.125476) (xy 12.170676 -19.182304)
			(xy 12.153621 -19.237195) (xy 12.128526 -19.288906) (xy 12.095957 -19.336268) (xy 12.076684 -19.357594)
			(xy 12.07008 -19.364706) (xy 12.062968 -19.382232) (xy 12.062968 -19.47164) (xy 12.07008 -19.489166)
			(xy 12.076684 -19.496278) (xy 12.09595 -19.517608) (xy 12.128515 -19.56497) (xy 12.153606 -19.616682)
			(xy 12.170656 -19.671572) (xy 12.179279 -19.728399) (xy 12.17928 -19.785876) (xy 12.170658 -19.842702)
			(xy 12.153609 -19.897593) (xy 12.128518 -19.949304) (xy 12.095954 -19.996667) (xy 12.076684 -20.017994)
			(xy 12.07008 -20.025106) (xy 12.062968 -20.042632) (xy 12.062968 -20.13204) (xy 12.07008 -20.149566)
			(xy 12.076684 -20.156678) (xy 12.09595 -20.178008) (xy 12.128515 -20.22537) (xy 12.153606 -20.277082)
			(xy 12.170656 -20.331972) (xy 12.179279 -20.388799) (xy 12.17928 -20.446276) (xy 12.170658 -20.503102)
			(xy 12.153609 -20.557993) (xy 12.128518 -20.609704) (xy 12.095954 -20.657067) (xy 12.076684 -20.678394)
			(xy 12.07008 -20.685506) (xy 12.062968 -20.703032) (xy 12.062968 -20.79244) (xy 12.07008 -20.809966)
			(xy 12.076684 -20.817078) (xy 12.09595 -20.838408) (xy 12.128515 -20.88577) (xy 12.153606 -20.937482)
			(xy 12.170656 -20.992372) (xy 12.179279 -21.049199) (xy 12.17928 -21.106676) (xy 12.170658 -21.163502)
			(xy 12.153609 -21.218393) (xy 12.128518 -21.270104) (xy 12.095954 -21.317467) (xy 12.076684 -21.338794)
			(xy 12.07008 -21.345906) (xy 12.062968 -21.363432) (xy 12.062968 -21.45284) (xy 12.07008 -21.470366)
			(xy 12.076684 -21.477478) (xy 12.095975 -21.498787) (xy 12.128538 -21.546154) (xy 12.153626 -21.597871)
			(xy 12.166404 -21.639022) (xy 16.073882 -21.639022) (xy 16.074424 -21.610284) (xy 16.083043 -21.553458)
			(xy 16.100089 -21.498567) (xy 16.125176 -21.446855) (xy 16.157737 -21.399492) (xy 16.177006 -21.378164)
			(xy 16.18361 -21.371052) (xy 16.190722 -21.353526) (xy 16.190722 -21.264118) (xy 16.18361 -21.246592)
			(xy 16.177006 -21.23948) (xy 16.157758 -21.218134) (xy 16.125193 -21.170774) (xy 16.100102 -21.119065)
			(xy 16.083051 -21.064178) (xy 16.074427 -21.007354) (xy 16.074424 -20.949879) (xy 16.083044 -20.893053)
			(xy 16.10009 -20.838164) (xy 16.125177 -20.786454) (xy 16.157738 -20.739091) (xy 16.177006 -20.717764)
			(xy 16.18361 -20.710652) (xy 16.190722 -20.693126) (xy 16.190722 -20.603718) (xy 16.18361 -20.586192)
			(xy 16.177006 -20.57908) (xy 16.157758 -20.557734) (xy 16.125193 -20.510374) (xy 16.100102 -20.458665)
			(xy 16.083051 -20.403778) (xy 16.074427 -20.346954) (xy 16.074424 -20.289479) (xy 16.083044 -20.232653)
			(xy 16.10009 -20.177764) (xy 16.125177 -20.126054) (xy 16.157738 -20.078691) (xy 16.177006 -20.057364)
			(xy 16.18361 -20.050252) (xy 16.190722 -20.032726) (xy 16.190722 -19.943318) (xy 16.18361 -19.925792)
			(xy 16.177006 -19.91868) (xy 16.157758 -19.897334) (xy 16.125193 -19.849974) (xy 16.100102 -19.798265)
			(xy 16.083051 -19.743378) (xy 16.074427 -19.686554) (xy 16.074424 -19.629079) (xy 16.083044 -19.572253)
			(xy 16.10009 -19.517364) (xy 16.125177 -19.465654) (xy 16.157738 -19.418291) (xy 16.177006 -19.396964)
			(xy 16.18361 -19.389852) (xy 16.190722 -19.372326) (xy 16.190722 -19.282918) (xy 16.18361 -19.265392)
			(xy 16.177006 -19.25828) (xy 16.157757 -19.236934) (xy 16.125186 -19.189578) (xy 16.100088 -19.137872)
			(xy 16.083032 -19.082985) (xy 16.074405 -19.02616) (xy 16.073882 -18.997422) (xy 16.074368 -18.970171)
			(xy 16.082124 -18.916223) (xy 16.097479 -18.863928) (xy 16.120121 -18.814351) (xy 16.149587 -18.768501)
			(xy 16.185278 -18.72731) (xy 16.226469 -18.691619) (xy 16.272319 -18.662153) (xy 16.321896 -18.639511)
			(xy 16.374191 -18.624156) (xy 16.428139 -18.6164) (xy 16.482641 -18.6164) (xy 16.536589 -18.624156)
			(xy 16.588884 -18.639511) (xy 16.638461 -18.662153) (xy 16.684311 -18.691619) (xy 16.725502 -18.72731)
			(xy 16.761193 -18.768501) (xy 16.790659 -18.814351) (xy 16.813301 -18.863928) (xy 16.828656 -18.916223)
			(xy 16.836412 -18.970171) (xy 16.836898 -18.997422) (xy 16.836388 -19.026161) (xy 16.827762 -19.082989)
			(xy 16.810709 -19.13788) (xy 16.785614 -19.189592) (xy 16.753046 -19.236954) (xy 16.733774 -19.25828)
			(xy 16.72717 -19.265392) (xy 16.720058 -19.282918) (xy 16.720058 -19.372326) (xy 16.72717 -19.389852)
			(xy 16.733774 -19.396964) (xy 16.753067 -19.418272) (xy 16.785631 -19.465637) (xy 16.810722 -19.517352)
			(xy 16.82777 -19.572246) (xy 16.836391 -19.629076) (xy 16.836389 -19.686556) (xy 16.827763 -19.743385)
			(xy 16.81071 -19.798278) (xy 16.785615 -19.84999) (xy 16.753047 -19.897353) (xy 16.733774 -19.91868)
			(xy 16.72717 -19.925792) (xy 16.720058 -19.943318) (xy 16.720058 -20.032726) (xy 16.72717 -20.050252)
			(xy 16.733774 -20.057364) (xy 16.753067 -20.078672) (xy 16.785631 -20.126037) (xy 16.810722 -20.177752)
			(xy 16.82777 -20.232646) (xy 16.836391 -20.289476) (xy 16.836389 -20.346956) (xy 16.827763 -20.403785)
			(xy 16.81071 -20.458678) (xy 16.785615 -20.51039) (xy 16.753047 -20.557753) (xy 16.733774 -20.57908)
			(xy 16.72717 -20.586192) (xy 16.720058 -20.603718) (xy 16.720058 -20.693126) (xy 16.72717 -20.710652)
			(xy 16.733774 -20.717764) (xy 16.753067 -20.739072) (xy 16.785631 -20.786437) (xy 16.810722 -20.838152)
			(xy 16.82777 -20.893046) (xy 16.836391 -20.949876) (xy 16.836389 -21.007356) (xy 16.827763 -21.064185)
			(xy 16.81071 -21.119078) (xy 16.785615 -21.17079) (xy 16.753047 -21.218153) (xy 16.733774 -21.23948)
			(xy 16.72717 -21.246592) (xy 16.720058 -21.264118) (xy 16.720058 -21.353526) (xy 16.72717 -21.371052)
			(xy 16.733774 -21.378164) (xy 16.753057 -21.39948) (xy 16.785621 -21.446845) (xy 16.810711 -21.49856)
			(xy 16.827759 -21.553453) (xy 16.836379 -21.610282) (xy 16.836898 -21.639022) (xy 16.836412 -21.666273)
			(xy 16.828656 -21.720221) (xy 16.813301 -21.772516) (xy 16.790659 -21.822093) (xy 16.761193 -21.867943)
			(xy 16.725502 -21.909134) (xy 16.684311 -21.944825) (xy 16.638461 -21.974291) (xy 16.588884 -21.996933)
			(xy 16.536589 -22.012288) (xy 16.482641 -22.020044) (xy 16.428139 -22.020044) (xy 16.374191 -22.012288)
			(xy 16.321896 -21.996933) (xy 16.272319 -21.974291) (xy 16.226469 -21.944825) (xy 16.185278 -21.909134)
			(xy 16.149587 -21.867943) (xy 16.120121 -21.822093) (xy 16.097479 -21.772516) (xy 16.082124 -21.720221)
			(xy 16.074368 -21.666273) (xy 16.073882 -21.639022) (xy 12.166404 -21.639022) (xy 12.170672 -21.652765)
			(xy 12.17929 -21.709596) (xy 12.179808 -21.738336) (xy 12.179322 -21.765587) (xy 12.171566 -21.819535)
			(xy 12.156211 -21.87183) (xy 12.133569 -21.921407) (xy 12.104103 -21.967257) (xy 12.068412 -22.008448)
			(xy 12.027221 -22.044139) (xy 11.981371 -22.073605) (xy 11.931794 -22.096247) (xy 11.879499 -22.111602)
			(xy 11.825551 -22.119358) (xy 11.771049 -22.119358) (xy 11.717101 -22.111602) (xy 11.664806 -22.096247)
			(xy 11.615229 -22.073605) (xy 11.569379 -22.044139) (xy 11.528188 -22.008448) (xy 11.492497 -21.967257)
			(xy 11.463031 -21.921407) (xy 11.440389 -21.87183) (xy 11.425034 -21.819535) (xy 11.417278 -21.765587)
			(xy 11.416792 -21.738336) (xy 9.195073 -21.738336) (xy 9.174049 -21.777941) (xy 9.106108 -21.889002)
			(xy 9.031522 -21.995714) (xy 8.950569 -22.097681) (xy 8.86355 -22.194523) (xy 8.770789 -22.28588)
			(xy 8.672631 -22.371412) (xy 8.569442 -22.4508) (xy 8.461605 -22.52375) (xy 8.34952 -22.589991) (xy 8.233607 -22.649274)
			(xy 8.114294 -22.701382) (xy 7.992027 -22.746118) (xy 7.86726 -22.783317) (xy 7.740457 -22.812841)
			(xy 7.61209 -22.834579) (xy 7.482637 -22.848452) (xy 7.352578 -22.854406) (xy 7.222399 -22.852421)
			(xy 7.092583 -22.842503) (xy 6.963613 -22.824689) (xy 6.835968 -22.799046) (xy 6.710125 -22.765669)
			(xy 6.58655 -22.724682) (xy 6.465704 -22.676238) (xy 6.348036 -22.620516) (xy 6.233984 -22.557725)
			(xy 6.123972 -22.488098) (xy 6.01841 -22.411893) (xy 5.91769 -22.329394) (xy 5.822186 -22.240909)
			(xy 5.732254 -22.146766) (xy 5.648229 -22.047315) (xy 5.570424 -21.942927) (xy 5.499127 -21.83399)
			(xy 5.434603 -21.720908) (xy 5.377094 -21.604104) (xy 5.326812 -21.484011) (xy 5.283946 -21.361075)
			(xy 5.248653 -21.235756) (xy 5.221067 -21.108517) (xy 5.201288 -20.979834) (xy 5.189392 -20.850184)
			(xy 5.185422 -20.72005) (xy 1.27 -20.72005) (xy 1.27 -22.327362) (xy 2.865626 -22.327362) (xy 2.869697 -22.27174)
			(xy 2.881823 -22.217303) (xy 2.901746 -22.165212) (xy 2.929042 -22.116577) (xy 2.963128 -22.072434)
			(xy 3.003277 -22.033725) (xy 3.048635 -22.001274) (xy 3.098235 -21.975773) (xy 3.151019 -21.957766)
			(xy 3.205862 -21.947636) (xy 3.261596 -21.945599) (xy 3.317033 -21.951699) (xy 3.37099 -21.965805)
			(xy 3.422319 -21.987617) (xy 3.469925 -22.016671) (xy 3.512793 -22.052346) (xy 3.55001 -22.093883)
			(xy 3.580783 -22.140396) (xy 3.604455 -22.190893) (xy 3.620523 -22.2443) (xy 3.628643 -22.299476)
			(xy 3.629152 -22.327362) (xy 3.628643 -22.355248) (xy 3.620523 -22.410424) (xy 3.604455 -22.463831)
			(xy 3.580783 -22.514328) (xy 3.55001 -22.560841) (xy 3.512793 -22.602378) (xy 3.469925 -22.638053)
			(xy 3.422319 -22.667107) (xy 3.37099 -22.688919) (xy 3.317033 -22.703025) (xy 3.261596 -22.709125)
			(xy 3.205862 -22.707088) (xy 3.151019 -22.696958) (xy 3.098235 -22.678951) (xy 3.048635 -22.65345)
			(xy 3.003277 -22.620999) (xy 2.963128 -22.58229) (xy 2.929042 -22.538147) (xy 2.901746 -22.489512)
			(xy 2.881823 -22.437421) (xy 2.869697 -22.382984) (xy 2.865626 -22.327362) (xy 1.27 -22.327362) (xy 1.27 -22.86)
			(xy 4.189982 -22.86) (xy 4.194053 -22.804378) (xy 4.206179 -22.749941) (xy 4.226102 -22.69785) (xy 4.253398 -22.649215)
			(xy 4.287484 -22.605072) (xy 4.327633 -22.566363) (xy 4.372991 -22.533912) (xy 4.422591 -22.508411)
			(xy 4.475375 -22.490404) (xy 4.530218 -22.480274) (xy 4.585952 -22.478237) (xy 4.641389 -22.484337)
			(xy 4.695346 -22.498443) (xy 4.746675 -22.520255) (xy 4.794281 -22.549309) (xy 4.837149 -22.584984)
			(xy 4.874366 -22.626521) (xy 4.905139 -22.673034) (xy 4.928811 -22.723531) (xy 4.944879 -22.776938)
			(xy 4.952999 -22.832114) (xy 4.953508 -22.86) (xy 4.952999 -22.887886) (xy 4.944879 -22.943062) (xy 4.928811 -22.996469)
			(xy 4.919043 -23.017305) (xy 11.299903 -23.017305) (xy 11.299903 -22.962799) (xy 11.30766 -22.908848)
			(xy 11.323016 -22.85655) (xy 11.345658 -22.806969) (xy 11.375126 -22.761116) (xy 11.41082 -22.719922)
			(xy 11.452012 -22.684228) (xy 11.497866 -22.65476) (xy 11.547446 -22.632117) (xy 11.599744 -22.616761)
			(xy 11.653695 -22.609003) (xy 11.708201 -22.609003) (xy 11.762152 -22.61676) (xy 11.81445 -22.632116)
			(xy 11.864031 -22.654758) (xy 11.909884 -22.684226) (xy 11.951078 -22.71992) (xy 11.986772 -22.761112)
			(xy 12.01624 -22.806966) (xy 12.038883 -22.856546) (xy 12.054239 -22.908844) (xy 12.061997 -22.962795)
			(xy 12.06246 -22.990048) (xy 12.061698 -23.014178) (xy 12.061632 -23.01621) (xy 12.711682 -23.01621)
			(xy 12.715753 -22.960588) (xy 12.727879 -22.906151) (xy 12.747802 -22.85406) (xy 12.775098 -22.805425)
			(xy 12.809184 -22.761282) (xy 12.849333 -22.722573) (xy 12.894691 -22.690122) (xy 12.944291 -22.664621)
			(xy 12.997075 -22.646614) (xy 13.051918 -22.636484) (xy 13.107652 -22.634447) (xy 13.163089 -22.640547)
			(xy 13.217046 -22.654653) (xy 13.268375 -22.676465) (xy 13.315981 -22.705519) (xy 13.358849 -22.741194)
			(xy 13.396066 -22.782731) (xy 13.426839 -22.829244) (xy 13.450511 -22.879741) (xy 13.466579 -22.933148)
			(xy 13.474699 -22.988324) (xy 13.475208 -23.01621) (xy 13.474699 -23.044096) (xy 13.466579 -23.099272)
			(xy 13.450511 -23.152679) (xy 13.426839 -23.203176) (xy 13.396066 -23.249689) (xy 13.358849 -23.291226)
			(xy 13.315981 -23.326901) (xy 13.268375 -23.355955) (xy 13.217046 -23.377767) (xy 13.163089 -23.391873)
			(xy 13.107652 -23.397973) (xy 13.051918 -23.395936) (xy 12.997075 -23.385806) (xy 12.944291 -23.367799)
			(xy 12.894691 -23.342298) (xy 12.849333 -23.309847) (xy 12.809184 -23.271138) (xy 12.775098 -23.226995)
			(xy 12.747802 -23.17836) (xy 12.727879 -23.126269) (xy 12.715753 -23.071832) (xy 12.711682 -23.01621)
			(xy 12.061632 -23.01621) (xy 12.061253 -23.027907) (xy 12.066888 -23.054781) (xy 12.079487 -23.079179)
			(xy 12.098137 -23.099332) (xy 12.121487 -23.113781) (xy 12.147845 -23.121477) (xy 12.175302 -23.121865)
			(xy 12.188698 -23.118826) (xy 12.212225 -23.113118) (xy 12.26025 -23.107008) (xy 12.284456 -23.106634)
			(xy 12.311709 -23.107091) (xy 12.365661 -23.114848) (xy 12.417959 -23.130203) (xy 12.46754 -23.152845)
			(xy 12.513394 -23.182313) (xy 12.554588 -23.218007) (xy 12.590282 -23.2592) (xy 12.619751 -23.305053)
			(xy 12.642394 -23.354634) (xy 12.657751 -23.406932) (xy 12.665508 -23.460884) (xy 12.665509 -23.51539)
			(xy 12.657752 -23.569341) (xy 12.651688 -23.589996) (xy 16.084548 -23.589996) (xy 16.088619 -23.534374)
			(xy 16.100745 -23.479937) (xy 16.120668 -23.427846) (xy 16.147964 -23.379211) (xy 16.18205 -23.335068)
			(xy 16.222199 -23.296359) (xy 16.267557 -23.263908) (xy 16.317157 -23.238407) (xy 16.369941 -23.2204)
			(xy 16.424784 -23.21027) (xy 16.480518 -23.208233) (xy 16.535955 -23.214333) (xy 16.589912 -23.228439)
			(xy 16.641241 -23.250251) (xy 16.688847 -23.279305) (xy 16.731715 -23.31498) (xy 16.768932 -23.356517)
			(xy 16.799705 -23.40303) (xy 16.823377 -23.453527) (xy 16.839445 -23.506934) (xy 16.847565 -23.56211)
			(xy 16.848074 -23.589996) (xy 16.847565 -23.617882) (xy 16.839445 -23.673058) (xy 16.823377 -23.726465)
			(xy 16.799705 -23.776962) (xy 16.768932 -23.823475) (xy 16.731715 -23.865012) (xy 16.713323 -23.880318)
			(xy 17.240756 -23.880318) (xy 17.244827 -23.824696) (xy 17.256953 -23.770259) (xy 17.276876 -23.718168)
			(xy 17.304172 -23.669533) (xy 17.338258 -23.62539) (xy 17.378407 -23.586681) (xy 17.423765 -23.55423)
			(xy 17.473365 -23.528729) (xy 17.526149 -23.510722) (xy 17.580992 -23.500592) (xy 17.636726 -23.498555)
			(xy 17.692163 -23.504655) (xy 17.74612 -23.518761) (xy 17.797449 -23.540573) (xy 17.845055 -23.569627)
			(xy 17.887923 -23.605302) (xy 17.92514 -23.646839) (xy 17.955913 -23.693352) (xy 17.979585 -23.743849)
			(xy 17.995653 -23.797256) (xy 18.003773 -23.852432) (xy 18.004282 -23.880318) (xy 18.256756 -23.880318)
			(xy 18.260827 -23.824696) (xy 18.272953 -23.770259) (xy 18.292876 -23.718168) (xy 18.320172 -23.669533)
			(xy 18.354258 -23.62539) (xy 18.394407 -23.586681) (xy 18.439765 -23.55423) (xy 18.489365 -23.528729)
			(xy 18.542149 -23.510722) (xy 18.596992 -23.500592) (xy 18.652726 -23.498555) (xy 18.708163 -23.504655)
			(xy 18.76212 -23.518761) (xy 18.813449 -23.540573) (xy 18.861055 -23.569627) (xy 18.903923 -23.605302)
			(xy 18.94114 -23.646839) (xy 18.971913 -23.693352) (xy 18.995585 -23.743849) (xy 19.011653 -23.797256)
			(xy 19.019773 -23.852432) (xy 19.020282 -23.880318) (xy 19.019773 -23.908204) (xy 19.011653 -23.96338)
			(xy 18.995585 -24.016787) (xy 18.971913 -24.067284) (xy 18.94114 -24.113797) (xy 18.903923 -24.155334)
			(xy 18.861055 -24.191009) (xy 18.813449 -24.220063) (xy 18.76212 -24.241875) (xy 18.708163 -24.255981)
			(xy 18.652726 -24.262081) (xy 18.596992 -24.260044) (xy 18.542149 -24.249914) (xy 18.489365 -24.231907)
			(xy 18.439765 -24.206406) (xy 18.394407 -24.173955) (xy 18.354258 -24.135246) (xy 18.320172 -24.091103)
			(xy 18.292876 -24.042468) (xy 18.272953 -23.990377) (xy 18.260827 -23.93594) (xy 18.256756 -23.880318)
			(xy 18.004282 -23.880318) (xy 18.003773 -23.908204) (xy 17.995653 -23.96338) (xy 17.979585 -24.016787)
			(xy 17.955913 -24.067284) (xy 17.92514 -24.113797) (xy 17.887923 -24.155334) (xy 17.845055 -24.191009)
			(xy 17.797449 -24.220063) (xy 17.74612 -24.241875) (xy 17.692163 -24.255981) (xy 17.636726 -24.262081)
			(xy 17.580992 -24.260044) (xy 17.526149 -24.249914) (xy 17.473365 -24.231907) (xy 17.423765 -24.206406)
			(xy 17.378407 -24.173955) (xy 17.338258 -24.135246) (xy 17.304172 -24.091103) (xy 17.276876 -24.042468)
			(xy 17.256953 -23.990377) (xy 17.244827 -23.93594) (xy 17.240756 -23.880318) (xy 16.713323 -23.880318)
			(xy 16.688847 -23.900687) (xy 16.641241 -23.929741) (xy 16.589912 -23.951553) (xy 16.535955 -23.965659)
			(xy 16.480518 -23.971759) (xy 16.424784 -23.969722) (xy 16.369941 -23.959592) (xy 16.317157 -23.941585)
			(xy 16.267557 -23.916084) (xy 16.222199 -23.883633) (xy 16.18205 -23.844924) (xy 16.147964 -23.800781)
			(xy 16.120668 -23.752146) (xy 16.100745 -23.700055) (xy 16.088619 -23.645618) (xy 16.084548 -23.589996)
			(xy 12.651688 -23.589996) (xy 12.642397 -23.62164) (xy 12.619754 -23.671221) (xy 12.590286 -23.717075)
			(xy 12.554592 -23.758268) (xy 12.5134 -23.793963) (xy 12.467546 -23.823431) (xy 12.417966 -23.846074)
			(xy 12.365667 -23.861431) (xy 12.311716 -23.869188) (xy 12.257209 -23.869189) (xy 12.203258 -23.861432)
			(xy 12.150959 -23.846076) (xy 12.101379 -23.823434) (xy 12.055525 -23.793966) (xy 12.014331 -23.758272)
			(xy 11.978637 -23.717079) (xy 11.949168 -23.671226) (xy 11.926525 -23.621645) (xy 11.911169 -23.569347)
			(xy 11.903411 -23.515395) (xy 11.902948 -23.488142) (xy 11.90371 -23.464012) (xy 11.904154 -23.450284)
			(xy 11.898517 -23.423411) (xy 11.885918 -23.399014) (xy 11.867268 -23.378862) (xy 11.843918 -23.364414)
			(xy 11.817561 -23.356716) (xy 11.790106 -23.356326) (xy 11.77671 -23.359364) (xy 11.753183 -23.36507)
			(xy 11.705158 -23.371181) (xy 11.680952 -23.371556) (xy 11.653699 -23.371097) (xy 11.599748 -23.36334)
			(xy 11.54745 -23.347984) (xy 11.497869 -23.325342) (xy 11.452016 -23.295874) (xy 11.410822 -23.26018)
			(xy 11.375128 -23.218988) (xy 11.34566 -23.173134) (xy 11.323017 -23.123554) (xy 11.307661 -23.071256)
			(xy 11.299903 -23.017305) (xy 4.919043 -23.017305) (xy 4.905139 -23.046966) (xy 4.874366 -23.093479)
			(xy 4.837149 -23.135016) (xy 4.794281 -23.170691) (xy 4.746675 -23.199745) (xy 4.695346 -23.221557)
			(xy 4.641389 -23.235663) (xy 4.585952 -23.241763) (xy 4.530218 -23.239726) (xy 4.475375 -23.229596)
			(xy 4.422591 -23.211589) (xy 4.372991 -23.186088) (xy 4.327633 -23.153637) (xy 4.287484 -23.114928)
			(xy 4.253398 -23.070785) (xy 4.226102 -23.02215) (xy 4.206179 -22.970059) (xy 4.194053 -22.915622)
			(xy 4.189982 -22.86) (xy 1.27 -22.86) (xy 1.27 -23.963195) (xy 2.233146 -23.963195) (xy 2.233146 -23.908693)
			(xy 2.240902 -23.854745) (xy 2.256257 -23.80245) (xy 2.278899 -23.752873) (xy 2.308365 -23.707023)
			(xy 2.344056 -23.665832) (xy 2.385247 -23.630141) (xy 2.431097 -23.600675) (xy 2.480674 -23.578033)
			(xy 2.532969 -23.562678) (xy 2.586917 -23.554922) (xy 2.614168 -23.554436) (xy 2.635756 -23.554709)
			(xy 2.678659 -23.559549) (xy 2.699766 -23.564088) (xy 2.712212 -23.567136) (xy 2.736088 -23.560786)
			(xy 2.816606 -23.486618) (xy 2.824988 -23.46325) (xy 2.822956 -23.45055) (xy 2.821143 -23.436971)
			(xy 2.819239 -23.409639) (xy 2.819146 -23.39594) (xy 2.819632 -23.368689) (xy 2.827388 -23.314741)
			(xy 2.842743 -23.262446) (xy 2.865385 -23.212869) (xy 2.894851 -23.167019) (xy 2.930542 -23.125828)
			(xy 2.971733 -23.090137) (xy 3.017583 -23.060671) (xy 3.06716 -23.038029) (xy 3.119455 -23.022674)
			(xy 3.173403 -23.014918) (xy 3.227905 -23.014918) (xy 3.281853 -23.022674) (xy 3.334148 -23.038029)
			(xy 3.383725 -23.060671) (xy 3.429575 -23.090137) (xy 3.470766 -23.125828) (xy 3.506457 -23.167019)
			(xy 3.535923 -23.212869) (xy 3.558565 -23.262446) (xy 3.57392 -23.314741) (xy 3.581676 -23.368689)
			(xy 3.582162 -23.39594) (xy 3.58204 -23.407847) (xy 3.580517 -23.431613) (xy 3.579114 -23.443438)
			(xy 3.577844 -23.453598) (xy 3.583178 -23.473156) (xy 3.640328 -23.546054) (xy 3.657854 -23.55596)
			(xy 3.668014 -23.556976) (xy 3.69549 -23.560743) (xy 3.749032 -23.575188) (xy 3.799919 -23.597231)
			(xy 3.847079 -23.626408) (xy 3.889518 -23.662106) (xy 3.926342 -23.703571) (xy 3.956776 -23.74993)
			(xy 3.980178 -23.800207) (xy 3.996055 -23.853342) (xy 4.004072 -23.908216) (xy 4.004564 -23.935944)
			(xy 4.004078 -23.963195) (xy 3.996322 -24.017143) (xy 3.980967 -24.069438) (xy 3.958325 -24.119015)
			(xy 3.928859 -24.164865) (xy 3.907129 -24.189944) (xy 13.821916 -24.189944) (xy 13.825987 -24.134322)
			(xy 13.838113 -24.079885) (xy 13.858036 -24.027794) (xy 13.885332 -23.979159) (xy 13.919418 -23.935016)
			(xy 13.959567 -23.896307) (xy 14.004925 -23.863856) (xy 14.054525 -23.838355) (xy 14.107309 -23.820348)
			(xy 14.162152 -23.810218) (xy 14.217886 -23.808181) (xy 14.273323 -23.814281) (xy 14.32728 -23.828387)
			(xy 14.378609 -23.850199) (xy 14.426215 -23.879253) (xy 14.469083 -23.914928) (xy 14.5063 -23.956465)
			(xy 14.537073 -24.002978) (xy 14.560745 -24.053475) (xy 14.576813 -24.106882) (xy 14.584933 -24.162058)
			(xy 14.585442 -24.189944) (xy 14.584933 -24.21783) (xy 14.576813 -24.273006) (xy 14.560745 -24.326413)
			(xy 14.548157 -24.353266) (xy 19.380198 -24.353266) (xy 19.384269 -24.297644) (xy 19.396395 -24.243207)
			(xy 19.416318 -24.191116) (xy 19.443614 -24.142481) (xy 19.4777 -24.098338) (xy 19.517849 -24.059629)
			(xy 19.563207 -24.027178) (xy 19.612807 -24.001677) (xy 19.665591 -23.98367) (xy 19.720434 -23.97354)
			(xy 19.776168 -23.971503) (xy 19.831605 -23.977603) (xy 19.885562 -23.991709) (xy 19.936891 -24.013521)
			(xy 19.984497 -24.042575) (xy 20.027365 -24.07825) (xy 20.064582 -24.119787) (xy 20.095355 -24.1663)
			(xy 20.119027 -24.216797) (xy 20.135095 -24.270204) (xy 20.143215 -24.32538) (xy 20.143724 -24.353266)
			(xy 20.143215 -24.381152) (xy 20.135095 -24.436328) (xy 20.119027 -24.489735) (xy 20.095355 -24.540232)
			(xy 20.064582 -24.586745) (xy 20.027365 -24.628282) (xy 19.984497 -24.663957) (xy 19.936891 -24.693011)
			(xy 19.885562 -24.714823) (xy 19.831605 -24.728929) (xy 19.776168 -24.735029) (xy 19.720434 -24.732992)
			(xy 19.665591 -24.722862) (xy 19.612807 -24.704855) (xy 19.563207 -24.679354) (xy 19.517849 -24.646903)
			(xy 19.4777 -24.608194) (xy 19.443614 -24.564051) (xy 19.416318 -24.515416) (xy 19.396395 -24.463325)
			(xy 19.384269 -24.408888) (xy 19.380198 -24.353266) (xy 14.548157 -24.353266) (xy 14.537073 -24.37691)
			(xy 14.5063 -24.423423) (xy 14.469083 -24.46496) (xy 14.426215 -24.500635) (xy 14.378609 -24.529689)
			(xy 14.32728 -24.551501) (xy 14.273323 -24.565607) (xy 14.217886 -24.571707) (xy 14.162152 -24.56967)
			(xy 14.107309 -24.55954) (xy 14.054525 -24.541533) (xy 14.004925 -24.516032) (xy 13.959567 -24.483581)
			(xy 13.919418 -24.444872) (xy 13.885332 -24.400729) (xy 13.858036 -24.352094) (xy 13.838113 -24.300003)
			(xy 13.825987 -24.245566) (xy 13.821916 -24.189944) (xy 3.907129 -24.189944) (xy 3.893168 -24.206056)
			(xy 3.851977 -24.241747) (xy 3.806127 -24.271213) (xy 3.75655 -24.293855) (xy 3.704255 -24.30921)
			(xy 3.650307 -24.316966) (xy 3.595805 -24.316966) (xy 3.541857 -24.30921) (xy 3.489562 -24.293855)
			(xy 3.439985 -24.271213) (xy 3.394135 -24.241747) (xy 3.352944 -24.206056) (xy 3.317253 -24.164865)
			(xy 3.287787 -24.119015) (xy 3.265145 -24.069438) (xy 3.24979 -24.017143) (xy 3.242034 -23.963195)
			(xy 3.241548 -23.935944) (xy 3.241669 -23.924037) (xy 3.243192 -23.900271) (xy 3.244596 -23.888446)
			(xy 3.245866 -23.878286) (xy 3.240532 -23.858728) (xy 3.183382 -23.78583) (xy 3.165856 -23.775924)
			(xy 3.155696 -23.774908) (xy 3.145457 -23.773613) (xy 3.125126 -23.770057) (xy 3.115056 -23.767796)
			(xy 3.10261 -23.764748) (xy 3.078734 -23.771098) (xy 2.998216 -23.845266) (xy 2.989834 -23.868634)
			(xy 2.991866 -23.881334) (xy 2.993678 -23.894913) (xy 2.995583 -23.922245) (xy 2.995676 -23.935944)
			(xy 2.99519 -23.963195) (xy 2.987434 -24.017143) (xy 2.972079 -24.069438) (xy 2.949437 -24.119015)
			(xy 2.919971 -24.164865) (xy 2.88428 -24.206056) (xy 2.843089 -24.241747) (xy 2.797239 -24.271213)
			(xy 2.747662 -24.293855) (xy 2.695367 -24.30921) (xy 2.641419 -24.316966) (xy 2.586917 -24.316966)
			(xy 2.532969 -24.30921) (xy 2.480674 -24.293855) (xy 2.431097 -24.271213) (xy 2.385247 -24.241747)
			(xy 2.344056 -24.206056) (xy 2.308365 -24.164865) (xy 2.278899 -24.119015) (xy 2.256257 -24.069438)
			(xy 2.240902 -24.017143) (xy 2.233146 -23.963195) (xy 1.27 -23.963195) (xy 1.27 -24.807418) (xy 8.62025 -24.807418)
			(xy 8.624321 -24.751796) (xy 8.636447 -24.697359) (xy 8.65637 -24.645268) (xy 8.683666 -24.596633)
			(xy 8.717752 -24.55249) (xy 8.757901 -24.513781) (xy 8.803259 -24.48133) (xy 8.852859 -24.455829)
			(xy 8.905643 -24.437822) (xy 8.960486 -24.427692) (xy 9.01622 -24.425655) (xy 9.071657 -24.431755)
			(xy 9.125614 -24.445861) (xy 9.176943 -24.467673) (xy 9.224549 -24.496727) (xy 9.267417 -24.532402)
			(xy 9.304634 -24.573939) (xy 9.335407 -24.620452) (xy 9.359079 -24.670949) (xy 9.375147 -24.724356)
			(xy 9.383267 -24.779532) (xy 9.383776 -24.807418) (xy 9.383267 -24.835304) (xy 9.375147 -24.89048)
			(xy 9.359079 -24.943887) (xy 9.335407 -24.994384) (xy 9.304634 -25.040897) (xy 9.267417 -25.082434)
			(xy 9.224549 -25.118109) (xy 9.176943 -25.147163) (xy 9.125614 -25.168975) (xy 9.071657 -25.183081)
			(xy 9.01622 -25.189181) (xy 8.960486 -25.187144) (xy 8.905643 -25.177014) (xy 8.852859 -25.159007)
			(xy 8.803259 -25.133506) (xy 8.757901 -25.101055) (xy 8.717752 -25.062346) (xy 8.683666 -25.018203)
			(xy 8.65637 -24.969568) (xy 8.636447 -24.917477) (xy 8.624321 -24.86304) (xy 8.62025 -24.807418)
			(xy 1.27 -24.807418) (xy 1.27 -25.390094) (xy 13.809726 -25.390094) (xy 13.810212 -25.362843) (xy 13.817968 -25.308895)
			(xy 13.833323 -25.2566) (xy 13.855965 -25.207023) (xy 13.885431 -25.161173) (xy 13.921122 -25.119982)
			(xy 13.962313 -25.084291) (xy 14.008163 -25.054825) (xy 14.05774 -25.032183) (xy 14.110035 -25.016828)
			(xy 14.163983 -25.009072) (xy 14.218485 -25.009072) (xy 14.272433 -25.016828) (xy 14.324728 -25.032183)
			(xy 14.374305 -25.054825) (xy 14.420155 -25.084291) (xy 14.461346 -25.119982) (xy 14.497037 -25.161173)
			(xy 14.526503 -25.207023) (xy 14.549145 -25.2566) (xy 14.5645 -25.308895) (xy 14.572256 -25.362843)
			(xy 14.572742 -25.390094) (xy 14.572174 -25.419114) (xy 14.563384 -25.476484) (xy 14.546005 -25.531861)
			(xy 14.520439 -25.583967) (xy 14.487276 -25.6316) (xy 14.447281 -25.673659) (xy 14.42466 -25.691846)
			(xy 14.414119 -25.700619) (xy 14.397684 -25.722554) (xy 14.387682 -25.748074) (xy 14.384837 -25.775336)
			(xy 14.389352 -25.802371) (xy 14.400903 -25.827228) (xy 14.418655 -25.848112) (xy 14.42974 -25.856184)
			(xy 14.451388 -25.871494) (xy 14.490642 -25.907134) (xy 14.524583 -25.947868) (xy 14.552556 -25.99291)
			(xy 14.574021 -26.041391) (xy 14.588565 -26.092378) (xy 14.595908 -26.144888) (xy 14.596364 -26.171398)
			(xy 14.595878 -26.198649) (xy 14.588122 -26.252597) (xy 14.572767 -26.304892) (xy 14.550125 -26.354469)
			(xy 14.520659 -26.400319) (xy 14.484968 -26.44151) (xy 14.443777 -26.477201) (xy 14.397927 -26.506667)
			(xy 14.34835 -26.529309) (xy 14.296055 -26.544664) (xy 14.242107 -26.55242) (xy 14.187605 -26.55242)
			(xy 14.133657 -26.544664) (xy 14.081362 -26.529309) (xy 14.031785 -26.506667) (xy 13.985935 -26.477201)
			(xy 13.944744 -26.44151) (xy 13.909053 -26.400319) (xy 13.879587 -26.354469) (xy 13.856945 -26.304892)
			(xy 13.84159 -26.252597) (xy 13.833834 -26.198649) (xy 13.833348 -26.171398) (xy 13.833914 -26.142378)
			(xy 13.842705 -26.085008) (xy 13.860085 -26.029631) (xy 13.885651 -25.977525) (xy 13.918814 -25.929893)
			(xy 13.95881 -25.887833) (xy 13.98143 -25.869646) (xy 13.99198 -25.860883) (xy 14.008417 -25.838946)
			(xy 14.018419 -25.813424) (xy 14.021264 -25.786159) (xy 14.016747 -25.759122) (xy 14.005193 -25.734264)
			(xy 13.987437 -25.713379) (xy 13.97635 -25.705308) (xy 13.954696 -25.690007) (xy 13.915442 -25.654364)
			(xy 13.881502 -25.613629) (xy 13.85353 -25.568586) (xy 13.832066 -25.520103) (xy 13.817523 -25.469115)
			(xy 13.810181 -25.416605) (xy 13.809726 -25.390094) (xy 1.27 -25.390094) (xy 1.27 -26.03373) (xy 5.317488 -26.03373)
			(xy 5.321559 -25.978108) (xy 5.333685 -25.923671) (xy 5.353608 -25.87158) (xy 5.380904 -25.822945)
			(xy 5.41499 -25.778802) (xy 5.455139 -25.740093) (xy 5.500497 -25.707642) (xy 5.550097 -25.682141)
			(xy 5.602881 -25.664134) (xy 5.657724 -25.654004) (xy 5.713458 -25.651967) (xy 5.768895 -25.658067)
			(xy 5.822852 -25.672173) (xy 5.874181 -25.693985) (xy 5.921787 -25.723039) (xy 5.964655 -25.758714)
			(xy 6.001872 -25.800251) (xy 6.032645 -25.846764) (xy 6.056317 -25.897261) (xy 6.072385 -25.950668)
			(xy 6.080505 -26.005844) (xy 6.081014 -26.03373) (xy 6.080505 -26.061616) (xy 6.072385 -26.116792)
			(xy 6.056317 -26.170199) (xy 6.032645 -26.220696) (xy 6.002411 -26.266394) (xy 8.520684 -26.266394)
			(xy 8.521172 -26.239143) (xy 8.528929 -26.185196) (xy 8.544285 -26.132902) (xy 8.566926 -26.083325)
			(xy 8.596392 -26.037475) (xy 8.632083 -25.996285) (xy 8.673273 -25.960593) (xy 8.719123 -25.931127)
			(xy 8.7687 -25.908485) (xy 8.820994 -25.89313) (xy 8.874941 -25.885372) (xy 8.902192 -25.884886)
			(xy 8.931517 -25.885418) (xy 8.989475 -25.8944) (xy 9.045374 -25.912152) (xy 9.097894 -25.938256)
			(xy 9.122156 -25.954736) (xy 9.13257 -25.961848) (xy 9.156954 -25.96515) (xy 9.259316 -25.927304)
			(xy 9.27608 -25.908762) (xy 9.279128 -25.89657) (xy 9.28648 -25.869486) (xy 9.308039 -25.817675)
			(xy 9.336958 -25.769581) (xy 9.372613 -25.726246) (xy 9.414234 -25.688603) (xy 9.460922 -25.657466)
			(xy 9.511669 -25.633507) (xy 9.565379 -25.617244) (xy 9.620893 -25.609028) (xy 9.648952 -25.608534)
			(xy 9.676203 -25.609016) (xy 9.730151 -25.616773) (xy 9.782446 -25.632128) (xy 9.832023 -25.654769)
			(xy 9.877874 -25.684236) (xy 9.919064 -25.719928) (xy 9.954755 -25.761118) (xy 9.984221 -25.806969)
			(xy 10.006863 -25.856546) (xy 10.022218 -25.908841) (xy 10.029974 -25.962789) (xy 10.029974 -25.990042)
			(xy 11.298934 -25.990042) (xy 11.303005 -25.93442) (xy 11.315131 -25.879983) (xy 11.335054 -25.827892)
			(xy 11.36235 -25.779257) (xy 11.396436 -25.735114) (xy 11.436585 -25.696405) (xy 11.481943 -25.663954)
			(xy 11.531543 -25.638453) (xy 11.584327 -25.620446) (xy 11.63917 -25.610316) (xy 11.694904 -25.608279)
			(xy 11.750341 -25.614379) (xy 11.804298 -25.628485) (xy 11.855627 -25.650297) (xy 11.903233 -25.679351)
			(xy 11.946101 -25.715026) (xy 11.983318 -25.756563) (xy 12.014091 -25.803076) (xy 12.037763 -25.853573)
			(xy 12.053831 -25.90698) (xy 12.061951 -25.962156) (xy 12.06246 -25.990042) (xy 12.061951 -26.017928)
			(xy 12.053831 -26.073104) (xy 12.037763 -26.126511) (xy 12.014091 -26.177008) (xy 11.983318 -26.223521)
			(xy 11.946101 -26.265058) (xy 11.903233 -26.300733) (xy 11.855627 -26.329787) (xy 11.804298 -26.351599)
			(xy 11.750341 -26.365705) (xy 11.694904 -26.371805) (xy 11.63917 -26.369768) (xy 11.584327 -26.359638)
			(xy 11.531543 -26.341631) (xy 11.481943 -26.31613) (xy 11.436585 -26.283679) (xy 11.396436 -26.24497)
			(xy 11.36235 -26.200827) (xy 11.335054 -26.152192) (xy 11.315131 -26.100101) (xy 11.303005 -26.045664)
			(xy 11.298934 -25.990042) (xy 10.029974 -25.990042) (xy 10.029974 -26.017291) (xy 10.022218 -26.071239)
			(xy 10.006863 -26.123534) (xy 9.984221 -26.173111) (xy 9.954755 -26.218962) (xy 9.919064 -26.260152)
			(xy 9.877874 -26.295844) (xy 9.832023 -26.325311) (xy 9.782446 -26.347952) (xy 9.730151 -26.363307)
			(xy 9.676203 -26.371064) (xy 9.648952 -26.37155) (xy 9.619628 -26.370989) (xy 9.561672 -26.362015)
			(xy 9.505773 -26.344271) (xy 9.453251 -26.318176) (xy 9.428988 -26.3017) (xy 9.418574 -26.294588)
			(xy 9.39419 -26.291286) (xy 9.291828 -26.329132) (xy 9.275064 -26.347674) (xy 9.272016 -26.359866)
			(xy 9.265246 -26.384902) (xy 9.245828 -26.432993) (xy 9.220069 -26.478007) (xy 9.188444 -26.519112)
			(xy 9.151537 -26.55555) (xy 9.131046 -26.571448) (xy 9.120886 -26.579322) (xy 9.110218 -26.601928)
			(xy 9.115806 -26.711656) (xy 9.12876 -26.733246) (xy 9.139682 -26.73985) (xy 9.163414 -26.754761)
			(xy 9.206651 -26.790425) (xy 9.244203 -26.832031) (xy 9.275264 -26.878684) (xy 9.299164 -26.92938)
			(xy 9.31539 -26.983027) (xy 9.323591 -27.03847) (xy 9.324086 -27.066494) (xy 9.3236 -27.093745) (xy 9.315844 -27.147693)
			(xy 9.300489 -27.199988) (xy 9.277847 -27.249565) (xy 9.248381 -27.295415) (xy 9.21269 -27.336606)
			(xy 9.171499 -27.372297) (xy 9.125649 -27.401763) (xy 9.076072 -27.424405) (xy 9.023777 -27.43976)
			(xy 8.969829 -27.447516) (xy 8.915327 -27.447516) (xy 8.861379 -27.43976) (xy 8.809084 -27.424405)
			(xy 8.759507 -27.401763) (xy 8.713657 -27.372297) (xy 8.672466 -27.336606) (xy 8.636775 -27.295415)
			(xy 8.607309 -27.249565) (xy 8.584667 -27.199988) (xy 8.569312 -27.147693) (xy 8.561556 -27.093745)
			(xy 8.56107 -27.066494) (xy 8.561625 -27.037006) (xy 8.570721 -26.978737) (xy 8.588679 -26.922562)
			(xy 8.615072 -26.869822) (xy 8.64927 -26.821774) (xy 8.690457 -26.779564) (xy 8.713724 -26.76144)
			(xy 8.723884 -26.753566) (xy 8.734552 -26.73096) (xy 8.728964 -26.621232) (xy 8.71601 -26.599642)
			(xy 8.705088 -26.593038) (xy 8.681343 -26.578146) (xy 8.638109 -26.542477) (xy 8.600558 -26.500868)
			(xy 8.569499 -26.454211) (xy 8.545601 -26.403513) (xy 8.529377 -26.349864) (xy 8.521178 -26.294418)
			(xy 8.520684 -26.266394) (xy 6.002411 -26.266394) (xy 6.001872 -26.267209) (xy 5.964655 -26.308746)
			(xy 5.921787 -26.344421) (xy 5.874181 -26.373475) (xy 5.822852 -26.395287) (xy 5.768895 -26.409393)
			(xy 5.713458 -26.415493) (xy 5.657724 -26.413456) (xy 5.602881 -26.403326) (xy 5.550097 -26.385319)
			(xy 5.500497 -26.359818) (xy 5.455139 -26.327367) (xy 5.41499 -26.288658) (xy 5.380904 -26.244515)
			(xy 5.353608 -26.19588) (xy 5.333685 -26.143789) (xy 5.321559 -26.089352) (xy 5.317488 -26.03373)
			(xy 1.27 -26.03373) (xy 1.27 -27.305254) (xy 1.996438 -27.305254) (xy 2.000509 -27.249632) (xy 2.012635 -27.195195)
			(xy 2.032558 -27.143104) (xy 2.059854 -27.094469) (xy 2.09394 -27.050326) (xy 2.134089 -27.011617)
			(xy 2.179447 -26.979166) (xy 2.229047 -26.953665) (xy 2.281831 -26.935658) (xy 2.336674 -26.925528)
			(xy 2.392408 -26.923491) (xy 2.447845 -26.929591) (xy 2.501802 -26.943697) (xy 2.553131 -26.965509)
			(xy 2.600737 -26.994563) (xy 2.643605 -27.030238) (xy 2.680822 -27.071775) (xy 2.711595 -27.118288)
			(xy 2.735267 -27.168785) (xy 2.751335 -27.222192) (xy 2.759455 -27.277368) (xy 2.759964 -27.305254)
			(xy 2.759455 -27.33314) (xy 2.751335 -27.388316) (xy 2.74507 -27.40914) (xy 3.866894 -27.40914) (xy 3.870965 -27.353518)
			(xy 3.883091 -27.299081) (xy 3.903014 -27.24699) (xy 3.93031 -27.198355) (xy 3.964396 -27.154212)
			(xy 4.004545 -27.115503) (xy 4.049903 -27.083052) (xy 4.099503 -27.057551) (xy 4.152287 -27.039544)
			(xy 4.20713 -27.029414) (xy 4.262864 -27.027377) (xy 4.318301 -27.033477) (xy 4.372258 -27.047583)
			(xy 4.37731 -27.04973) (xy 5.317488 -27.04973) (xy 5.321559 -26.994108) (xy 5.333685 -26.939671)
			(xy 5.353608 -26.88758) (xy 5.380904 -26.838945) (xy 5.41499 -26.794802) (xy 5.455139 -26.756093)
			(xy 5.500497 -26.723642) (xy 5.550097 -26.698141) (xy 5.602881 -26.680134) (xy 5.657724 -26.670004)
			(xy 5.713458 -26.667967) (xy 5.768895 -26.674067) (xy 5.822852 -26.688173) (xy 5.874181 -26.709985)
			(xy 5.921787 -26.739039) (xy 5.964655 -26.774714) (xy 6.001872 -26.816251) (xy 6.032645 -26.862764)
			(xy 6.056317 -26.913261) (xy 6.072385 -26.966668) (xy 6.080505 -27.021844) (xy 6.081014 -27.04973)
			(xy 6.080505 -27.077616) (xy 6.072385 -27.132792) (xy 6.056317 -27.186199) (xy 6.032645 -27.236696)
			(xy 6.001872 -27.283209) (xy 5.964655 -27.324746) (xy 5.921787 -27.360421) (xy 5.874181 -27.389475)
			(xy 5.822852 -27.411287) (xy 5.768895 -27.425393) (xy 5.713458 -27.431493) (xy 5.657724 -27.429456)
			(xy 5.602881 -27.419326) (xy 5.550097 -27.401319) (xy 5.500497 -27.375818) (xy 5.455139 -27.343367)
			(xy 5.41499 -27.304658) (xy 5.380904 -27.260515) (xy 5.353608 -27.21188) (xy 5.333685 -27.159789)
			(xy 5.321559 -27.105352) (xy 5.317488 -27.04973) (xy 4.37731 -27.04973) (xy 4.423587 -27.069395)
			(xy 4.471193 -27.098449) (xy 4.514061 -27.134124) (xy 4.551278 -27.175661) (xy 4.582051 -27.222174)
			(xy 4.605723 -27.272671) (xy 4.621791 -27.326078) (xy 4.629911 -27.381254) (xy 4.63042 -27.40914)
			(xy 4.629911 -27.437026) (xy 4.621791 -27.492202) (xy 4.605723 -27.545609) (xy 4.582051 -27.596106)
			(xy 4.551278 -27.642619) (xy 4.514061 -27.684156) (xy 4.471193 -27.719831) (xy 4.423587 -27.748885)
			(xy 4.372258 -27.770697) (xy 4.318301 -27.784803) (xy 4.262864 -27.790903) (xy 4.20713 -27.788866)
			(xy 4.152287 -27.778736) (xy 4.099503 -27.760729) (xy 4.049903 -27.735228) (xy 4.004545 -27.702777)
			(xy 3.964396 -27.664068) (xy 3.93031 -27.619925) (xy 3.903014 -27.57129) (xy 3.883091 -27.519199)
			(xy 3.870965 -27.464762) (xy 3.866894 -27.40914) (xy 2.74507 -27.40914) (xy 2.735267 -27.441723)
			(xy 2.711595 -27.49222) (xy 2.680822 -27.538733) (xy 2.643605 -27.58027) (xy 2.600737 -27.615945)
			(xy 2.553131 -27.644999) (xy 2.501802 -27.666811) (xy 2.447845 -27.680917) (xy 2.392408 -27.687017)
			(xy 2.336674 -27.68498) (xy 2.281831 -27.67485) (xy 2.229047 -27.656843) (xy 2.179447 -27.631342)
			(xy 2.134089 -27.598891) (xy 2.09394 -27.560182) (xy 2.059854 -27.516039) (xy 2.032558 -27.467404)
			(xy 2.012635 -27.415313) (xy 2.000509 -27.360876) (xy 1.996438 -27.305254) (xy 1.27 -27.305254) (xy 1.27 -29.357393)
			(xy 2.192227 -29.357393) (xy 2.192227 -29.302887) (xy 2.199984 -29.248936) (xy 2.215341 -29.196638)
			(xy 2.237983 -29.147058) (xy 2.267451 -29.101205) (xy 2.303145 -29.060012) (xy 2.344338 -29.024319)
			(xy 2.390192 -28.994851) (xy 2.439772 -28.972209) (xy 2.49207 -28.956854) (xy 2.546021 -28.949097)
			(xy 2.573274 -28.948634) (xy 2.599566 -28.949079) (xy 2.651651 -28.956309) (xy 2.70225 -28.970623)
			(xy 2.750404 -28.99175) (xy 2.7952 -29.019289) (xy 2.835791 -29.052719) (xy 2.871405 -29.091407)
			(xy 2.90137 -29.134619) (xy 2.925116 -29.181536) (xy 2.942195 -29.23127) (xy 2.94767 -29.25699) (xy 2.949956 -29.267912)
			(xy 2.96291 -29.285946) (xy 3.049778 -29.334968) (xy 3.071876 -29.336746) (xy 3.08229 -29.332936)
			(xy 3.114026 -29.322058) (xy 3.180068 -29.310299) (xy 3.213608 -29.309568) (xy 3.24687 -29.310279)
			(xy 3.312394 -29.32177) (xy 3.34391 -29.332428) (xy 3.35407 -29.336238) (xy 3.375406 -29.334714)
			(xy 3.461004 -29.289502) (xy 3.474212 -29.272738) (xy 3.477006 -29.262324) (xy 3.484477 -29.235384)
			(xy 3.506179 -29.183862) (xy 3.535169 -29.136061) (xy 3.570825 -29.093003) (xy 3.612385 -29.055611)
			(xy 3.658957 -29.024685) (xy 3.709545 -29.000889) (xy 3.763065 -28.984733) (xy 3.81837 -28.976561)
			(xy 3.846322 -28.976066) (xy 3.873573 -28.976544) (xy 3.927522 -28.984301) (xy 3.979817 -28.999656)
			(xy 4.029394 -29.022298) (xy 4.075245 -29.051764) (xy 4.116435 -29.087456) (xy 4.152127 -29.128647)
			(xy 4.181593 -29.174498) (xy 4.204234 -29.224075) (xy 4.21959 -29.27637) (xy 4.227346 -29.330319)
			(xy 4.227346 -29.384821) (xy 4.21959 -29.43877) (xy 4.204234 -29.491065) (xy 4.181593 -29.540642)
			(xy 4.152127 -29.586493) (xy 4.116435 -29.627684) (xy 4.075245 -29.663376) (xy 4.029394 -29.692842)
			(xy 3.979817 -29.715484) (xy 3.927522 -29.730839) (xy 3.873573 -29.738596) (xy 3.846322 -29.739082)
			(xy 3.813059 -29.738386) (xy 3.747536 -29.726885) (xy 3.71602 -29.716222) (xy 3.70586 -29.712412)
			(xy 3.684524 -29.713936) (xy 3.598926 -29.759148) (xy 3.585718 -29.775912) (xy 3.582924 -29.786326)
			(xy 3.575475 -29.813273) (xy 3.55377 -29.864794) (xy 3.524777 -29.912596) (xy 3.489117 -29.955654)
			(xy 3.447555 -29.993045) (xy 3.40098 -30.023969) (xy 3.350389 -30.047764) (xy 3.296868 -30.06392)
			(xy 3.241561 -30.07209) (xy 3.213608 -30.072584) (xy 3.187316 -30.072139) (xy 3.13523 -30.064909)
			(xy 3.084632 -30.050596) (xy 3.036478 -30.029469) (xy 2.991681 -30.001929) (xy 2.951091 -29.968499)
			(xy 2.915476 -29.929811) (xy 2.885512 -29.886599) (xy 2.861766 -29.839682) (xy 2.844687 -29.789948)
			(xy 2.839212 -29.764228) (xy 2.836926 -29.753306) (xy 2.823972 -29.735272) (xy 2.737104 -29.68625)
			(xy 2.715006 -29.684472) (xy 2.704592 -29.688282) (xy 2.672858 -29.699165) (xy 2.606814 -29.710921)
			(xy 2.573274 -29.71165) (xy 2.546021 -29.711183) (xy 2.49207 -29.703426) (xy 2.439772 -29.688071)
			(xy 2.390192 -29.665429) (xy 2.344338 -29.635961) (xy 2.303145 -29.600268) (xy 2.267451 -29.559075)
			(xy 2.237983 -29.513222) (xy 2.215341 -29.463642) (xy 2.199984 -29.411344) (xy 2.192227 -29.357393)
			(xy 1.27 -29.357393) (xy 1.27 -31.417593) (xy 6.219901 -31.417593) (xy 6.219901 -31.363087) (xy 6.227658 -31.309135)
			(xy 6.243015 -31.256837) (xy 6.265658 -31.207256) (xy 6.295126 -31.161402) (xy 6.33082 -31.120209)
			(xy 6.372014 -31.084515) (xy 6.417868 -31.055047) (xy 6.467448 -31.032404) (xy 6.519747 -31.017048)
			(xy 6.573699 -31.009291) (xy 6.600952 -31.008828) (xy 6.618064 -31.009021) (xy 6.652151 -31.012072)
			(xy 6.669024 -31.014924) (xy 6.680289 -31.016336) (xy 6.702174 -31.010398) (xy 6.711188 -31.003494)
			(xy 6.735572 -30.982412) (xy 6.743934 -30.974463) (xy 6.753072 -30.953308) (xy 6.753098 -30.941772)
			(xy 6.752844 -30.922468) (xy 6.752844 -30.058868) (xy 6.753098 -30.038802) (xy 6.752906 -30.027294)
			(xy 6.743819 -30.006187) (xy 6.735572 -29.998162) (xy 6.711188 -29.97708) (xy 6.7022 -29.970129)
			(xy 6.680295 -29.964203) (xy 6.669024 -29.96565) (xy 6.652153 -29.968519) (xy 6.618065 -29.971572)
			(xy 6.600952 -29.971746) (xy 6.573699 -29.971287) (xy 6.519747 -29.96353) (xy 6.467449 -29.948174)
			(xy 6.417869 -29.925532) (xy 6.372015 -29.896063) (xy 6.330822 -29.86037) (xy 6.295128 -29.819177)
			(xy 6.265659 -29.773323) (xy 6.243017 -29.723743) (xy 6.22766 -29.671444) (xy 6.219903 -29.617493)
			(xy 6.219903 -29.562987) (xy 6.22766 -29.509036) (xy 6.243017 -29.456737) (xy 6.265659 -29.407157)
			(xy 6.295128 -29.361303) (xy 6.330822 -29.32011) (xy 6.372015 -29.284417) (xy 6.417869 -29.254948)
			(xy 6.467449 -29.232306) (xy 6.519747 -29.21695) (xy 6.573699 -29.209193) (xy 6.600952 -29.20873)
			(xy 6.62796 -29.209165) (xy 6.681437 -29.216777) (xy 6.733306 -29.231857) (xy 6.782529 -29.254102)
			(xy 6.828122 -29.283068) (xy 6.869174 -29.318175) (xy 6.904863 -29.358722) (xy 6.934476 -29.403898)
			(xy 6.957421 -29.452799) (xy 6.973238 -29.504447) (xy 6.977888 -29.531056) (xy 6.979412 -29.541724)
			(xy 6.990842 -29.559504) (xy 7.071106 -29.612844) (xy 7.09168 -29.616654) (xy 7.102348 -29.614114)
			(xy 7.128986 -29.608046) (xy 7.183234 -29.601556) (xy 7.210552 -29.60116) (xy 7.23787 -29.601549)
			(xy 7.292119 -29.608042) (xy 7.318756 -29.614114) (xy 7.329424 -29.616654) (xy 7.349998 -29.612844)
			(xy 7.430262 -29.559504) (xy 7.441692 -29.541724) (xy 7.443216 -29.531056) (xy 7.447911 -29.504458)
			(xy 7.463735 -29.45282) (xy 7.486682 -29.40393) (xy 7.516294 -29.358763) (xy 7.551979 -29.318224)
			(xy 7.593024 -29.283121) (xy 7.638609 -29.254156) (xy 7.687822 -29.231909) (xy 7.73968 -29.216824)
			(xy 7.793148 -29.209201) (xy 7.820152 -29.20873) (xy 7.847522 -29.209217) (xy 7.9017 -29.217029)
			(xy 7.954203 -29.232512) (xy 8.00395 -29.25535) (xy 8.049918 -29.28507) (xy 8.07085 -29.30271) (xy 8.077962 -29.308806)
			(xy 8.09498 -29.315156) (xy 8.180324 -29.315156) (xy 8.197342 -29.308806) (xy 8.204454 -29.30271)
			(xy 8.225394 -29.285081) (xy 8.271364 -29.255367) (xy 8.32111 -29.232529) (xy 8.373609 -29.217036)
			(xy 8.427783 -29.209205) (xy 8.455152 -29.20873) (xy 8.472264 -29.208923) (xy 8.506351 -29.211974)
			(xy 8.523224 -29.214826) (xy 8.534489 -29.216238) (xy 8.556374 -29.2103) (xy 8.565388 -29.203396)
			(xy 8.589772 -29.182314) (xy 8.598133 -29.174364) (xy 8.607272 -29.15321) (xy 8.607298 -29.141674)
			(xy 8.607044 -29.12237) (xy 8.607044 -28.25877) (xy 8.607298 -28.238704) (xy 8.607104 -28.227197)
			(xy 8.598019 -28.20609) (xy 8.589772 -28.198064) (xy 8.565388 -28.176982) (xy 8.5564 -28.170031)
			(xy 8.534495 -28.164105) (xy 8.523224 -28.165552) (xy 8.506353 -28.168421) (xy 8.472265 -28.171474)
			(xy 8.455152 -28.171648) (xy 8.427899 -28.171185) (xy 8.373948 -28.163428) (xy 8.32165 -28.148072)
			(xy 8.272069 -28.12543) (xy 8.226216 -28.095962) (xy 8.185023 -28.060268) (xy 8.149329 -28.019076)
			(xy 8.119861 -27.973222) (xy 8.097218 -27.923642) (xy 8.081862 -27.871344) (xy 8.074105 -27.817393)
			(xy 8.074105 -27.762887) (xy 8.081862 -27.708936) (xy 8.097218 -27.656638) (xy 8.119861 -27.607058)
			(xy 8.149329 -27.561204) (xy 8.185023 -27.520012) (xy 8.226216 -27.484318) (xy 8.272069 -27.45485)
			(xy 8.32165 -27.432208) (xy 8.373948 -27.416852) (xy 8.427899 -27.409095) (xy 8.455152 -27.408632)
			(xy 8.48216 -27.409065) (xy 8.535638 -27.416678) (xy 8.587506 -27.431757) (xy 8.63673 -27.454003)
			(xy 8.682323 -27.482969) (xy 8.723374 -27.518076) (xy 8.759064 -27.558623) (xy 8.788676 -27.603799)
			(xy 8.811621 -27.6527) (xy 8.827438 -27.704349) (xy 8.832088 -27.730958) (xy 8.833612 -27.741626)
			(xy 8.845042 -27.759406) (xy 8.925306 -27.812746) (xy 8.94588 -27.816556) (xy 8.956548 -27.814016)
			(xy 8.98318 -27.807888) (xy 9.037428 -27.801266) (xy 9.064752 -27.800808) (xy 9.08693 -27.801102)
			(xy 9.131076 -27.805429) (xy 9.15289 -27.809444) (xy 9.163304 -27.811476) (xy 9.183116 -27.807412)
			(xy 9.260078 -27.754072) (xy 9.271 -27.737054) (xy 9.272778 -27.72664) (xy 9.277652 -27.700297) (xy 9.293869 -27.649236)
			(xy 9.317071 -27.600946) (xy 9.346801 -27.556378) (xy 9.382475 -27.516408) (xy 9.42339 -27.481823)
			(xy 9.468742 -27.453302) (xy 9.517638 -27.431408) (xy 9.569117 -27.416571) (xy 9.622165 -27.409082)
			(xy 9.648952 -27.408632) (xy 9.676203 -27.409118) (xy 9.730151 -27.416875) (xy 9.782445 -27.43223)
			(xy 9.832022 -27.454871) (xy 9.877872 -27.484338) (xy 9.919062 -27.520029) (xy 9.954754 -27.561219)
			(xy 9.98422 -27.60707) (xy 10.006861 -27.656647) (xy 10.022216 -27.708941) (xy 10.029972 -27.762889)
			(xy 10.029972 -27.817391) (xy 10.022216 -27.871339) (xy 10.006861 -27.923633) (xy 9.98422 -27.97321)
			(xy 9.954754 -28.019061) (xy 9.919062 -28.060251) (xy 9.877872 -28.095942) (xy 9.832022 -28.125409)
			(xy 9.782445 -28.14805) (xy 9.730151 -28.163405) (xy 9.676203 -28.171162) (xy 9.648952 -28.171648)
			(xy 9.63743 -28.171555) (xy 9.614427 -28.170156) (xy 9.602978 -28.168854) (xy 9.592064 -28.168135)
			(xy 9.571269 -28.174833) (xy 9.562846 -28.181808) (xy 9.53897 -28.203398) (xy 9.531117 -28.21125)
			(xy 9.522429 -28.231664) (xy 9.522206 -28.242768) (xy 9.52246 -28.25877) (xy 9.52246 -29.137356)
			(xy 9.522588 -29.148442) (xy 9.531155 -29.168863) (xy 9.53897 -29.176726) (xy 9.562846 -29.198316)
			(xy 9.571252 -29.205319) (xy 9.592061 -29.212018) (xy 9.602978 -29.21127) (xy 9.614426 -29.209954)
			(xy 9.637429 -29.208559) (xy 9.648952 -29.208476) (xy 9.676203 -29.208954) (xy 9.730152 -29.216711)
			(xy 9.782447 -29.232066) (xy 9.832024 -29.254708) (xy 9.877875 -29.284174) (xy 9.919065 -29.319866)
			(xy 9.954757 -29.361057) (xy 9.984223 -29.406908) (xy 10.006864 -29.456485) (xy 10.02222 -29.50878)
			(xy 10.029976 -29.562729) (xy 10.029976 -29.617231) (xy 10.02222 -29.67118) (xy 10.006864 -29.723475)
			(xy 9.984223 -29.773052) (xy 9.954757 -29.818903) (xy 9.919065 -29.860094) (xy 9.877875 -29.895786)
			(xy 9.832024 -29.925252) (xy 9.782447 -29.947894) (xy 9.730152 -29.963249) (xy 9.676203 -29.971006)
			(xy 9.648952 -29.971492) (xy 9.622206 -29.970975) (xy 9.56924 -29.963488) (xy 9.517838 -29.948682)
			(xy 9.469005 -29.926847) (xy 9.423698 -29.89841) (xy 9.382803 -29.863928) (xy 9.347121 -29.824075)
			(xy 9.317351 -29.779633) (xy 9.294075 -29.73147) (xy 9.277749 -29.68053) (xy 9.272778 -29.654246)
			(xy 9.271 -29.643832) (xy 9.260332 -29.626814) (xy 9.183116 -29.573728) (xy 9.163304 -29.569664)
			(xy 9.153144 -29.571696) (xy 9.131271 -29.575746) (xy 9.086995 -29.58007) (xy 9.064752 -29.580332)
			(xy 9.037364 -29.579883) (xy 8.982988 -29.573265) (xy 8.956294 -29.567124) (xy 8.94588 -29.564584)
			(xy 8.925306 -29.56814) (xy 8.845042 -29.621734) (xy 8.833612 -29.63926) (xy 8.831834 -29.649928)
			(xy 8.827178 -29.676501) (xy 8.811321 -29.728066) (xy 8.788356 -29.776883) (xy 8.758742 -29.821977)
			(xy 8.723071 -29.862448) (xy 8.682052 -29.89749) (xy 8.636506 -29.926402) (xy 8.58734 -29.948609)
			(xy 8.535535 -29.963667) (xy 8.482126 -29.971276) (xy 8.455152 -29.971746) (xy 8.427782 -29.971263)
			(xy 8.373603 -29.963451) (xy 8.3211 -29.947967) (xy 8.271353 -29.925128) (xy 8.225386 -29.895406)
			(xy 8.204454 -29.877766) (xy 8.197342 -29.87167) (xy 8.180324 -29.86532) (xy 8.09498 -29.86532) (xy 8.077962 -29.87167)
			(xy 8.07085 -29.877766) (xy 8.049906 -29.89539) (xy 8.003937 -29.925105) (xy 7.954192 -29.947945)
			(xy 7.901694 -29.963439) (xy 7.84752 -29.97127) (xy 7.820152 -29.971746) (xy 7.80304 -29.971553)
			(xy 7.768953 -29.968502) (xy 7.75208 -29.96565) (xy 7.740815 -29.964247) (xy 7.718931 -29.97018)
			(xy 7.709916 -29.97708) (xy 7.685532 -29.998162) (xy 7.677135 -30.00608) (xy 7.668016 -30.027259)
			(xy 7.668006 -30.038802) (xy 7.66826 -30.058868) (xy 7.66826 -30.922468) (xy 7.668006 -30.941772)
			(xy 7.668154 -30.953283) (xy 7.677271 -30.974391) (xy 7.685532 -30.982412) (xy 7.709916 -31.003494)
			(xy 7.718904 -31.010445) (xy 7.740809 -31.016372) (xy 7.75208 -31.014924) (xy 7.768951 -31.012055)
			(xy 7.803039 -31.009002) (xy 7.820152 -31.008828) (xy 7.847522 -31.009315) (xy 7.9017 -31.017127)
			(xy 7.954203 -31.032611) (xy 8.00395 -31.055448) (xy 8.049918 -31.085168) (xy 8.07085 -31.102808)
			(xy 8.077962 -31.108904) (xy 8.094726 -31.115254) (xy 8.180324 -31.115254) (xy 8.197342 -31.108904)
			(xy 8.2042 -31.102554) (xy 8.225136 -31.084879) (xy 8.271156 -31.05514) (xy 8.320959 -31.032296)
			(xy 8.37352 -31.016817) (xy 8.427755 -31.009023) (xy 8.455152 -31.008574) (xy 8.482162 -31.008972)
			(xy 8.535642 -31.016586) (xy 8.587514 -31.031667) (xy 8.636739 -31.053916) (xy 8.682334 -31.082885)
			(xy 8.723386 -31.117997) (xy 8.759074 -31.158549) (xy 8.788685 -31.20373) (xy 8.811627 -31.252636)
			(xy 8.82744 -31.304289) (xy 8.832088 -31.3309) (xy 8.833612 -31.341568) (xy 8.845042 -31.359348)
			(xy 8.925306 -31.412688) (xy 8.94588 -31.416498) (xy 8.956548 -31.413958) (xy 8.983186 -31.40789)
			(xy 9.037434 -31.4014) (xy 9.064752 -31.401004) (xy 9.086925 -31.401225) (xy 9.131072 -31.405428)
			(xy 9.15289 -31.409386) (xy 9.163304 -31.411418) (xy 9.183116 -31.407354) (xy 9.260078 -31.354014)
			(xy 9.271 -31.336996) (xy 9.272778 -31.326582) (xy 9.277608 -31.30023) (xy 9.293833 -31.249169) (xy 9.317041 -31.20088)
			(xy 9.346778 -31.156313) (xy 9.382456 -31.116344) (xy 9.423376 -31.08176) (xy 9.468732 -31.053241)
			(xy 9.517631 -31.031348) (xy 9.569113 -31.016512) (xy 9.622164 -31.009023) (xy 9.648952 -31.008574)
			(xy 9.676203 -31.009056) (xy 9.730151 -31.016813) (xy 9.782446 -31.032168) (xy 9.832023 -31.054809)
			(xy 9.877874 -31.084276) (xy 9.919064 -31.119968) (xy 9.954755 -31.161158) (xy 9.984221 -31.207009)
			(xy 10.006863 -31.256586) (xy 10.022218 -31.308881) (xy 10.029974 -31.362829) (xy 10.029974 -31.417331)
			(xy 10.022218 -31.471279) (xy 10.006863 -31.523574) (xy 9.984221 -31.573151) (xy 9.954755 -31.619002)
			(xy 9.919064 -31.660192) (xy 9.877874 -31.695884) (xy 9.832023 -31.725351) (xy 9.782446 -31.747992)
			(xy 9.730151 -31.763347) (xy 9.676203 -31.771104) (xy 9.648952 -31.77159) (xy 9.63743 -31.771495)
			(xy 9.614427 -31.770096) (xy 9.602978 -31.768796) (xy 9.592064 -31.768067) (xy 9.571267 -31.774771)
			(xy 9.562846 -31.78175) (xy 9.53897 -31.80334) (xy 9.531144 -31.811215) (xy 9.522441 -31.831612)
			(xy 9.522206 -31.84271) (xy 9.52246 -31.858712) (xy 9.52246 -32.722312) (xy 9.522206 -32.737552)
			(xy 9.522386 -32.748665) (xy 9.531085 -32.769089) (xy 9.53897 -32.776922) (xy 9.562846 -32.798512)
			(xy 9.571253 -32.805514) (xy 9.592061 -32.812214) (xy 9.602978 -32.811466) (xy 9.614426 -32.81015)
			(xy 9.637429 -32.808755) (xy 9.648952 -32.808672) (xy 9.676203 -32.809158) (xy 9.730151 -32.816915)
			(xy 9.782445 -32.83227) (xy 9.832022 -32.854911) (xy 9.877872 -32.884378) (xy 9.919062 -32.920069)
			(xy 9.954754 -32.961259) (xy 9.98422 -33.00711) (xy 10.006861 -33.056687) (xy 10.022216 -33.108981)
			(xy 10.029972 -33.162929) (xy 10.029972 -33.217431) (xy 10.022216 -33.271379) (xy 10.006861 -33.323673)
			(xy 9.98422 -33.37325) (xy 9.954754 -33.419101) (xy 9.919062 -33.460291) (xy 9.877872 -33.495982)
			(xy 9.832022 -33.525449) (xy 9.782445 -33.54809) (xy 9.730151 -33.563445) (xy 9.676203 -33.571202)
			(xy 9.648952 -33.571688) (xy 9.622186 -33.571269) (xy 9.569176 -33.563805) (xy 9.517731 -33.549002)
			(xy 9.468862 -33.52715) (xy 9.423528 -33.49868) (xy 9.38262 -33.464151) (xy 9.346943 -33.42424) (xy 9.317196 -33.379733)
			(xy 9.293966 -33.331504) (xy 9.277707 -33.2805) (xy 9.272778 -33.254188) (xy 9.271 -33.243774) (xy 9.260332 -33.226756)
			(xy 9.183116 -33.17367) (xy 9.163304 -33.169606) (xy 9.153144 -33.171638) (xy 9.131265 -33.175621)
			(xy 9.08699 -33.179819) (xy 9.064752 -33.18002) (xy 9.03737 -33.179652) (xy 8.982994 -33.173153)
			(xy 8.956294 -33.167066) (xy 8.94588 -33.164526) (xy 8.925306 -33.168082) (xy 8.845042 -33.221676)
			(xy 8.833612 -33.239202) (xy 8.831834 -33.24987) (xy 8.827134 -33.276435) (xy 8.811284 -33.328) (xy 8.788327 -33.376817)
			(xy 8.758719 -33.421912) (xy 8.723052 -33.462385) (xy 8.682038 -33.497428) (xy 8.636496 -33.526342)
			(xy 8.587333 -33.54855) (xy 8.535531 -33.563609) (xy 8.482125 -33.571218) (xy 8.455152 -33.571688)
			(xy 8.427783 -33.571194) (xy 8.373605 -33.563384) (xy 8.321102 -33.547901) (xy 8.271354 -33.525066)
			(xy 8.225386 -33.495347) (xy 8.204454 -33.477708) (xy 8.197342 -33.471612) (xy 8.180324 -33.465262)
			(xy 8.09498 -33.465262) (xy 8.077962 -33.471612) (xy 8.07085 -33.477708) (xy 8.049911 -33.495338)
			(xy 8.00394 -33.525051) (xy 7.954194 -33.547889) (xy 7.901695 -33.563382) (xy 7.847521 -33.571213)
			(xy 7.820152 -33.571688) (xy 7.80304 -33.571494) (xy 7.768953 -33.568444) (xy 7.75208 -33.565592)
			(xy 7.740815 -33.564179) (xy 7.718929 -33.570117) (xy 7.709916 -33.577022) (xy 7.685532 -33.598104)
			(xy 7.677163 -33.606047) (xy 7.668029 -33.627207) (xy 7.668006 -33.638744) (xy 7.66826 -33.65881)
			(xy 7.66826 -34.52241) (xy 7.668006 -34.541714) (xy 7.668187 -34.553223) (xy 7.677281 -34.57433)
			(xy 7.685532 -34.582354) (xy 7.709916 -34.603436) (xy 7.718908 -34.610382) (xy 7.74081 -34.616314)
			(xy 7.75208 -34.614866) (xy 7.768951 -34.611997) (xy 7.803039 -34.608944) (xy 7.820152 -34.60877)
			(xy 7.847403 -34.60926) (xy 7.90135 -34.617017) (xy 7.953644 -34.632372) (xy 8.003221 -34.655013)
			(xy 8.049071 -34.684479) (xy 8.090261 -34.720171) (xy 8.125952 -34.76136) (xy 8.155418 -34.807211)
			(xy 8.178059 -34.856787) (xy 8.193414 -34.909082) (xy 8.20117 -34.963029) (xy 8.20117 -34.990024)
			(xy 9.266934 -34.990024) (xy 9.271005 -34.934402) (xy 9.283131 -34.879965) (xy 9.303054 -34.827874)
			(xy 9.33035 -34.779239) (xy 9.364436 -34.735096) (xy 9.404585 -34.696387) (xy 9.449943 -34.663936)
			(xy 9.499543 -34.638435) (xy 9.552327 -34.620428) (xy 9.60717 -34.610298) (xy 9.662904 -34.608261)
			(xy 9.718341 -34.614361) (xy 9.772298 -34.628467) (xy 9.823627 -34.650279) (xy 9.871233 -34.679333)
			(xy 9.914101 -34.715008) (xy 9.951318 -34.756545) (xy 9.982091 -34.803058) (xy 10.005763 -34.853555)
			(xy 10.021831 -34.906962) (xy 10.029951 -34.962138) (xy 10.03046 -34.990024) (xy 10.029951 -35.01791)
			(xy 10.021831 -35.073086) (xy 10.005763 -35.126493) (xy 9.982091 -35.17699) (xy 9.951318 -35.223503)
			(xy 9.914101 -35.26504) (xy 9.871233 -35.300715) (xy 9.823627 -35.329769) (xy 9.772298 -35.351581)
			(xy 9.718341 -35.365687) (xy 9.662904 -35.371787) (xy 9.60717 -35.36975) (xy 9.552327 -35.35962)
			(xy 9.499543 -35.341613) (xy 9.449943 -35.316112) (xy 9.404585 -35.283661) (xy 9.364436 -35.244952)
			(xy 9.33035 -35.200809) (xy 9.303054 -35.152174) (xy 9.283131 -35.100083) (xy 9.271005 -35.045646)
			(xy 9.266934 -34.990024) (xy 8.20117 -34.990024) (xy 8.20117 -35.017531) (xy 8.193414 -35.071478)
			(xy 8.178059 -35.123773) (xy 8.155418 -35.173349) (xy 8.125952 -35.2192) (xy 8.090261 -35.260389)
			(xy 8.049071 -35.296081) (xy 8.003221 -35.325547) (xy 7.953644 -35.348188) (xy 7.90135 -35.363543)
			(xy 7.847403 -35.3713) (xy 7.820152 -35.371786) (xy 7.793175 -35.371325) (xy 7.739757 -35.363738)
			(xy 7.687943 -35.348695) (xy 7.638768 -35.326495) (xy 7.593214 -35.297584) (xy 7.552192 -35.262537)
			(xy 7.516522 -35.222057) (xy 7.486917 -35.176951) (xy 7.463968 -35.128121) (xy 7.448133 -35.076543)
			(xy 7.44347 -35.049968) (xy 7.441692 -35.0393) (xy 7.430262 -35.021774) (xy 7.349998 -34.96818) (xy 7.329424 -34.964624)
			(xy 7.31901 -34.967164) (xy 7.292317 -34.97331) (xy 7.23794 -34.979928) (xy 7.210552 -34.980372)
			(xy 7.183164 -34.979922) (xy 7.128788 -34.973305) (xy 7.102094 -34.967164) (xy 7.09168 -34.964624)
			(xy 7.071106 -34.96818) (xy 6.990842 -35.021774) (xy 6.979412 -35.0393) (xy 6.977634 -35.049968)
			(xy 6.973009 -35.076547) (xy 6.957146 -35.128112) (xy 6.934177 -35.176928) (xy 6.904559 -35.222021)
			(xy 6.868883 -35.262492) (xy 6.827862 -35.297533) (xy 6.782312 -35.326444) (xy 6.733144 -35.34865)
			(xy 6.681338 -35.363707) (xy 6.627927 -35.371316) (xy 6.600952 -35.371786) (xy 6.573699 -35.371327)
			(xy 6.519747 -35.36357) (xy 6.467449 -35.348214) (xy 6.417869 -35.325572) (xy 6.372015 -35.296103)
			(xy 6.330822 -35.26041) (xy 6.295128 -35.219217) (xy 6.265659 -35.173363) (xy 6.243017 -35.123783)
			(xy 6.22766 -35.071484) (xy 6.219903 -35.017533) (xy 6.219903 -34.963027) (xy 6.22766 -34.909076)
			(xy 6.243017 -34.856777) (xy 6.265659 -34.807197) (xy 6.295128 -34.761343) (xy 6.330822 -34.72015)
			(xy 6.372015 -34.684457) (xy 6.417869 -34.654988) (xy 6.467449 -34.632346) (xy 6.519747 -34.61699)
			(xy 6.573699 -34.609233) (xy 6.600952 -34.60877) (xy 6.618064 -34.608962) (xy 6.652151 -34.612014)
			(xy 6.669024 -34.614866) (xy 6.680289 -34.616268) (xy 6.702173 -34.610336) (xy 6.711188 -34.603436)
			(xy 6.735572 -34.582354) (xy 6.743962 -34.574429) (xy 6.753084 -34.553255) (xy 6.753098 -34.541714)
			(xy 6.752844 -34.52241) (xy 6.752844 -33.65881) (xy 6.753098 -33.638744) (xy 6.752939 -33.627234)
			(xy 6.743829 -33.606126) (xy 6.735572 -33.598104) (xy 6.711188 -33.577022) (xy 6.702198 -33.570075)
			(xy 6.680294 -33.564145) (xy 6.669024 -33.565592) (xy 6.652153 -33.56846) (xy 6.618064 -33.571514)
			(xy 6.600952 -33.571688) (xy 6.573699 -33.571225) (xy 6.519748 -33.563468) (xy 6.46745 -33.548112)
			(xy 6.417869 -33.52547) (xy 6.372016 -33.496002) (xy 6.330823 -33.460308) (xy 6.295129 -33.419116)
			(xy 6.265661 -33.373262) (xy 6.243018 -33.323682) (xy 6.227662 -33.271384) (xy 6.219905 -33.217433)
			(xy 6.219905 -33.162927) (xy 6.227662 -33.108976) (xy 6.243018 -33.056678) (xy 6.265661 -33.007098)
			(xy 6.295129 -32.961244) (xy 6.330823 -32.920052) (xy 6.372016 -32.884358) (xy 6.417869 -32.85489)
			(xy 6.46745 -32.832248) (xy 6.519748 -32.816892) (xy 6.573699 -32.809135) (xy 6.600952 -32.808672)
			(xy 6.62796 -32.809134) (xy 6.681436 -32.816741) (xy 6.733305 -32.831816) (xy 6.782528 -32.854057)
			(xy 6.828122 -32.88302) (xy 6.869174 -32.918125) (xy 6.904863 -32.958669) (xy 6.934477 -33.003843)
			(xy 6.957421 -33.052743) (xy 6.973238 -33.10439) (xy 6.977888 -33.130998) (xy 6.979412 -33.141666)
			(xy 6.990842 -33.159446) (xy 7.071106 -33.212786) (xy 7.09168 -33.216596) (xy 7.102348 -33.214056)
			(xy 7.12898 -33.207929) (xy 7.183228 -33.201306) (xy 7.210552 -33.200848) (xy 7.237877 -33.201301)
			(xy 7.292125 -33.207924) (xy 7.318756 -33.214056) (xy 7.329424 -33.216596) (xy 7.349998 -33.212786)
			(xy 7.430262 -33.159446) (xy 7.441692 -33.141666) (xy 7.443216 -33.130998) (xy 7.447867 -33.104392)
			(xy 7.463698 -33.052754) (xy 7.486653 -33.003864) (xy 7.516271 -32.958698) (xy 7.551961 -32.91816)
			(xy 7.59301 -32.883059) (xy 7.638599 -32.854096) (xy 7.687815 -32.83185) (xy 7.739677 -32.816765)
			(xy 7.793147 -32.809143) (xy 7.820152 -32.808672) (xy 7.847522 -32.809149) (xy 7.901701 -32.816961)
			(xy 7.954205 -32.832447) (xy 8.003952 -32.855287) (xy 8.049919 -32.885011) (xy 8.07085 -32.902652)
			(xy 8.077962 -32.908748) (xy 8.09498 -32.915098) (xy 8.180324 -32.915098) (xy 8.197342 -32.908748)
			(xy 8.204454 -32.902652) (xy 8.225399 -32.885029) (xy 8.271368 -32.855313) (xy 8.321112 -32.832473)
			(xy 8.37361 -32.816978) (xy 8.427784 -32.809147) (xy 8.455152 -32.808672) (xy 8.472264 -32.808864)
			(xy 8.506351 -32.811916) (xy 8.523224 -32.814768) (xy 8.534489 -32.81617) (xy 8.556373 -32.810237)
			(xy 8.565388 -32.803338) (xy 8.589772 -32.782256) (xy 8.598161 -32.774331) (xy 8.607284 -32.753157)
			(xy 8.607298 -32.741616) (xy 8.607044 -32.722312) (xy 8.607044 -31.858712) (xy 8.607298 -31.838646)
			(xy 8.607138 -31.827136) (xy 8.598029 -31.806028) (xy 8.589772 -31.798006) (xy 8.565388 -31.776924)
			(xy 8.556397 -31.769977) (xy 8.534494 -31.764047) (xy 8.523224 -31.765494) (xy 8.506353 -31.768362)
			(xy 8.472265 -31.771416) (xy 8.455152 -31.77159) (xy 8.427783 -31.771096) (xy 8.373605 -31.763285)
			(xy 8.321102 -31.747803) (xy 8.271355 -31.724967) (xy 8.225387 -31.695249) (xy 8.204454 -31.67761)
			(xy 8.197342 -31.671514) (xy 8.180578 -31.665164) (xy 8.09498 -31.665164) (xy 8.077962 -31.671514)
			(xy 8.071104 -31.677864) (xy 8.050168 -31.69554) (xy 8.004148 -31.725278) (xy 7.954345 -31.748122)
			(xy 7.901784 -31.7636) (xy 7.847549 -31.771395) (xy 7.820152 -31.771844) (xy 7.793173 -31.771418)
			(xy 7.739752 -31.76383) (xy 7.687935 -31.748785) (xy 7.638758 -31.726583) (xy 7.593203 -31.697667)
			(xy 7.552181 -31.662617) (xy 7.516511 -31.622131) (xy 7.486907 -31.57702) (xy 7.463961 -31.528186)
			(xy 7.448131 -31.476603) (xy 7.44347 -31.450026) (xy 7.441692 -31.439358) (xy 7.430262 -31.421832)
			(xy 7.349998 -31.368238) (xy 7.329424 -31.364682) (xy 7.31901 -31.367222) (xy 7.292307 -31.373291)
			(xy 7.237933 -31.379788) (xy 7.210552 -31.380176) (xy 7.18317 -31.379806) (xy 7.128794 -31.373308)
			(xy 7.102094 -31.367222) (xy 7.09168 -31.364682) (xy 7.071106 -31.368238) (xy 6.990842 -31.421832)
			(xy 6.979412 -31.439358) (xy 6.977634 -31.450026) (xy 6.972977 -31.476599) (xy 6.95712 -31.528164)
			(xy 6.934155 -31.576981) (xy 6.904542 -31.622074) (xy 6.86887 -31.662546) (xy 6.827852 -31.697588)
			(xy 6.782305 -31.7265) (xy 6.733139 -31.748707) (xy 6.681335 -31.763765) (xy 6.627926 -31.771374)
			(xy 6.600952 -31.771844) (xy 6.573699 -31.771389) (xy 6.519747 -31.763632) (xy 6.467448 -31.748276)
			(xy 6.417868 -31.725633) (xy 6.372014 -31.696165) (xy 6.33082 -31.660471) (xy 6.295126 -31.619278)
			(xy 6.265658 -31.573424) (xy 6.243015 -31.523843) (xy 6.227658 -31.471545) (xy 6.219901 -31.417593)
			(xy 1.27 -31.417593) (xy 1.27 -33.710626) (xy 2.52425 -33.710626) (xy 2.528321 -33.655004) (xy 2.540447 -33.600567)
			(xy 2.56037 -33.548476) (xy 2.587666 -33.499841) (xy 2.621752 -33.455698) (xy 2.661901 -33.416989)
			(xy 2.707259 -33.384538) (xy 2.756859 -33.359037) (xy 2.809643 -33.34103) (xy 2.864486 -33.3309)
			(xy 2.92022 -33.328863) (xy 2.975657 -33.334963) (xy 3.029614 -33.349069) (xy 3.080943 -33.370881)
			(xy 3.128549 -33.399935) (xy 3.171417 -33.43561) (xy 3.208634 -33.477147) (xy 3.239407 -33.52366)
			(xy 3.263079 -33.574157) (xy 3.279147 -33.627564) (xy 3.287267 -33.68274) (xy 3.287776 -33.710626)
			(xy 3.287267 -33.738512) (xy 3.279596 -33.790636) (xy 3.426966 -33.790636) (xy 3.431037 -33.735014)
			(xy 3.443163 -33.680577) (xy 3.463086 -33.628486) (xy 3.490382 -33.579851) (xy 3.524468 -33.535708)
			(xy 3.564617 -33.496999) (xy 3.609975 -33.464548) (xy 3.659575 -33.439047) (xy 3.712359 -33.42104)
			(xy 3.767202 -33.41091) (xy 3.822936 -33.408873) (xy 3.878373 -33.414973) (xy 3.93233 -33.429079)
			(xy 3.983659 -33.450891) (xy 4.031265 -33.479945) (xy 4.074133 -33.51562) (xy 4.11135 -33.557157)
			(xy 4.142123 -33.60367) (xy 4.165795 -33.654167) (xy 4.181863 -33.707574) (xy 4.189983 -33.76275)
			(xy 4.190334 -33.782) (xy 4.661152 -33.782) (xy 4.665223 -33.726378) (xy 4.677349 -33.671941) (xy 4.697272 -33.61985)
			(xy 4.724568 -33.571215) (xy 4.758654 -33.527072) (xy 4.798803 -33.488363) (xy 4.844161 -33.455912)
			(xy 4.893761 -33.430411) (xy 4.946545 -33.412404) (xy 5.001388 -33.402274) (xy 5.057122 -33.400237)
			(xy 5.112559 -33.406337) (xy 5.166516 -33.420443) (xy 5.217845 -33.442255) (xy 5.265451 -33.471309)
			(xy 5.308319 -33.506984) (xy 5.345536 -33.548521) (xy 5.376309 -33.595034) (xy 5.399981 -33.645531)
			(xy 5.416049 -33.698938) (xy 5.424169 -33.754114) (xy 5.424678 -33.782) (xy 5.424169 -33.809886)
			(xy 5.416049 -33.865062) (xy 5.399981 -33.918469) (xy 5.376309 -33.968966) (xy 5.345536 -34.015479)
			(xy 5.308319 -34.057016) (xy 5.265451 -34.092691) (xy 5.217845 -34.121745) (xy 5.166516 -34.143557)
			(xy 5.112559 -34.157663) (xy 5.057122 -34.163763) (xy 5.001388 -34.161726) (xy 4.946545 -34.151596)
			(xy 4.893761 -34.133589) (xy 4.844161 -34.108088) (xy 4.798803 -34.075637) (xy 4.758654 -34.036928)
			(xy 4.724568 -33.992785) (xy 4.697272 -33.94415) (xy 4.677349 -33.892059) (xy 4.665223 -33.837622)
			(xy 4.661152 -33.782) (xy 4.190334 -33.782) (xy 4.190492 -33.790636) (xy 4.189983 -33.818522) (xy 4.181863 -33.873698)
			(xy 4.165795 -33.927105) (xy 4.142123 -33.977602) (xy 4.11135 -34.024115) (xy 4.074133 -34.065652)
			(xy 4.031265 -34.101327) (xy 3.983659 -34.130381) (xy 3.93233 -34.152193) (xy 3.878373 -34.166299)
			(xy 3.822936 -34.172399) (xy 3.767202 -34.170362) (xy 3.712359 -34.160232) (xy 3.659575 -34.142225)
			(xy 3.609975 -34.116724) (xy 3.564617 -34.084273) (xy 3.524468 -34.045564) (xy 3.490382 -34.001421)
			(xy 3.463086 -33.952786) (xy 3.443163 -33.900695) (xy 3.431037 -33.846258) (xy 3.426966 -33.790636)
			(xy 3.279596 -33.790636) (xy 3.279147 -33.793688) (xy 3.263079 -33.847095) (xy 3.239407 -33.897592)
			(xy 3.208634 -33.944105) (xy 3.171417 -33.985642) (xy 3.128549 -34.021317) (xy 3.080943 -34.050371)
			(xy 3.029614 -34.072183) (xy 2.975657 -34.086289) (xy 2.92022 -34.092389) (xy 2.864486 -34.090352)
			(xy 2.809643 -34.080222) (xy 2.756859 -34.062215) (xy 2.707259 -34.036714) (xy 2.661901 -34.004263)
			(xy 2.621752 -33.965554) (xy 2.587666 -33.921411) (xy 2.56037 -33.872776) (xy 2.540447 -33.820685)
			(xy 2.528321 -33.766248) (xy 2.52425 -33.710626) (xy 1.27 -33.710626) (xy 1.27 -35.290506) (xy 1.91897 -35.290506)
			(xy 1.919415 -35.263694) (xy 1.926928 -35.210599) (xy 1.941807 -35.159081) (xy 1.963759 -35.110156)
			(xy 1.99235 -35.064791) (xy 2.027017 -35.023879) (xy 2.067074 -34.988228) (xy 2.08915 -34.973006)
			(xy 2.100719 -34.964754) (xy 2.119124 -34.943116) (xy 2.13086 -34.917248) (xy 2.13502 -34.889148)
			(xy 2.131282 -34.860989) (xy 2.119937 -34.834947) (xy 2.10186 -34.813035) (xy 2.09042 -34.804604)
			(xy 2.068938 -34.789286) (xy 2.030028 -34.753651) (xy 1.9964 -34.712995) (xy 1.968693 -34.668094)
			(xy 1.947437 -34.619804) (xy 1.933036 -34.569045) (xy 1.925766 -34.516787) (xy 1.92532 -34.490406)
			(xy 1.925806 -34.463155) (xy 1.933562 -34.409207) (xy 1.948917 -34.356912) (xy 1.971559 -34.307335)
			(xy 2.001025 -34.261485) (xy 2.036716 -34.220294) (xy 2.077907 -34.184603) (xy 2.123757 -34.155137)
			(xy 2.173334 -34.132495) (xy 2.225629 -34.11714) (xy 2.279577 -34.109384) (xy 2.334079 -34.109384)
			(xy 2.388027 -34.11714) (xy 2.440322 -34.132495) (xy 2.489899 -34.155137) (xy 2.535749 -34.184603)
			(xy 2.57694 -34.220294) (xy 2.612631 -34.261485) (xy 2.642097 -34.307335) (xy 2.664739 -34.356912)
			(xy 2.680094 -34.409207) (xy 2.68785 -34.463155) (xy 2.688336 -34.490406) (xy 2.687898 -34.517218)
			(xy 2.680383 -34.570313) (xy 2.665502 -34.621831) (xy 2.643549 -34.670756) (xy 2.614957 -34.716122)
			(xy 2.58029 -34.757033) (xy 2.540233 -34.792684) (xy 2.518156 -34.807906) (xy 2.506594 -34.816168)
			(xy 2.488189 -34.837803) (xy 2.476452 -34.863669) (xy 2.47229 -34.891767) (xy 2.476026 -34.919926)
			(xy 2.487371 -34.945967) (xy 2.505447 -34.967878) (xy 2.516886 -34.976308) (xy 2.538353 -34.991647)
			(xy 2.577267 -35.027275) (xy 2.6109 -35.067926) (xy 2.63861 -35.112824) (xy 2.659869 -35.161112)
			(xy 2.674271 -35.211869) (xy 2.68154 -35.264126) (xy 2.681986 -35.290506) (xy 2.6815 -35.317757)
			(xy 2.673744 -35.371705) (xy 2.658389 -35.424) (xy 2.635747 -35.473577) (xy 2.606281 -35.519427)
			(xy 2.57059 -35.560618) (xy 2.529399 -35.596309) (xy 2.483549 -35.625775) (xy 2.433972 -35.648417)
			(xy 2.381677 -35.663772) (xy 2.327729 -35.671528) (xy 2.273227 -35.671528) (xy 2.219279 -35.663772)
			(xy 2.166984 -35.648417) (xy 2.117407 -35.625775) (xy 2.071557 -35.596309) (xy 2.030366 -35.560618)
			(xy 1.994675 -35.519427) (xy 1.965209 -35.473577) (xy 1.942567 -35.424) (xy 1.927212 -35.371705)
			(xy 1.919456 -35.317757) (xy 1.91897 -35.290506) (xy 1.27 -35.290506) (xy 1.27 -35.91941) (xy 2.665728 -35.91941)
			(xy 2.669799 -35.863788) (xy 2.681925 -35.809351) (xy 2.701848 -35.75726) (xy 2.729144 -35.708625)
			(xy 2.76323 -35.664482) (xy 2.803379 -35.625773) (xy 2.848737 -35.593322) (xy 2.898337 -35.567821)
			(xy 2.951121 -35.549814) (xy 3.005964 -35.539684) (xy 3.061698 -35.537647) (xy 3.117135 -35.543747)
			(xy 3.171092 -35.557853) (xy 3.222421 -35.579665) (xy 3.270027 -35.608719) (xy 3.312895 -35.644394)
			(xy 3.350112 -35.685931) (xy 3.380885 -35.732444) (xy 3.404557 -35.782941) (xy 3.420625 -35.836348)
			(xy 3.427317 -35.881818) (xy 3.668774 -35.881818) (xy 3.672845 -35.826196) (xy 3.684971 -35.771759)
			(xy 3.704894 -35.719668) (xy 3.73219 -35.671033) (xy 3.766276 -35.62689) (xy 3.806425 -35.588181)
			(xy 3.851783 -35.55573) (xy 3.901383 -35.530229) (xy 3.954167 -35.512222) (xy 4.00901 -35.502092)
			(xy 4.064744 -35.500055) (xy 4.120181 -35.506155) (xy 4.174138 -35.520261) (xy 4.225467 -35.542073)
			(xy 4.273073 -35.571127) (xy 4.315941 -35.606802) (xy 4.353158 -35.648339) (xy 4.383931 -35.694852)
			(xy 4.407603 -35.745349) (xy 4.423671 -35.798756) (xy 4.431791 -35.853932) (xy 4.4323 -35.881818)
			(xy 4.43186 -35.905948) (xy 4.661152 -35.905948) (xy 4.665223 -35.850326) (xy 4.677349 -35.795889)
			(xy 4.697272 -35.743798) (xy 4.724568 -35.695163) (xy 4.758654 -35.65102) (xy 4.798803 -35.612311)
			(xy 4.844161 -35.57986) (xy 4.893761 -35.554359) (xy 4.946545 -35.536352) (xy 5.001388 -35.526222)
			(xy 5.057122 -35.524185) (xy 5.112559 -35.530285) (xy 5.166516 -35.544391) (xy 5.217845 -35.566203)
			(xy 5.265451 -35.595257) (xy 5.308319 -35.630932) (xy 5.345536 -35.672469) (xy 5.376309 -35.718982)
			(xy 5.399981 -35.769479) (xy 5.416049 -35.822886) (xy 5.424169 -35.878062) (xy 5.424678 -35.905948)
			(xy 5.424169 -35.933834) (xy 5.416049 -35.98901) (xy 5.399981 -36.042417) (xy 5.376309 -36.092914)
			(xy 5.345536 -36.139427) (xy 5.308319 -36.180964) (xy 5.265451 -36.216639) (xy 5.217845 -36.245693)
			(xy 5.166516 -36.267505) (xy 5.112559 -36.281611) (xy 5.057122 -36.287711) (xy 5.001388 -36.285674)
			(xy 4.946545 -36.275544) (xy 4.893761 -36.257537) (xy 4.844161 -36.232036) (xy 4.798803 -36.199585)
			(xy 4.758654 -36.160876) (xy 4.724568 -36.116733) (xy 4.697272 -36.068098) (xy 4.677349 -36.016007)
			(xy 4.665223 -35.96157) (xy 4.661152 -35.905948) (xy 4.43186 -35.905948) (xy 4.431791 -35.909704)
			(xy 4.423671 -35.96488) (xy 4.407603 -36.018287) (xy 4.383931 -36.068784) (xy 4.353158 -36.115297)
			(xy 4.315941 -36.156834) (xy 4.273073 -36.192509) (xy 4.225467 -36.221563) (xy 4.174138 -36.243375)
			(xy 4.120181 -36.257481) (xy 4.064744 -36.263581) (xy 4.00901 -36.261544) (xy 3.954167 -36.251414)
			(xy 3.901383 -36.233407) (xy 3.851783 -36.207906) (xy 3.806425 -36.175455) (xy 3.766276 -36.136746)
			(xy 3.73219 -36.092603) (xy 3.704894 -36.043968) (xy 3.684971 -35.991877) (xy 3.672845 -35.93744)
			(xy 3.668774 -35.881818) (xy 3.427317 -35.881818) (xy 3.428745 -35.891524) (xy 3.429254 -35.91941)
			(xy 3.428745 -35.947296) (xy 3.420625 -36.002472) (xy 3.404557 -36.055879) (xy 3.380885 -36.106376)
			(xy 3.350112 -36.152889) (xy 3.312895 -36.194426) (xy 3.270027 -36.230101) (xy 3.222421 -36.259155)
			(xy 3.171092 -36.280967) (xy 3.117135 -36.295073) (xy 3.061698 -36.301173) (xy 3.005964 -36.299136)
			(xy 2.951121 -36.289006) (xy 2.898337 -36.270999) (xy 2.848737 -36.245498) (xy 2.803379 -36.213047)
			(xy 2.76323 -36.174338) (xy 2.729144 -36.130195) (xy 2.701848 -36.08156) (xy 2.681925 -36.029469)
			(xy 2.669799 -35.975032) (xy 2.665728 -35.91941) (xy 1.27 -35.91941) (xy 1.27 -36.760912) (xy 3.474718 -36.760912)
			(xy 3.478789 -36.70529) (xy 3.490915 -36.650853) (xy 3.510838 -36.598762) (xy 3.538134 -36.550127)
			(xy 3.57222 -36.505984) (xy 3.612369 -36.467275) (xy 3.657727 -36.434824) (xy 3.707327 -36.409323)
			(xy 3.760111 -36.391316) (xy 3.814954 -36.381186) (xy 3.870688 -36.379149) (xy 3.926125 -36.385249)
			(xy 3.980082 -36.399355) (xy 4.031411 -36.421167) (xy 4.079017 -36.450221) (xy 4.121885 -36.485896)
			(xy 4.159102 -36.527433) (xy 4.189875 -36.573946) (xy 4.213547 -36.624443) (xy 4.229615 -36.67785)
			(xy 4.237735 -36.733026) (xy 4.238244 -36.760912) (xy 4.490718 -36.760912) (xy 4.494789 -36.70529)
			(xy 4.506915 -36.650853) (xy 4.526838 -36.598762) (xy 4.554134 -36.550127) (xy 4.58822 -36.505984)
			(xy 4.628369 -36.467275) (xy 4.673727 -36.434824) (xy 4.723327 -36.409323) (xy 4.776111 -36.391316)
			(xy 4.830954 -36.381186) (xy 4.886688 -36.379149) (xy 4.942125 -36.385249) (xy 4.996082 -36.399355)
			(xy 5.047411 -36.421167) (xy 5.095017 -36.450221) (xy 5.137885 -36.485896) (xy 5.175102 -36.527433)
			(xy 5.205875 -36.573946) (xy 5.229547 -36.624443) (xy 5.245615 -36.67785) (xy 5.253735 -36.733026)
			(xy 5.254244 -36.760912) (xy 5.506718 -36.760912) (xy 5.510789 -36.70529) (xy 5.522915 -36.650853)
			(xy 5.542838 -36.598762) (xy 5.570134 -36.550127) (xy 5.60422 -36.505984) (xy 5.644369 -36.467275)
			(xy 5.689727 -36.434824) (xy 5.739327 -36.409323) (xy 5.792111 -36.391316) (xy 5.846954 -36.381186)
			(xy 5.902688 -36.379149) (xy 5.958125 -36.385249) (xy 6.012082 -36.399355) (xy 6.063411 -36.421167)
			(xy 6.111017 -36.450221) (xy 6.153885 -36.485896) (xy 6.191102 -36.527433) (xy 6.221875 -36.573946)
			(xy 6.245547 -36.624443) (xy 6.261615 -36.67785) (xy 6.269735 -36.733026) (xy 6.270244 -36.760912)
			(xy 6.269735 -36.788798) (xy 6.261615 -36.843974) (xy 6.245547 -36.897381) (xy 6.221875 -36.947878)
			(xy 6.191102 -36.994391) (xy 6.153885 -37.035928) (xy 6.111017 -37.071603) (xy 6.063411 -37.100657)
			(xy 6.012082 -37.122469) (xy 5.958125 -37.136575) (xy 5.902688 -37.142675) (xy 5.846954 -37.140638)
			(xy 5.792111 -37.130508) (xy 5.739327 -37.112501) (xy 5.689727 -37.087) (xy 5.644369 -37.054549)
			(xy 5.60422 -37.01584) (xy 5.570134 -36.971697) (xy 5.542838 -36.923062) (xy 5.522915 -36.870971)
			(xy 5.510789 -36.816534) (xy 5.506718 -36.760912) (xy 5.254244 -36.760912) (xy 5.253735 -36.788798)
			(xy 5.245615 -36.843974) (xy 5.229547 -36.897381) (xy 5.205875 -36.947878) (xy 5.175102 -36.994391)
			(xy 5.137885 -37.035928) (xy 5.095017 -37.071603) (xy 5.047411 -37.100657) (xy 4.996082 -37.122469)
			(xy 4.942125 -37.136575) (xy 4.886688 -37.142675) (xy 4.830954 -37.140638) (xy 4.776111 -37.130508)
			(xy 4.723327 -37.112501) (xy 4.673727 -37.087) (xy 4.628369 -37.054549) (xy 4.58822 -37.01584) (xy 4.554134 -36.971697)
			(xy 4.526838 -36.923062) (xy 4.506915 -36.870971) (xy 4.494789 -36.816534) (xy 4.490718 -36.760912)
			(xy 4.238244 -36.760912) (xy 4.237735 -36.788798) (xy 4.229615 -36.843974) (xy 4.213547 -36.897381)
			(xy 4.189875 -36.947878) (xy 4.159102 -36.994391) (xy 4.121885 -37.035928) (xy 4.079017 -37.071603)
			(xy 4.031411 -37.100657) (xy 3.980082 -37.122469) (xy 3.926125 -37.136575) (xy 3.870688 -37.142675)
			(xy 3.814954 -37.140638) (xy 3.760111 -37.130508) (xy 3.707327 -37.112501) (xy 3.657727 -37.087)
			(xy 3.612369 -37.054549) (xy 3.57222 -37.01584) (xy 3.538134 -36.971697) (xy 3.510838 -36.923062)
			(xy 3.490915 -36.870971) (xy 3.478789 -36.816534) (xy 3.474718 -36.760912) (xy 1.27 -36.760912) (xy 1.27 -41.166542)
			(xy 2.403856 -41.166542) (xy 2.404383 -41.137625) (xy 2.413107 -41.080453) (xy 2.430362 -41.025254)
			(xy 2.455752 -40.973292) (xy 2.488695 -40.925758) (xy 2.528436 -40.883741) (xy 2.550922 -40.865552)
			(xy 2.559705 -40.85801) (xy 2.569876 -40.837236) (xy 2.57048 -40.825674) (xy 2.57048 -40.74541) (xy 2.569911 -40.733842)
			(xy 2.559716 -40.713071) (xy 2.550922 -40.705532) (xy 2.528438 -40.687342) (xy 2.488703 -40.645322)
			(xy 2.455764 -40.597787) (xy 2.430376 -40.545825) (xy 2.41312 -40.490628) (xy 2.404391 -40.433458)
			(xy 2.403856 -40.404542) (xy 2.404363 -40.377285) (xy 2.412125 -40.323327) (xy 2.427482 -40.271021)
			(xy 2.450122 -40.221431) (xy 2.479584 -40.175565) (xy 2.515271 -40.134356) (xy 2.556456 -40.098641)
			(xy 2.579116 -40.083486) (xy 2.586099 -40.078654) (xy 2.59662 -40.065337) (xy 2.602175 -40.0493)
			(xy 2.602484 -40.040814) (xy 2.602484 -39.95547) (xy 2.602172 -39.946989) (xy 2.59658 -39.930974)
			(xy 2.58608 -39.91765) (xy 2.579116 -39.912798) (xy 2.556451 -39.897647) (xy 2.515254 -39.86194)
			(xy 2.479559 -39.820734) (xy 2.45009 -39.774867) (xy 2.427448 -39.725274) (xy 2.412094 -39.672964)
			(xy 2.40434 -39.619001) (xy 2.403856 -39.591742) (xy 2.404383 -39.562825) (xy 2.413107 -39.505653)
			(xy 2.430362 -39.450454) (xy 2.455752 -39.398492) (xy 2.488695 -39.350958) (xy 2.528436 -39.308941)
			(xy 2.550922 -39.290752) (xy 2.559705 -39.28321) (xy 2.569876 -39.262436) (xy 2.57048 -39.250874)
			(xy 2.57048 -39.17061) (xy 2.569911 -39.159042) (xy 2.559716 -39.138271) (xy 2.550922 -39.130732)
			(xy 2.528438 -39.112542) (xy 2.488703 -39.070522) (xy 2.455764 -39.022987) (xy 2.430376 -38.971025)
			(xy 2.41312 -38.915828) (xy 2.404391 -38.858658) (xy 2.403856 -38.829742) (xy 2.404317 -38.802489)
			(xy 2.412074 -38.748538) (xy 2.42743 -38.69624) (xy 2.450073 -38.646659) (xy 2.479541 -38.600806)
			(xy 2.515235 -38.559613) (xy 2.556428 -38.52392) (xy 2.602281 -38.494452) (xy 2.651862 -38.471809)
			(xy 2.70416 -38.456454) (xy 2.758111 -38.448697) (xy 2.785364 -38.448234) (xy 2.81484 -38.448792)
			(xy 2.87309 -38.457856) (xy 2.929253 -38.475774) (xy 2.981991 -38.502118) (xy 3.030047 -38.536263)
			(xy 3.040664 -38.546603) (xy 6.274009 -38.546603) (xy 6.274009 -38.492097) (xy 6.281766 -38.438147)
			(xy 6.297122 -38.385849) (xy 6.319765 -38.336269) (xy 6.349233 -38.290416) (xy 6.384927 -38.249224)
			(xy 6.426119 -38.213531) (xy 6.471973 -38.184063) (xy 6.521553 -38.161421) (xy 6.57385 -38.146065)
			(xy 6.627801 -38.138309) (xy 6.655054 -38.137846) (xy 6.683971 -38.13838) (xy 6.741142 -38.147103)
			(xy 6.796341 -38.164357) (xy 6.848303 -38.189745) (xy 6.895837 -38.222687) (xy 6.937854 -38.262427)
			(xy 6.956044 -38.284912) (xy 6.963589 -38.293691) (xy 6.984361 -38.303865) (xy 6.995922 -38.30447)
			(xy 7.076186 -38.30447) (xy 7.087754 -38.303902) (xy 7.108526 -38.293707) (xy 7.116064 -38.284912)
			(xy 7.134278 -38.262448) (xy 7.176293 -38.222711) (xy 7.223823 -38.18977) (xy 7.27578 -38.164378)
			(xy 7.330973 -38.147117) (xy 7.388139 -38.138384) (xy 7.417054 -38.137846) (xy 7.444305 -38.138324)
			(xy 7.498253 -38.146081) (xy 7.550548 -38.161437) (xy 7.600125 -38.184078) (xy 7.645976 -38.213545)
			(xy 7.687166 -38.249237) (xy 7.722857 -38.290428) (xy 7.752324 -38.336278) (xy 7.774965 -38.385856)
			(xy 7.79032 -38.438151) (xy 7.798076 -38.492099) (xy 7.798076 -38.546601) (xy 7.79032 -38.600549)
			(xy 7.774965 -38.652844) (xy 7.752324 -38.702422) (xy 7.722857 -38.748272) (xy 7.687166 -38.789463)
			(xy 7.645976 -38.825155) (xy 7.600125 -38.854622) (xy 7.550548 -38.877263) (xy 7.498253 -38.892619)
			(xy 7.444305 -38.900376) (xy 7.417054 -38.900862) (xy 7.388138 -38.900319) (xy 7.330967 -38.891598)
			(xy 7.275768 -38.874345) (xy 7.223806 -38.848958) (xy 7.176272 -38.816018) (xy 7.134254 -38.77628)
			(xy 7.116064 -38.753796) (xy 7.108514 -38.745022) (xy 7.087746 -38.734845) (xy 7.076186 -38.734238)
			(xy 6.995922 -38.734238) (xy 6.984354 -38.734808) (xy 6.963582 -38.745001) (xy 6.956044 -38.753796)
			(xy 6.937827 -38.776258) (xy 6.895813 -38.815994) (xy 6.848283 -38.848936) (xy 6.796327 -38.874328)
			(xy 6.741134 -38.891589) (xy 6.683968 -38.900324) (xy 6.655054 -38.900862) (xy 6.627801 -38.900391)
			(xy 6.57385 -38.892635) (xy 6.521553 -38.877279) (xy 6.471973 -38.854637) (xy 6.426119 -38.825169)
			(xy 6.384927 -38.789476) (xy 6.349233 -38.748284) (xy 6.319765 -38.702431) (xy 6.297122 -38.652851)
			(xy 6.281766 -38.600553) (xy 6.274009 -38.546603) (xy 3.040664 -38.546603) (xy 3.072279 -38.577394)
			(xy 3.090418 -38.600634) (xy 3.096768 -38.609016) (xy 3.113532 -38.618922) (xy 3.204718 -38.632384)
			(xy 3.223768 -38.627558) (xy 3.231896 -38.621716) (xy 3.256621 -38.604185) (xy 3.310481 -38.576389)
			(xy 3.368059 -38.55746) (xy 3.427905 -38.547877) (xy 3.45821 -38.547294) (xy 3.486767 -38.547791)
			(xy 3.543247 -38.556288) (xy 3.597827 -38.573112) (xy 3.649289 -38.597887) (xy 3.69648 -38.630059)
			(xy 3.738346 -38.668909) (xy 3.773951 -38.713568) (xy 3.788664 -38.738048) (xy 3.793411 -38.745572)
			(xy 3.807015 -38.757018) (xy 3.823717 -38.763108) (xy 3.832606 -38.763448) (xy 3.92049 -38.763448)
			(xy 3.929364 -38.76301) (xy 3.946041 -38.756931) (xy 3.959648 -38.745533) (xy 3.964432 -38.738048)
			(xy 3.979148 -38.713573) (xy 4.014768 -38.668934) (xy 4.056641 -38.630101) (xy 4.103832 -38.597939)
			(xy 4.155288 -38.573168) (xy 4.209861 -38.556339) (xy 4.266332 -38.547828) (xy 4.294886 -38.547294)
			(xy 4.322139 -38.547753) (xy 4.376091 -38.55551) (xy 4.428389 -38.570865) (xy 4.47797 -38.593508)
			(xy 4.523824 -38.622976) (xy 4.565018 -38.65867) (xy 4.600712 -38.699863) (xy 4.63018 -38.745716)
			(xy 4.652823 -38.795297) (xy 4.66818 -38.847595) (xy 4.675937 -38.901547) (xy 4.675937 -38.928802)
			(xy 5.182868 -38.928802) (xy 5.186939 -38.87318) (xy 5.199065 -38.818743) (xy 5.218988 -38.766652)
			(xy 5.246284 -38.718017) (xy 5.28037 -38.673874) (xy 5.320519 -38.635165) (xy 5.365877 -38.602714)
			(xy 5.415477 -38.577213) (xy 5.468261 -38.559206) (xy 5.523104 -38.549076) (xy 5.578838 -38.547039)
			(xy 5.634275 -38.553139) (xy 5.688232 -38.567245) (xy 5.739561 -38.589057) (xy 5.787167 -38.618111)
			(xy 5.830035 -38.653786) (xy 5.867252 -38.695323) (xy 5.898025 -38.741836) (xy 5.921697 -38.792333)
			(xy 5.937765 -38.84574) (xy 5.945885 -38.900916) (xy 5.946394 -38.928802) (xy 5.945885 -38.956688)
			(xy 5.937765 -39.011864) (xy 5.921697 -39.065271) (xy 5.898025 -39.115768) (xy 5.867252 -39.162281)
			(xy 5.830035 -39.203818) (xy 5.787167 -39.239493) (xy 5.739561 -39.268547) (xy 5.688232 -39.290359)
			(xy 5.634275 -39.304465) (xy 5.578838 -39.310565) (xy 5.523104 -39.308528) (xy 5.468261 -39.298398)
			(xy 5.415477 -39.280391) (xy 5.365877 -39.25489) (xy 5.320519 -39.222439) (xy 5.28037 -39.18373)
			(xy 5.246284 -39.139587) (xy 5.218988 -39.090952) (xy 5.199065 -39.038861) (xy 5.186939 -38.984424)
			(xy 5.182868 -38.928802) (xy 4.675937 -38.928802) (xy 4.675937 -38.956053) (xy 4.66818 -39.010005)
			(xy 4.652823 -39.062303) (xy 4.63018 -39.111884) (xy 4.600712 -39.157737) (xy 4.565018 -39.19893)
			(xy 4.523824 -39.234624) (xy 4.47797 -39.264092) (xy 4.428389 -39.286735) (xy 4.376091 -39.30209)
			(xy 4.322139 -39.309847) (xy 4.294886 -39.31031) (xy 4.266328 -39.309814) (xy 4.209849 -39.301317)
			(xy 4.155269 -39.284493) (xy 4.103808 -39.259717) (xy 4.056616 -39.227545) (xy 4.01475 -39.188695)
			(xy 3.979146 -39.144036) (xy 3.964432 -39.119556) (xy 3.959687 -39.112031) (xy 3.946082 -39.100585)
			(xy 3.929379 -39.094495) (xy 3.92049 -39.094156) (xy 3.832606 -39.094156) (xy 3.823731 -39.094589)
			(xy 3.807054 -39.10067) (xy 3.793447 -39.11207) (xy 3.788664 -39.119556) (xy 3.773921 -39.144014)
			(xy 3.738305 -39.188653) (xy 3.696437 -39.227487) (xy 3.649251 -39.259651) (xy 3.597799 -39.284425)
			(xy 3.54323 -39.301258) (xy 3.486763 -39.309773) (xy 3.45821 -39.31031) (xy 3.431137 -39.309799)
			(xy 3.377535 -39.302152) (xy 3.325554 -39.286997) (xy 3.276242 -39.264638) (xy 3.230589 -39.235526)
			(xy 3.189515 -39.200247) (xy 3.153848 -39.15951) (xy 3.138678 -39.137082) (xy 3.13232 -39.128307)
			(xy 3.114022 -39.116733) (xy 3.103372 -39.11473) (xy 3.071368 -39.109904) (xy 3.060604 -39.108825)
			(xy 3.039817 -39.114746) (xy 3.031236 -39.121334) (xy 3.019806 -39.130732) (xy 3.011035 -39.138285)
			(xy 3.000856 -39.15905) (xy 3.000248 -39.17061) (xy 3.000248 -39.250874) (xy 3.000817 -39.262442)
			(xy 3.011011 -39.283214) (xy 3.019806 -39.290752) (xy 3.042287 -39.308946) (xy 3.082022 -39.350965)
			(xy 3.114961 -39.3985) (xy 3.14035 -39.45046) (xy 3.157607 -39.505657) (xy 3.166337 -39.562826) (xy 3.166872 -39.591742)
			(xy 3.166339 -39.618998) (xy 3.158581 -39.672954) (xy 3.143228 -39.725259) (xy 3.120591 -39.774848)
			(xy 3.091133 -39.820715) (xy 3.055451 -39.861925) (xy 3.01427 -39.897641) (xy 2.991612 -39.912798)
			(xy 2.984622 -39.91762) (xy 2.974108 -39.930944) (xy 2.968554 -39.946983) (xy 2.968244 -39.95547)
			(xy 2.968244 -40.040814) (xy 2.968598 -40.04929) (xy 2.974177 -40.0653) (xy 2.984658 -40.078628)
			(xy 2.991612 -40.083486) (xy 3.01429 -40.098618) (xy 3.055485 -40.13433) (xy 3.091179 -40.17554)
			(xy 3.120645 -40.221409) (xy 3.143285 -40.271005) (xy 3.158637 -40.323318) (xy 3.166389 -40.377283)
			(xy 3.166872 -40.404542) (xy 3.166323 -40.433458) (xy 3.157602 -40.490628) (xy 3.140351 -40.545827)
			(xy 3.114965 -40.597789) (xy 3.082026 -40.645324) (xy 3.04229 -40.687341) (xy 3.019806 -40.705532)
			(xy 3.011035 -40.713085) (xy 3.000856 -40.73385) (xy 3.000248 -40.74541) (xy 3.000248 -40.825674)
			(xy 3.000817 -40.837242) (xy 3.011011 -40.858014) (xy 3.019806 -40.865552) (xy 3.042287 -40.883746)
			(xy 3.082022 -40.925765) (xy 3.114961 -40.9733) (xy 3.14035 -41.02526) (xy 3.157607 -41.080457) (xy 3.166337 -41.137626)
			(xy 3.166872 -41.166542) (xy 3.166386 -41.193793) (xy 3.15863 -41.247741) (xy 3.143275 -41.300036)
			(xy 3.120633 -41.349613) (xy 3.091167 -41.395463) (xy 3.055476 -41.436654) (xy 3.014285 -41.472345)
			(xy 2.968435 -41.501811) (xy 2.918858 -41.524453) (xy 2.866563 -41.539808) (xy 2.812615 -41.547564)
			(xy 2.758113 -41.547564) (xy 2.704165 -41.539808) (xy 2.65187 -41.524453) (xy 2.602293 -41.501811)
			(xy 2.556443 -41.472345) (xy 2.515252 -41.436654) (xy 2.479561 -41.395463) (xy 2.450095 -41.349613)
			(xy 2.427453 -41.300036) (xy 2.412098 -41.247741) (xy 2.404342 -41.193793) (xy 2.403856 -41.166542)
			(xy 1.27 -41.166542) (xy 1.27 -42.250614) (xy 2.72872 -42.250614) (xy 2.732791 -42.194992) (xy 2.744917 -42.140555)
			(xy 2.76484 -42.088464) (xy 2.792136 -42.039829) (xy 2.826222 -41.995686) (xy 2.866371 -41.956977)
			(xy 2.911729 -41.924526) (xy 2.961329 -41.899025) (xy 3.014113 -41.881018) (xy 3.068956 -41.870888)
			(xy 3.12469 -41.868851) (xy 3.180127 -41.874951) (xy 3.234084 -41.889057) (xy 3.285413 -41.910869)
			(xy 3.333019 -41.939923) (xy 3.375887 -41.975598) (xy 3.413104 -42.017135) (xy 3.443877 -42.063648)
			(xy 3.467549 -42.114145) (xy 3.483617 -42.167552) (xy 3.491737 -42.222728) (xy 3.492246 -42.250614)
			(xy 3.491737 -42.2785) (xy 3.483617 -42.333676) (xy 3.467549 -42.387083) (xy 3.460557 -42.401998)
			(xy 4.015484 -42.401998) (xy 4.019555 -42.346376) (xy 4.031681 -42.291939) (xy 4.051604 -42.239848)
			(xy 4.0789 -42.191213) (xy 4.112986 -42.14707) (xy 4.153135 -42.108361) (xy 4.198493 -42.07591) (xy 4.248093 -42.050409)
			(xy 4.300877 -42.032402) (xy 4.35572 -42.022272) (xy 4.411454 -42.020235) (xy 4.466891 -42.026335)
			(xy 4.520848 -42.040441) (xy 4.572177 -42.062253) (xy 4.619783 -42.091307) (xy 4.662651 -42.126982)
			(xy 4.699868 -42.168519) (xy 4.730641 -42.215032) (xy 4.754313 -42.265529) (xy 4.770381 -42.318936)
			(xy 4.774531 -42.347134) (xy 5.291072 -42.347134) (xy 5.295143 -42.291512) (xy 5.307269 -42.237075)
			(xy 5.327192 -42.184984) (xy 5.354488 -42.136349) (xy 5.388574 -42.092206) (xy 5.428723 -42.053497)
			(xy 5.474081 -42.021046) (xy 5.523681 -41.995545) (xy 5.576465 -41.977538) (xy 5.631308 -41.967408)
			(xy 5.687042 -41.965371) (xy 5.742479 -41.971471) (xy 5.796436 -41.985577) (xy 5.847765 -42.007389)
			(xy 5.895371 -42.036443) (xy 5.938239 -42.072118) (xy 5.975456 -42.113655) (xy 6.006229 -42.160168)
			(xy 6.029901 -42.210665) (xy 6.045969 -42.264072) (xy 6.054089 -42.319248) (xy 6.054598 -42.347134)
			(xy 6.054089 -42.37502) (xy 6.045969 -42.430196) (xy 6.029901 -42.483603) (xy 6.006229 -42.5341)
			(xy 5.975456 -42.580613) (xy 5.938239 -42.62215) (xy 5.895371 -42.657825) (xy 5.847765 -42.686879)
			(xy 5.796436 -42.708691) (xy 5.742479 -42.722797) (xy 5.687042 -42.728897) (xy 5.631308 -42.72686)
			(xy 5.576465 -42.71673) (xy 5.523681 -42.698723) (xy 5.474081 -42.673222) (xy 5.428723 -42.640771)
			(xy 5.388574 -42.602062) (xy 5.354488 -42.557919) (xy 5.327192 -42.509284) (xy 5.307269 -42.457193)
			(xy 5.295143 -42.402756) (xy 5.291072 -42.347134) (xy 4.774531 -42.347134) (xy 4.778501 -42.374112)
			(xy 4.77901 -42.401998) (xy 4.778501 -42.429884) (xy 4.770381 -42.48506) (xy 4.754313 -42.538467)
			(xy 4.730641 -42.588964) (xy 4.699868 -42.635477) (xy 4.662651 -42.677014) (xy 4.619783 -42.712689)
			(xy 4.572177 -42.741743) (xy 4.520848 -42.763555) (xy 4.466891 -42.777661) (xy 4.411454 -42.783761)
			(xy 4.35572 -42.781724) (xy 4.300877 -42.771594) (xy 4.248093 -42.753587) (xy 4.198493 -42.728086)
			(xy 4.153135 -42.695635) (xy 4.112986 -42.656926) (xy 4.0789 -42.612783) (xy 4.051604 -42.564148)
			(xy 4.031681 -42.512057) (xy 4.019555 -42.45762) (xy 4.015484 -42.401998) (xy 3.460557 -42.401998)
			(xy 3.443877 -42.43758) (xy 3.413104 -42.484093) (xy 3.375887 -42.52563) (xy 3.333019 -42.561305)
			(xy 3.285413 -42.590359) (xy 3.234084 -42.612171) (xy 3.180127 -42.626277) (xy 3.12469 -42.632377)
			(xy 3.068956 -42.63034) (xy 3.014113 -42.62021) (xy 2.961329 -42.602203) (xy 2.911729 -42.576702)
			(xy 2.866371 -42.544251) (xy 2.826222 -42.505542) (xy 2.792136 -42.461399) (xy 2.76484 -42.412764)
			(xy 2.744917 -42.360673) (xy 2.732791 -42.306236) (xy 2.72872 -42.250614) (xy 1.27 -42.250614) (xy 1.27 -44.647358)
			(xy 2.846068 -44.647358) (xy 2.850139 -44.591736) (xy 2.862265 -44.537299) (xy 2.882188 -44.485208)
			(xy 2.909484 -44.436573) (xy 2.94357 -44.39243) (xy 2.983719 -44.353721) (xy 3.029077 -44.32127)
			(xy 3.078677 -44.295769) (xy 3.131461 -44.277762) (xy 3.186304 -44.267632) (xy 3.242038 -44.265595)
			(xy 3.297475 -44.271695) (xy 3.351432 -44.285801) (xy 3.402761 -44.307613) (xy 3.450367 -44.336667)
			(xy 3.493235 -44.372342) (xy 3.530452 -44.413879) (xy 3.561225 -44.460392) (xy 3.584897 -44.510889)
			(xy 3.600965 -44.564296) (xy 3.609085 -44.619472) (xy 3.609594 -44.647358) (xy 3.609085 -44.675244)
			(xy 3.606984 -44.689522) (xy 3.862068 -44.689522) (xy 3.866139 -44.6339) (xy 3.878265 -44.579463)
			(xy 3.898188 -44.527372) (xy 3.925484 -44.478737) (xy 3.95957 -44.434594) (xy 3.999719 -44.395885)
			(xy 4.045077 -44.363434) (xy 4.094677 -44.337933) (xy 4.147461 -44.319926) (xy 4.202304 -44.309796)
			(xy 4.258038 -44.307759) (xy 4.313475 -44.313859) (xy 4.367432 -44.327965) (xy 4.418761 -44.349777)
			(xy 4.466367 -44.378831) (xy 4.509235 -44.414506) (xy 4.546452 -44.456043) (xy 4.577225 -44.502556)
			(xy 4.600897 -44.553053) (xy 4.616965 -44.60646) (xy 4.622984 -44.647358) (xy 4.878068 -44.647358)
			(xy 4.882139 -44.591736) (xy 4.894265 -44.537299) (xy 4.914188 -44.485208) (xy 4.941484 -44.436573)
			(xy 4.97557 -44.39243) (xy 5.015719 -44.353721) (xy 5.061077 -44.32127) (xy 5.110677 -44.295769)
			(xy 5.163461 -44.277762) (xy 5.218304 -44.267632) (xy 5.274038 -44.265595) (xy 5.329475 -44.271695)
			(xy 5.383432 -44.285801) (xy 5.434761 -44.307613) (xy 5.482367 -44.336667) (xy 5.525235 -44.372342)
			(xy 5.562452 -44.413879) (xy 5.593225 -44.460392) (xy 5.616897 -44.510889) (xy 5.632965 -44.564296)
			(xy 5.641085 -44.619472) (xy 5.641594 -44.647358) (xy 5.641085 -44.675244) (xy 5.632965 -44.73042)
			(xy 5.616897 -44.783827) (xy 5.593225 -44.834324) (xy 5.562452 -44.880837) (xy 5.525235 -44.922374)
			(xy 5.482367 -44.958049) (xy 5.434761 -44.987103) (xy 5.383432 -45.008915) (xy 5.329475 -45.023021)
			(xy 5.274038 -45.029121) (xy 5.218304 -45.027084) (xy 5.163461 -45.016954) (xy 5.110677 -44.998947)
			(xy 5.061077 -44.973446) (xy 5.015719 -44.940995) (xy 4.97557 -44.902286) (xy 4.941484 -44.858143)
			(xy 4.914188 -44.809508) (xy 4.894265 -44.757417) (xy 4.882139 -44.70298) (xy 4.878068 -44.647358)
			(xy 4.622984 -44.647358) (xy 4.625085 -44.661636) (xy 4.625594 -44.689522) (xy 4.625085 -44.717408)
			(xy 4.616965 -44.772584) (xy 4.600897 -44.825991) (xy 4.577225 -44.876488) (xy 4.546452 -44.923001)
			(xy 4.509235 -44.964538) (xy 4.466367 -45.000213) (xy 4.418761 -45.029267) (xy 4.367432 -45.051079)
			(xy 4.313475 -45.065185) (xy 4.258038 -45.071285) (xy 4.202304 -45.069248) (xy 4.147461 -45.059118)
			(xy 4.094677 -45.041111) (xy 4.045077 -45.01561) (xy 3.999719 -44.983159) (xy 3.95957 -44.94445)
			(xy 3.925484 -44.900307) (xy 3.898188 -44.851672) (xy 3.878265 -44.799581) (xy 3.866139 -44.745144)
			(xy 3.862068 -44.689522) (xy 3.606984 -44.689522) (xy 3.600965 -44.73042) (xy 3.584897 -44.783827)
			(xy 3.561225 -44.834324) (xy 3.530452 -44.880837) (xy 3.493235 -44.922374) (xy 3.450367 -44.958049)
			(xy 3.402761 -44.987103) (xy 3.351432 -45.008915) (xy 3.297475 -45.023021) (xy 3.242038 -45.029121)
			(xy 3.186304 -45.027084) (xy 3.131461 -45.016954) (xy 3.078677 -44.998947) (xy 3.029077 -44.973446)
			(xy 2.983719 -44.940995) (xy 2.94357 -44.902286) (xy 2.909484 -44.858143) (xy 2.882188 -44.809508)
			(xy 2.862265 -44.757417) (xy 2.850139 -44.70298) (xy 2.846068 -44.647358) (xy 1.27 -44.647358) (xy 1.27 -45.071792)
			(xy 6.365492 -45.071792) (xy 6.369563 -45.01617) (xy 6.381689 -44.961733) (xy 6.401612 -44.909642)
			(xy 6.428908 -44.861007) (xy 6.462994 -44.816864) (xy 6.503143 -44.778155) (xy 6.548501 -44.745704)
			(xy 6.598101 -44.720203) (xy 6.650885 -44.702196) (xy 6.705728 -44.692066) (xy 6.761462 -44.690029)
			(xy 6.816899 -44.696129) (xy 6.870856 -44.710235) (xy 6.922185 -44.732047) (xy 6.969791 -44.761101)
			(xy 7.012659 -44.796776) (xy 7.049876 -44.838313) (xy 7.080649 -44.884826) (xy 7.104321 -44.935323)
			(xy 7.120389 -44.98873) (xy 7.128509 -45.043906) (xy 7.129018 -45.071792) (xy 7.128509 -45.099678)
			(xy 7.120389 -45.154854) (xy 7.104321 -45.208261) (xy 7.080649 -45.258758) (xy 7.049876 -45.305271)
			(xy 7.012659 -45.346808) (xy 6.969791 -45.382483) (xy 6.922185 -45.411537) (xy 6.870856 -45.433349)
			(xy 6.816899 -45.447455) (xy 6.761462 -45.453555) (xy 6.705728 -45.451518) (xy 6.650885 -45.441388)
			(xy 6.598101 -45.423381) (xy 6.548501 -45.39788) (xy 6.503143 -45.365429) (xy 6.462994 -45.32672)
			(xy 6.428908 -45.282577) (xy 6.401612 -45.233942) (xy 6.381689 -45.181851) (xy 6.369563 -45.127414)
			(xy 6.365492 -45.071792) (xy 1.27 -45.071792) (xy 1.27 -45.851318) (xy 7.87476 -45.851318) (xy 7.878831 -45.795696)
			(xy 7.890957 -45.741259) (xy 7.91088 -45.689168) (xy 7.938176 -45.640533) (xy 7.972262 -45.59639)
			(xy 8.012411 -45.557681) (xy 8.057769 -45.52523) (xy 8.107369 -45.499729) (xy 8.160153 -45.481722)
			(xy 8.214996 -45.471592) (xy 8.27073 -45.469555) (xy 8.326167 -45.475655) (xy 8.380124 -45.489761)
			(xy 8.431453 -45.511573) (xy 8.479059 -45.540627) (xy 8.521927 -45.576302) (xy 8.559144 -45.617839)
			(xy 8.589917 -45.664352) (xy 8.613589 -45.714849) (xy 8.629657 -45.768256) (xy 8.637777 -45.823432)
			(xy 8.638286 -45.851318) (xy 8.637777 -45.879204) (xy 8.629657 -45.93438) (xy 8.613589 -45.987787)
			(xy 8.589917 -46.038284) (xy 8.559144 -46.084797) (xy 8.521927 -46.126334) (xy 8.479059 -46.162009)
			(xy 8.431453 -46.191063) (xy 8.380124 -46.212875) (xy 8.326167 -46.226981) (xy 8.27073 -46.233081)
			(xy 8.214996 -46.231044) (xy 8.160153 -46.220914) (xy 8.107369 -46.202907) (xy 8.057769 -46.177406)
			(xy 8.012411 -46.144955) (xy 7.972262 -46.106246) (xy 7.938176 -46.062103) (xy 7.91088 -46.013468)
			(xy 7.890957 -45.961377) (xy 7.878831 -45.90694) (xy 7.87476 -45.851318) (xy 1.27 -45.851318) (xy 1.27 -49.601951)
			(xy 2.291062 -49.601951) (xy 2.291062 -49.547449) (xy 2.298818 -49.493502) (xy 2.314173 -49.441208)
			(xy 2.336814 -49.391631) (xy 2.36628 -49.345781) (xy 2.401971 -49.304591) (xy 2.443161 -49.2689)
			(xy 2.489011 -49.239434) (xy 2.538588 -49.216793) (xy 2.590882 -49.201438) (xy 2.644829 -49.193682)
			(xy 2.67208 -49.193196) (xy 2.69945 -49.193675) (xy 2.753628 -49.20149) (xy 2.806131 -49.216976)
			(xy 2.855878 -49.239815) (xy 2.901846 -49.269536) (xy 2.922778 -49.287176) (xy 2.92989 -49.293272)
			(xy 2.946908 -49.299622) (xy 3.032252 -49.299622) (xy 3.04927 -49.293272) (xy 3.056382 -49.287176)
			(xy 3.077315 -49.269535) (xy 3.123283 -49.239811) (xy 3.173029 -49.216965) (xy 3.225531 -49.201469)
			(xy 3.279709 -49.19364) (xy 3.334451 -49.19364) (xy 3.388629 -49.201469) (xy 3.441131 -49.216965)
			(xy 3.490877 -49.239811) (xy 3.536845 -49.269535) (xy 3.557778 -49.287176) (xy 3.56489 -49.293272)
			(xy 3.581908 -49.299622) (xy 3.667252 -49.299622) (xy 3.68427 -49.293272) (xy 3.691382 -49.287176)
			(xy 3.712307 -49.269528) (xy 3.758282 -49.239818) (xy 3.808031 -49.216985) (xy 3.860534 -49.201495)
			(xy 3.91471 -49.193669) (xy 3.94208 -49.193196) (xy 3.968397 -49.193617) (xy 4.020532 -49.200844)
			(xy 4.071181 -49.215163) (xy 4.119383 -49.236304) (xy 4.164224 -49.263865) (xy 4.204855 -49.297323)
			(xy 4.223004 -49.316386) (xy 4.230524 -49.323789) (xy 4.249805 -49.332313) (xy 4.260342 -49.332896)
			(xy 4.335018 -49.332896) (xy 4.345564 -49.332337) (xy 4.36486 -49.323823) (xy 4.372356 -49.316386)
			(xy 4.390509 -49.297325) (xy 4.431126 -49.263846) (xy 4.475963 -49.236274) (xy 4.524167 -49.215132)
			(xy 4.574821 -49.200823) (xy 4.626962 -49.19362) (xy 4.65328 -49.193196) (xy 4.680532 -49.193674)
			(xy 4.73448 -49.20143) (xy 4.786775 -49.216786) (xy 4.836353 -49.239427) (xy 4.882204 -49.268894)
			(xy 4.923394 -49.304586) (xy 4.959086 -49.345776) (xy 4.988553 -49.391627) (xy 5.011194 -49.441205)
			(xy 5.02655 -49.4935) (xy 5.034306 -49.547448) (xy 5.034306 -49.601952) (xy 5.02655 -49.6559) (xy 5.011194 -49.708195)
			(xy 4.988553 -49.757773) (xy 4.959086 -49.803624) (xy 4.923394 -49.844814) (xy 4.882204 -49.880506)
			(xy 4.836353 -49.909973) (xy 4.786775 -49.932614) (xy 4.73448 -49.94797) (xy 4.680532 -49.955726)
			(xy 4.65328 -49.956212) (xy 4.626964 -49.955748) (xy 4.574831 -49.94853) (xy 4.524183 -49.934219)
			(xy 4.475981 -49.913086) (xy 4.431139 -49.885533) (xy 4.390507 -49.852081) (xy 4.372356 -49.833022)
			(xy 4.36485 -49.825602) (xy 4.345558 -49.817087) (xy 4.335018 -49.816512) (xy 4.260342 -49.816512)
			(xy 4.249793 -49.817047) (xy 4.230497 -49.825577) (xy 4.223004 -49.833022) (xy 4.204852 -49.852085)
			(xy 4.164237 -49.885567) (xy 4.119401 -49.913142) (xy 4.071196 -49.934284) (xy 4.020541 -49.948591)
			(xy 3.968399 -49.955791) (xy 3.94208 -49.956212) (xy 3.914709 -49.955755) (xy 3.86053 -49.947934)
			(xy 3.808027 -49.932443) (xy 3.75828 -49.909599) (xy 3.712314 -49.879874) (xy 3.691382 -49.862232)
			(xy 3.68427 -49.856136) (xy 3.667252 -49.849786) (xy 3.581908 -49.849786) (xy 3.56489 -49.856136)
			(xy 3.557778 -49.862232) (xy 3.536845 -49.879873) (xy 3.490877 -49.909597) (xy 3.441131 -49.932443)
			(xy 3.388629 -49.947939) (xy 3.334451 -49.955768) (xy 3.279709 -49.955768) (xy 3.225531 -49.947939)
			(xy 3.173029 -49.932443) (xy 3.123283 -49.909597) (xy 3.077315 -49.879873) (xy 3.056382 -49.862232)
			(xy 3.04927 -49.856136) (xy 3.032252 -49.849786) (xy 2.946908 -49.849786) (xy 2.92989 -49.856136)
			(xy 2.922778 -49.862232) (xy 2.901831 -49.879853) (xy 2.855862 -49.909566) (xy 2.806118 -49.932405)
			(xy 2.753621 -49.947901) (xy 2.699448 -49.955735) (xy 2.67208 -49.956212) (xy 2.644829 -49.955718)
			(xy 2.590882 -49.947962) (xy 2.538588 -49.932607) (xy 2.489011 -49.909966) (xy 2.443161 -49.8805)
			(xy 2.401971 -49.844809) (xy 2.36628 -49.803619) (xy 2.336814 -49.757769) (xy 2.314173 -49.708192)
			(xy 2.298818 -49.655898) (xy 2.291062 -49.601951) (xy 1.27 -49.601951) (xy 1.27 -51.689071) (xy 2.2555 -51.689071)
			(xy 2.2555 -51.634569) (xy 2.263256 -51.580621) (xy 2.278611 -51.528327) (xy 2.301252 -51.47875)
			(xy 2.330718 -51.4329) (xy 2.36641 -51.39171) (xy 2.4076 -51.356018) (xy 2.45345 -51.326552) (xy 2.503027 -51.303911)
			(xy 2.555321 -51.288556) (xy 2.609269 -51.2808) (xy 2.63652 -51.280314) (xy 2.663891 -51.280765)
			(xy 2.718071 -51.288586) (xy 2.770574 -51.304078) (xy 2.820321 -51.326923) (xy 2.866287 -51.356651)
			(xy 2.887218 -51.374294) (xy 2.89433 -51.38039) (xy 2.911348 -51.38674) (xy 2.996692 -51.38674) (xy 3.01371 -51.38039)
			(xy 3.020822 -51.374294) (xy 3.041772 -51.356677) (xy 3.08774 -51.326962) (xy 3.137483 -51.304122)
			(xy 3.18998 -51.288626) (xy 3.244152 -51.280791) (xy 3.27152 -51.280314) (xy 3.289863 -51.280554)
			(xy 3.326376 -51.284112) (xy 3.344418 -51.287426) (xy 3.35534 -51.289458) (xy 3.375914 -51.284632)
			(xy 3.453892 -51.225704) (xy 3.464306 -51.206908) (xy 3.465068 -51.195986) (xy 3.467952 -51.167701)
			(xy 3.480991 -51.112363) (xy 3.502089 -51.059569) (xy 3.53078 -51.010486) (xy 3.566431 -50.966199)
			(xy 3.586988 -50.946558) (xy 3.594408 -50.939052) (xy 3.602922 -50.91976) (xy 3.603498 -50.90922)
			(xy 3.603498 -50.834544) (xy 3.602959 -50.823995) (xy 3.594431 -50.8047) (xy 3.586988 -50.797206)
			(xy 3.567909 -50.779071) (xy 3.534432 -50.73845) (xy 3.506861 -50.69361) (xy 3.485723 -50.645402)
			(xy 3.471418 -50.594745) (xy 3.464219 -50.542601) (xy 3.463798 -50.516282) (xy 3.464284 -50.489031)
			(xy 3.47204 -50.435083) (xy 3.487395 -50.382788) (xy 3.510037 -50.333211) (xy 3.539503 -50.287361)
			(xy 3.575194 -50.24617) (xy 3.616385 -50.210479) (xy 3.662235 -50.181013) (xy 3.711812 -50.158371)
			(xy 3.764107 -50.143016) (xy 3.818055 -50.13526) (xy 3.872557 -50.13526) (xy 3.926505 -50.143016)
			(xy 3.9788 -50.158371) (xy 4.028377 -50.181013) (xy 4.074227 -50.210479) (xy 4.115418 -50.24617)
			(xy 4.151109 -50.287361) (xy 4.180575 -50.333211) (xy 4.203217 -50.382788) (xy 4.218572 -50.435083)
			(xy 4.226328 -50.489031) (xy 4.226814 -50.516282) (xy 4.226391 -50.542599) (xy 4.219164 -50.594734)
			(xy 4.204845 -50.645383) (xy 4.183705 -50.693584) (xy 4.156144 -50.738426) (xy 4.122686 -50.779057)
			(xy 4.103624 -50.797206) (xy 4.096221 -50.804727) (xy 4.087697 -50.824007) (xy 4.087114 -50.834544)
			(xy 4.087114 -50.90922) (xy 4.087669 -50.919767) (xy 4.096185 -50.939063) (xy 4.103624 -50.946558)
			(xy 4.1227 -50.964696) (xy 4.15618 -51.005315) (xy 4.183752 -51.050154) (xy 4.204891 -51.098361)
			(xy 4.219196 -51.149019) (xy 4.226394 -51.201162) (xy 4.226814 -51.227482) (xy 4.226328 -51.254734)
			(xy 4.218574 -51.308684) (xy 4.20322 -51.360981) (xy 4.18058 -51.410561) (xy 4.151115 -51.456414)
			(xy 4.115423 -51.497606) (xy 4.074233 -51.5333) (xy 4.028382 -51.562769) (xy 3.978804 -51.585412)
			(xy 3.926507 -51.600768) (xy 3.872558 -51.608526) (xy 3.845306 -51.60899) (xy 3.826963 -51.60876)
			(xy 3.79045 -51.605195) (xy 3.772408 -51.601878) (xy 3.761486 -51.599846) (xy 3.740912 -51.604672)
			(xy 3.662934 -51.6636) (xy 3.65252 -51.682396) (xy 3.651758 -51.693318) (xy 3.64886 -51.721576) (xy 3.635828 -51.776861)
			(xy 3.614743 -51.829603) (xy 3.586072 -51.878637) (xy 3.550448 -51.922878) (xy 3.508659 -51.961348)
			(xy 3.461629 -51.993198) (xy 3.410396 -52.017724) (xy 3.356093 -52.034383) (xy 3.29992 -52.042806)
			(xy 3.27152 -52.04333) (xy 3.244149 -52.042869) (xy 3.189969 -52.035053) (xy 3.137466 -52.019563)
			(xy 3.087719 -51.99672) (xy 3.041753 -51.966993) (xy 3.020822 -51.94935) (xy 3.01371 -51.943254)
			(xy 2.996692 -51.936904) (xy 2.911348 -51.936904) (xy 2.89433 -51.943254) (xy 2.887218 -51.94935)
			(xy 2.866284 -51.966986) (xy 2.820312 -51.9967) (xy 2.770565 -52.019538) (xy 2.718065 -52.035029)
			(xy 2.663889 -52.042857) (xy 2.63652 -52.04333) (xy 2.609269 -52.04284) (xy 2.555321 -52.035084)
			(xy 2.503027 -52.019729) (xy 2.45345 -51.997088) (xy 2.4076 -51.967622) (xy 2.36641 -51.93193) (xy 2.330718 -51.89074)
			(xy 2.301252 -51.84489) (xy 2.278611 -51.795313) (xy 2.263256 -51.743019) (xy 2.2555 -51.689071)
			(xy 1.27 -51.689071) (xy 1.27 -52.564103) (xy 3.827227 -52.564103) (xy 3.827227 -52.509597) (xy 3.834984 -52.455646)
			(xy 3.85034 -52.403349) (xy 3.872983 -52.353769) (xy 3.902451 -52.307916) (xy 3.938145 -52.266723)
			(xy 3.979337 -52.23103) (xy 4.02519 -52.201562) (xy 4.074771 -52.17892) (xy 4.127068 -52.163564)
			(xy 4.181019 -52.155807) (xy 4.208272 -52.155344) (xy 4.235642 -52.155816) (xy 4.289821 -52.163631)
			(xy 4.342325 -52.179118) (xy 4.392072 -52.201958) (xy 4.438039 -52.231683) (xy 4.45897 -52.249324)
			(xy 4.466082 -52.25542) (xy 4.4831 -52.26177) (xy 4.568444 -52.26177) (xy 4.585462 -52.25542) (xy 4.592574 -52.249324)
			(xy 4.613508 -52.231687) (xy 4.65948 -52.201974) (xy 4.709227 -52.179138) (xy 4.761727 -52.163646)
			(xy 4.815903 -52.155818) (xy 4.843272 -52.155344) (xy 4.870523 -52.155826) (xy 4.924471 -52.163583)
			(xy 4.976766 -52.178938) (xy 5.026343 -52.201579) (xy 5.072194 -52.231046) (xy 5.113384 -52.266738)
			(xy 5.149075 -52.307928) (xy 5.178541 -52.353779) (xy 5.201183 -52.403356) (xy 5.216538 -52.455651)
			(xy 5.224294 -52.509599) (xy 5.224294 -52.564101) (xy 5.216538 -52.618049) (xy 5.201183 -52.670344)
			(xy 5.178541 -52.719921) (xy 5.149075 -52.765772) (xy 5.113384 -52.806962) (xy 5.072194 -52.842654)
			(xy 5.026343 -52.872121) (xy 4.976766 -52.894762) (xy 4.924471 -52.910117) (xy 4.870523 -52.917874)
			(xy 4.843272 -52.91836) (xy 4.815901 -52.91792) (xy 4.76172 -52.910097) (xy 4.709216 -52.894603)
			(xy 4.65947 -52.871755) (xy 4.613505 -52.842024) (xy 4.592574 -52.82438) (xy 4.585462 -52.818284)
			(xy 4.568444 -52.811934) (xy 4.4831 -52.811934) (xy 4.466082 -52.818284) (xy 4.45897 -52.82438) (xy 4.43802 -52.841997)
			(xy 4.392052 -52.871713) (xy 4.342309 -52.894553) (xy 4.289813 -52.910049) (xy 4.23564 -52.917883)
			(xy 4.208272 -52.91836) (xy 4.181019 -52.917893) (xy 4.127068 -52.910136) (xy 4.074771 -52.89478)
			(xy 4.02519 -52.872138) (xy 3.979337 -52.84267) (xy 3.938145 -52.806977) (xy 3.902451 -52.765784)
			(xy 3.872983 -52.719931) (xy 3.85034 -52.670351) (xy 3.834984 -52.618054) (xy 3.827227 -52.564103)
			(xy 1.27 -52.564103) (xy 1.27 -54.238906) (xy 8.386062 -54.238906) (xy 8.390133 -54.183284) (xy 8.402259 -54.128847)
			(xy 8.422182 -54.076756) (xy 8.449478 -54.028121) (xy 8.483564 -53.983978) (xy 8.523713 -53.945269)
			(xy 8.569071 -53.912818) (xy 8.618671 -53.887317) (xy 8.671455 -53.86931) (xy 8.726298 -53.85918)
			(xy 8.782032 -53.857143) (xy 8.837469 -53.863243) (xy 8.891426 -53.877349) (xy 8.942755 -53.899161)
			(xy 8.990361 -53.928215) (xy 9.033229 -53.96389) (xy 9.070446 -54.005427) (xy 9.101219 -54.05194)
			(xy 9.124891 -54.102437) (xy 9.140959 -54.155844) (xy 9.149079 -54.21102) (xy 9.149588 -54.238906)
			(xy 9.149079 -54.266792) (xy 9.140959 -54.321968) (xy 9.124891 -54.375375) (xy 9.101219 -54.425872)
			(xy 9.070446 -54.472385) (xy 9.033229 -54.513922) (xy 8.990361 -54.549597) (xy 8.942755 -54.578651)
			(xy 8.891426 -54.600463) (xy 8.837469 -54.614569) (xy 8.782032 -54.620669) (xy 8.726298 -54.618632)
			(xy 8.671455 -54.608502) (xy 8.618671 -54.590495) (xy 8.569071 -54.564994) (xy 8.523713 -54.532543)
			(xy 8.483564 -54.493834) (xy 8.449478 -54.449691) (xy 8.422182 -54.401056) (xy 8.402259 -54.348965)
			(xy 8.390133 -54.294528) (xy 8.386062 -54.238906) (xy 1.27 -54.238906) (xy 1.27 -54.989041) (xy 3.901168 -54.989041)
			(xy 3.901168 -54.934539) (xy 3.908924 -54.880592) (xy 3.924279 -54.828297) (xy 3.94692 -54.77872)
			(xy 3.976386 -54.73287) (xy 4.012077 -54.69168) (xy 4.053267 -54.655988) (xy 4.099117 -54.626522)
			(xy 4.148693 -54.603881) (xy 4.200988 -54.588525) (xy 4.254935 -54.580768) (xy 4.282186 -54.580282)
			(xy 4.310277 -54.580788) (xy 4.365854 -54.589013) (xy 4.419622 -54.605302) (xy 4.47042 -54.629303)
			(xy 4.517147 -54.660496) (xy 4.558792 -54.698207) (xy 4.594455 -54.741618) (xy 4.609338 -54.765448)
			(xy 4.614672 -54.774592) (xy 4.63169 -54.786784) (xy 4.724908 -54.80685) (xy 4.745482 -54.802786)
			(xy 4.754118 -54.79669) (xy 4.778175 -54.780679) (xy 4.830109 -54.755339) (xy 4.885269 -54.738117)
			(xy 4.942395 -54.729405) (xy 4.971288 -54.728872) (xy 4.998541 -54.729337) (xy 5.052492 -54.737094)
			(xy 5.104789 -54.75245) (xy 5.15437 -54.775092) (xy 5.200223 -54.80456) (xy 5.241415 -54.840253)
			(xy 5.277109 -54.881446) (xy 5.306577 -54.927299) (xy 5.32922 -54.976879) (xy 5.344576 -55.029176)
			(xy 5.352333 -55.083127) (xy 5.352796 -55.11038) (xy 5.352319 -55.13775) (xy 5.344504 -55.191929)
			(xy 5.329018 -55.244432) (xy 5.306178 -55.294179) (xy 5.276456 -55.340146) (xy 5.258816 -55.361078)
			(xy 5.25272 -55.36819) (xy 5.24637 -55.385208) (xy 5.24637 -55.470552) (xy 5.25272 -55.48757) (xy 5.258816 -55.494682)
			(xy 5.276457 -55.515615) (xy 5.306181 -55.561583) (xy 5.329026 -55.611329) (xy 5.344522 -55.663831)
			(xy 5.352351 -55.718009) (xy 5.352351 -55.772751) (xy 5.344522 -55.826929) (xy 5.329026 -55.879431)
			(xy 5.306181 -55.929177) (xy 5.276457 -55.975145) (xy 5.258816 -55.996078) (xy 5.25272 -56.00319)
			(xy 5.24637 -56.020208) (xy 5.24637 -56.105552) (xy 5.25272 -56.12257) (xy 5.258816 -56.129682) (xy 5.276463 -56.150608)
			(xy 5.306173 -56.196583) (xy 5.329007 -56.246332) (xy 5.344496 -56.298834) (xy 5.352323 -56.35301)
			(xy 5.352796 -56.38038) (xy 5.35231 -56.407631) (xy 5.344554 -56.461579) (xy 5.329199 -56.513874)
			(xy 5.306557 -56.563451) (xy 5.277091 -56.609301) (xy 5.2414 -56.650492) (xy 5.200209 -56.686183)
			(xy 5.154359 -56.715649) (xy 5.104782 -56.738291) (xy 5.052487 -56.753646) (xy 4.998539 -56.761402)
			(xy 4.944037 -56.761402) (xy 4.890089 -56.753646) (xy 4.837794 -56.738291) (xy 4.788217 -56.715649)
			(xy 4.742367 -56.686183) (xy 4.701176 -56.650492) (xy 4.665485 -56.609301) (xy 4.636019 -56.563451)
			(xy 4.613377 -56.513874) (xy 4.598022 -56.461579) (xy 4.590266 -56.407631) (xy 4.58978 -56.38038)
			(xy 4.590215 -56.353008) (xy 4.598037 -56.298827) (xy 4.613533 -56.246323) (xy 4.636382 -56.196577)
			(xy 4.666114 -56.150612) (xy 4.68376 -56.129682) (xy 4.689856 -56.12257) (xy 4.696206 -56.105552)
			(xy 4.696206 -56.020208) (xy 4.689856 -56.00319) (xy 4.68376 -55.996078) (xy 4.666119 -55.975145)
			(xy 4.636394 -55.929178) (xy 4.613549 -55.879431) (xy 4.598052 -55.826929) (xy 4.590224 -55.772751)
			(xy 4.590224 -55.718009) (xy 4.598052 -55.663831) (xy 4.613549 -55.611329) (xy 4.636394 -55.561582)
			(xy 4.666119 -55.515615) (xy 4.68376 -55.494682) (xy 4.689856 -55.48757) (xy 4.696206 -55.470552)
			(xy 4.696206 -55.385208) (xy 4.689856 -55.36819) (xy 4.68376 -55.361078) (xy 4.672806 -55.348285)
			(xy 4.652967 -55.321064) (xy 4.644136 -55.306722) (xy 4.638802 -55.297578) (xy 4.621784 -55.285386)
			(xy 4.528566 -55.26532) (xy 4.507992 -55.269384) (xy 4.499356 -55.27548) (xy 4.475304 -55.291499)
			(xy 4.423368 -55.316838) (xy 4.368207 -55.334058) (xy 4.31108 -55.342767) (xy 4.282186 -55.343298)
			(xy 4.254935 -55.342812) (xy 4.200988 -55.335055) (xy 4.148693 -55.319699) (xy 4.099117 -55.297058)
			(xy 4.053267 -55.267592) (xy 4.012077 -55.2319) (xy 3.976386 -55.19071) (xy 3.94692 -55.14486) (xy 3.924279 -55.095283)
			(xy 3.908924 -55.042988) (xy 3.901168 -54.989041) (xy 1.27 -54.989041) (xy 1.27 -55.420841) (xy 2.224768 -55.420841)
			(xy 2.224768 -55.366339) (xy 2.232524 -55.312392) (xy 2.247879 -55.260097) (xy 2.27052 -55.21052)
			(xy 2.299986 -55.16467) (xy 2.335677 -55.12348) (xy 2.376867 -55.087788) (xy 2.422717 -55.058322)
			(xy 2.472293 -55.035681) (xy 2.524588 -55.020325) (xy 2.578535 -55.012568) (xy 2.605786 -55.012082)
			(xy 2.632103 -55.012504) (xy 2.684238 -55.019731) (xy 2.734887 -55.034051) (xy 2.783088 -55.055191)
			(xy 2.82793 -55.082752) (xy 2.86856 -55.11621) (xy 2.88671 -55.135272) (xy 2.89423 -55.142676) (xy 2.913511 -55.1512)
			(xy 2.924048 -55.151782) (xy 2.998724 -55.151782) (xy 3.009271 -55.151231) (xy 3.028567 -55.142712)
			(xy 3.036062 -55.135272) (xy 3.054229 -55.116225) (xy 3.094841 -55.082741) (xy 3.139674 -55.055165)
			(xy 3.187876 -55.03402) (xy 3.238528 -55.019709) (xy 3.290668 -55.012505) (xy 3.316986 -55.012082)
			(xy 3.344239 -55.012545) (xy 3.39819 -55.020302) (xy 3.450489 -55.035657) (xy 3.500069 -55.0583)
			(xy 3.545923 -55.087767) (xy 3.587116 -55.123461) (xy 3.62281 -55.164654) (xy 3.652279 -55.210507)
			(xy 3.674921 -55.260088) (xy 3.690278 -55.312386) (xy 3.698035 -55.366337) (xy 3.698035 -55.420843)
			(xy 3.690278 -55.474794) (xy 3.674921 -55.527092) (xy 3.652279 -55.576673) (xy 3.62281 -55.622526)
			(xy 3.587116 -55.663719) (xy 3.545923 -55.699413) (xy 3.500069 -55.72888) (xy 3.450489 -55.751523)
			(xy 3.39819 -55.766878) (xy 3.344239 -55.774635) (xy 3.316986 -55.775098) (xy 3.29067 -55.774635)
			(xy 3.238537 -55.767417) (xy 3.187889 -55.753106) (xy 3.139687 -55.731973) (xy 3.094844 -55.70442)
			(xy 3.054212 -55.670968) (xy 3.036062 -55.651908) (xy 3.028555 -55.644489) (xy 3.009264 -55.635974)
			(xy 2.998724 -55.635398) (xy 2.924048 -55.635398) (xy 2.9135 -55.63594) (xy 2.894204 -55.644466)
			(xy 2.88671 -55.651908) (xy 2.868572 -55.670984) (xy 2.827952 -55.704462) (xy 2.783112 -55.732033)
			(xy 2.734905 -55.753172) (xy 2.684249 -55.767477) (xy 2.632105 -55.774677) (xy 2.605786 -55.775098)
			(xy 2.578535 -55.774612) (xy 2.524588 -55.766855) (xy 2.472293 -55.751499) (xy 2.422717 -55.728858)
			(xy 2.376867 -55.699392) (xy 2.335677 -55.6637) (xy 2.299986 -55.62251) (xy 2.27052 -55.57666) (xy 2.247879 -55.527083)
			(xy 2.232524 -55.474788) (xy 2.224768 -55.420841) (xy 1.27 -55.420841) (xy 1.27 -57.48528) (xy 4.606034 -57.48528)
			(xy 4.610105 -57.429658) (xy 4.622231 -57.375221) (xy 4.642154 -57.32313) (xy 4.66945 -57.274495)
			(xy 4.703536 -57.230352) (xy 4.743685 -57.191643) (xy 4.789043 -57.159192) (xy 4.838643 -57.133691)
			(xy 4.891427 -57.115684) (xy 4.94627 -57.105554) (xy 5.002004 -57.103517) (xy 5.057441 -57.109617)
			(xy 5.111398 -57.123723) (xy 5.162727 -57.145535) (xy 5.210333 -57.174589) (xy 5.253201 -57.210264)
			(xy 5.290418 -57.251801) (xy 5.321191 -57.298314) (xy 5.344863 -57.348811) (xy 5.360931 -57.402218)
			(xy 5.369051 -57.457394) (xy 5.36956 -57.48528) (xy 5.369051 -57.513166) (xy 5.360931 -57.568342)
			(xy 5.344863 -57.621749) (xy 5.321191 -57.672246) (xy 5.290418 -57.718759) (xy 5.253201 -57.760296)
			(xy 5.210333 -57.795971) (xy 5.162727 -57.825025) (xy 5.111398 -57.846837) (xy 5.057441 -57.860943)
			(xy 5.002004 -57.867043) (xy 4.94627 -57.865006) (xy 4.891427 -57.854876) (xy 4.838643 -57.836869)
			(xy 4.789043 -57.811368) (xy 4.743685 -57.778917) (xy 4.703536 -57.740208) (xy 4.66945 -57.696065)
			(xy 4.642154 -57.64743) (xy 4.622231 -57.595339) (xy 4.610105 -57.540902) (xy 4.606034 -57.48528)
			(xy 1.27 -57.48528) (xy 1.27 -58.076084) (xy 5.358128 -58.076084) (xy 5.362199 -58.020462) (xy 5.374325 -57.966025)
			(xy 5.394248 -57.913934) (xy 5.421544 -57.865299) (xy 5.45563 -57.821156) (xy 5.495779 -57.782447)
			(xy 5.541137 -57.749996) (xy 5.590737 -57.724495) (xy 5.643521 -57.706488) (xy 5.698364 -57.696358)
			(xy 5.754098 -57.694321) (xy 5.809535 -57.700421) (xy 5.863492 -57.714527) (xy 5.914821 -57.736339)
			(xy 5.962427 -57.765393) (xy 6.005295 -57.801068) (xy 6.042512 -57.842605) (xy 6.058848 -57.867296)
			(xy 7.643112 -57.867296) (xy 7.647183 -57.811674) (xy 7.659309 -57.757237) (xy 7.679232 -57.705146)
			(xy 7.706528 -57.656511) (xy 7.740614 -57.612368) (xy 7.780763 -57.573659) (xy 7.826121 -57.541208)
			(xy 7.875721 -57.515707) (xy 7.928505 -57.4977) (xy 7.983348 -57.48757) (xy 8.039082 -57.485533)
			(xy 8.094519 -57.491633) (xy 8.148476 -57.505739) (xy 8.199805 -57.527551) (xy 8.247411 -57.556605)
			(xy 8.290279 -57.59228) (xy 8.327496 -57.633817) (xy 8.358269 -57.68033) (xy 8.381941 -57.730827)
			(xy 8.398009 -57.784234) (xy 8.406129 -57.83941) (xy 8.406638 -57.867296) (xy 8.406129 -57.895182)
			(xy 8.398009 -57.950358) (xy 8.381941 -58.003765) (xy 8.358269 -58.054262) (xy 8.327496 -58.100775)
			(xy 8.290279 -58.142312) (xy 8.247411 -58.177987) (xy 8.199805 -58.207041) (xy 8.148476 -58.228853)
			(xy 8.094519 -58.242959) (xy 8.039082 -58.249059) (xy 7.983348 -58.247022) (xy 7.928505 -58.236892)
			(xy 7.875721 -58.218885) (xy 7.826121 -58.193384) (xy 7.780763 -58.160933) (xy 7.740614 -58.122224)
			(xy 7.706528 -58.078081) (xy 7.679232 -58.029446) (xy 7.659309 -57.977355) (xy 7.647183 -57.922918)
			(xy 7.643112 -57.867296) (xy 6.058848 -57.867296) (xy 6.073285 -57.889118) (xy 6.096957 -57.939615)
			(xy 6.113025 -57.993022) (xy 6.121145 -58.048198) (xy 6.121654 -58.076084) (xy 6.121145 -58.10397)
			(xy 6.113025 -58.159146) (xy 6.096957 -58.212553) (xy 6.073285 -58.26305) (xy 6.042512 -58.309563)
			(xy 6.005295 -58.3511) (xy 5.962427 -58.386775) (xy 5.914821 -58.415829) (xy 5.863492 -58.437641)
			(xy 5.809535 -58.451747) (xy 5.754098 -58.457847) (xy 5.698364 -58.45581) (xy 5.643521 -58.44568)
			(xy 5.590737 -58.427673) (xy 5.541137 -58.402172) (xy 5.495779 -58.369721) (xy 5.45563 -58.331012)
			(xy 5.421544 -58.286869) (xy 5.394248 -58.238234) (xy 5.374325 -58.186143) (xy 5.362199 -58.131706)
			(xy 5.358128 -58.076084) (xy 1.27 -58.076084) (xy 1.27 -58.561224) (xy 6.562342 -58.561224) (xy 6.566413 -58.505602)
			(xy 6.578539 -58.451165) (xy 6.598462 -58.399074) (xy 6.625758 -58.350439) (xy 6.659844 -58.306296)
			(xy 6.699993 -58.267587) (xy 6.745351 -58.235136) (xy 6.794951 -58.209635) (xy 6.847735 -58.191628)
			(xy 6.902578 -58.181498) (xy 6.958312 -58.179461) (xy 7.013749 -58.185561) (xy 7.067706 -58.199667)
			(xy 7.119035 -58.221479) (xy 7.166641 -58.250533) (xy 7.209509 -58.286208) (xy 7.246726 -58.327745)
			(xy 7.277499 -58.374258) (xy 7.301171 -58.424755) (xy 7.308681 -58.449718) (xy 8.808972 -58.449718)
			(xy 8.813043 -58.394096) (xy 8.825169 -58.339659) (xy 8.845092 -58.287568) (xy 8.872388 -58.238933)
			(xy 8.906474 -58.19479) (xy 8.946623 -58.156081) (xy 8.991981 -58.12363) (xy 9.041581 -58.098129)
			(xy 9.094365 -58.080122) (xy 9.149208 -58.069992) (xy 9.204942 -58.067955) (xy 9.260379 -58.074055)
			(xy 9.314336 -58.088161) (xy 9.365665 -58.109973) (xy 9.413271 -58.139027) (xy 9.456139 -58.174702)
			(xy 9.493356 -58.216239) (xy 9.524129 -58.262752) (xy 9.547801 -58.313249) (xy 9.563869 -58.366656)
			(xy 9.571989 -58.421832) (xy 9.572498 -58.449718) (xy 9.571989 -58.477604) (xy 9.563869 -58.53278)
			(xy 9.547801 -58.586187) (xy 9.524129 -58.636684) (xy 9.493356 -58.683197) (xy 9.456139 -58.724734)
			(xy 9.413271 -58.760409) (xy 9.365665 -58.789463) (xy 9.314336 -58.811275) (xy 9.260379 -58.825381)
			(xy 9.204942 -58.831481) (xy 9.149208 -58.829444) (xy 9.094365 -58.819314) (xy 9.041581 -58.801307)
			(xy 8.991981 -58.775806) (xy 8.946623 -58.743355) (xy 8.906474 -58.704646) (xy 8.872388 -58.660503)
			(xy 8.845092 -58.611868) (xy 8.825169 -58.559777) (xy 8.813043 -58.50534) (xy 8.808972 -58.449718)
			(xy 7.308681 -58.449718) (xy 7.317239 -58.478162) (xy 7.325359 -58.533338) (xy 7.325868 -58.561224)
			(xy 7.325359 -58.58911) (xy 7.317239 -58.644286) (xy 7.301171 -58.697693) (xy 7.277499 -58.74819)
			(xy 7.246726 -58.794703) (xy 7.209509 -58.83624) (xy 7.166641 -58.871915) (xy 7.119035 -58.900969)
			(xy 7.067706 -58.922781) (xy 7.013749 -58.936887) (xy 6.958312 -58.942987) (xy 6.902578 -58.94095)
			(xy 6.847735 -58.93082) (xy 6.794951 -58.912813) (xy 6.745351 -58.887312) (xy 6.699993 -58.854861)
			(xy 6.659844 -58.816152) (xy 6.625758 -58.772009) (xy 6.598462 -58.723374) (xy 6.578539 -58.671283)
			(xy 6.566413 -58.616846) (xy 6.562342 -58.561224) (xy 1.27 -58.561224) (xy 1.27 -59.974734) (xy 5.087112 -59.974734)
			(xy 5.087538 -59.947907) (xy 5.095059 -59.894782) (xy 5.109943 -59.843233) (xy 5.131897 -59.794276)
			(xy 5.160489 -59.748874) (xy 5.195155 -59.707922) (xy 5.235214 -59.672227) (xy 5.257292 -59.65698)
			(xy 5.268861 -59.648764) (xy 5.28727 -59.627185) (xy 5.299027 -59.601372) (xy 5.303223 -59.573319)
			(xy 5.299533 -59.545196) (xy 5.288243 -59.519175) (xy 5.270226 -59.497268) (xy 5.258816 -59.488832)
			(xy 5.237368 -59.473467) (xy 5.198453 -59.437844) (xy 5.164819 -59.397197) (xy 5.137107 -59.352304)
			(xy 5.115845 -59.30402) (xy 5.101439 -59.253267) (xy 5.094164 -59.201013) (xy 5.093716 -59.174634)
			(xy 5.094202 -59.147383) (xy 5.101958 -59.093435) (xy 5.117313 -59.04114) (xy 5.139955 -58.991563)
			(xy 5.169421 -58.945713) (xy 5.205112 -58.904522) (xy 5.246303 -58.868831) (xy 5.292153 -58.839365)
			(xy 5.34173 -58.816723) (xy 5.394025 -58.801368) (xy 5.447973 -58.793612) (xy 5.502475 -58.793612)
			(xy 5.556423 -58.801368) (xy 5.608718 -58.816723) (xy 5.658295 -58.839365) (xy 5.704145 -58.868831)
			(xy 5.745336 -58.904522) (xy 5.781027 -58.945713) (xy 5.810493 -58.991563) (xy 5.833135 -59.04114)
			(xy 5.84849 -59.093435) (xy 5.856246 -59.147383) (xy 5.856732 -59.174634) (xy 5.856262 -59.20146)
			(xy 5.848747 -59.254582) (xy 5.833869 -59.306129) (xy 5.811921 -59.355085) (xy 5.783337 -59.400487)
			(xy 5.748678 -59.441441) (xy 5.708627 -59.477139) (xy 5.686552 -59.492388) (xy 5.675019 -59.500647)
			(xy 5.656621 -59.52222) (xy 5.644869 -59.548022) (xy 5.640672 -59.576063) (xy 5.644353 -59.604176)
			(xy 5.655629 -59.63019) (xy 5.673627 -59.652097) (xy 5.685028 -59.660536) (xy 5.706501 -59.675867)
			(xy 5.745413 -59.711498) (xy 5.779043 -59.752151) (xy 5.806752 -59.79705) (xy 5.82801 -59.845339)
			(xy 5.842411 -59.896096) (xy 5.849682 -59.948354) (xy 5.850128 -59.974734) (xy 5.849642 -60.001985)
			(xy 5.841886 -60.055933) (xy 5.826531 -60.108228) (xy 5.803889 -60.157805) (xy 5.774423 -60.203655)
			(xy 5.738732 -60.244846) (xy 5.697541 -60.280537) (xy 5.651691 -60.310003) (xy 5.602114 -60.332645)
			(xy 5.549819 -60.348) (xy 5.495871 -60.355756) (xy 5.441369 -60.355756) (xy 5.387421 -60.348) (xy 5.335126 -60.332645)
			(xy 5.285549 -60.310003) (xy 5.239699 -60.280537) (xy 5.198508 -60.244846) (xy 5.162817 -60.203655)
			(xy 5.133351 -60.157805) (xy 5.110709 -60.108228) (xy 5.095354 -60.055933) (xy 5.087598 -60.001985)
			(xy 5.087112 -59.974734) (xy 1.27 -59.974734) (xy 1.27 -60.601606) (xy 4.333238 -60.601606) (xy 4.337309 -60.545984)
			(xy 4.349435 -60.491547) (xy 4.369358 -60.439456) (xy 4.396654 -60.390821) (xy 4.43074 -60.346678)
			(xy 4.470889 -60.307969) (xy 4.516247 -60.275518) (xy 4.565847 -60.250017) (xy 4.618631 -60.23201)
			(xy 4.673474 -60.22188) (xy 4.729208 -60.219843) (xy 4.784645 -60.225943) (xy 4.838602 -60.240049)
			(xy 4.889931 -60.261861) (xy 4.937537 -60.290915) (xy 4.980405 -60.32659) (xy 5.017622 -60.368127)
			(xy 5.048395 -60.41464) (xy 5.072067 -60.465137) (xy 5.088135 -60.518544) (xy 5.096255 -60.57372)
			(xy 5.096764 -60.601606) (xy 5.096255 -60.629492) (xy 5.088135 -60.684668) (xy 5.072067 -60.738075)
			(xy 5.051501 -60.781946) (xy 5.674358 -60.781946) (xy 5.678429 -60.726324) (xy 5.690555 -60.671887)
			(xy 5.710478 -60.619796) (xy 5.737774 -60.571161) (xy 5.77186 -60.527018) (xy 5.812009 -60.488309)
			(xy 5.857367 -60.455858) (xy 5.906967 -60.430357) (xy 5.959751 -60.41235) (xy 6.014594 -60.40222)
			(xy 6.070328 -60.400183) (xy 6.125765 -60.406283) (xy 6.179722 -60.420389) (xy 6.231051 -60.442201)
			(xy 6.278657 -60.471255) (xy 6.321525 -60.50693) (xy 6.358742 -60.548467) (xy 6.389515 -60.59498)
			(xy 6.404528 -60.627006) (xy 6.721346 -60.627006) (xy 6.725417 -60.571384) (xy 6.737543 -60.516947)
			(xy 6.757466 -60.464856) (xy 6.784762 -60.416221) (xy 6.818848 -60.372078) (xy 6.858997 -60.333369)
			(xy 6.904355 -60.300918) (xy 6.953955 -60.275417) (xy 7.006739 -60.25741) (xy 7.061582 -60.24728)
			(xy 7.117316 -60.245243) (xy 7.172753 -60.251343) (xy 7.22671 -60.265449) (xy 7.278039 -60.287261)
			(xy 7.325645 -60.316315) (xy 7.368513 -60.35199) (xy 7.40573 -60.393527) (xy 7.436503 -60.44004)
			(xy 7.460175 -60.490537) (xy 7.476243 -60.543944) (xy 7.484363 -60.59912) (xy 7.484872 -60.627006)
			(xy 7.484756 -60.633356) (xy 8.813036 -60.633356) (xy 8.817107 -60.577734) (xy 8.829233 -60.523297)
			(xy 8.849156 -60.471206) (xy 8.876452 -60.422571) (xy 8.910538 -60.378428) (xy 8.950687 -60.339719)
			(xy 8.996045 -60.307268) (xy 9.045645 -60.281767) (xy 9.098429 -60.26376) (xy 9.153272 -60.25363)
			(xy 9.209006 -60.251593) (xy 9.264443 -60.257693) (xy 9.3184 -60.271799) (xy 9.369729 -60.293611)
			(xy 9.417335 -60.322665) (xy 9.460203 -60.35834) (xy 9.49742 -60.399877) (xy 9.528193 -60.44639)
			(xy 9.551865 -60.496887) (xy 9.567933 -60.550294) (xy 9.576053 -60.60547) (xy 9.576562 -60.633356)
			(xy 9.576053 -60.661242) (xy 9.567933 -60.716418) (xy 9.551865 -60.769825) (xy 9.528193 -60.820322)
			(xy 9.49742 -60.866835) (xy 9.460203 -60.908372) (xy 9.417335 -60.944047) (xy 9.369729 -60.973101)
			(xy 9.3184 -60.994913) (xy 9.264443 -61.009019) (xy 9.209006 -61.015119) (xy 9.153272 -61.013082)
			(xy 9.098429 -61.002952) (xy 9.045645 -60.984945) (xy 8.996045 -60.959444) (xy 8.950687 -60.926993)
			(xy 8.910538 -60.888284) (xy 8.876452 -60.844141) (xy 8.849156 -60.795506) (xy 8.829233 -60.743415)
			(xy 8.817107 -60.688978) (xy 8.813036 -60.633356) (xy 7.484756 -60.633356) (xy 7.484363 -60.654892)
			(xy 7.476243 -60.710068) (xy 7.460175 -60.763475) (xy 7.436503 -60.813972) (xy 7.40573 -60.860485)
			(xy 7.368513 -60.902022) (xy 7.325645 -60.937697) (xy 7.278039 -60.966751) (xy 7.22671 -60.988563)
			(xy 7.172753 -61.002669) (xy 7.117316 -61.008769) (xy 7.061582 -61.006732) (xy 7.006739 -60.996602)
			(xy 6.953955 -60.978595) (xy 6.904355 -60.953094) (xy 6.858997 -60.920643) (xy 6.818848 -60.881934)
			(xy 6.784762 -60.837791) (xy 6.757466 -60.789156) (xy 6.737543 -60.737065) (xy 6.725417 -60.682628)
			(xy 6.721346 -60.627006) (xy 6.404528 -60.627006) (xy 6.413187 -60.645477) (xy 6.429255 -60.698884)
			(xy 6.437375 -60.75406) (xy 6.437884 -60.781946) (xy 6.437375 -60.809832) (xy 6.429255 -60.865008)
			(xy 6.413187 -60.918415) (xy 6.389515 -60.968912) (xy 6.358742 -61.015425) (xy 6.321525 -61.056962)
			(xy 6.278657 -61.092637) (xy 6.231051 -61.121691) (xy 6.179722 -61.143503) (xy 6.125765 -61.157609)
			(xy 6.070328 -61.163709) (xy 6.014594 -61.161672) (xy 5.959751 -61.151542) (xy 5.906967 -61.133535)
			(xy 5.857367 -61.108034) (xy 5.812009 -61.075583) (xy 5.77186 -61.036874) (xy 5.737774 -60.992731)
			(xy 5.710478 -60.944096) (xy 5.690555 -60.892005) (xy 5.678429 -60.837568) (xy 5.674358 -60.781946)
			(xy 5.051501 -60.781946) (xy 5.048395 -60.788572) (xy 5.017622 -60.835085) (xy 4.980405 -60.876622)
			(xy 4.937537 -60.912297) (xy 4.889931 -60.941351) (xy 4.838602 -60.963163) (xy 4.784645 -60.977269)
			(xy 4.729208 -60.983369) (xy 4.673474 -60.981332) (xy 4.618631 -60.971202) (xy 4.565847 -60.953195)
			(xy 4.516247 -60.927694) (xy 4.470889 -60.895243) (xy 4.43074 -60.856534) (xy 4.396654 -60.812391)
			(xy 4.369358 -60.763756) (xy 4.349435 -60.711665) (xy 4.337309 -60.657228) (xy 4.333238 -60.601606)
			(xy 1.27 -60.601606) (xy 1.27 -62.429136) (xy 2.093212 -62.429136) (xy 2.097283 -62.373514) (xy 2.109409 -62.319077)
			(xy 2.129332 -62.266986) (xy 2.156628 -62.218351) (xy 2.190714 -62.174208) (xy 2.230863 -62.135499)
			(xy 2.276221 -62.103048) (xy 2.325821 -62.077547) (xy 2.378605 -62.05954) (xy 2.433448 -62.04941)
			(xy 2.489182 -62.047373) (xy 2.544619 -62.053473) (xy 2.598576 -62.067579) (xy 2.649905 -62.089391)
			(xy 2.697511 -62.118445) (xy 2.700622 -62.121034) (xy 4.242306 -62.121034) (xy 4.246377 -62.065412)
			(xy 4.258503 -62.010975) (xy 4.278426 -61.958884) (xy 4.305722 -61.910249) (xy 4.339808 -61.866106)
			(xy 4.379957 -61.827397) (xy 4.425315 -61.794946) (xy 4.474915 -61.769445) (xy 4.527699 -61.751438)
			(xy 4.582542 -61.741308) (xy 4.638276 -61.739271) (xy 4.693713 -61.745371) (xy 4.74767 -61.759477)
			(xy 4.798999 -61.781289) (xy 4.846605 -61.810343) (xy 4.889473 -61.846018) (xy 4.92669 -61.887555)
			(xy 4.957463 -61.934068) (xy 4.981135 -61.984565) (xy 4.997203 -62.037972) (xy 5.005323 -62.093148)
			(xy 5.005832 -62.121034) (xy 5.005323 -62.14892) (xy 4.997203 -62.204096) (xy 4.981135 -62.257503)
			(xy 4.957463 -62.308) (xy 4.92669 -62.354513) (xy 4.889473 -62.39605) (xy 4.846605 -62.431725) (xy 4.798999 -62.460779)
			(xy 4.74767 -62.482591) (xy 4.693713 -62.496697) (xy 4.638276 -62.502797) (xy 4.582542 -62.50076)
			(xy 4.527699 -62.49063) (xy 4.474915 -62.472623) (xy 4.425315 -62.447122) (xy 4.379957 -62.414671)
			(xy 4.339808 -62.375962) (xy 4.305722 -62.331819) (xy 4.278426 -62.283184) (xy 4.258503 -62.231093)
			(xy 4.246377 -62.176656) (xy 4.242306 -62.121034) (xy 2.700622 -62.121034) (xy 2.740379 -62.15412)
			(xy 2.777596 -62.195657) (xy 2.808369 -62.24217) (xy 2.832041 -62.292667) (xy 2.848109 -62.346074)
			(xy 2.856229 -62.40125) (xy 2.856738 -62.429136) (xy 2.856229 -62.457022) (xy 2.848109 -62.512198)
			(xy 2.832041 -62.565605) (xy 2.808369 -62.616102) (xy 2.777596 -62.662615) (xy 2.740379 -62.704152)
			(xy 2.697511 -62.739827) (xy 2.649905 -62.768881) (xy 2.598576 -62.790693) (xy 2.544619 -62.804799)
			(xy 2.489182 -62.810899) (xy 2.433448 -62.808862) (xy 2.378605 -62.798732) (xy 2.325821 -62.780725)
			(xy 2.276221 -62.755224) (xy 2.230863 -62.722773) (xy 2.190714 -62.684064) (xy 2.156628 -62.639921)
			(xy 2.129332 -62.591286) (xy 2.109409 -62.539195) (xy 2.097283 -62.484758) (xy 2.093212 -62.429136)
			(xy 1.27 -62.429136) (xy 1.27 -62.839421) (xy 6.918936 -62.839421) (xy 6.918936 -62.784919) (xy 6.926692 -62.730971)
			(xy 6.942048 -62.678676) (xy 6.964689 -62.629098) (xy 6.994155 -62.583247) (xy 7.029847 -62.542057)
			(xy 7.071037 -62.506365) (xy 7.116888 -62.476899) (xy 7.166466 -62.454258) (xy 7.218761 -62.438902)
			(xy 7.272709 -62.431146) (xy 7.29996 -62.43066) (xy 7.328807 -62.431188) (xy 7.385844 -62.439865)
			(xy 7.440921 -62.457041) (xy 7.492779 -62.482324) (xy 7.540233 -62.515137) (xy 7.56158 -62.534546)
			(xy 7.569962 -62.54242) (xy 7.591806 -62.549278) (xy 7.69366 -62.535054) (xy 7.71271 -62.5221) (xy 7.718552 -62.512194)
			(xy 7.733389 -62.488089) (xy 7.769038 -62.444125) (xy 7.810789 -62.405908) (xy 7.857726 -62.374275)
			(xy 7.908819 -62.34992) (xy 7.962948 -62.333376) (xy 8.018928 -62.325007) (xy 8.047228 -62.324488)
			(xy 8.070783 -62.324863) (xy 8.117527 -62.330723) (xy 8.140446 -62.336172) (xy 8.15467 -62.339728)
			(xy 8.181848 -62.331092) (xy 8.26008 -62.24016) (xy 8.264652 -62.211966) (xy 8.259064 -62.198504)
			(xy 8.249754 -62.175114) (xy 8.236628 -62.126514) (xy 8.230005 -62.076609) (xy 8.2296 -62.051438)
			(xy 8.230067 -62.024185) (xy 8.237825 -61.970235) (xy 8.253181 -61.917937) (xy 8.275824 -61.868357)
			(xy 8.305292 -61.822505) (xy 8.340985 -61.781312) (xy 8.382178 -61.745619) (xy 8.428031 -61.716152)
			(xy 8.477611 -61.69351) (xy 8.529909 -61.678154) (xy 8.583859 -61.670397) (xy 8.638365 -61.670397)
			(xy 8.692315 -61.678155) (xy 8.744613 -61.693511) (xy 8.794193 -61.716154) (xy 8.840045 -61.745622)
			(xy 8.881238 -61.781315) (xy 8.916931 -61.822508) (xy 8.946398 -61.868361) (xy 8.96904 -61.917941)
			(xy 8.984396 -61.970239) (xy 8.992153 -62.024189) (xy 8.992153 -62.078695) (xy 8.984395 -62.132645)
			(xy 8.969039 -62.184943) (xy 8.946396 -62.234523) (xy 8.916928 -62.280375) (xy 8.881235 -62.321568)
			(xy 8.840042 -62.357261) (xy 8.794189 -62.386728) (xy 8.744609 -62.40937) (xy 8.692311 -62.424726)
			(xy 8.638361 -62.432483) (xy 8.611108 -62.432946) (xy 8.587554 -62.432564) (xy 8.540809 -62.426708)
			(xy 8.51789 -62.421262) (xy 8.503666 -62.417706) (xy 8.476488 -62.426342) (xy 8.398256 -62.517274)
			(xy 8.393684 -62.545468) (xy 8.399272 -62.55893) (xy 8.408595 -62.582315) (xy 8.421715 -62.630918)
			(xy 8.428333 -62.680824) (xy 8.428736 -62.705996) (xy 8.428219 -62.733246) (xy 8.420463 -62.787191)
			(xy 8.40511 -62.839483) (xy 8.382471 -62.889059) (xy 8.353008 -62.934908) (xy 8.31732 -62.976097)
			(xy 8.276134 -63.011789) (xy 8.230287 -63.041256) (xy 8.180713 -63.063899) (xy 8.128422 -63.079257)
			(xy 8.074478 -63.087016) (xy 8.047228 -63.087504) (xy 8.018382 -63.086966) (xy 7.961346 -63.078289)
			(xy 7.90627 -63.061114) (xy 7.854411 -63.035834) (xy 7.806956 -63.003025) (xy 7.785608 -62.983618)
			(xy 7.777226 -62.975744) (xy 7.755382 -62.968886) (xy 7.653528 -62.98311) (xy 7.634478 -62.996064)
			(xy 7.628636 -63.00597) (xy 7.613794 -63.030072) (xy 7.578147 -63.074038) (xy 7.536398 -63.112257)
			(xy 7.489462 -63.143891) (xy 7.438369 -63.168246) (xy 7.38424 -63.18479) (xy 7.32826 -63.193157)
			(xy 7.29996 -63.193676) (xy 7.272709 -63.193194) (xy 7.218761 -63.185438) (xy 7.166466 -63.170082)
			(xy 7.116888 -63.147441) (xy 7.071037 -63.117975) (xy 7.029847 -63.082283) (xy 6.994155 -63.041093)
			(xy 6.964689 -62.995242) (xy 6.942048 -62.945664) (xy 6.926692 -62.893369) (xy 6.918936 -62.839421)
			(xy 1.27 -62.839421) (xy 1.27 -63.273432) (xy 3.576826 -63.273432) (xy 3.580897 -63.21781) (xy 3.593023 -63.163373)
			(xy 3.612946 -63.111282) (xy 3.640242 -63.062647) (xy 3.674328 -63.018504) (xy 3.714477 -62.979795)
			(xy 3.759835 -62.947344) (xy 3.809435 -62.921843) (xy 3.862219 -62.903836) (xy 3.917062 -62.893706)
			(xy 3.972796 -62.891669) (xy 4.028233 -62.897769) (xy 4.08219 -62.911875) (xy 4.133519 -62.933687)
			(xy 4.181125 -62.962741) (xy 4.223993 -62.998416) (xy 4.26121 -63.039953) (xy 4.291983 -63.086466)
			(xy 4.315655 -63.136963) (xy 4.331723 -63.19037) (xy 4.339843 -63.245546) (xy 4.340352 -63.273432)
			(xy 4.339843 -63.301318) (xy 4.331723 -63.356494) (xy 4.315655 -63.409901) (xy 4.291983 -63.460398)
			(xy 4.26121 -63.506911) (xy 4.223993 -63.548448) (xy 4.181125 -63.584123) (xy 4.133519 -63.613177)
			(xy 4.08219 -63.634989) (xy 4.028233 -63.649095) (xy 3.972796 -63.655195) (xy 3.917062 -63.653158)
			(xy 3.862219 -63.643028) (xy 3.809435 -63.625021) (xy 3.759835 -63.59952) (xy 3.714477 -63.567069)
			(xy 3.674328 -63.52836) (xy 3.640242 -63.484217) (xy 3.612946 -63.435582) (xy 3.593023 -63.383491)
			(xy 3.580897 -63.329054) (xy 3.576826 -63.273432) (xy 1.27 -63.273432) (xy 1.27 -64.312292) (xy 5.066028 -64.312292)
			(xy 5.070099 -64.25667) (xy 5.082225 -64.202233) (xy 5.102148 -64.150142) (xy 5.129444 -64.101507)
			(xy 5.16353 -64.057364) (xy 5.203679 -64.018655) (xy 5.249037 -63.986204) (xy 5.298637 -63.960703)
			(xy 5.351421 -63.942696) (xy 5.406264 -63.932566) (xy 5.461998 -63.930529) (xy 5.517435 -63.936629)
			(xy 5.571392 -63.950735) (xy 5.622721 -63.972547) (xy 5.670327 -64.001601) (xy 5.713195 -64.037276)
			(xy 5.750412 -64.078813) (xy 5.781185 -64.125326) (xy 5.804857 -64.175823) (xy 5.820925 -64.22923)
			(xy 5.829045 -64.284406) (xy 5.829554 -64.312292) (xy 5.829045 -64.340178) (xy 5.820925 -64.395354)
			(xy 5.804857 -64.448761) (xy 5.781185 -64.499258) (xy 5.750412 -64.545771) (xy 5.713195 -64.587308)
			(xy 5.670327 -64.622983) (xy 5.622721 -64.652037) (xy 5.571392 -64.673849) (xy 5.517435 -64.687955)
			(xy 5.461998 -64.694055) (xy 5.406264 -64.692018) (xy 5.351421 -64.681888) (xy 5.298637 -64.663881)
			(xy 5.249037 -64.63838) (xy 5.203679 -64.605929) (xy 5.16353 -64.56722) (xy 5.129444 -64.523077)
			(xy 5.102148 -64.474442) (xy 5.082225 -64.422351) (xy 5.070099 -64.367914) (xy 5.066028 -64.312292)
			(xy 1.27 -64.312292) (xy 1.27 -64.737234) (xy 1.896362 -64.737234) (xy 1.900433 -64.681612) (xy 1.912559 -64.627175)
			(xy 1.932482 -64.575084) (xy 1.959778 -64.526449) (xy 1.993864 -64.482306) (xy 2.034013 -64.443597)
			(xy 2.079371 -64.411146) (xy 2.128971 -64.385645) (xy 2.181755 -64.367638) (xy 2.236598 -64.357508)
			(xy 2.292332 -64.355471) (xy 2.347769 -64.361571) (xy 2.401726 -64.375677) (xy 2.453055 -64.397489)
			(xy 2.500661 -64.426543) (xy 2.543529 -64.462218) (xy 2.580746 -64.503755) (xy 2.611519 -64.550268)
			(xy 2.635191 -64.600765) (xy 2.651259 -64.654172) (xy 2.659379 -64.709348) (xy 2.659888 -64.737234)
			(xy 2.659379 -64.76512) (xy 2.651259 -64.820296) (xy 2.635191 -64.873703) (xy 2.611519 -64.9242)
			(xy 2.580746 -64.970713) (xy 2.543529 -65.01225) (xy 2.500661 -65.047925) (xy 2.453055 -65.076979)
			(xy 2.401726 -65.098791) (xy 2.347769 -65.112897) (xy 2.292332 -65.118997) (xy 2.236598 -65.11696)
			(xy 2.181755 -65.10683) (xy 2.128971 -65.088823) (xy 2.079371 -65.063322) (xy 2.034013 -65.030871)
			(xy 1.993864 -64.992162) (xy 1.959778 -64.948019) (xy 1.932482 -64.899384) (xy 1.912559 -64.847293)
			(xy 1.900433 -64.792856) (xy 1.896362 -64.737234) (xy 1.27 -64.737234) (xy 1.27 -65.124076) (xy 6.107428 -65.124076)
			(xy 6.111499 -65.068454) (xy 6.123625 -65.014017) (xy 6.143548 -64.961926) (xy 6.170844 -64.913291)
			(xy 6.20493 -64.869148) (xy 6.245079 -64.830439) (xy 6.290437 -64.797988) (xy 6.340037 -64.772487)
			(xy 6.392821 -64.75448) (xy 6.447664 -64.74435) (xy 6.503398 -64.742313) (xy 6.558835 -64.748413)
			(xy 6.612792 -64.762519) (xy 6.664121 -64.784331) (xy 6.711727 -64.813385) (xy 6.754595 -64.84906)
			(xy 6.791812 -64.890597) (xy 6.822585 -64.93711) (xy 6.846257 -64.987607) (xy 6.862325 -65.041014)
			(xy 6.870445 -65.09619) (xy 6.870954 -65.124076) (xy 6.870445 -65.151962) (xy 6.862325 -65.207138)
			(xy 6.846257 -65.260545) (xy 6.822585 -65.311042) (xy 6.791812 -65.357555) (xy 6.754595 -65.399092)
			(xy 6.711727 -65.434767) (xy 6.664121 -65.463821) (xy 6.612792 -65.485633) (xy 6.558835 -65.499739)
			(xy 6.503398 -65.505839) (xy 6.447664 -65.503802) (xy 6.392821 -65.493672) (xy 6.340037 -65.475665)
			(xy 6.290437 -65.450164) (xy 6.245079 -65.417713) (xy 6.20493 -65.379004) (xy 6.170844 -65.334861)
			(xy 6.143548 -65.286226) (xy 6.123625 -65.234135) (xy 6.111499 -65.179698) (xy 6.107428 -65.124076)
			(xy 1.27 -65.124076) (xy 1.27 -65.882774) (xy 3.101592 -65.882774) (xy 3.105663 -65.827152) (xy 3.117789 -65.772715)
			(xy 3.137712 -65.720624) (xy 3.165008 -65.671989) (xy 3.199094 -65.627846) (xy 3.239243 -65.589137)
			(xy 3.284601 -65.556686) (xy 3.334201 -65.531185) (xy 3.386985 -65.513178) (xy 3.441828 -65.503048)
			(xy 3.497562 -65.501011) (xy 3.552999 -65.507111) (xy 3.606956 -65.521217) (xy 3.658285 -65.543029)
			(xy 3.705891 -65.572083) (xy 3.748759 -65.607758) (xy 3.785976 -65.649295) (xy 3.816749 -65.695808)
			(xy 3.840421 -65.746305) (xy 3.856489 -65.799712) (xy 3.864609 -65.854888) (xy 3.865118 -65.882774)
			(xy 3.864609 -65.91066) (xy 3.856489 -65.965836) (xy 3.840421 -66.019243) (xy 3.816749 -66.06974)
			(xy 3.785976 -66.116253) (xy 3.748759 -66.15779) (xy 3.705891 -66.193465) (xy 3.658285 -66.222519)
			(xy 3.606956 -66.244331) (xy 3.552999 -66.258437) (xy 3.497562 -66.264537) (xy 3.441828 -66.2625)
			(xy 3.386985 -66.25237) (xy 3.334201 -66.234363) (xy 3.284601 -66.208862) (xy 3.239243 -66.176411)
			(xy 3.199094 -66.137702) (xy 3.165008 -66.093559) (xy 3.137712 -66.044924) (xy 3.117789 -65.992833)
			(xy 3.105663 -65.938396) (xy 3.101592 -65.882774) (xy 1.27 -65.882774) (xy 1.27 -66.567812) (xy 6.304532 -66.567812)
			(xy 6.308603 -66.51219) (xy 6.320729 -66.457753) (xy 6.340652 -66.405662) (xy 6.367948 -66.357027)
			(xy 6.402034 -66.312884) (xy 6.442183 -66.274175) (xy 6.487541 -66.241724) (xy 6.537141 -66.216223)
			(xy 6.589925 -66.198216) (xy 6.644768 -66.188086) (xy 6.700502 -66.186049) (xy 6.755939 -66.192149)
			(xy 6.809896 -66.206255) (xy 6.861225 -66.228067) (xy 6.908831 -66.257121) (xy 6.951699 -66.292796)
			(xy 6.988916 -66.334333) (xy 7.019689 -66.380846) (xy 7.043361 -66.431343) (xy 7.059429 -66.48475)
			(xy 7.067549 -66.539926) (xy 7.068058 -66.567812) (xy 7.067549 -66.595698) (xy 7.059429 -66.650874)
			(xy 7.043361 -66.704281) (xy 7.019689 -66.754778) (xy 6.988916 -66.801291) (xy 6.951699 -66.842828)
			(xy 6.908831 -66.878503) (xy 6.861225 -66.907557) (xy 6.809896 -66.929369) (xy 6.755939 -66.943475)
			(xy 6.700502 -66.949575) (xy 6.644768 -66.947538) (xy 6.589925 -66.937408) (xy 6.537141 -66.919401)
			(xy 6.487541 -66.8939) (xy 6.442183 -66.861449) (xy 6.402034 -66.82274) (xy 6.367948 -66.778597)
			(xy 6.340652 -66.729962) (xy 6.320729 -66.677871) (xy 6.308603 -66.623434) (xy 6.304532 -66.567812)
			(xy 1.27 -66.567812) (xy 1.27 -67.201034) (xy 4.242306 -67.201034) (xy 4.246377 -67.145412) (xy 4.258503 -67.090975)
			(xy 4.278426 -67.038884) (xy 4.305722 -66.990249) (xy 4.339808 -66.946106) (xy 4.379957 -66.907397)
			(xy 4.425315 -66.874946) (xy 4.474915 -66.849445) (xy 4.527699 -66.831438) (xy 4.582542 -66.821308)
			(xy 4.638276 -66.819271) (xy 4.693713 -66.825371) (xy 4.74767 -66.839477) (xy 4.798999 -66.861289)
			(xy 4.846605 -66.890343) (xy 4.889473 -66.926018) (xy 4.92669 -66.967555) (xy 4.957463 -67.014068)
			(xy 4.981135 -67.064565) (xy 4.997203 -67.117972) (xy 5.005323 -67.173148) (xy 5.005832 -67.201034)
			(xy 5.005323 -67.22892) (xy 4.997203 -67.284096) (xy 4.981135 -67.337503) (xy 4.957463 -67.388) (xy 4.92669 -67.434513)
			(xy 4.889473 -67.47605) (xy 4.846605 -67.511725) (xy 4.798999 -67.540779) (xy 4.74767 -67.562591)
			(xy 4.693713 -67.576697) (xy 4.638276 -67.582797) (xy 4.582542 -67.58076) (xy 4.527699 -67.57063)
			(xy 4.474915 -67.552623) (xy 4.425315 -67.527122) (xy 4.379957 -67.494671) (xy 4.339808 -67.455962)
			(xy 4.305722 -67.411819) (xy 4.278426 -67.363184) (xy 4.258503 -67.311093) (xy 4.246377 -67.256656)
			(xy 4.242306 -67.201034) (xy 1.27 -67.201034) (xy 1.27 -68.166234) (xy 1.405126 -68.166234) (xy 1.409197 -68.110612)
			(xy 1.421323 -68.056175) (xy 1.441246 -68.004084) (xy 1.468542 -67.955449) (xy 1.502628 -67.911306)
			(xy 1.542777 -67.872597) (xy 1.588135 -67.840146) (xy 1.637735 -67.814645) (xy 1.690519 -67.796638)
			(xy 1.745362 -67.786508) (xy 1.801096 -67.784471) (xy 1.856533 -67.790571) (xy 1.91049 -67.804677)
			(xy 1.961819 -67.826489) (xy 2.009425 -67.855543) (xy 2.052293 -67.891218) (xy 2.077563 -67.919421)
			(xy 6.918936 -67.919421) (xy 6.918936 -67.864919) (xy 6.926692 -67.810971) (xy 6.942048 -67.758676)
			(xy 6.964689 -67.709098) (xy 6.994155 -67.663247) (xy 7.029847 -67.622057) (xy 7.071037 -67.586365)
			(xy 7.116888 -67.556899) (xy 7.166466 -67.534258) (xy 7.218761 -67.518902) (xy 7.272709 -67.511146)
			(xy 7.29996 -67.51066) (xy 7.328807 -67.511188) (xy 7.385844 -67.519865) (xy 7.440921 -67.537041)
			(xy 7.492779 -67.562324) (xy 7.540233 -67.595137) (xy 7.56158 -67.614546) (xy 7.569962 -67.62242)
			(xy 7.591806 -67.629278) (xy 7.69366 -67.615054) (xy 7.71271 -67.6021) (xy 7.718552 -67.592194) (xy 7.733389 -67.568089)
			(xy 7.769038 -67.524125) (xy 7.810789 -67.485908) (xy 7.857726 -67.454275) (xy 7.908819 -67.42992)
			(xy 7.962948 -67.413376) (xy 8.018928 -67.405007) (xy 8.047228 -67.404488) (xy 8.074481 -67.404959)
			(xy 8.128431 -67.412716) (xy 8.180729 -67.428072) (xy 8.230309 -67.450714) (xy 8.276162 -67.480181)
			(xy 8.317354 -67.515875) (xy 8.353047 -67.557067) (xy 8.382515 -67.60292) (xy 8.405158 -67.652499)
			(xy 8.420514 -67.704797) (xy 8.428271 -67.758747) (xy 8.428271 -67.813253) (xy 8.420514 -67.867203)
			(xy 8.405158 -67.919501) (xy 8.382515 -67.96908) (xy 8.353047 -68.014933) (xy 8.317354 -68.056125)
			(xy 8.276162 -68.091819) (xy 8.230309 -68.121286) (xy 8.180729 -68.143928) (xy 8.128431 -68.159284)
			(xy 8.074481 -68.167041) (xy 8.047228 -68.167504) (xy 8.018382 -68.166966) (xy 7.961346 -68.158289)
			(xy 7.90627 -68.141114) (xy 7.854411 -68.115834) (xy 7.806956 -68.083025) (xy 7.785608 -68.063618)
			(xy 7.777226 -68.055744) (xy 7.755382 -68.048886) (xy 7.653528 -68.06311) (xy 7.634478 -68.076064)
			(xy 7.628636 -68.08597) (xy 7.613794 -68.110072) (xy 7.578147 -68.154038) (xy 7.536398 -68.192257)
			(xy 7.489462 -68.223891) (xy 7.438369 -68.248246) (xy 7.38424 -68.26479) (xy 7.32826 -68.273157)
			(xy 7.29996 -68.273676) (xy 7.272709 -68.273194) (xy 7.218761 -68.265438) (xy 7.166466 -68.250082)
			(xy 7.116888 -68.227441) (xy 7.071037 -68.197975) (xy 7.029847 -68.162283) (xy 6.994155 -68.121093)
			(xy 6.964689 -68.075242) (xy 6.942048 -68.025664) (xy 6.926692 -67.973369) (xy 6.918936 -67.919421)
			(xy 2.077563 -67.919421) (xy 2.08951 -67.932755) (xy 2.120283 -67.979268) (xy 2.143955 -68.029765)
			(xy 2.160023 -68.083172) (xy 2.168143 -68.138348) (xy 2.168652 -68.166234) (xy 2.168143 -68.19412)
			(xy 2.160023 -68.249296) (xy 2.143955 -68.302703) (xy 2.120283 -68.3532) (xy 2.12013 -68.353432)
			(xy 3.576826 -68.353432) (xy 3.580897 -68.29781) (xy 3.593023 -68.243373) (xy 3.612946 -68.191282)
			(xy 3.640242 -68.142647) (xy 3.674328 -68.098504) (xy 3.714477 -68.059795) (xy 3.759835 -68.027344)
			(xy 3.809435 -68.001843) (xy 3.862219 -67.983836) (xy 3.917062 -67.973706) (xy 3.972796 -67.971669)
			(xy 4.028233 -67.977769) (xy 4.08219 -67.991875) (xy 4.133519 -68.013687) (xy 4.181125 -68.042741)
			(xy 4.223993 -68.078416) (xy 4.26121 -68.119953) (xy 4.291983 -68.166466) (xy 4.315655 -68.216963)
			(xy 4.331723 -68.27037) (xy 4.339843 -68.325546) (xy 4.340352 -68.353432) (xy 4.339843 -68.381318)
			(xy 4.331723 -68.436494) (xy 4.315655 -68.489901) (xy 4.291983 -68.540398) (xy 4.26121 -68.586911)
			(xy 4.223993 -68.628448) (xy 4.181125 -68.664123) (xy 4.133519 -68.693177) (xy 4.08219 -68.714989)
			(xy 4.028233 -68.729095) (xy 3.972796 -68.735195) (xy 3.917062 -68.733158) (xy 3.862219 -68.723028)
			(xy 3.809435 -68.705021) (xy 3.759835 -68.67952) (xy 3.714477 -68.647069) (xy 3.674328 -68.60836)
			(xy 3.640242 -68.564217) (xy 3.612946 -68.515582) (xy 3.593023 -68.463491) (xy 3.580897 -68.409054)
			(xy 3.576826 -68.353432) (xy 2.12013 -68.353432) (xy 2.08951 -68.399713) (xy 2.052293 -68.44125)
			(xy 2.009425 -68.476925) (xy 1.961819 -68.505979) (xy 1.91049 -68.527791) (xy 1.856533 -68.541897)
			(xy 1.801096 -68.547997) (xy 1.745362 -68.54596) (xy 1.690519 -68.53583) (xy 1.637735 -68.517823)
			(xy 1.588135 -68.492322) (xy 1.542777 -68.459871) (xy 1.502628 -68.421162) (xy 1.468542 -68.377019)
			(xy 1.441246 -68.328384) (xy 1.421323 -68.276293) (xy 1.409197 -68.221856) (xy 1.405126 -68.166234)
			(xy 1.27 -68.166234) (xy 1.27 -69.392292) (xy 5.050026 -69.392292) (xy 5.054097 -69.33667) (xy 5.066223 -69.282233)
			(xy 5.086146 -69.230142) (xy 5.113442 -69.181507) (xy 5.147528 -69.137364) (xy 5.187677 -69.098655)
			(xy 5.233035 -69.066204) (xy 5.282635 -69.040703) (xy 5.335419 -69.022696) (xy 5.390262 -69.012566)
			(xy 5.445996 -69.010529) (xy 5.501433 -69.016629) (xy 5.55539 -69.030735) (xy 5.606719 -69.052547)
			(xy 5.654325 -69.081601) (xy 5.697193 -69.117276) (xy 5.73441 -69.158813) (xy 5.765183 -69.205326)
			(xy 5.788855 -69.255823) (xy 5.804923 -69.30923) (xy 5.813043 -69.364406) (xy 5.813552 -69.392292)
			(xy 5.813043 -69.420178) (xy 5.804923 -69.475354) (xy 5.788855 -69.528761) (xy 5.765183 -69.579258)
			(xy 5.73441 -69.625771) (xy 5.697193 -69.667308) (xy 5.654325 -69.702983) (xy 5.606719 -69.732037)
			(xy 5.55539 -69.753849) (xy 5.501433 -69.767955) (xy 5.445996 -69.774055) (xy 5.390262 -69.772018)
			(xy 5.335419 -69.761888) (xy 5.282635 -69.743881) (xy 5.233035 -69.71838) (xy 5.187677 -69.685929)
			(xy 5.147528 -69.64722) (xy 5.113442 -69.603077) (xy 5.086146 -69.554442) (xy 5.066223 -69.502351)
			(xy 5.054097 -69.447914) (xy 5.050026 -69.392292) (xy 1.27 -69.392292) (xy 1.27 -70.204076) (xy 6.107428 -70.204076)
			(xy 6.111499 -70.148454) (xy 6.123625 -70.094017) (xy 6.143548 -70.041926) (xy 6.170844 -69.993291)
			(xy 6.20493 -69.949148) (xy 6.245079 -69.910439) (xy 6.290437 -69.877988) (xy 6.340037 -69.852487)
			(xy 6.392821 -69.83448) (xy 6.447664 -69.82435) (xy 6.503398 -69.822313) (xy 6.558835 -69.828413)
			(xy 6.612792 -69.842519) (xy 6.664121 -69.864331) (xy 6.711727 -69.893385) (xy 6.754595 -69.92906)
			(xy 6.791812 -69.970597) (xy 6.822585 -70.01711) (xy 6.846257 -70.067607) (xy 6.862325 -70.121014)
			(xy 6.870445 -70.17619) (xy 6.870954 -70.204076) (xy 6.870445 -70.231962) (xy 6.862325 -70.287138)
			(xy 6.846257 -70.340545) (xy 6.822585 -70.391042) (xy 6.791812 -70.437555) (xy 6.754595 -70.479092)
			(xy 6.711727 -70.514767) (xy 6.664121 -70.543821) (xy 6.612792 -70.565633) (xy 6.558835 -70.579739)
			(xy 6.503398 -70.585839) (xy 6.447664 -70.583802) (xy 6.392821 -70.573672) (xy 6.340037 -70.555665)
			(xy 6.290437 -70.530164) (xy 6.245079 -70.497713) (xy 6.20493 -70.459004) (xy 6.170844 -70.414861)
			(xy 6.143548 -70.366226) (xy 6.123625 -70.314135) (xy 6.111499 -70.259698) (xy 6.107428 -70.204076)
			(xy 1.27 -70.204076) (xy 1.27 -70.720966) (xy 4.463032 -70.720966) (xy 4.467103 -70.665344) (xy 4.479229 -70.610907)
			(xy 4.499152 -70.558816) (xy 4.526448 -70.510181) (xy 4.560534 -70.466038) (xy 4.600683 -70.427329)
			(xy 4.646041 -70.394878) (xy 4.695641 -70.369377) (xy 4.748425 -70.35137) (xy 4.803268 -70.34124)
			(xy 4.859002 -70.339203) (xy 4.914439 -70.345303) (xy 4.968396 -70.359409) (xy 5.019725 -70.381221)
			(xy 5.067331 -70.410275) (xy 5.110199 -70.44595) (xy 5.147416 -70.487487) (xy 5.178189 -70.534) (xy 5.201861 -70.584497)
			(xy 5.217929 -70.637904) (xy 5.226049 -70.69308) (xy 5.226558 -70.720966) (xy 5.226049 -70.748852)
			(xy 5.217929 -70.804028) (xy 5.201861 -70.857435) (xy 5.178189 -70.907932) (xy 5.147416 -70.954445)
			(xy 5.110199 -70.995982) (xy 5.067331 -71.031657) (xy 5.019725 -71.060711) (xy 4.968396 -71.082523)
			(xy 4.914439 -71.096629) (xy 4.859002 -71.102729) (xy 4.803268 -71.100692) (xy 4.748425 -71.090562)
			(xy 4.695641 -71.072555) (xy 4.646041 -71.047054) (xy 4.600683 -71.014603) (xy 4.560534 -70.975894)
			(xy 4.526448 -70.931751) (xy 4.499152 -70.883116) (xy 4.479229 -70.831025) (xy 4.467103 -70.776588)
			(xy 4.463032 -70.720966) (xy 1.27 -70.720966) (xy 1.27 -71.288402) (xy 1.735072 -71.288402) (xy 1.739143 -71.23278)
			(xy 1.751269 -71.178343) (xy 1.771192 -71.126252) (xy 1.798488 -71.077617) (xy 1.832574 -71.033474)
			(xy 1.872723 -70.994765) (xy 1.918081 -70.962314) (xy 1.967681 -70.936813) (xy 2.020465 -70.918806)
			(xy 2.075308 -70.908676) (xy 2.131042 -70.906639) (xy 2.186479 -70.912739) (xy 2.240436 -70.926845)
			(xy 2.291765 -70.948657) (xy 2.339371 -70.977711) (xy 2.382239 -71.013386) (xy 2.419456 -71.054923)
			(xy 2.450229 -71.101436) (xy 2.473901 -71.151933) (xy 2.489969 -71.20534) (xy 2.498089 -71.260516)
			(xy 2.498598 -71.288402) (xy 2.498089 -71.316288) (xy 2.489969 -71.371464) (xy 2.473901 -71.424871)
			(xy 2.450229 -71.475368) (xy 2.419456 -71.521881) (xy 2.382239 -71.563418) (xy 2.339371 -71.599093)
			(xy 2.291765 -71.628147) (xy 2.240436 -71.649959) (xy 2.186479 -71.664065) (xy 2.131042 -71.670165)
			(xy 2.075308 -71.668128) (xy 2.020465 -71.657998) (xy 1.967681 -71.639991) (xy 1.918081 -71.61449)
			(xy 1.872723 -71.582039) (xy 1.832574 -71.54333) (xy 1.798488 -71.499187) (xy 1.771192 -71.450552)
			(xy 1.751269 -71.398461) (xy 1.739143 -71.344024) (xy 1.735072 -71.288402) (xy 1.27 -71.288402) (xy 1.27 -71.673974)
			(xy 3.37896 -71.673974) (xy 3.383031 -71.618352) (xy 3.395157 -71.563915) (xy 3.41508 -71.511824)
			(xy 3.442376 -71.463189) (xy 3.476462 -71.419046) (xy 3.516611 -71.380337) (xy 3.561969 -71.347886)
			(xy 3.611569 -71.322385) (xy 3.664353 -71.304378) (xy 3.719196 -71.294248) (xy 3.77493 -71.292211)
			(xy 3.830367 -71.298311) (xy 3.884324 -71.312417) (xy 3.935653 -71.334229) (xy 3.983259 -71.363283)
			(xy 4.026127 -71.398958) (xy 4.033123 -71.406766) (xy 7.013446 -71.406766) (xy 7.017517 -71.351144)
			(xy 7.029643 -71.296707) (xy 7.049566 -71.244616) (xy 7.076862 -71.195981) (xy 7.110948 -71.151838)
			(xy 7.151097 -71.113129) (xy 7.196455 -71.080678) (xy 7.246055 -71.055177) (xy 7.298839 -71.03717)
			(xy 7.353682 -71.02704) (xy 7.409416 -71.025003) (xy 7.464853 -71.031103) (xy 7.51881 -71.045209)
			(xy 7.570139 -71.067021) (xy 7.617745 -71.096075) (xy 7.643747 -71.117714) (xy 9.0457 -71.117714)
			(xy 9.049771 -71.062092) (xy 9.061897 -71.007655) (xy 9.08182 -70.955564) (xy 9.109116 -70.906929)
			(xy 9.143202 -70.862786) (xy 9.183351 -70.824077) (xy 9.228709 -70.791626) (xy 9.278309 -70.766125)
			(xy 9.331093 -70.748118) (xy 9.385936 -70.737988) (xy 9.44167 -70.735951) (xy 9.497107 -70.742051)
			(xy 9.551064 -70.756157) (xy 9.602393 -70.777969) (xy 9.649999 -70.807023) (xy 9.692867 -70.842698)
			(xy 9.730084 -70.884235) (xy 9.760857 -70.930748) (xy 9.784529 -70.981245) (xy 9.800597 -71.034652)
			(xy 9.808717 -71.089828) (xy 9.809226 -71.117714) (xy 9.808717 -71.1456) (xy 9.800597 -71.200776)
			(xy 9.784529 -71.254183) (xy 9.760857 -71.30468) (xy 9.730084 -71.351193) (xy 9.692867 -71.39273)
			(xy 9.649999 -71.428405) (xy 9.602393 -71.457459) (xy 9.551064 -71.479271) (xy 9.497107 -71.493377)
			(xy 9.44167 -71.499477) (xy 9.385936 -71.49744) (xy 9.331093 -71.48731) (xy 9.278309 -71.469303)
			(xy 9.228709 -71.443802) (xy 9.183351 -71.411351) (xy 9.143202 -71.372642) (xy 9.109116 -71.328499)
			(xy 9.08182 -71.279864) (xy 9.061897 -71.227773) (xy 9.049771 -71.173336) (xy 9.0457 -71.117714)
			(xy 7.643747 -71.117714) (xy 7.660613 -71.13175) (xy 7.69783 -71.173287) (xy 7.728603 -71.2198) (xy 7.752275 -71.270297)
			(xy 7.768343 -71.323704) (xy 7.776463 -71.37888) (xy 7.776972 -71.406766) (xy 7.776463 -71.434652)
			(xy 7.768343 -71.489828) (xy 7.752275 -71.543235) (xy 7.728603 -71.593732) (xy 7.69783 -71.640245)
			(xy 7.660613 -71.681782) (xy 7.617745 -71.717457) (xy 7.570139 -71.746511) (xy 7.51881 -71.768323)
			(xy 7.464853 -71.782429) (xy 7.409416 -71.788529) (xy 7.353682 -71.786492) (xy 7.298839 -71.776362)
			(xy 7.246055 -71.758355) (xy 7.196455 -71.732854) (xy 7.151097 -71.700403) (xy 7.110948 -71.661694)
			(xy 7.076862 -71.617551) (xy 7.049566 -71.568916) (xy 7.029643 -71.516825) (xy 7.017517 -71.462388)
			(xy 7.013446 -71.406766) (xy 4.033123 -71.406766) (xy 4.063344 -71.440495) (xy 4.094117 -71.487008)
			(xy 4.117789 -71.537505) (xy 4.133857 -71.590912) (xy 4.141977 -71.646088) (xy 4.142486 -71.673974)
			(xy 4.141977 -71.70186) (xy 4.133857 -71.757036) (xy 4.117789 -71.810443) (xy 4.094117 -71.86094)
			(xy 4.063344 -71.907453) (xy 4.026127 -71.94899) (xy 3.983259 -71.984665) (xy 3.935653 -72.013719)
			(xy 3.884324 -72.035531) (xy 3.830367 -72.049637) (xy 3.77493 -72.055737) (xy 3.719196 -72.0537)
			(xy 3.664353 -72.04357) (xy 3.611569 -72.025563) (xy 3.561969 -72.000062) (xy 3.516611 -71.967611)
			(xy 3.476462 -71.928902) (xy 3.442376 -71.884759) (xy 3.41508 -71.836124) (xy 3.395157 -71.784033)
			(xy 3.383031 -71.729596) (xy 3.37896 -71.673974) (xy 1.27 -71.673974) (xy 1.27 -72.459088) (xy 9.088118 -72.459088)
			(xy 9.092189 -72.403466) (xy 9.104315 -72.349029) (xy 9.124238 -72.296938) (xy 9.151534 -72.248303)
			(xy 9.18562 -72.20416) (xy 9.225769 -72.165451) (xy 9.271127 -72.133) (xy 9.320727 -72.107499) (xy 9.373511 -72.089492)
			(xy 9.428354 -72.079362) (xy 9.484088 -72.077325) (xy 9.539525 -72.083425) (xy 9.593482 -72.097531)
			(xy 9.644811 -72.119343) (xy 9.692417 -72.148397) (xy 9.735285 -72.184072) (xy 9.772502 -72.225609)
			(xy 9.803275 -72.272122) (xy 9.826947 -72.322619) (xy 9.843015 -72.376026) (xy 9.851135 -72.431202)
			(xy 9.851644 -72.459088) (xy 9.851135 -72.486974) (xy 9.843015 -72.54215) (xy 9.826947 -72.595557)
			(xy 9.803275 -72.646054) (xy 9.772502 -72.692567) (xy 9.735285 -72.734104) (xy 9.692417 -72.769779)
			(xy 9.644811 -72.798833) (xy 9.593482 -72.820645) (xy 9.539525 -72.834751) (xy 9.484088 -72.840851)
			(xy 9.428354 -72.838814) (xy 9.373511 -72.828684) (xy 9.320727 -72.810677) (xy 9.271127 -72.785176)
			(xy 9.225769 -72.752725) (xy 9.18562 -72.714016) (xy 9.151534 -72.669873) (xy 9.124238 -72.621238)
			(xy 9.104315 -72.569147) (xy 9.092189 -72.51471) (xy 9.088118 -72.459088) (xy 1.27 -72.459088) (xy 1.27 -73.289668)
			(xy 3.554728 -73.289668) (xy 3.558799 -73.234046) (xy 3.570925 -73.179609) (xy 3.590848 -73.127518)
			(xy 3.618144 -73.078883) (xy 3.65223 -73.03474) (xy 3.692379 -72.996031) (xy 3.737737 -72.96358)
			(xy 3.787337 -72.938079) (xy 3.840121 -72.920072) (xy 3.894964 -72.909942) (xy 3.950698 -72.907905)
			(xy 4.006135 -72.914005) (xy 4.060092 -72.928111) (xy 4.111421 -72.949923) (xy 4.159027 -72.978977)
			(xy 4.201895 -73.014652) (xy 4.239112 -73.056189) (xy 4.269885 -73.102702) (xy 4.293557 -73.153199)
			(xy 4.309625 -73.206606) (xy 4.317745 -73.261782) (xy 4.318254 -73.289668) (xy 4.317745 -73.317554)
			(xy 4.309625 -73.37273) (xy 4.293557 -73.426137) (xy 4.269885 -73.476634) (xy 4.239112 -73.523147)
			(xy 4.201895 -73.564684) (xy 4.159027 -73.600359) (xy 4.111421 -73.629413) (xy 4.060092 -73.651225)
			(xy 4.006135 -73.665331) (xy 3.950698 -73.671431) (xy 3.894964 -73.669394) (xy 3.840121 -73.659264)
			(xy 3.787337 -73.641257) (xy 3.737737 -73.615756) (xy 3.692379 -73.583305) (xy 3.65223 -73.544596)
			(xy 3.618144 -73.500453) (xy 3.590848 -73.451818) (xy 3.570925 -73.399727) (xy 3.558799 -73.34529)
			(xy 3.554728 -73.289668) (xy 1.27 -73.289668) (xy 1.27 -73.679812) (xy 1.270425 -73.689881) (xy 1.278143 -73.708482)
			(xy 1.284986 -73.71588) (xy 1.457198 -73.888092) (xy 1.464596 -73.89494) (xy 1.483194 -73.902676)
			(xy 1.493266 -73.903078) (xy 7.638796 -73.903078) (xy 7.648867 -73.9035) (xy 7.667475 -73.911211)
			(xy 7.674864 -73.918064) (xy 8.113014 -74.356214) (xy 8.120409 -74.363068) (xy 8.139008 -74.37081)
			(xy 8.149082 -74.3712)
		)
		(stroke
			(width 0)
			(type solid)
		)
		(fill yes)
		(layer "In9.Cu")
		(net "P3V3_SSD0")
	)
	(gr_poly
		(pts
			(xy 466.737446 -324.848982) (xy 466.744601 -324.847269) (xy 466.757614 -324.840423) (xy 466.7631 -324.83552)
			(xy 466.976714 -324.621906) (xy 466.981704 -324.616408) (xy 466.988554 -324.603243) (xy 466.990176 -324.595998)
			(xy 466.991192 -324.586346) (xy 466.991192 -306.203096) (xy 466.991615 -306.193026) (xy 466.99933 -306.174422)
			(xy 467.006178 -306.167028) (xy 467.05012 -306.123086) (xy 467.055108 -306.117587) (xy 467.061952 -306.104421)
			(xy 467.063582 -306.097178) (xy 467.064598 -306.087526) (xy 467.064598 -246.475504) (xy 467.064253 -246.466812)
			(xy 467.058414 -246.450439) (xy 467.053168 -246.4435) (xy 467.049866 -246.43969) (xy 466.645752 -246.035576)
			(xy 466.638904 -246.028179) (xy 466.63117 -246.00958) (xy 466.630766 -245.999508) (xy 466.630766 -245.499636)
			(xy 466.630426 -245.490942) (xy 466.624591 -245.474565) (xy 466.619336 -245.467632) (xy 466.616034 -245.463822)
			(xy 463.243422 -242.09121) (xy 463.236572 -242.083813) (xy 463.22883 -242.065215) (xy 463.228436 -242.055142)
			(xy 463.228436 -86.568788) (xy 463.228862 -86.55872) (xy 463.236584 -86.540122) (xy 463.243422 -86.53272)
			(xy 466.277452 -83.49869) (xy 466.284041 -83.491311) (xy 466.291507 -83.473012) (xy 466.29193 -83.46313)
			(xy 466.29193 -83.457288) (xy 466.710014 -83.039204) (xy 466.715004 -83.033706) (xy 466.721854 -83.020541)
			(xy 466.723476 -83.013296) (xy 466.724492 -83.003644) (xy 466.724492 -82.803746) (xy 466.724925 -82.79368)
			(xy 466.732652 -82.775089) (xy 466.739478 -82.767678) (xy 466.962998 -82.544158) (xy 466.967984 -82.538658)
			(xy 466.974824 -82.525491) (xy 466.97646 -82.51825) (xy 466.977476 -82.508598) (xy 466.977476 -9.03859)
			(xy 466.977129 -9.029899) (xy 466.971284 -9.01353) (xy 466.966046 -9.006586) (xy 466.962744 -9.002776)
			(xy 466.726016 -8.766048) (xy 466.723166 -8.763341) (xy 466.716789 -8.758745) (xy 466.713316 -8.756904)
			(xy 466.707888 -8.754325) (xy 466.696209 -8.75151) (xy 466.690202 -8.751316) (xy 464.787234 -8.751316)
			(xy 464.782279 -8.751201) (xy 464.772555 -8.749288) (xy 464.76793 -8.747506) (xy 464.749134 -8.739886)
			(xy 464.744967 -8.738406) (xy 464.736281 -8.736746) (xy 464.731862 -8.736584) (xy 461.004666 -8.736584)
			(xy 460.995977 -8.736937) (xy 460.979618 -8.742793) (xy 460.972662 -8.748014) (xy 460.968852 -8.751316)
			(xy 456.155298 -13.56487) (xy 456.152592 -13.567721) (xy 456.147999 -13.574099) (xy 456.146154 -13.57757)
			(xy 456.143571 -13.582997) (xy 456.140751 -13.594677) (xy 456.140566 -13.600684) (xy 456.140566 -14.923008)
			(xy 456.140141 -14.933077) (xy 456.13242 -14.951676) (xy 456.12558 -14.959076) (xy 455.967084 -15.117572)
			(xy 455.884547 -15.200122) (xy 459.541372 -15.200122) (xy 459.541372 -13.599922) (xy 459.54188 -13.535242)
			(xy 459.550003 -13.406136) (xy 459.566216 -13.277796) (xy 459.590456 -13.150726) (xy 459.622626 -13.02543)
			(xy 459.662601 -12.9024) (xy 459.710222 -12.782124) (xy 459.765301 -12.665075) (xy 459.827621 -12.551715)
			(xy 459.896936 -12.442492) (xy 459.972972 -12.337837) (xy 460.05543 -12.238163) (xy 460.143983 -12.143863)
			(xy 460.238283 -12.05531) (xy 460.337957 -11.972852) (xy 460.442612 -11.896816) (xy 460.551835 -11.827501)
			(xy 460.665195 -11.765181) (xy 460.782244 -11.710102) (xy 460.90252 -11.662481) (xy 461.02555 -11.622506)
			(xy 461.150846 -11.590336) (xy 461.277916 -11.566096) (xy 461.406256 -11.549883) (xy 461.535362 -11.54176)
			(xy 461.664722 -11.54176) (xy 461.793828 -11.549883) (xy 461.922168 -11.566096) (xy 462.049238 -11.590336)
			(xy 462.174534 -11.622506) (xy 462.297564 -11.662481) (xy 462.41784 -11.710102) (xy 462.534889 -11.765181)
			(xy 462.648249 -11.827501) (xy 462.757472 -11.896816) (xy 462.862127 -11.972852) (xy 462.961801 -12.05531)
			(xy 463.056101 -12.143863) (xy 463.144654 -12.238163) (xy 463.227112 -12.337837) (xy 463.303148 -12.442492)
			(xy 463.372463 -12.551715) (xy 463.434783 -12.665075) (xy 463.489862 -12.782124) (xy 463.537483 -12.9024)
			(xy 463.577458 -13.02543) (xy 463.609628 -13.150726) (xy 463.633868 -13.277796) (xy 463.650081 -13.406136)
			(xy 463.658204 -13.535242) (xy 463.658712 -13.599922) (xy 463.658712 -15.200122) (xy 463.658204 -15.264802)
			(xy 463.650081 -15.393908) (xy 463.633868 -15.522248) (xy 463.609628 -15.649318) (xy 463.577458 -15.774614)
			(xy 463.537483 -15.897644) (xy 463.489862 -16.01792) (xy 463.434783 -16.134969) (xy 463.372463 -16.248329)
			(xy 463.303148 -16.357552) (xy 463.227112 -16.462207) (xy 463.144654 -16.561881) (xy 463.056101 -16.656181)
			(xy 462.961801 -16.744734) (xy 462.862127 -16.827192) (xy 462.757472 -16.903228) (xy 462.648249 -16.972543)
			(xy 462.534889 -17.034863) (xy 462.41784 -17.089942) (xy 462.297564 -17.137563) (xy 462.174534 -17.177538)
			(xy 462.049238 -17.209708) (xy 461.922168 -17.233948) (xy 461.793828 -17.250161) (xy 461.664722 -17.258284)
			(xy 461.535362 -17.258284) (xy 461.406256 -17.250161) (xy 461.277916 -17.233948) (xy 461.150846 -17.209708)
			(xy 461.02555 -17.177538) (xy 460.90252 -17.137563) (xy 460.782244 -17.089942) (xy 460.665195 -17.034863)
			(xy 460.551835 -16.972543) (xy 460.442612 -16.903228) (xy 460.337957 -16.827192) (xy 460.238283 -16.744734)
			(xy 460.143983 -16.656181) (xy 460.05543 -16.561881) (xy 459.972972 -16.462207) (xy 459.896936 -16.357552)
			(xy 459.827621 -16.248329) (xy 459.765301 -16.134969) (xy 459.710222 -16.01792) (xy 459.662601 -15.897644)
			(xy 459.622626 -15.774614) (xy 459.590456 -15.649318) (xy 459.566216 -15.522248) (xy 459.550003 -15.393908)
			(xy 459.54188 -15.264802) (xy 459.541372 -15.200122) (xy 455.884547 -15.200122) (xy 454.330816 -16.754094)
			(xy 454.328008 -16.756975) (xy 454.32328 -16.763482) (xy 454.321418 -16.767048) (xy 454.318935 -16.772434)
			(xy 454.316243 -16.78398) (xy 454.316084 -16.789908) (xy 454.316084 -18.264632) (xy 454.446638 -18.264632)
			(xy 454.450709 -18.20901) (xy 454.462835 -18.154573) (xy 454.482758 -18.102482) (xy 454.510054 -18.053847)
			(xy 454.54414 -18.009704) (xy 454.584289 -17.970995) (xy 454.629647 -17.938544) (xy 454.679247 -17.913043)
			(xy 454.732031 -17.895036) (xy 454.786874 -17.884906) (xy 454.842608 -17.882869) (xy 454.898045 -17.888969)
			(xy 454.952002 -17.903075) (xy 455.003331 -17.924887) (xy 455.050937 -17.953941) (xy 455.093805 -17.989616)
			(xy 455.131022 -18.031153) (xy 455.161795 -18.077666) (xy 455.185467 -18.128163) (xy 455.201535 -18.18157)
			(xy 455.209655 -18.236746) (xy 455.210164 -18.264632) (xy 455.209655 -18.292518) (xy 455.201535 -18.347694)
			(xy 455.185467 -18.401101) (xy 455.161795 -18.451598) (xy 455.131022 -18.498111) (xy 455.093805 -18.539648)
			(xy 455.050937 -18.575323) (xy 455.003331 -18.604377) (xy 454.952002 -18.626189) (xy 454.898045 -18.640295)
			(xy 454.842608 -18.646395) (xy 454.786874 -18.644358) (xy 454.732031 -18.634228) (xy 454.679247 -18.616221)
			(xy 454.629647 -18.59072) (xy 454.584289 -18.558269) (xy 454.54414 -18.51956) (xy 454.510054 -18.475417)
			(xy 454.482758 -18.426782) (xy 454.462835 -18.374691) (xy 454.450709 -18.320254) (xy 454.446638 -18.264632)
			(xy 454.316084 -18.264632) (xy 454.316084 -19.633184) (xy 454.554334 -19.633184) (xy 454.558405 -19.577562)
			(xy 454.570531 -19.523125) (xy 454.590454 -19.471034) (xy 454.61775 -19.422399) (xy 454.651836 -19.378256)
			(xy 454.691985 -19.339547) (xy 454.737343 -19.307096) (xy 454.786943 -19.281595) (xy 454.839727 -19.263588)
			(xy 454.89457 -19.253458) (xy 454.950304 -19.251421) (xy 455.005741 -19.257521) (xy 455.059698 -19.271627)
			(xy 455.111027 -19.293439) (xy 455.158633 -19.322493) (xy 455.201501 -19.358168) (xy 455.238718 -19.399705)
			(xy 455.269491 -19.446218) (xy 455.293163 -19.496715) (xy 455.309231 -19.550122) (xy 455.317351 -19.605298)
			(xy 455.31786 -19.633184) (xy 455.317351 -19.66107) (xy 455.309231 -19.716246) (xy 455.293163 -19.769653)
			(xy 455.269491 -19.82015) (xy 455.238718 -19.866663) (xy 455.201501 -19.9082) (xy 455.158633 -19.943875)
			(xy 455.111027 -19.972929) (xy 455.059698 -19.994741) (xy 455.005741 -20.008847) (xy 454.950304 -20.014947)
			(xy 454.89457 -20.01291) (xy 454.839727 -20.00278) (xy 454.786943 -19.984773) (xy 454.737343 -19.959272)
			(xy 454.691985 -19.926821) (xy 454.651836 -19.888112) (xy 454.61775 -19.843969) (xy 454.590454 -19.795334)
			(xy 454.570531 -19.743243) (xy 454.558405 -19.688806) (xy 454.554334 -19.633184) (xy 454.316084 -19.633184)
			(xy 454.316084 -20.755102) (xy 454.45883 -20.755102) (xy 454.462901 -20.69948) (xy 454.475027 -20.645043)
			(xy 454.49495 -20.592952) (xy 454.522246 -20.544317) (xy 454.556332 -20.500174) (xy 454.596481 -20.461465)
			(xy 454.641839 -20.429014) (xy 454.691439 -20.403513) (xy 454.744223 -20.385506) (xy 454.799066 -20.375376)
			(xy 454.8548 -20.373339) (xy 454.910237 -20.379439) (xy 454.964194 -20.393545) (xy 455.015523 -20.415357)
			(xy 455.063129 -20.444411) (xy 455.105997 -20.480086) (xy 455.143214 -20.521623) (xy 455.173987 -20.568136)
			(xy 455.197659 -20.618633) (xy 455.213727 -20.67204) (xy 455.221847 -20.727216) (xy 455.222356 -20.755102)
			(xy 455.221847 -20.782988) (xy 455.213727 -20.838164) (xy 455.197659 -20.891571) (xy 455.173987 -20.942068)
			(xy 455.143214 -20.988581) (xy 455.105997 -21.030118) (xy 455.063129 -21.065793) (xy 455.015523 -21.094847)
			(xy 454.964194 -21.116659) (xy 454.910237 -21.130765) (xy 454.8548 -21.136865) (xy 454.799066 -21.134828)
			(xy 454.744223 -21.124698) (xy 454.691439 -21.106691) (xy 454.641839 -21.08119) (xy 454.596481 -21.048739)
			(xy 454.556332 -21.01003) (xy 454.522246 -20.965887) (xy 454.49495 -20.917252) (xy 454.475027 -20.865161)
			(xy 454.462901 -20.810724) (xy 454.45883 -20.755102) (xy 454.316084 -20.755102) (xy 454.316084 -23.698454)
			(xy 454.316084 -23.701248) (xy 454.316967 -23.710335) (xy 454.32428 -23.72705) (xy 454.336969 -23.74016)
			(xy 454.34504 -23.744428) (xy 454.373996 -23.75662) (xy 454.428352 -23.77948) (xy 454.433032 -23.781328)
			(xy 454.442881 -23.783382) (xy 454.44791 -23.783544) (xy 454.457816 -23.783544) (xy 454.467468 -23.77948)
			(xy 454.476104 -23.775924) (xy 454.48474 -23.771352) (xy 454.494646 -23.765002) (xy 454.497694 -23.762208)
			(xy 454.518894 -23.743637) (xy 454.565727 -23.712283) (xy 454.616652 -23.688138) (xy 454.670568 -23.671724)
			(xy 454.726309 -23.663397) (xy 454.754488 -23.662894) (xy 454.754742 -23.662894) (xy 454.781991 -23.663383)
			(xy 454.835934 -23.671144) (xy 454.888223 -23.686503) (xy 454.937795 -23.709146) (xy 454.98364 -23.738613)
			(xy 455.024825 -23.774305) (xy 455.060512 -23.815494) (xy 455.089974 -23.861342) (xy 455.112612 -23.910916)
			(xy 455.127965 -23.963207) (xy 455.13572 -24.017151) (xy 455.13572 -24.071649) (xy 455.127965 -24.125593)
			(xy 455.112612 -24.177884) (xy 455.089974 -24.227458) (xy 455.060512 -24.273306) (xy 455.024825 -24.314495)
			(xy 454.98364 -24.350187) (xy 454.937795 -24.379654) (xy 454.888223 -24.402297) (xy 454.835934 -24.417656)
			(xy 454.781991 -24.425417) (xy 454.754742 -24.42591) (xy 454.754488 -24.42591) (xy 454.726306 -24.42541)
			(xy 454.670554 -24.417125) (xy 454.61663 -24.400724) (xy 454.565707 -24.376564) (xy 454.518895 -24.345171)
			(xy 454.497694 -24.326596) (xy 454.494646 -24.323802) (xy 454.481438 -24.315166) (xy 454.479406 -24.31415)
			(xy 454.45426 -24.302974) (xy 454.446386 -24.300434) (xy 454.440036 -24.299164) (xy 454.427844 -24.29764)
			(xy 454.416668 -24.30145) (xy 454.411446 -24.303431) (xy 454.401965 -24.309333) (xy 454.397872 -24.313134)
			(xy 454.388728 -24.322024) (xy 454.385201 -24.325343) (xy 454.377149 -24.330721) (xy 454.372726 -24.332692)
			(xy 454.372472 -24.332692) (xy 454.34377 -24.345138) (xy 454.338228 -24.348194) (xy 454.328727 -24.356551)
			(xy 454.324974 -24.361648) (xy 454.324212 -24.362664) (xy 454.320074 -24.369563) (xy 454.315931 -24.385101)
			(xy 454.316084 -24.393144) (xy 454.316084 -30.745738) (xy 457.614517 -30.745738) (xy 457.614517 -30.616598)
			(xy 457.622467 -30.487703) (xy 457.638337 -30.359543) (xy 457.662066 -30.232602) (xy 457.693565 -30.107363)
			(xy 457.732714 -29.9843) (xy 457.779365 -29.863881) (xy 457.83334 -29.746562) (xy 457.894435 -29.632788)
			(xy 457.962418 -29.522991) (xy 458.037032 -29.417588) (xy 458.117993 -29.316978) (xy 458.204993 -29.221543)
			(xy 458.297704 -29.131644) (xy 458.395774 -29.047623) (xy 458.498829 -28.969799) (xy 458.60648 -28.898467)
			(xy 458.718319 -28.833897) (xy 458.83392 -28.776335) (xy 458.952845 -28.725998) (xy 459.074644 -28.683078)
			(xy 459.198854 -28.647737) (xy 459.325003 -28.62011) (xy 459.452615 -28.600301) (xy 459.581204 -28.588385)
			(xy 459.710282 -28.584409) (xy 459.83936 -28.588385) (xy 459.967949 -28.600301) (xy 460.095561 -28.62011)
			(xy 460.22171 -28.647737) (xy 460.34592 -28.683078) (xy 460.467719 -28.725998) (xy 460.586644 -28.776335)
			(xy 460.702245 -28.833897) (xy 460.814084 -28.898467) (xy 460.921735 -28.969799) (xy 461.02479 -29.047623)
			(xy 461.12286 -29.131644) (xy 461.215571 -29.221543) (xy 461.302571 -29.316978) (xy 461.383532 -29.417588)
			(xy 461.458146 -29.522991) (xy 461.526129 -29.632788) (xy 461.587224 -29.746562) (xy 461.641199 -29.863881)
			(xy 461.68785 -29.9843) (xy 461.726999 -30.107363) (xy 461.758498 -30.232602) (xy 461.782227 -30.359543)
			(xy 461.798097 -30.487703) (xy 461.806047 -30.616598) (xy 461.806544 -30.681168) (xy 461.806047 -30.745738)
			(xy 461.798097 -30.874633) (xy 461.782227 -31.002793) (xy 461.758498 -31.129734) (xy 461.726999 -31.254973)
			(xy 461.68785 -31.378036) (xy 461.641199 -31.498455) (xy 461.587224 -31.615774) (xy 461.526129 -31.729548)
			(xy 461.458146 -31.839345) (xy 461.383532 -31.944748) (xy 461.302571 -32.045358) (xy 461.215571 -32.140793)
			(xy 461.12286 -32.230692) (xy 461.02479 -32.314713) (xy 460.921735 -32.392537) (xy 460.814084 -32.463869)
			(xy 460.702245 -32.528439) (xy 460.586644 -32.586001) (xy 460.467719 -32.636338) (xy 460.34592 -32.679258)
			(xy 460.22171 -32.714599) (xy 460.095561 -32.742226) (xy 459.967949 -32.762035) (xy 459.83936 -32.773951)
			(xy 459.710282 -32.777928) (xy 459.581204 -32.773951) (xy 459.452615 -32.762035) (xy 459.325003 -32.742226)
			(xy 459.198854 -32.714599) (xy 459.074644 -32.679258) (xy 458.952845 -32.636338) (xy 458.83392 -32.586001)
			(xy 458.718319 -32.528439) (xy 458.60648 -32.463869) (xy 458.498829 -32.392537) (xy 458.395774 -32.314713)
			(xy 458.297704 -32.230692) (xy 458.204993 -32.140793) (xy 458.117993 -32.045358) (xy 458.037032 -31.944748)
			(xy 457.962418 -31.839345) (xy 457.894435 -31.729548) (xy 457.83334 -31.615774) (xy 457.779365 -31.498455)
			(xy 457.732714 -31.378036) (xy 457.693565 -31.254973) (xy 457.662066 -31.129734) (xy 457.638337 -31.002793)
			(xy 457.622467 -30.874633) (xy 457.614517 -30.745738) (xy 454.316084 -30.745738) (xy 454.316084 -73.78192)
			(xy 454.3171 -73.791572) (xy 454.318729 -73.798815) (xy 454.325571 -73.811984) (xy 454.330562 -73.81748)
			(xy 455.298048 -74.784966) (xy 458.026514 -74.784966) (xy 458.030585 -74.729344) (xy 458.042711 -74.674907)
			(xy 458.062634 -74.622816) (xy 458.08993 -74.574181) (xy 458.124016 -74.530038) (xy 458.164165 -74.491329)
			(xy 458.209523 -74.458878) (xy 458.259123 -74.433377) (xy 458.311907 -74.41537) (xy 458.36675 -74.40524)
			(xy 458.422484 -74.403203) (xy 458.477921 -74.409303) (xy 458.531878 -74.423409) (xy 458.583207 -74.445221)
			(xy 458.630813 -74.474275) (xy 458.673681 -74.50995) (xy 458.710898 -74.551487) (xy 458.741671 -74.598)
			(xy 458.765343 -74.648497) (xy 458.781411 -74.701904) (xy 458.789531 -74.75708) (xy 458.79004 -74.784966)
			(xy 458.789531 -74.812852) (xy 458.781411 -74.868028) (xy 458.765343 -74.921435) (xy 458.741671 -74.971932)
			(xy 458.710898 -75.018445) (xy 458.673681 -75.059982) (xy 458.630813 -75.095657) (xy 458.583207 -75.124711)
			(xy 458.531878 -75.146523) (xy 458.477921 -75.160629) (xy 458.422484 -75.166729) (xy 458.36675 -75.164692)
			(xy 458.311907 -75.154562) (xy 458.259123 -75.136555) (xy 458.209523 -75.111054) (xy 458.164165 -75.078603)
			(xy 458.124016 -75.039894) (xy 458.08993 -74.995751) (xy 458.062634 -74.947116) (xy 458.042711 -74.895025)
			(xy 458.030585 -74.840588) (xy 458.026514 -74.784966) (xy 455.298048 -74.784966) (xy 455.78522 -75.272138)
			(xy 455.792069 -75.279535) (xy 455.799802 -75.298134) (xy 455.800206 -75.308206) (xy 455.800206 -76.441808)
			(xy 458.137766 -76.441808) (xy 458.141837 -76.386186) (xy 458.153963 -76.331749) (xy 458.173886 -76.279658)
			(xy 458.201182 -76.231023) (xy 458.235268 -76.18688) (xy 458.275417 -76.148171) (xy 458.320775 -76.11572)
			(xy 458.370375 -76.090219) (xy 458.423159 -76.072212) (xy 458.478002 -76.062082) (xy 458.533736 -76.060045)
			(xy 458.589173 -76.066145) (xy 458.64313 -76.080251) (xy 458.694459 -76.102063) (xy 458.742065 -76.131117)
			(xy 458.784933 -76.166792) (xy 458.82215 -76.208329) (xy 458.852923 -76.254842) (xy 458.876595 -76.305339)
			(xy 458.892663 -76.358746) (xy 458.900783 -76.413922) (xy 458.901292 -76.441808) (xy 458.900783 -76.469694)
			(xy 458.892663 -76.52487) (xy 458.876595 -76.578277) (xy 458.852923 -76.628774) (xy 458.82215 -76.675287)
			(xy 458.784933 -76.716824) (xy 458.742065 -76.752499) (xy 458.694459 -76.781553) (xy 458.64313 -76.803365)
			(xy 458.589173 -76.817471) (xy 458.533736 -76.823571) (xy 458.478002 -76.821534) (xy 458.423159 -76.811404)
			(xy 458.370375 -76.793397) (xy 458.320775 -76.767896) (xy 458.275417 -76.735445) (xy 458.235268 -76.696736)
			(xy 458.201182 -76.652593) (xy 458.173886 -76.603958) (xy 458.153963 -76.551867) (xy 458.141837 -76.49743)
			(xy 458.137766 -76.441808) (xy 455.800206 -76.441808) (xy 455.800206 -76.734416) (xy 455.80046 -76.740512)
			(xy 455.801694 -76.748171) (xy 455.808163 -76.762264) (xy 455.81316 -76.768198) (xy 455.833959 -76.788011)
			(xy 455.869954 -76.832775) (xy 455.89883 -76.88243) (xy 455.919935 -76.935853) (xy 455.932791 -76.991836)
			(xy 455.937107 -77.049115) (xy 455.932786 -77.106393) (xy 455.919926 -77.162376) (xy 455.898817 -77.215797)
			(xy 455.869937 -77.26545) (xy 455.833938 -77.310211) (xy 455.81316 -77.330046) (xy 455.808175 -77.335989)
			(xy 455.801697 -77.350076) (xy 455.80046 -77.357732) (xy 455.800206 -77.363828) (xy 455.800206 -103.685653)
			(xy 456.792771 -103.685653) (xy 456.792771 -103.631147) (xy 456.800529 -103.577195) (xy 456.815886 -103.524896)
			(xy 456.838531 -103.475315) (xy 456.868001 -103.429462) (xy 456.903697 -103.38827) (xy 456.944893 -103.352578)
			(xy 456.990749 -103.323112) (xy 457.040332 -103.300473) (xy 457.092632 -103.285121) (xy 457.146585 -103.277369)
			(xy 457.173838 -103.276908) (xy 457.200153 -103.277348) (xy 457.252283 -103.284588) (xy 457.302926 -103.298912)
			(xy 457.351125 -103.32005) (xy 457.395968 -103.347601) (xy 457.436606 -103.381044) (xy 457.454762 -103.400098)
			(xy 457.462296 -103.407484) (xy 457.481567 -103.416017) (xy 457.4921 -103.416608) (xy 457.566776 -103.416608)
			(xy 457.577325 -103.416077) (xy 457.596621 -103.407543) (xy 457.604114 -103.400098) (xy 457.623934 -103.37931)
			(xy 457.668706 -103.343335) (xy 457.718364 -103.314475) (xy 457.771786 -103.293382) (xy 457.827765 -103.280533)
			(xy 457.885038 -103.276218) (xy 457.942311 -103.280533) (xy 457.99829 -103.293382) (xy 458.051712 -103.314475)
			(xy 458.10137 -103.343335) (xy 458.146142 -103.37931) (xy 458.165962 -103.400098) (xy 458.173496 -103.407484)
			(xy 458.192767 -103.416017) (xy 458.2033 -103.416608) (xy 458.277976 -103.416608) (xy 458.288525 -103.416077)
			(xy 458.307821 -103.407543) (xy 458.315314 -103.400098) (xy 458.333469 -103.381042) (xy 458.374099 -103.347585)
			(xy 458.418939 -103.320026) (xy 458.46714 -103.298888) (xy 458.517788 -103.284571) (xy 458.569922 -103.277346)
			(xy 458.596238 -103.276908) (xy 458.623489 -103.277364) (xy 458.677434 -103.285126) (xy 458.729727 -103.300485)
			(xy 458.779301 -103.323129) (xy 458.825149 -103.352598) (xy 458.866336 -103.388291) (xy 458.902025 -103.429482)
			(xy 458.931489 -103.475332) (xy 458.954129 -103.524909) (xy 458.969482 -103.577203) (xy 458.977238 -103.631149)
			(xy 458.977238 -103.685651) (xy 458.969482 -103.739597) (xy 458.954129 -103.791891) (xy 458.931489 -103.841468)
			(xy 458.902025 -103.887319) (xy 458.866336 -103.928509) (xy 458.825149 -103.964202) (xy 458.779301 -103.993671)
			(xy 458.729727 -104.016315) (xy 458.677434 -104.031674) (xy 458.623489 -104.039436) (xy 458.596238 -104.039924)
			(xy 458.569923 -104.03949) (xy 458.517793 -104.032247) (xy 458.46715 -104.017921) (xy 458.418952 -103.996782)
			(xy 458.374109 -103.969231) (xy 458.33347 -103.935788) (xy 458.315314 -103.916734) (xy 458.307785 -103.909341)
			(xy 458.288511 -103.900811) (xy 458.277976 -103.900224) (xy 458.2033 -103.900224) (xy 458.192748 -103.900733)
			(xy 458.173452 -103.909281) (xy 458.165962 -103.916734) (xy 458.146142 -103.937522) (xy 458.10137 -103.973497)
			(xy 458.051712 -104.002357) (xy 457.99829 -104.02345) (xy 457.942311 -104.036299) (xy 457.885038 -104.040614)
			(xy 457.827765 -104.036299) (xy 457.771786 -104.02345) (xy 457.718364 -104.002357) (xy 457.668706 -103.973497)
			(xy 457.623934 -103.937522) (xy 457.604114 -103.916734) (xy 457.596585 -103.909341) (xy 457.577311 -103.900811)
			(xy 457.566776 -103.900224) (xy 457.4921 -103.900224) (xy 457.481548 -103.900733) (xy 457.462252 -103.909281)
			(xy 457.454762 -103.916734) (xy 457.436625 -103.935807) (xy 457.39599 -103.969262) (xy 457.351146 -103.996817)
			(xy 457.302942 -104.017953) (xy 457.252291 -104.032266) (xy 457.200155 -104.039487) (xy 457.173838 -104.039924)
			(xy 457.146585 -104.039431) (xy 457.092632 -104.031679) (xy 457.040332 -104.016327) (xy 456.990749 -103.993688)
			(xy 456.944893 -103.964222) (xy 456.903697 -103.92853) (xy 456.868001 -103.887338) (xy 456.838531 -103.841485)
			(xy 456.815886 -103.791904) (xy 456.800529 -103.739605) (xy 456.792771 -103.685653) (xy 455.800206 -103.685653)
			(xy 455.800206 -106.802446) (xy 456.721028 -106.802446) (xy 456.721028 -106.747954) (xy 456.728782 -106.694018)
			(xy 456.744133 -106.641733) (xy 456.766768 -106.592166) (xy 456.796226 -106.546323) (xy 456.831909 -106.50514)
			(xy 456.873088 -106.469453) (xy 456.918927 -106.439989) (xy 456.968492 -106.417349) (xy 457.020775 -106.401992)
			(xy 457.07471 -106.394231) (xy 457.101956 -106.393742) (xy 457.128272 -106.394159) (xy 457.180403 -106.401402)
			(xy 457.231047 -106.41573) (xy 457.279246 -106.436872) (xy 457.324089 -106.464428) (xy 457.364725 -106.497876)
			(xy 457.38288 -106.516932) (xy 457.390416 -106.524317) (xy 457.409685 -106.532853) (xy 457.420218 -106.533442)
			(xy 457.494894 -106.533442) (xy 457.505443 -106.532911) (xy 457.524738 -106.524376) (xy 457.532232 -106.516932)
			(xy 457.552052 -106.496144) (xy 457.596824 -106.460169) (xy 457.646482 -106.431309) (xy 457.699904 -106.410216)
			(xy 457.755883 -106.397367) (xy 457.813156 -106.393052) (xy 457.870429 -106.397367) (xy 457.926408 -106.410216)
			(xy 457.97983 -106.431309) (xy 458.029488 -106.460169) (xy 458.07426 -106.496144) (xy 458.09408 -106.516932)
			(xy 458.101616 -106.524317) (xy 458.120885 -106.532853) (xy 458.131418 -106.533442) (xy 458.206094 -106.533442)
			(xy 458.216643 -106.532911) (xy 458.235938 -106.524376) (xy 458.243432 -106.516932) (xy 458.261585 -106.497874)
			(xy 458.302215 -106.464416) (xy 458.347055 -106.436856) (xy 458.395257 -106.415718) (xy 458.445905 -106.401402)
			(xy 458.49804 -106.394179) (xy 458.524356 -106.393742) (xy 458.551614 -106.394102) (xy 458.605577 -106.401855)
			(xy 458.657887 -106.417209) (xy 458.70748 -106.439852) (xy 458.753344 -106.469323) (xy 458.794548 -106.505021)
			(xy 458.830251 -106.54622) (xy 458.859727 -106.592082) (xy 458.882375 -106.641671) (xy 458.897736 -106.69398)
			(xy 458.905495 -106.747942) (xy 458.905495 -106.802458) (xy 458.897736 -106.85642) (xy 458.882375 -106.908729)
			(xy 458.859727 -106.958318) (xy 458.830251 -107.00418) (xy 458.794548 -107.045379) (xy 458.753344 -107.081077)
			(xy 458.70748 -107.110548) (xy 458.657887 -107.133191) (xy 458.605577 -107.148545) (xy 458.551615 -107.156298)
			(xy 458.524356 -107.156758) (xy 458.49804 -107.156333) (xy 458.44591 -107.149092) (xy 458.395265 -107.134765)
			(xy 458.347066 -107.113625) (xy 458.302224 -107.08607) (xy 458.261587 -107.052624) (xy 458.243432 -107.033568)
			(xy 458.235891 -107.026188) (xy 458.216626 -107.017649) (xy 458.206094 -107.017058) (xy 458.131418 -107.017058)
			(xy 458.12087 -107.017596) (xy 458.101575 -107.026126) (xy 458.09408 -107.033568) (xy 458.07426 -107.054356)
			(xy 458.029488 -107.090331) (xy 457.97983 -107.119191) (xy 457.926408 -107.140284) (xy 457.870429 -107.153133)
			(xy 457.813156 -107.157448) (xy 457.755883 -107.153133) (xy 457.699904 -107.140284) (xy 457.646482 -107.119191)
			(xy 457.596824 -107.090331) (xy 457.552052 -107.054356) (xy 457.532232 -107.033568) (xy 457.524691 -107.026188)
			(xy 457.505426 -107.017649) (xy 457.494894 -107.017058) (xy 457.420218 -107.017058) (xy 457.40967 -107.017596)
			(xy 457.390375 -107.026126) (xy 457.38288 -107.033568) (xy 457.364721 -107.05262) (xy 457.324093 -107.086079)
			(xy 457.279253 -107.113639) (xy 457.231053 -107.134778) (xy 457.180406 -107.149096) (xy 457.128272 -107.15632)
			(xy 457.101956 -107.156758) (xy 457.07471 -107.156169) (xy 457.020775 -107.148408) (xy 456.968492 -107.133051)
			(xy 456.918927 -107.110411) (xy 456.873088 -107.080947) (xy 456.831909 -107.04526) (xy 456.796226 -107.004077)
			(xy 456.766768 -106.958234) (xy 456.744133 -106.908667) (xy 456.728782 -106.856382) (xy 456.721028 -106.802446)
			(xy 455.800206 -106.802446) (xy 455.800206 -107.618784) (xy 455.800968 -107.626404) (xy 455.801222 -107.62869)
			(xy 455.801476 -107.629452) (xy 455.803508 -107.639866) (xy 455.807064 -107.650026) (xy 455.814684 -107.66679)
			(xy 455.820018 -107.672632) (xy 455.820526 -107.67314) (xy 455.839879 -107.694487) (xy 455.872594 -107.741917)
			(xy 455.897807 -107.793726) (xy 455.914946 -107.848736) (xy 455.923621 -107.905697) (xy 455.924158 -107.934506)
			(xy 455.923606 -107.964019) (xy 455.914515 -108.022341) (xy 455.896552 -108.078567) (xy 455.870144 -108.131356)
			(xy 455.835921 -108.179448) (xy 455.8157 -108.200952) (xy 455.815446 -108.201206) (xy 455.810874 -108.206032)
			(xy 455.806556 -108.213144) (xy 455.803752 -108.218586) (xy 455.800551 -108.230399) (xy 455.800206 -108.236512)
			(xy 455.800206 -108.26623) (xy 455.800206 -108.2675) (xy 455.800543 -108.273613) (xy 455.803756 -108.285423)
			(xy 455.806556 -108.290868) (xy 455.810874 -108.29798) (xy 455.815446 -108.302806) (xy 455.8157 -108.30306)
			(xy 455.835919 -108.324567) (xy 455.870148 -108.372656) (xy 455.896561 -108.425444) (xy 455.914527 -108.48167)
			(xy 455.923619 -108.539993) (xy 455.924158 -108.569506) (xy 455.92363 -108.598316) (xy 455.914961 -108.655279)
			(xy 455.897822 -108.71029) (xy 455.872601 -108.762096) (xy 455.839874 -108.809519) (xy 455.820526 -108.830872)
			(xy 455.820018 -108.83138) (xy 455.814684 -108.837222) (xy 455.804778 -108.858812) (xy 455.800206 -108.868972)
			(xy 455.800206 -109.502448) (xy 457.714602 -109.502448) (xy 457.718673 -109.446826) (xy 457.730799 -109.392389)
			(xy 457.750722 -109.340298) (xy 457.778018 -109.291663) (xy 457.812104 -109.24752) (xy 457.852253 -109.208811)
			(xy 457.897611 -109.17636) (xy 457.947211 -109.150859) (xy 457.999995 -109.132852) (xy 458.054838 -109.122722)
			(xy 458.110572 -109.120685) (xy 458.166009 -109.126785) (xy 458.219966 -109.140891) (xy 458.271295 -109.162703)
			(xy 458.318901 -109.191757) (xy 458.361769 -109.227432) (xy 458.398986 -109.268969) (xy 458.429759 -109.315482)
			(xy 458.453431 -109.365979) (xy 458.469499 -109.419386) (xy 458.477619 -109.474562) (xy 458.478128 -109.502448)
			(xy 458.477619 -109.530334) (xy 458.469499 -109.58551) (xy 458.453431 -109.638917) (xy 458.429759 -109.689414)
			(xy 458.398986 -109.735927) (xy 458.361769 -109.777464) (xy 458.318901 -109.813139) (xy 458.271295 -109.842193)
			(xy 458.219966 -109.864005) (xy 458.166009 -109.878111) (xy 458.110572 -109.884211) (xy 458.054838 -109.882174)
			(xy 457.999995 -109.872044) (xy 457.947211 -109.854037) (xy 457.897611 -109.828536) (xy 457.852253 -109.796085)
			(xy 457.812104 -109.757376) (xy 457.778018 -109.713233) (xy 457.750722 -109.664598) (xy 457.730799 -109.612507)
			(xy 457.718673 -109.55807) (xy 457.714602 -109.502448) (xy 455.800206 -109.502448) (xy 455.800206 -110.002828)
			(xy 455.800308 -110.00744) (xy 455.801971 -110.016512) (xy 455.803508 -110.020862) (xy 455.806302 -110.028228)
			(xy 455.80808 -110.032546) (xy 455.818494 -110.04677) (xy 455.821404 -110.049489) (xy 455.827912 -110.054081)
			(xy 455.831448 -110.055914) (xy 455.84872 -110.064296) (xy 455.853985 -110.066738) (xy 455.865272 -110.069434)
			(xy 455.871072 -110.06963) (xy 455.93 -110.06963) (xy 455.936295 -110.069442) (xy 455.948502 -110.06636)
			(xy 455.95413 -110.063534) (xy 455.973688 -110.05312) (xy 455.983086 -110.046516) (xy 455.984864 -110.044992)
			(xy 455.986896 -110.043214) (xy 455.987658 -110.042198) (xy 455.990198 -110.038642) (xy 455.990706 -110.038134)
			(xy 456.006421 -110.017849) (xy 456.043063 -109.98193) (xy 456.084813 -109.952102) (xy 456.13067 -109.92908)
			(xy 456.179532 -109.913417) (xy 456.230227 -109.905489) (xy 456.255882 -109.905038) (xy 456.281869 -109.90552)
			(xy 456.333202 -109.913648) (xy 456.382632 -109.929706) (xy 456.428942 -109.953299) (xy 456.47099 -109.983847)
			(xy 456.507741 -110.020597) (xy 456.538291 -110.062643) (xy 456.561887 -110.108951) (xy 456.577948 -110.15838)
			(xy 456.586079 -110.209713) (xy 456.586079 -110.261687) (xy 456.577948 -110.31302) (xy 456.561887 -110.362449)
			(xy 456.538291 -110.408757) (xy 456.507741 -110.450803) (xy 456.47099 -110.487553) (xy 456.43231 -110.515654)
			(xy 459.128112 -110.515654) (xy 459.132183 -110.460032) (xy 459.144309 -110.405595) (xy 459.164232 -110.353504)
			(xy 459.191528 -110.304869) (xy 459.225614 -110.260726) (xy 459.265763 -110.222017) (xy 459.311121 -110.189566)
			(xy 459.360721 -110.164065) (xy 459.413505 -110.146058) (xy 459.468348 -110.135928) (xy 459.524082 -110.133891)
			(xy 459.579519 -110.139991) (xy 459.633476 -110.154097) (xy 459.684805 -110.175909) (xy 459.732411 -110.204963)
			(xy 459.775279 -110.240638) (xy 459.812496 -110.282175) (xy 459.843269 -110.328688) (xy 459.866941 -110.379185)
			(xy 459.883009 -110.432592) (xy 459.891129 -110.487768) (xy 459.891638 -110.515654) (xy 459.891129 -110.54354)
			(xy 459.883009 -110.598716) (xy 459.866941 -110.652123) (xy 459.843269 -110.70262) (xy 459.812496 -110.749133)
			(xy 459.775279 -110.79067) (xy 459.732411 -110.826345) (xy 459.684805 -110.855399) (xy 459.633476 -110.877211)
			(xy 459.579519 -110.891317) (xy 459.524082 -110.897417) (xy 459.468348 -110.89538) (xy 459.413505 -110.88525)
			(xy 459.360721 -110.867243) (xy 459.311121 -110.841742) (xy 459.265763 -110.809291) (xy 459.225614 -110.770582)
			(xy 459.191528 -110.726439) (xy 459.164232 -110.677804) (xy 459.144309 -110.625713) (xy 459.132183 -110.571276)
			(xy 459.128112 -110.515654) (xy 456.43231 -110.515654) (xy 456.428942 -110.518101) (xy 456.382632 -110.541694)
			(xy 456.333202 -110.557752) (xy 456.281869 -110.56588) (xy 456.255882 -110.566454) (xy 456.230228 -110.565969)
			(xy 456.179536 -110.558044) (xy 456.130676 -110.542385) (xy 456.084821 -110.51937) (xy 456.043069 -110.48955)
			(xy 456.006422 -110.45364) (xy 455.990706 -110.433358) (xy 455.990198 -110.43285) (xy 455.987658 -110.429294)
			(xy 455.986896 -110.428278) (xy 455.985118 -110.426754) (xy 455.983086 -110.424976) (xy 455.973942 -110.418626)
			(xy 455.951844 -110.406942) (xy 455.946682 -110.404617) (xy 455.935658 -110.402049) (xy 455.93 -110.401862)
			(xy 455.87666 -110.401862) (xy 455.865738 -110.403132) (xy 455.854054 -110.405926) (xy 455.843386 -110.409736)
			(xy 455.829416 -110.416594) (xy 455.818748 -110.424468) (xy 455.80808 -110.4392) (xy 455.807064 -110.441232)
			(xy 455.806302 -110.443264) (xy 455.803508 -110.45063) (xy 455.801965 -110.454978) (xy 455.800305 -110.464052)
			(xy 455.800206 -110.468664) (xy 455.800206 -110.903004) (xy 455.800306 -110.907616) (xy 455.801965 -110.91669)
			(xy 455.803508 -110.921038) (xy 455.806302 -110.928404) (xy 455.80808 -110.932722) (xy 455.818494 -110.946946)
			(xy 455.821407 -110.949662) (xy 455.827917 -110.954247) (xy 455.831448 -110.95609) (xy 455.84872 -110.964472)
			(xy 455.853986 -110.96691) (xy 455.865272 -110.969603) (xy 455.871072 -110.969806) (xy 455.93 -110.969806)
			(xy 455.936295 -110.969618) (xy 455.948501 -110.966534) (xy 455.95413 -110.96371) (xy 455.973688 -110.953296)
			(xy 455.983086 -110.946692) (xy 455.984864 -110.945168) (xy 455.986896 -110.94339) (xy 455.987658 -110.942374)
			(xy 455.990198 -110.938818) (xy 455.990706 -110.93831) (xy 456.006422 -110.918026) (xy 456.043065 -110.88211)
			(xy 456.084816 -110.852283) (xy 456.130672 -110.829263) (xy 456.179533 -110.813601) (xy 456.230227 -110.805674)
			(xy 456.255882 -110.805214) (xy 456.28187 -110.805696) (xy 456.333208 -110.813824) (xy 456.382641 -110.829884)
			(xy 456.428954 -110.853479) (xy 456.471005 -110.884029) (xy 456.507759 -110.920781) (xy 456.538312 -110.962831)
			(xy 456.561909 -111.009142) (xy 456.577972 -111.058575) (xy 456.586103 -111.109912) (xy 456.586103 -111.161888)
			(xy 456.577972 -111.213225) (xy 456.561909 -111.262658) (xy 456.538312 -111.308969) (xy 456.507759 -111.351019)
			(xy 456.471005 -111.387771) (xy 456.428954 -111.418321) (xy 456.382641 -111.441916) (xy 456.333208 -111.457976)
			(xy 456.28187 -111.466104) (xy 456.255882 -111.46663) (xy 456.230228 -111.466145) (xy 456.179537 -111.458219)
			(xy 456.130678 -111.44256) (xy 456.084823 -111.419544) (xy 456.043073 -111.389722) (xy 456.006429 -111.353811)
			(xy 455.990706 -111.333534) (xy 455.990198 -111.333026) (xy 455.987658 -111.32947) (xy 455.986896 -111.328454)
			(xy 455.985118 -111.32693) (xy 455.983086 -111.325152) (xy 455.973942 -111.318802) (xy 455.951844 -111.307118)
			(xy 455.946682 -111.304794) (xy 455.935658 -111.302227) (xy 455.93 -111.302038) (xy 455.87666 -111.302038)
			(xy 455.865738 -111.303308) (xy 455.854054 -111.306102) (xy 455.843386 -111.309912) (xy 455.829416 -111.31677)
			(xy 455.818748 -111.324644) (xy 455.80808 -111.339376) (xy 455.807064 -111.341408) (xy 455.806302 -111.34344)
			(xy 455.803508 -111.350806) (xy 455.801963 -111.355153) (xy 455.800299 -111.364227) (xy 455.800206 -111.36884)
			(xy 455.800206 -111.802926) (xy 455.800308 -111.807538) (xy 455.801971 -111.816611) (xy 455.803508 -111.82096)
			(xy 455.806302 -111.828326) (xy 455.80808 -111.832644) (xy 455.818494 -111.846868) (xy 455.821404 -111.849587)
			(xy 455.827912 -111.854179) (xy 455.831448 -111.856012) (xy 455.84872 -111.864394) (xy 455.853985 -111.866836)
			(xy 455.865272 -111.869532) (xy 455.871072 -111.869728) (xy 455.93 -111.869728) (xy 455.936295 -111.86954)
			(xy 455.948502 -111.866458) (xy 455.95413 -111.863632) (xy 455.973688 -111.853218) (xy 455.983086 -111.846614)
			(xy 455.984864 -111.844836) (xy 455.986896 -111.843312) (xy 455.987658 -111.842296) (xy 455.990198 -111.83874)
			(xy 455.990706 -111.838232) (xy 456.006421 -111.817947) (xy 456.043063 -111.782028) (xy 456.084814 -111.7522)
			(xy 456.13067 -111.729178) (xy 456.179532 -111.713515) (xy 456.230227 -111.705587) (xy 456.255882 -111.705136)
			(xy 456.281869 -111.705618) (xy 456.333203 -111.713746) (xy 456.382633 -111.729804) (xy 456.428943 -111.753398)
			(xy 456.470991 -111.783946) (xy 456.472699 -111.785654) (xy 457.757782 -111.785654) (xy 457.761853 -111.730032)
			(xy 457.773979 -111.675595) (xy 457.793902 -111.623504) (xy 457.821198 -111.574869) (xy 457.855284 -111.530726)
			(xy 457.895433 -111.492017) (xy 457.940791 -111.459566) (xy 457.990391 -111.434065) (xy 458.043175 -111.416058)
			(xy 458.098018 -111.405928) (xy 458.153752 -111.403891) (xy 458.209189 -111.409991) (xy 458.263146 -111.424097)
			(xy 458.314475 -111.445909) (xy 458.362081 -111.474963) (xy 458.404949 -111.510638) (xy 458.442166 -111.552175)
			(xy 458.472939 -111.598688) (xy 458.496611 -111.649185) (xy 458.512679 -111.702592) (xy 458.520799 -111.757768)
			(xy 458.521308 -111.785654) (xy 458.520799 -111.81354) (xy 458.512679 -111.868716) (xy 458.496611 -111.922123)
			(xy 458.472939 -111.97262) (xy 458.442166 -112.019133) (xy 458.404949 -112.06067) (xy 458.362081 -112.096345)
			(xy 458.314475 -112.125399) (xy 458.263146 -112.147211) (xy 458.209189 -112.161317) (xy 458.153752 -112.167417)
			(xy 458.098018 -112.16538) (xy 458.043175 -112.15525) (xy 457.990391 -112.137243) (xy 457.940791 -112.111742)
			(xy 457.895433 -112.079291) (xy 457.855284 -112.040582) (xy 457.821198 -111.996439) (xy 457.793902 -111.947804)
			(xy 457.773979 -111.895713) (xy 457.761853 -111.841276) (xy 457.757782 -111.785654) (xy 456.472699 -111.785654)
			(xy 456.507743 -111.820695) (xy 456.538293 -111.862742) (xy 456.561889 -111.90905) (xy 456.57795 -111.95848)
			(xy 456.586081 -112.009813) (xy 456.586081 -112.061787) (xy 456.57795 -112.11312) (xy 456.561889 -112.16255)
			(xy 456.538293 -112.208858) (xy 456.507743 -112.250905) (xy 456.470991 -112.287654) (xy 456.458187 -112.296956)
			(xy 459.194914 -112.296956) (xy 459.198985 -112.241334) (xy 459.211111 -112.186897) (xy 459.231034 -112.134806)
			(xy 459.25833 -112.086171) (xy 459.292416 -112.042028) (xy 459.332565 -112.003319) (xy 459.377923 -111.970868)
			(xy 459.427523 -111.945367) (xy 459.480307 -111.92736) (xy 459.53515 -111.91723) (xy 459.590884 -111.915193)
			(xy 459.646321 -111.921293) (xy 459.700278 -111.935399) (xy 459.751607 -111.957211) (xy 459.799213 -111.986265)
			(xy 459.842081 -112.02194) (xy 459.879298 -112.063477) (xy 459.910071 -112.10999) (xy 459.933743 -112.160487)
			(xy 459.949811 -112.213894) (xy 459.957931 -112.26907) (xy 459.95844 -112.296956) (xy 459.957931 -112.324842)
			(xy 459.949811 -112.380018) (xy 459.933743 -112.433425) (xy 459.910071 -112.483922) (xy 459.879298 -112.530435)
			(xy 459.842081 -112.571972) (xy 459.799213 -112.607647) (xy 459.751607 -112.636701) (xy 459.700278 -112.658513)
			(xy 459.646321 -112.672619) (xy 459.590884 -112.678719) (xy 459.53515 -112.676682) (xy 459.480307 -112.666552)
			(xy 459.427523 -112.648545) (xy 459.377923 -112.623044) (xy 459.332565 -112.590593) (xy 459.292416 -112.551884)
			(xy 459.25833 -112.507741) (xy 459.231034 -112.459106) (xy 459.211111 -112.407015) (xy 459.198985 -112.352578)
			(xy 459.194914 -112.296956) (xy 456.458187 -112.296956) (xy 456.428943 -112.318202) (xy 456.382633 -112.341796)
			(xy 456.333203 -112.357854) (xy 456.281869 -112.365982) (xy 456.255882 -112.366552) (xy 456.230228 -112.366067)
			(xy 456.179536 -112.358142) (xy 456.130677 -112.342483) (xy 456.084821 -112.319468) (xy 456.043069 -112.289647)
			(xy 456.006423 -112.253737) (xy 455.990706 -112.233456) (xy 455.990198 -112.232948) (xy 455.987658 -112.229392)
			(xy 455.986896 -112.228376) (xy 455.985118 -112.226852) (xy 455.983086 -112.225074) (xy 455.973942 -112.218724)
			(xy 455.951844 -112.20704) (xy 455.946682 -112.204715) (xy 455.935658 -112.202147) (xy 455.93 -112.20196)
			(xy 455.87666 -112.20196) (xy 455.865738 -112.20323) (xy 455.854054 -112.206024) (xy 455.843386 -112.209834)
			(xy 455.829416 -112.216692) (xy 455.818748 -112.224566) (xy 455.80808 -112.239298) (xy 455.807064 -112.24133)
			(xy 455.806302 -112.243362) (xy 455.803508 -112.250728) (xy 455.801965 -112.255076) (xy 455.800304 -112.26415)
			(xy 455.800206 -112.268762) (xy 455.800206 -112.702848) (xy 455.80031 -112.707459) (xy 455.801976 -112.716531)
			(xy 455.803508 -112.720882) (xy 455.806302 -112.728248) (xy 455.80808 -112.732566) (xy 455.818494 -112.74679)
			(xy 455.821405 -112.749508) (xy 455.827913 -112.754098) (xy 455.831448 -112.755934) (xy 455.84872 -112.764316)
			(xy 455.853986 -112.766757) (xy 455.865272 -112.769452) (xy 455.871072 -112.76965) (xy 455.93 -112.76965)
			(xy 455.936295 -112.769462) (xy 455.948502 -112.766381) (xy 455.95413 -112.763554) (xy 455.973688 -112.75314)
			(xy 455.983086 -112.746536) (xy 455.984864 -112.745012) (xy 455.986896 -112.743234) (xy 455.987658 -112.742218)
			(xy 455.990198 -112.738662) (xy 455.990706 -112.738154) (xy 456.006424 -112.717873) (xy 456.043069 -112.681962)
			(xy 456.084821 -112.652141) (xy 456.130676 -112.629125) (xy 456.179536 -112.613466) (xy 456.230228 -112.60554)
			(xy 456.255882 -112.605058) (xy 456.281875 -112.60554) (xy 456.333221 -112.61367) (xy 456.382663 -112.629732)
			(xy 456.428983 -112.653331) (xy 456.471042 -112.683886) (xy 456.507802 -112.720645) (xy 456.538359 -112.762701)
			(xy 456.561961 -112.80902) (xy 456.578026 -112.858462) (xy 456.586159 -112.909807) (xy 456.586159 -112.961793)
			(xy 456.578026 -113.013138) (xy 456.561961 -113.06258) (xy 456.538359 -113.108899) (xy 456.507802 -113.150955)
			(xy 456.471042 -113.187714) (xy 456.428983 -113.218269) (xy 456.382663 -113.241868) (xy 456.333221 -113.25793)
			(xy 456.281875 -113.26606) (xy 456.255882 -113.266474) (xy 456.230229 -113.265989) (xy 456.179539 -113.258062)
			(xy 456.130682 -113.242401) (xy 456.08483 -113.219382) (xy 456.043083 -113.189557) (xy 456.006444 -113.153643)
			(xy 455.990706 -113.133378) (xy 455.990198 -113.13287) (xy 455.987658 -113.129314) (xy 455.986896 -113.128298)
			(xy 455.985118 -113.126774) (xy 455.983086 -113.124996) (xy 455.973942 -113.118646) (xy 455.951844 -113.106962)
			(xy 455.946681 -113.10464) (xy 455.935658 -113.102076) (xy 455.93 -113.101882) (xy 455.87666 -113.101882)
			(xy 455.865738 -113.103152) (xy 455.854054 -113.105946) (xy 455.843386 -113.109756) (xy 455.829416 -113.116614)
			(xy 455.818748 -113.124488) (xy 455.80808 -113.13922) (xy 455.807064 -113.141252) (xy 455.806302 -113.143284)
			(xy 455.803508 -113.15065) (xy 455.801967 -113.154998) (xy 455.80031 -113.164072) (xy 455.800206 -113.168684)
			(xy 455.800206 -113.568734) (xy 459.189834 -113.568734) (xy 459.193905 -113.513112) (xy 459.206031 -113.458675)
			(xy 459.225954 -113.406584) (xy 459.25325 -113.357949) (xy 459.287336 -113.313806) (xy 459.327485 -113.275097)
			(xy 459.372843 -113.242646) (xy 459.422443 -113.217145) (xy 459.475227 -113.199138) (xy 459.53007 -113.189008)
			(xy 459.585804 -113.186971) (xy 459.641241 -113.193071) (xy 459.695198 -113.207177) (xy 459.746527 -113.228989)
			(xy 459.794133 -113.258043) (xy 459.837001 -113.293718) (xy 459.874218 -113.335255) (xy 459.904991 -113.381768)
			(xy 459.928663 -113.432265) (xy 459.944731 -113.485672) (xy 459.952851 -113.540848) (xy 459.95336 -113.568734)
			(xy 459.952851 -113.59662) (xy 459.944731 -113.651796) (xy 459.928663 -113.705203) (xy 459.904991 -113.7557)
			(xy 459.874218 -113.802213) (xy 459.837001 -113.84375) (xy 459.794133 -113.879425) (xy 459.746527 -113.908479)
			(xy 459.695198 -113.930291) (xy 459.641241 -113.944397) (xy 459.585804 -113.950497) (xy 459.53007 -113.94846)
			(xy 459.475227 -113.93833) (xy 459.422443 -113.920323) (xy 459.372843 -113.894822) (xy 459.327485 -113.862371)
			(xy 459.287336 -113.823662) (xy 459.25325 -113.779519) (xy 459.225954 -113.730884) (xy 459.206031 -113.678793)
			(xy 459.193905 -113.624356) (xy 459.189834 -113.568734) (xy 455.800206 -113.568734) (xy 455.800206 -115.058698)
			(xy 456.28636 -115.058698) (xy 456.290431 -115.003076) (xy 456.302557 -114.948639) (xy 456.32248 -114.896548)
			(xy 456.349776 -114.847913) (xy 456.383862 -114.80377) (xy 456.424011 -114.765061) (xy 456.469369 -114.73261)
			(xy 456.518969 -114.707109) (xy 456.571753 -114.689102) (xy 456.626596 -114.678972) (xy 456.68233 -114.676935)
			(xy 456.737767 -114.683035) (xy 456.791724 -114.697141) (xy 456.843053 -114.718953) (xy 456.890659 -114.748007)
			(xy 456.933527 -114.783682) (xy 456.970744 -114.825219) (xy 457.001517 -114.871732) (xy 457.025189 -114.922229)
			(xy 457.041257 -114.975636) (xy 457.043426 -114.990372) (xy 457.665072 -114.990372) (xy 457.669143 -114.93475)
			(xy 457.681269 -114.880313) (xy 457.701192 -114.828222) (xy 457.728488 -114.779587) (xy 457.762574 -114.735444)
			(xy 457.802723 -114.696735) (xy 457.848081 -114.664284) (xy 457.897681 -114.638783) (xy 457.950465 -114.620776)
			(xy 458.005308 -114.610646) (xy 458.061042 -114.608609) (xy 458.116479 -114.614709) (xy 458.170436 -114.628815)
			(xy 458.221765 -114.650627) (xy 458.269371 -114.679681) (xy 458.312239 -114.715356) (xy 458.349456 -114.756893)
			(xy 458.380229 -114.803406) (xy 458.403901 -114.853903) (xy 458.419969 -114.90731) (xy 458.427819 -114.960654)
			(xy 459.191866 -114.960654) (xy 459.195937 -114.905032) (xy 459.208063 -114.850595) (xy 459.227986 -114.798504)
			(xy 459.255282 -114.749869) (xy 459.289368 -114.705726) (xy 459.329517 -114.667017) (xy 459.374875 -114.634566)
			(xy 459.424475 -114.609065) (xy 459.477259 -114.591058) (xy 459.532102 -114.580928) (xy 459.587836 -114.578891)
			(xy 459.643273 -114.584991) (xy 459.69723 -114.599097) (xy 459.748559 -114.620909) (xy 459.796165 -114.649963)
			(xy 459.839033 -114.685638) (xy 459.87625 -114.727175) (xy 459.907023 -114.773688) (xy 459.930695 -114.824185)
			(xy 459.946763 -114.877592) (xy 459.954883 -114.932768) (xy 459.955392 -114.960654) (xy 459.954883 -114.98854)
			(xy 459.946763 -115.043716) (xy 459.930695 -115.097123) (xy 459.907023 -115.14762) (xy 459.87625 -115.194133)
			(xy 459.839033 -115.23567) (xy 459.796165 -115.271345) (xy 459.748559 -115.300399) (xy 459.69723 -115.322211)
			(xy 459.643273 -115.336317) (xy 459.587836 -115.342417) (xy 459.532102 -115.34038) (xy 459.477259 -115.33025)
			(xy 459.424475 -115.312243) (xy 459.374875 -115.286742) (xy 459.329517 -115.254291) (xy 459.289368 -115.215582)
			(xy 459.255282 -115.171439) (xy 459.227986 -115.122804) (xy 459.208063 -115.070713) (xy 459.195937 -115.016276)
			(xy 459.191866 -114.960654) (xy 458.427819 -114.960654) (xy 458.428089 -114.962486) (xy 458.428598 -114.990372)
			(xy 458.428089 -115.018258) (xy 458.419969 -115.073434) (xy 458.403901 -115.126841) (xy 458.380229 -115.177338)
			(xy 458.349456 -115.223851) (xy 458.312239 -115.265388) (xy 458.269371 -115.301063) (xy 458.221765 -115.330117)
			(xy 458.170436 -115.351929) (xy 458.116479 -115.366035) (xy 458.061042 -115.372135) (xy 458.005308 -115.370098)
			(xy 457.950465 -115.359968) (xy 457.897681 -115.341961) (xy 457.848081 -115.31646) (xy 457.802723 -115.284009)
			(xy 457.762574 -115.2453) (xy 457.728488 -115.201157) (xy 457.701192 -115.152522) (xy 457.681269 -115.100431)
			(xy 457.669143 -115.045994) (xy 457.665072 -114.990372) (xy 457.043426 -114.990372) (xy 457.049377 -115.030812)
			(xy 457.049886 -115.058698) (xy 457.049377 -115.086584) (xy 457.041257 -115.14176) (xy 457.025189 -115.195167)
			(xy 457.001517 -115.245664) (xy 456.970744 -115.292177) (xy 456.933527 -115.333714) (xy 456.890659 -115.369389)
			(xy 456.843053 -115.398443) (xy 456.791724 -115.420255) (xy 456.737767 -115.434361) (xy 456.68233 -115.440461)
			(xy 456.626596 -115.438424) (xy 456.571753 -115.428294) (xy 456.518969 -115.410287) (xy 456.469369 -115.384786)
			(xy 456.424011 -115.352335) (xy 456.383862 -115.313626) (xy 456.349776 -115.269483) (xy 456.32248 -115.220848)
			(xy 456.302557 -115.168757) (xy 456.290431 -115.11432) (xy 456.28636 -115.058698) (xy 455.800206 -115.058698)
			(xy 455.800206 -117.248178) (xy 456.038964 -117.248178) (xy 456.043035 -117.192556) (xy 456.055161 -117.138119)
			(xy 456.075084 -117.086028) (xy 456.10238 -117.037393) (xy 456.136466 -116.99325) (xy 456.176615 -116.954541)
			(xy 456.221973 -116.92209) (xy 456.271573 -116.896589) (xy 456.324357 -116.878582) (xy 456.3792 -116.868452)
			(xy 456.434934 -116.866415) (xy 456.490371 -116.872515) (xy 456.544328 -116.886621) (xy 456.595657 -116.908433)
			(xy 456.643263 -116.937487) (xy 456.686131 -116.973162) (xy 456.723348 -117.014699) (xy 456.754121 -117.061212)
			(xy 456.777793 -117.111709) (xy 456.793861 -117.165116) (xy 456.801981 -117.220292) (xy 456.80249 -117.248178)
			(xy 457.054964 -117.248178) (xy 457.059035 -117.192556) (xy 457.071161 -117.138119) (xy 457.091084 -117.086028)
			(xy 457.11838 -117.037393) (xy 457.152466 -116.99325) (xy 457.192615 -116.954541) (xy 457.237973 -116.92209)
			(xy 457.287573 -116.896589) (xy 457.340357 -116.878582) (xy 457.3952 -116.868452) (xy 457.450934 -116.866415)
			(xy 457.506371 -116.872515) (xy 457.560328 -116.886621) (xy 457.611657 -116.908433) (xy 457.659263 -116.937487)
			(xy 457.702131 -116.973162) (xy 457.739348 -117.014699) (xy 457.770121 -117.061212) (xy 457.793793 -117.111709)
			(xy 457.809861 -117.165116) (xy 457.817981 -117.220292) (xy 457.81849 -117.248178) (xy 458.070964 -117.248178)
			(xy 458.075035 -117.192556) (xy 458.087161 -117.138119) (xy 458.107084 -117.086028) (xy 458.13438 -117.037393)
			(xy 458.168466 -116.99325) (xy 458.208615 -116.954541) (xy 458.253973 -116.92209) (xy 458.303573 -116.896589)
			(xy 458.356357 -116.878582) (xy 458.4112 -116.868452) (xy 458.466934 -116.866415) (xy 458.522371 -116.872515)
			(xy 458.576328 -116.886621) (xy 458.627657 -116.908433) (xy 458.675263 -116.937487) (xy 458.718131 -116.973162)
			(xy 458.755348 -117.014699) (xy 458.786121 -117.061212) (xy 458.809793 -117.111709) (xy 458.825861 -117.165116)
			(xy 458.833981 -117.220292) (xy 458.83449 -117.248178) (xy 458.833981 -117.276064) (xy 458.825861 -117.33124)
			(xy 458.809793 -117.384647) (xy 458.786121 -117.435144) (xy 458.755348 -117.481657) (xy 458.718131 -117.523194)
			(xy 458.675263 -117.558869) (xy 458.627657 -117.587923) (xy 458.576328 -117.609735) (xy 458.522371 -117.623841)
			(xy 458.466934 -117.629941) (xy 458.4112 -117.627904) (xy 458.356357 -117.617774) (xy 458.303573 -117.599767)
			(xy 458.253973 -117.574266) (xy 458.208615 -117.541815) (xy 458.168466 -117.503106) (xy 458.13438 -117.458963)
			(xy 458.107084 -117.410328) (xy 458.087161 -117.358237) (xy 458.075035 -117.3038) (xy 458.070964 -117.248178)
			(xy 457.81849 -117.248178) (xy 457.817981 -117.276064) (xy 457.809861 -117.33124) (xy 457.793793 -117.384647)
			(xy 457.770121 -117.435144) (xy 457.739348 -117.481657) (xy 457.702131 -117.523194) (xy 457.659263 -117.558869)
			(xy 457.611657 -117.587923) (xy 457.560328 -117.609735) (xy 457.506371 -117.623841) (xy 457.450934 -117.629941)
			(xy 457.3952 -117.627904) (xy 457.340357 -117.617774) (xy 457.287573 -117.599767) (xy 457.237973 -117.574266)
			(xy 457.192615 -117.541815) (xy 457.152466 -117.503106) (xy 457.11838 -117.458963) (xy 457.091084 -117.410328)
			(xy 457.071161 -117.358237) (xy 457.059035 -117.3038) (xy 457.054964 -117.248178) (xy 456.80249 -117.248178)
			(xy 456.801981 -117.276064) (xy 456.793861 -117.33124) (xy 456.777793 -117.384647) (xy 456.754121 -117.435144)
			(xy 456.723348 -117.481657) (xy 456.686131 -117.523194) (xy 456.643263 -117.558869) (xy 456.595657 -117.587923)
			(xy 456.544328 -117.609735) (xy 456.490371 -117.623841) (xy 456.434934 -117.629941) (xy 456.3792 -117.627904)
			(xy 456.324357 -117.617774) (xy 456.271573 -117.599767) (xy 456.221973 -117.574266) (xy 456.176615 -117.541815)
			(xy 456.136466 -117.503106) (xy 456.10238 -117.458963) (xy 456.075084 -117.410328) (xy 456.055161 -117.358237)
			(xy 456.043035 -117.3038) (xy 456.038964 -117.248178) (xy 455.800206 -117.248178) (xy 455.800206 -119.353838)
			(xy 455.800643 -119.363546) (xy 455.807874 -119.381567) (xy 455.821286 -119.395608) (xy 455.829924 -119.400066)
			(xy 455.853038 -119.41048) (xy 455.914506 -119.43842) (xy 455.920167 -119.440201) (xy 455.931976 -119.441361)
			(xy 455.937874 -119.440706) (xy 455.944224 -119.439436) (xy 455.947018 -119.438674) (xy 455.968354 -119.430546)
			(xy 455.974958 -119.425212) (xy 455.975212 -119.424958) (xy 455.995837 -119.408482) (xy 456.040764 -119.380765)
			(xy 456.08908 -119.3595) (xy 456.139865 -119.345091) (xy 456.19215 -119.337814) (xy 456.218544 -119.337328)
			(xy 456.245792 -119.337817) (xy 456.299733 -119.345579) (xy 456.352021 -119.360938) (xy 456.40159 -119.383583)
			(xy 456.447432 -119.413051) (xy 456.488614 -119.448743) (xy 456.524297 -119.489932) (xy 456.553756 -119.53578)
			(xy 456.57639 -119.585354) (xy 456.591738 -119.637645) (xy 456.599488 -119.691588) (xy 456.600052 -119.718836)
			(xy 456.599591 -119.745709) (xy 456.592046 -119.798922) (xy 456.577109 -119.85055) (xy 456.555078 -119.899573)
			(xy 456.526386 -119.945019) (xy 456.491603 -119.985991) (xy 456.451415 -120.021677) (xy 456.406618 -120.051373)
			(xy 456.358098 -120.07449) (xy 456.306814 -120.090571) (xy 456.253782 -120.099298) (xy 456.226926 -120.100344)
			(xy 456.218036 -120.100344) (xy 456.191757 -120.099892) (xy 456.139702 -120.092646) (xy 456.089136 -120.078315)
			(xy 456.041019 -120.05717) (xy 455.996265 -120.029613) (xy 455.97572 -120.013222) (xy 455.974958 -120.012714)
			(xy 455.963528 -120.00611) (xy 455.956162 -120.002554) (xy 455.948034 -119.999506) (xy 455.94152 -119.997387)
			(xy 455.927866 -119.996347) (xy 455.92111 -119.997474) (xy 455.90968 -120.001284) (xy 455.89444 -120.008142)
			(xy 455.893932 -120.008142) (xy 455.826622 -120.03913) (xy 455.823066 -120.041162) (xy 455.814024 -120.047813)
			(xy 455.802291 -120.066918) (xy 455.80046 -120.077992) (xy 455.800206 -120.08231) (xy 455.800206 -123.308364)
			(xy 455.799772 -123.318429) (xy 455.792042 -123.337017) (xy 455.78522 -123.344432) (xy 454.022968 -125.106684)
			(xy 454.015569 -125.113527) (xy 453.99697 -125.121252) (xy 453.9869 -125.12167) (xy 444.337694 -125.12167)
			(xy 444.332881 -125.121791) (xy 444.323421 -125.123576) (xy 444.318898 -125.125226) (xy 444.31077 -125.128528)
			(xy 444.302134 -125.136148) (xy 444.301626 -125.136656) (xy 444.252604 -125.181614) (xy 444.249296 -125.184832)
			(xy 444.243797 -125.192244) (xy 444.241682 -125.196346) (xy 444.237364 -125.204728) (xy 444.236602 -125.21438)
			(xy 444.23371 -125.241432) (xy 444.221242 -125.294389) (xy 444.201385 -125.345041) (xy 444.174541 -125.392362)
			(xy 444.141254 -125.435394) (xy 444.122048 -125.454664) (xy 444.114682 -125.461522) (xy 444.102236 -125.490224)
			(xy 444.100512 -125.494733) (xy 444.098603 -125.504195) (xy 444.098426 -125.50902) (xy 444.098426 -125.558042)
			(xy 444.099188 -125.565662) (xy 444.100966 -125.576076) (xy 444.101982 -125.582426) (xy 444.10884 -125.597412)
			(xy 444.111634 -125.602492) (xy 444.121286 -125.616462) (xy 444.124842 -125.620018) (xy 444.14592 -125.641626)
			(xy 444.18167 -125.690262) (xy 444.209317 -125.74392) (xy 444.228171 -125.801262) (xy 444.237762 -125.860856)
			(xy 444.23838 -125.891036) (xy 444.23838 -125.892052) (xy 444.238126 -125.899672) (xy 444.237872 -125.904244)
			(xy 444.236537 -125.930887) (xy 444.227347 -125.983435) (xy 444.210927 -126.03419) (xy 444.187599 -126.082164)
			(xy 444.157816 -126.126422) (xy 444.122159 -126.166099) (xy 444.081323 -126.200424) (xy 444.036105 -126.228726)
			(xy 443.987385 -126.250455) (xy 443.936114 -126.265186) (xy 443.883291 -126.272632) (xy 443.856618 -126.273052)
			(xy 443.829365 -126.272567) (xy 443.775413 -126.264813) (xy 443.723113 -126.24946) (xy 443.673531 -126.226821)
			(xy 443.627675 -126.197356) (xy 443.586479 -126.161665) (xy 443.550782 -126.120474) (xy 443.521309 -126.074623)
			(xy 443.498662 -126.025045) (xy 443.4833 -125.972748) (xy 443.475537 -125.918797) (xy 443.47511 -125.891544)
			(xy 443.47511 -125.89129) (xy 443.475537 -125.865771) (xy 443.48234 -125.815189) (xy 443.495823 -125.765964)
			(xy 443.515746 -125.718975) (xy 443.541754 -125.675061) (xy 443.573382 -125.635004) (xy 443.591442 -125.61697)
			(xy 443.594895 -125.613472) (xy 443.600516 -125.605411) (xy 443.602618 -125.600968) (xy 443.610492 -125.583442)
			(xy 443.612494 -125.578602) (xy 443.614669 -125.568358) (xy 443.61481 -125.563122) (xy 443.61481 -125.50902)
			(xy 443.61465 -125.504194) (xy 443.612735 -125.49473) (xy 443.611 -125.490224) (xy 443.598554 -125.461522)
			(xy 443.591188 -125.454664) (xy 443.571978 -125.435395) (xy 443.538664 -125.392377) (xy 443.511806 -125.345059)
			(xy 443.491949 -125.294403) (xy 443.479497 -125.241438) (xy 443.476634 -125.21438) (xy 443.475872 -125.204728)
			(xy 443.471554 -125.196346) (xy 443.469426 -125.192252) (xy 443.463931 -125.18484) (xy 443.460632 -125.181614)
			(xy 443.41161 -125.136656) (xy 443.411102 -125.136148) (xy 443.40907 -125.13437) (xy 443.405694 -125.131524)
			(xy 443.39816 -125.126923) (xy 443.394084 -125.125226) (xy 443.385194 -125.12167) (xy 440.284108 -125.12167)
			(xy 440.275416 -125.122015) (xy 440.259047 -125.12786) (xy 440.252104 -125.1331) (xy 440.248294 -125.136402)
			(xy 439.218324 -126.166372) (xy 439.215617 -126.169222) (xy 439.211022 -126.1756) (xy 439.20918 -126.179072)
			(xy 439.206601 -126.1845) (xy 439.203785 -126.196179) (xy 439.203592 -126.202186) (xy 439.203592 -127.361188)
			(xy 439.203688 -127.366206) (xy 439.205614 -127.376055) (xy 439.207402 -127.380746) (xy 440.373262 -130.194812)
			(xy 440.375267 -130.199377) (xy 440.380763 -130.207695) (xy 440.384184 -130.211322) (xy 440.552078 -130.37947)
			(xy 440.586296 -130.41449) (xy 440.648469 -130.490136) (xy 440.702931 -130.571509) (xy 440.74916 -130.657826)
			(xy 440.768486 -130.702812) (xy 443.647341 -137.65276) (xy 444.341248 -137.65276) (xy 444.345319 -137.597138)
			(xy 444.357445 -137.542701) (xy 444.377368 -137.49061) (xy 444.404664 -137.441975) (xy 444.43875 -137.397832)
			(xy 444.478899 -137.359123) (xy 444.524257 -137.326672) (xy 444.573857 -137.301171) (xy 444.626641 -137.283164)
			(xy 444.681484 -137.273034) (xy 444.737218 -137.270997) (xy 444.792655 -137.277097) (xy 444.846612 -137.291203)
			(xy 444.897941 -137.313015) (xy 444.945547 -137.342069) (xy 444.988415 -137.377744) (xy 445.025632 -137.419281)
			(xy 445.056405 -137.465794) (xy 445.080077 -137.516291) (xy 445.096145 -137.569698) (xy 445.104265 -137.624874)
			(xy 445.104774 -137.65276) (xy 445.104265 -137.680646) (xy 445.096145 -137.735822) (xy 445.080077 -137.789229)
			(xy 445.056405 -137.839726) (xy 445.025632 -137.886239) (xy 444.988415 -137.927776) (xy 444.977268 -137.937053)
			(xy 445.665563 -137.937053) (xy 445.665563 -137.882547) (xy 445.67332 -137.828597) (xy 445.688676 -137.7763)
			(xy 445.711319 -137.72672) (xy 445.740787 -137.680868) (xy 445.77648 -137.639676) (xy 445.817673 -137.603983)
			(xy 445.863526 -137.574516) (xy 445.913106 -137.551874) (xy 445.965403 -137.536519) (xy 446.019353 -137.528763)
			(xy 446.046606 -137.5283) (xy 446.074709 -137.528782) (xy 446.130306 -137.537029) (xy 446.184092 -137.553344)
			(xy 446.234901 -137.577374) (xy 446.281636 -137.608598) (xy 446.323284 -137.646341) (xy 446.3415 -137.667746)
			(xy 446.348803 -137.675928) (xy 446.368414 -137.685684) (xy 446.379346 -137.686542) (xy 446.466976 -137.689082)
			(xy 446.487296 -137.680446) (xy 446.494662 -137.672318) (xy 446.512803 -137.653333) (xy 446.553392 -137.620017)
			(xy 446.598162 -137.592577) (xy 446.64627 -137.571529) (xy 446.696808 -137.557272) (xy 446.748823 -137.550074)
			(xy 446.775078 -137.549636) (xy 446.802335 -137.550009) (xy 446.856295 -137.557765) (xy 446.908601 -137.573121)
			(xy 446.95819 -137.595765) (xy 447.004051 -137.625235) (xy 447.045251 -137.660933) (xy 447.080951 -137.702131)
			(xy 447.110425 -137.747991) (xy 447.133072 -137.797578) (xy 447.148431 -137.849884) (xy 447.156189 -137.903843)
			(xy 447.156189 -137.958357) (xy 447.148431 -138.012316) (xy 447.133072 -138.064622) (xy 447.110425 -138.114209)
			(xy 447.080951 -138.160069) (xy 447.045251 -138.201267) (xy 447.004051 -138.236965) (xy 446.95819 -138.266435)
			(xy 446.908601 -138.289079) (xy 446.856295 -138.304435) (xy 446.802335 -138.312191) (xy 446.775078 -138.312652)
			(xy 446.746976 -138.312128) (xy 446.69138 -138.303892) (xy 446.637595 -138.287587) (xy 446.586784 -138.263565)
			(xy 446.540049 -138.232347) (xy 446.4984 -138.194609) (xy 446.480184 -138.173206) (xy 446.472879 -138.165026)
			(xy 446.45327 -138.155267) (xy 446.442338 -138.15441) (xy 446.354708 -138.15187) (xy 446.334388 -138.160506)
			(xy 446.327022 -138.168634) (xy 446.308879 -138.187617) (xy 446.268292 -138.220935) (xy 446.223523 -138.248377)
			(xy 446.175415 -138.269425) (xy 446.124877 -138.283682) (xy 446.072861 -138.290879) (xy 446.046606 -138.291316)
			(xy 446.019353 -138.290837) (xy 445.965403 -138.283081) (xy 445.913106 -138.267726) (xy 445.863526 -138.245084)
			(xy 445.817673 -138.215617) (xy 445.77648 -138.179924) (xy 445.740787 -138.138732) (xy 445.711319 -138.09288)
			(xy 445.688676 -138.0433) (xy 445.67332 -137.991003) (xy 445.665563 -137.937053) (xy 444.977268 -137.937053)
			(xy 444.945547 -137.963451) (xy 444.897941 -137.992505) (xy 444.846612 -138.014317) (xy 444.792655 -138.028423)
			(xy 444.737218 -138.034523) (xy 444.681484 -138.032486) (xy 444.626641 -138.022356) (xy 444.573857 -138.004349)
			(xy 444.524257 -137.978848) (xy 444.478899 -137.946397) (xy 444.43875 -137.907688) (xy 444.404664 -137.863545)
			(xy 444.377368 -137.81491) (xy 444.357445 -137.762819) (xy 444.345319 -137.708382) (xy 444.341248 -137.65276)
			(xy 443.647341 -137.65276) (xy 449.393056 -151.5237) (xy 449.41115 -151.56904) (xy 449.439447 -151.662476)
			(xy 449.458493 -151.758227) (xy 449.468106 -151.855379) (xy 449.468748 -151.904192) (xy 449.468748 -159.966914)
			(xy 449.468282 -160.010296) (xy 449.460744 -160.096732) (xy 449.445719 -160.182185) (xy 449.434966 -160.224216)
			(xy 449.0847 -161.535364) (xy 449.073013 -161.57737) (xy 449.043272 -161.659339) (xy 449.006495 -161.738401)
			(xy 448.985132 -161.77641) (xy 440.480704 -176.514506) (xy 440.475624 -176.526444) (xy 439.68797 -179.413916)
			(xy 439.686192 -179.422806) (xy 437.188159 -207.97393) (xy 454.542396 -207.97393) (xy 454.546467 -207.918308)
			(xy 454.558593 -207.863871) (xy 454.578516 -207.81178) (xy 454.605812 -207.763145) (xy 454.639898 -207.719002)
			(xy 454.680047 -207.680293) (xy 454.725405 -207.647842) (xy 454.775005 -207.622341) (xy 454.827789 -207.604334)
			(xy 454.882632 -207.594204) (xy 454.938366 -207.592167) (xy 454.993803 -207.598267) (xy 455.04776 -207.612373)
			(xy 455.099089 -207.634185) (xy 455.146695 -207.663239) (xy 455.189563 -207.698914) (xy 455.22678 -207.740451)
			(xy 455.257553 -207.786964) (xy 455.281225 -207.837461) (xy 455.297293 -207.890868) (xy 455.305413 -207.946044)
			(xy 455.305922 -207.97393) (xy 455.305413 -208.001816) (xy 455.297293 -208.056992) (xy 455.281225 -208.110399)
			(xy 455.257553 -208.160896) (xy 455.22678 -208.207409) (xy 455.189563 -208.248946) (xy 455.146695 -208.284621)
			(xy 455.099089 -208.313675) (xy 455.04776 -208.335487) (xy 454.993803 -208.349593) (xy 454.938366 -208.355693)
			(xy 454.882632 -208.353656) (xy 454.827789 -208.343526) (xy 454.775005 -208.325519) (xy 454.725405 -208.300018)
			(xy 454.680047 -208.267567) (xy 454.639898 -208.228858) (xy 454.605812 -208.184715) (xy 454.578516 -208.13608)
			(xy 454.558593 -208.083989) (xy 454.546467 -208.029552) (xy 454.542396 -207.97393) (xy 437.188159 -207.97393)
			(xy 437.065064 -209.380836) (xy 445.288416 -209.380836) (xy 445.288416 -208.517236) (xy 445.288906 -208.487268)
			(xy 445.296729 -208.427846) (xy 445.312242 -208.369953) (xy 445.335178 -208.31458) (xy 445.365145 -208.262674)
			(xy 445.401632 -208.215124) (xy 445.444012 -208.172744) (xy 445.491562 -208.136257) (xy 445.543468 -208.10629)
			(xy 445.598841 -208.083354) (xy 445.656734 -208.067841) (xy 445.716156 -208.060018) (xy 445.776092 -208.060018)
			(xy 445.835514 -208.067841) (xy 445.893407 -208.083354) (xy 445.94878 -208.10629) (xy 446.000686 -208.136257)
			(xy 446.048236 -208.172744) (xy 446.090616 -208.215124) (xy 446.127103 -208.262674) (xy 446.15707 -208.31458)
			(xy 446.180006 -208.369953) (xy 446.195519 -208.427846) (xy 446.203342 -208.487268) (xy 446.203832 -208.517236)
			(xy 446.203832 -209.380836) (xy 446.203342 -209.410804) (xy 446.195519 -209.470226) (xy 446.180006 -209.528119)
			(xy 446.15707 -209.583492) (xy 446.127103 -209.635398) (xy 446.090616 -209.682948) (xy 446.048236 -209.725328)
			(xy 446.000686 -209.761815) (xy 445.94878 -209.791782) (xy 445.893407 -209.814718) (xy 445.835514 -209.830231)
			(xy 445.776092 -209.838054) (xy 445.716156 -209.838054) (xy 445.656734 -209.830231) (xy 445.598841 -209.814718)
			(xy 445.543468 -209.791782) (xy 445.491562 -209.761815) (xy 445.444012 -209.725328) (xy 445.401632 -209.682948)
			(xy 445.365145 -209.635398) (xy 445.335178 -209.583492) (xy 445.312242 -209.528119) (xy 445.296729 -209.470226)
			(xy 445.288906 -209.410804) (xy 445.288416 -209.380836) (xy 437.065064 -209.380836) (xy 437.015373 -209.94878)
			(xy 451.586598 -209.94878) (xy 451.590669 -209.893158) (xy 451.602795 -209.838721) (xy 451.622718 -209.78663)
			(xy 451.650014 -209.737995) (xy 451.6841 -209.693852) (xy 451.724249 -209.655143) (xy 451.769607 -209.622692)
			(xy 451.819207 -209.597191) (xy 451.871991 -209.579184) (xy 451.926834 -209.569054) (xy 451.982568 -209.567017)
			(xy 452.038005 -209.573117) (xy 452.091962 -209.587223) (xy 452.143291 -209.609035) (xy 452.190897 -209.638089)
			(xy 452.233765 -209.673764) (xy 452.270982 -209.715301) (xy 452.301755 -209.761814) (xy 452.325427 -209.812311)
			(xy 452.341495 -209.865718) (xy 452.349615 -209.920894) (xy 452.350124 -209.94878) (xy 452.349615 -209.976666)
			(xy 452.341495 -210.031842) (xy 452.325427 -210.085249) (xy 452.301755 -210.135746) (xy 452.270982 -210.182259)
			(xy 452.233765 -210.223796) (xy 452.190897 -210.259471) (xy 452.143291 -210.288525) (xy 452.091962 -210.310337)
			(xy 452.038005 -210.324443) (xy 451.982568 -210.330543) (xy 451.926834 -210.328506) (xy 451.871991 -210.318376)
			(xy 451.819207 -210.300369) (xy 451.769607 -210.274868) (xy 451.724249 -210.242417) (xy 451.6841 -210.203708)
			(xy 451.650014 -210.159565) (xy 451.622718 -210.11093) (xy 451.602795 -210.058839) (xy 451.590669 -210.004402)
			(xy 451.586598 -209.94878) (xy 437.015373 -209.94878) (xy 435.980078 -221.781624) (xy 435.980078 -221.79026)
			(xy 436.006898 -222.0976) (xy 451.742046 -222.0976) (xy 451.746117 -222.041978) (xy 451.758243 -221.987541)
			(xy 451.778166 -221.93545) (xy 451.805462 -221.886815) (xy 451.839548 -221.842672) (xy 451.879697 -221.803963)
			(xy 451.925055 -221.771512) (xy 451.974655 -221.746011) (xy 452.027439 -221.728004) (xy 452.082282 -221.717874)
			(xy 452.138016 -221.715837) (xy 452.193453 -221.721937) (xy 452.24741 -221.736043) (xy 452.298739 -221.757855)
			(xy 452.346345 -221.786909) (xy 452.389213 -221.822584) (xy 452.42643 -221.864121) (xy 452.457203 -221.910634)
			(xy 452.480875 -221.961131) (xy 452.496943 -222.014538) (xy 452.505063 -222.069714) (xy 452.505572 -222.0976)
			(xy 452.505063 -222.125486) (xy 452.496943 -222.180662) (xy 452.480875 -222.234069) (xy 452.457203 -222.284566)
			(xy 452.42643 -222.331079) (xy 452.389213 -222.372616) (xy 452.346345 -222.408291) (xy 452.298739 -222.437345)
			(xy 452.24741 -222.459157) (xy 452.193453 -222.473263) (xy 452.138016 -222.479363) (xy 452.082282 -222.477326)
			(xy 452.027439 -222.467196) (xy 451.974655 -222.449189) (xy 451.925055 -222.423688) (xy 451.879697 -222.391237)
			(xy 451.839548 -222.352528) (xy 451.805462 -222.308385) (xy 451.778166 -222.25975) (xy 451.758243 -222.207659)
			(xy 451.746117 -222.153222) (xy 451.742046 -222.0976) (xy 436.006898 -222.0976) (xy 436.113268 -223.316546)
			(xy 443.32982 -223.316546) (xy 443.333891 -223.260924) (xy 443.346017 -223.206487) (xy 443.36594 -223.154396)
			(xy 443.393236 -223.105761) (xy 443.427322 -223.061618) (xy 443.467471 -223.022909) (xy 443.512829 -222.990458)
			(xy 443.562429 -222.964957) (xy 443.615213 -222.94695) (xy 443.670056 -222.93682) (xy 443.72579 -222.934783)
			(xy 443.781227 -222.940883) (xy 443.835184 -222.954989) (xy 443.886513 -222.976801) (xy 443.934119 -223.005855)
			(xy 443.976987 -223.04153) (xy 444.014204 -223.083067) (xy 444.044977 -223.12958) (xy 444.068649 -223.180077)
			(xy 444.084717 -223.233484) (xy 444.092837 -223.28866) (xy 444.093346 -223.316546) (xy 444.092837 -223.344432)
			(xy 444.084717 -223.399608) (xy 444.068649 -223.453015) (xy 444.044977 -223.503512) (xy 444.014204 -223.550025)
			(xy 443.976987 -223.591562) (xy 443.934119 -223.627237) (xy 443.886513 -223.656291) (xy 443.835184 -223.678103)
			(xy 443.781227 -223.692209) (xy 443.72579 -223.698309) (xy 443.670056 -223.696272) (xy 443.615213 -223.686142)
			(xy 443.562429 -223.668135) (xy 443.512829 -223.642634) (xy 443.467471 -223.610183) (xy 443.427322 -223.571474)
			(xy 443.393236 -223.527331) (xy 443.36594 -223.478696) (xy 443.346017 -223.426605) (xy 443.333891 -223.372168)
			(xy 443.32982 -223.316546) (xy 436.113268 -223.316546) (xy 436.234067 -224.700846) (xy 443.326518 -224.700846)
			(xy 443.330589 -224.645224) (xy 443.342715 -224.590787) (xy 443.362638 -224.538696) (xy 443.389934 -224.490061)
			(xy 443.42402 -224.445918) (xy 443.464169 -224.407209) (xy 443.509527 -224.374758) (xy 443.559127 -224.349257)
			(xy 443.611911 -224.33125) (xy 443.666754 -224.32112) (xy 443.722488 -224.319083) (xy 443.777925 -224.325183)
			(xy 443.831882 -224.339289) (xy 443.883211 -224.361101) (xy 443.930817 -224.390155) (xy 443.973685 -224.42583)
			(xy 444.010902 -224.467367) (xy 444.041675 -224.51388) (xy 444.065347 -224.564377) (xy 444.081415 -224.617784)
			(xy 444.089535 -224.67296) (xy 444.090044 -224.700846) (xy 444.089535 -224.728732) (xy 444.081415 -224.783908)
			(xy 444.065347 -224.837315) (xy 444.041675 -224.887812) (xy 444.010902 -224.934325) (xy 443.973685 -224.975862)
			(xy 443.930817 -225.011537) (xy 443.883211 -225.040591) (xy 443.831882 -225.062403) (xy 443.777925 -225.076509)
			(xy 443.722488 -225.082609) (xy 443.666754 -225.080572) (xy 443.611911 -225.070442) (xy 443.559127 -225.052435)
			(xy 443.509527 -225.026934) (xy 443.464169 -224.994483) (xy 443.42402 -224.955774) (xy 443.389934 -224.911631)
			(xy 443.362638 -224.862996) (xy 443.342715 -224.810905) (xy 443.330589 -224.756468) (xy 443.326518 -224.700846)
			(xy 436.234067 -224.700846) (xy 436.40691 -226.681538) (xy 457.325982 -226.681538) (xy 457.330053 -226.625916)
			(xy 457.342179 -226.571479) (xy 457.362102 -226.519388) (xy 457.389398 -226.470753) (xy 457.423484 -226.42661)
			(xy 457.463633 -226.387901) (xy 457.508991 -226.35545) (xy 457.558591 -226.329949) (xy 457.611375 -226.311942)
			(xy 457.666218 -226.301812) (xy 457.721952 -226.299775) (xy 457.777389 -226.305875) (xy 457.831346 -226.319981)
			(xy 457.882675 -226.341793) (xy 457.930281 -226.370847) (xy 457.973149 -226.406522) (xy 458.010366 -226.448059)
			(xy 458.041139 -226.494572) (xy 458.064811 -226.545069) (xy 458.080879 -226.598476) (xy 458.088999 -226.653652)
			(xy 458.089508 -226.681538) (xy 458.088999 -226.709424) (xy 458.080879 -226.7646) (xy 458.064811 -226.818007)
			(xy 458.041139 -226.868504) (xy 458.010366 -226.915017) (xy 457.973149 -226.956554) (xy 457.930281 -226.992229)
			(xy 457.882675 -227.021283) (xy 457.831346 -227.043095) (xy 457.777389 -227.057201) (xy 457.721952 -227.063301)
			(xy 457.666218 -227.061264) (xy 457.611375 -227.051134) (xy 457.558591 -227.033127) (xy 457.508991 -227.007626)
			(xy 457.463633 -226.975175) (xy 457.423484 -226.936466) (xy 457.389398 -226.892323) (xy 457.362102 -226.843688)
			(xy 457.342179 -226.791597) (xy 457.330053 -226.73716) (xy 457.325982 -226.681538) (xy 436.40691 -226.681538)
			(xy 436.580244 -228.667848) (xy 442.823618 -228.667848) (xy 442.823618 -228.613352) (xy 442.831374 -228.55941)
			(xy 442.846727 -228.50712) (xy 442.869366 -228.457548) (xy 442.898829 -228.411703) (xy 442.934517 -228.370517)
			(xy 442.975703 -228.334829) (xy 443.021548 -228.305366) (xy 443.07112 -228.282727) (xy 443.12341 -228.267374)
			(xy 443.177352 -228.259618) (xy 443.2046 -228.259132) (xy 443.233517 -228.259638) (xy 443.29069 -228.268368)
			(xy 443.345889 -228.285628) (xy 443.397851 -228.311022) (xy 443.445385 -228.343968) (xy 443.487401 -228.383711)
			(xy 443.50559 -228.406198) (xy 443.513212 -228.41499) (xy 443.534101 -228.425182) (xy 443.545722 -228.425756)
			(xy 443.625478 -228.425756) (xy 443.637109 -228.425205) (xy 443.658019 -228.415026) (xy 443.66561 -228.406198)
			(xy 443.683795 -228.383709) (xy 443.725816 -228.343975) (xy 443.773352 -228.311036) (xy 443.825315 -228.285649)
			(xy 443.880513 -228.268394) (xy 443.937684 -228.259666) (xy 443.9666 -228.259132) (xy 443.993854 -228.259538)
			(xy 444.047807 -228.267295) (xy 444.100108 -228.282652) (xy 444.14969 -228.305295) (xy 444.195545 -228.334765)
			(xy 444.23674 -228.37046) (xy 444.272435 -228.411655) (xy 444.301905 -228.45751) (xy 444.324548 -228.507092)
			(xy 444.339905 -228.559393) (xy 444.347662 -228.613346) (xy 444.347662 -228.667854) (xy 444.339905 -228.721807)
			(xy 444.324548 -228.774108) (xy 444.301905 -228.82369) (xy 444.272435 -228.869545) (xy 444.23674 -228.91074)
			(xy 444.195545 -228.946435) (xy 444.14969 -228.975905) (xy 444.100108 -228.998548) (xy 444.047807 -229.013905)
			(xy 443.993854 -229.021662) (xy 443.9666 -229.022148) (xy 443.937682 -229.021649) (xy 443.880509 -229.012919)
			(xy 443.825309 -228.995658) (xy 443.773347 -228.970263) (xy 443.725814 -228.937315) (xy 443.683799 -228.89757)
			(xy 443.66561 -228.875082) (xy 443.657992 -228.866286) (xy 443.637099 -228.856097) (xy 443.625478 -228.855524)
			(xy 443.545722 -228.855524) (xy 443.534092 -228.856082) (xy 443.513182 -228.866256) (xy 443.50559 -228.875082)
			(xy 443.4874 -228.897567) (xy 443.445381 -228.937302) (xy 443.397846 -228.970242) (xy 443.345884 -228.99563)
			(xy 443.290686 -229.012886) (xy 443.233516 -229.021614) (xy 443.2046 -229.022148) (xy 443.177352 -229.021582)
			(xy 443.12341 -229.013826) (xy 443.07112 -228.998473) (xy 443.021548 -228.975834) (xy 442.975703 -228.946371)
			(xy 442.934517 -228.910683) (xy 442.898829 -228.869497) (xy 442.869366 -228.823652) (xy 442.846727 -228.77408)
			(xy 442.831374 -228.72179) (xy 442.823618 -228.667848) (xy 436.580244 -228.667848) (xy 436.619873 -229.12197)
			(xy 444.350392 -229.12197) (xy 444.354463 -229.066348) (xy 444.366589 -229.011911) (xy 444.386512 -228.95982)
			(xy 444.413808 -228.911185) (xy 444.447894 -228.867042) (xy 444.488043 -228.828333) (xy 444.533401 -228.795882)
			(xy 444.583001 -228.770381) (xy 444.635785 -228.752374) (xy 444.690628 -228.742244) (xy 444.746362 -228.740207)
			(xy 444.801799 -228.746307) (xy 444.855756 -228.760413) (xy 444.907085 -228.782225) (xy 444.954691 -228.811279)
			(xy 444.997559 -228.846954) (xy 445.034776 -228.888491) (xy 445.065549 -228.935004) (xy 445.089221 -228.985501)
			(xy 445.105289 -229.038908) (xy 445.113409 -229.094084) (xy 445.113918 -229.12197) (xy 445.113409 -229.149856)
			(xy 445.105289 -229.205032) (xy 445.089221 -229.258439) (xy 445.065549 -229.308936) (xy 445.034776 -229.355449)
			(xy 444.997559 -229.396986) (xy 444.954691 -229.432661) (xy 444.907085 -229.461715) (xy 444.855756 -229.483527)
			(xy 444.801799 -229.497633) (xy 444.746362 -229.503733) (xy 444.690628 -229.501696) (xy 444.635785 -229.491566)
			(xy 444.583001 -229.473559) (xy 444.533401 -229.448058) (xy 444.488043 -229.415607) (xy 444.447894 -229.376898)
			(xy 444.413808 -229.332755) (xy 444.386512 -229.28412) (xy 444.366589 -229.232029) (xy 444.354463 -229.177592)
			(xy 444.350392 -229.12197) (xy 436.619873 -229.12197) (xy 436.727263 -230.3526) (xy 461.872582 -230.3526)
			(xy 461.876653 -230.296978) (xy 461.888779 -230.242541) (xy 461.908702 -230.19045) (xy 461.935998 -230.141815)
			(xy 461.970084 -230.097672) (xy 462.010233 -230.058963) (xy 462.055591 -230.026512) (xy 462.105191 -230.001011)
			(xy 462.157975 -229.983004) (xy 462.212818 -229.972874) (xy 462.268552 -229.970837) (xy 462.323989 -229.976937)
			(xy 462.377946 -229.991043) (xy 462.429275 -230.012855) (xy 462.476881 -230.041909) (xy 462.519749 -230.077584)
			(xy 462.556966 -230.119121) (xy 462.587739 -230.165634) (xy 462.611411 -230.216131) (xy 462.627479 -230.269538)
			(xy 462.635599 -230.324714) (xy 462.636108 -230.3526) (xy 462.635599 -230.380486) (xy 462.627479 -230.435662)
			(xy 462.611411 -230.489069) (xy 462.587739 -230.539566) (xy 462.556966 -230.586079) (xy 462.519749 -230.627616)
			(xy 462.476881 -230.663291) (xy 462.429275 -230.692345) (xy 462.377946 -230.714157) (xy 462.323989 -230.728263)
			(xy 462.268552 -230.734363) (xy 462.212818 -230.732326) (xy 462.157975 -230.722196) (xy 462.105191 -230.704189)
			(xy 462.055591 -230.678688) (xy 462.010233 -230.646237) (xy 461.970084 -230.607528) (xy 461.935998 -230.563385)
			(xy 461.908702 -230.51475) (xy 461.888779 -230.462659) (xy 461.876653 -230.408222) (xy 461.872582 -230.3526)
			(xy 436.727263 -230.3526) (xy 436.931624 -232.69448) (xy 451.24192 -232.69448) (xy 451.245991 -232.638858)
			(xy 451.258117 -232.584421) (xy 451.27804 -232.53233) (xy 451.305336 -232.483695) (xy 451.339422 -232.439552)
			(xy 451.379571 -232.400843) (xy 451.424929 -232.368392) (xy 451.474529 -232.342891) (xy 451.527313 -232.324884)
			(xy 451.582156 -232.314754) (xy 451.63789 -232.312717) (xy 451.693327 -232.318817) (xy 451.747284 -232.332923)
			(xy 451.798613 -232.354735) (xy 451.846219 -232.383789) (xy 451.889087 -232.419464) (xy 451.926304 -232.461001)
			(xy 451.957077 -232.507514) (xy 451.980749 -232.558011) (xy 451.996817 -232.611418) (xy 452.004937 -232.666594)
			(xy 452.005446 -232.69448) (xy 452.004937 -232.722366) (xy 451.996817 -232.777542) (xy 451.980749 -232.830949)
			(xy 451.957077 -232.881446) (xy 451.926304 -232.927959) (xy 451.889087 -232.969496) (xy 451.846219 -233.005171)
			(xy 451.798613 -233.034225) (xy 451.747284 -233.056037) (xy 451.693327 -233.070143) (xy 451.63789 -233.076243)
			(xy 451.582156 -233.074206) (xy 451.527313 -233.064076) (xy 451.474529 -233.046069) (xy 451.424929 -233.020568)
			(xy 451.379571 -232.988117) (xy 451.339422 -232.949408) (xy 451.305336 -232.905265) (xy 451.27804 -232.85663)
			(xy 451.258117 -232.804539) (xy 451.245991 -232.750102) (xy 451.24192 -232.69448) (xy 436.931624 -232.69448)
			(xy 436.971078 -233.1466) (xy 442.035182 -233.1466) (xy 442.039253 -233.090978) (xy 442.051379 -233.036541)
			(xy 442.071302 -232.98445) (xy 442.098598 -232.935815) (xy 442.132684 -232.891672) (xy 442.172833 -232.852963)
			(xy 442.218191 -232.820512) (xy 442.267791 -232.795011) (xy 442.320575 -232.777004) (xy 442.375418 -232.766874)
			(xy 442.431152 -232.764837) (xy 442.486589 -232.770937) (xy 442.540546 -232.785043) (xy 442.591875 -232.806855)
			(xy 442.639481 -232.835909) (xy 442.682349 -232.871584) (xy 442.719566 -232.913121) (xy 442.750339 -232.959634)
			(xy 442.774011 -233.010131) (xy 442.790079 -233.063538) (xy 442.798199 -233.118714) (xy 442.798708 -233.1466)
			(xy 442.798199 -233.174486) (xy 442.790079 -233.229662) (xy 442.775866 -233.276902) (xy 443.9318 -233.276902)
			(xy 443.935871 -233.22128) (xy 443.947997 -233.166843) (xy 443.96792 -233.114752) (xy 443.995216 -233.066117)
			(xy 444.029302 -233.021974) (xy 444.069451 -232.983265) (xy 444.114809 -232.950814) (xy 444.164409 -232.925313)
			(xy 444.217193 -232.907306) (xy 444.272036 -232.897176) (xy 444.32777 -232.895139) (xy 444.383207 -232.901239)
			(xy 444.437164 -232.915345) (xy 444.488493 -232.937157) (xy 444.536099 -232.966211) (xy 444.578967 -233.001886)
			(xy 444.616184 -233.043423) (xy 444.646957 -233.089936) (xy 444.670629 -233.140433) (xy 444.686697 -233.19384)
			(xy 444.694817 -233.249016) (xy 444.695326 -233.276902) (xy 444.694817 -233.304788) (xy 444.686697 -233.359964)
			(xy 444.670629 -233.413371) (xy 444.646957 -233.463868) (xy 444.616184 -233.510381) (xy 444.578967 -233.551918)
			(xy 444.536099 -233.587593) (xy 444.488493 -233.616647) (xy 444.437164 -233.638459) (xy 444.383207 -233.652565)
			(xy 444.32777 -233.658665) (xy 444.272036 -233.656628) (xy 444.217193 -233.646498) (xy 444.164409 -233.628491)
			(xy 444.114809 -233.60299) (xy 444.069451 -233.570539) (xy 444.029302 -233.53183) (xy 443.995216 -233.487687)
			(xy 443.96792 -233.439052) (xy 443.947997 -233.386961) (xy 443.935871 -233.332524) (xy 443.9318 -233.276902)
			(xy 442.775866 -233.276902) (xy 442.774011 -233.283069) (xy 442.750339 -233.333566) (xy 442.719566 -233.380079)
			(xy 442.682349 -233.421616) (xy 442.639481 -233.457291) (xy 442.591875 -233.486345) (xy 442.540546 -233.508157)
			(xy 442.486589 -233.522263) (xy 442.431152 -233.528363) (xy 442.375418 -233.526326) (xy 442.320575 -233.516196)
			(xy 442.267791 -233.498189) (xy 442.218191 -233.472688) (xy 442.172833 -233.440237) (xy 442.132684 -233.401528)
			(xy 442.098598 -233.357385) (xy 442.071302 -233.30875) (xy 442.051379 -233.256659) (xy 442.039253 -233.202222)
			(xy 442.035182 -233.1466) (xy 436.971078 -233.1466) (xy 437.102783 -234.655869) (xy 448.021157 -234.655869)
			(xy 448.021157 -234.595931) (xy 448.028981 -234.536505) (xy 448.044494 -234.478608) (xy 448.067432 -234.423232)
			(xy 448.097401 -234.371324) (xy 448.13389 -234.323771) (xy 448.176273 -234.281388) (xy 448.223825 -234.2449)
			(xy 448.275734 -234.214931) (xy 448.33111 -234.191993) (xy 448.389007 -234.17648) (xy 448.448433 -234.168657)
			(xy 448.478402 -234.168188) (xy 449.342002 -234.168188) (xy 449.371969 -234.168686) (xy 449.431391 -234.176509)
			(xy 449.489283 -234.192022) (xy 449.544656 -234.214958) (xy 449.596561 -234.244925) (xy 449.64411 -234.281411)
			(xy 449.68649 -234.323792) (xy 449.722976 -234.371341) (xy 449.752943 -234.423246) (xy 449.775879 -234.478618)
			(xy 449.791391 -234.536511) (xy 449.799214 -234.595933) (xy 449.799214 -234.655867) (xy 449.791391 -234.715289)
			(xy 449.775879 -234.773182) (xy 449.752943 -234.828554) (xy 449.749404 -234.834684) (xy 450.697598 -234.834684)
			(xy 450.701669 -234.779062) (xy 450.713795 -234.724625) (xy 450.733718 -234.672534) (xy 450.761014 -234.623899)
			(xy 450.7951 -234.579756) (xy 450.835249 -234.541047) (xy 450.880607 -234.508596) (xy 450.930207 -234.483095)
			(xy 450.982991 -234.465088) (xy 451.037834 -234.454958) (xy 451.093568 -234.452921) (xy 451.149005 -234.459021)
			(xy 451.202962 -234.473127) (xy 451.254291 -234.494939) (xy 451.301897 -234.523993) (xy 451.344765 -234.559668)
			(xy 451.381982 -234.601205) (xy 451.412755 -234.647718) (xy 451.436427 -234.698215) (xy 451.452495 -234.751622)
			(xy 451.460615 -234.806798) (xy 451.461124 -234.834684) (xy 451.460615 -234.86257) (xy 451.452495 -234.917746)
			(xy 451.436427 -234.971153) (xy 451.412755 -235.02165) (xy 451.381982 -235.068163) (xy 451.344765 -235.1097)
			(xy 451.301897 -235.145375) (xy 451.254291 -235.174429) (xy 451.202962 -235.196241) (xy 451.149005 -235.210347)
			(xy 451.093568 -235.216447) (xy 451.037834 -235.21441) (xy 450.982991 -235.20428) (xy 450.930207 -235.186273)
			(xy 450.880607 -235.160772) (xy 450.835249 -235.128321) (xy 450.7951 -235.089612) (xy 450.761014 -235.045469)
			(xy 450.733718 -234.996834) (xy 450.713795 -234.944743) (xy 450.701669 -234.890306) (xy 450.697598 -234.834684)
			(xy 449.749404 -234.834684) (xy 449.722976 -234.880459) (xy 449.68649 -234.928008) (xy 449.64411 -234.970389)
			(xy 449.596561 -235.006875) (xy 449.544656 -235.036842) (xy 449.489283 -235.059778) (xy 449.431391 -235.075291)
			(xy 449.371969 -235.083114) (xy 449.342002 -235.083604) (xy 448.478402 -235.083604) (xy 448.448433 -235.083143)
			(xy 448.389007 -235.07532) (xy 448.33111 -235.059807) (xy 448.275734 -235.036869) (xy 448.223825 -235.0069)
			(xy 448.176273 -234.970412) (xy 448.13389 -234.928029) (xy 448.097401 -234.880476) (xy 448.067432 -234.828568)
			(xy 448.044494 -234.773192) (xy 448.028981 -234.715295) (xy 448.021157 -234.655869) (xy 437.102783 -234.655869)
			(xy 437.263657 -236.4994) (xy 444.422782 -236.4994) (xy 444.426853 -236.443778) (xy 444.438979 -236.389341)
			(xy 444.458902 -236.33725) (xy 444.486198 -236.288615) (xy 444.520284 -236.244472) (xy 444.560433 -236.205763)
			(xy 444.605791 -236.173312) (xy 444.655391 -236.147811) (xy 444.708175 -236.129804) (xy 444.763018 -236.119674)
			(xy 444.818752 -236.117637) (xy 444.874189 -236.123737) (xy 444.928146 -236.137843) (xy 444.979475 -236.159655)
			(xy 445.027081 -236.188709) (xy 445.069949 -236.224384) (xy 445.107166 -236.265921) (xy 445.137939 -236.312434)
			(xy 445.161611 -236.362931) (xy 445.169274 -236.388402) (xy 450.160898 -236.388402) (xy 450.161419 -236.359485)
			(xy 450.170147 -236.302314) (xy 450.187405 -236.247115) (xy 450.212796 -236.195154) (xy 450.245739 -236.14762)
			(xy 450.285479 -236.105603) (xy 450.307964 -236.087412) (xy 450.316766 -236.079801) (xy 450.32695 -236.058903)
			(xy 450.327522 -236.04728) (xy 450.327522 -235.967524) (xy 450.326947 -235.955897) (xy 450.316783 -235.934987)
			(xy 450.307964 -235.927392) (xy 450.285469 -235.909215) (xy 450.245736 -235.867191) (xy 450.2128 -235.819653)
			(xy 450.187414 -235.767689) (xy 450.170159 -235.71249) (xy 450.161432 -235.655319) (xy 450.160898 -235.626402)
			(xy 450.161384 -235.599151) (xy 450.16914 -235.545203) (xy 450.184495 -235.492908) (xy 450.207137 -235.443331)
			(xy 450.236603 -235.397481) (xy 450.272294 -235.35629) (xy 450.313485 -235.320599) (xy 450.359335 -235.291133)
			(xy 450.408912 -235.268491) (xy 450.461207 -235.253136) (xy 450.515155 -235.24538) (xy 450.569657 -235.24538)
			(xy 450.623605 -235.253136) (xy 450.6759 -235.268491) (xy 450.725477 -235.291133) (xy 450.771327 -235.320599)
			(xy 450.812518 -235.35629) (xy 450.848209 -235.397481) (xy 450.877675 -235.443331) (xy 450.900317 -235.492908)
			(xy 450.915672 -235.545203) (xy 450.923428 -235.599151) (xy 450.923914 -235.626402) (xy 450.92343 -235.655321)
			(xy 450.914698 -235.712495) (xy 450.897436 -235.767696) (xy 450.872038 -235.819658) (xy 450.839087 -235.867191)
			(xy 450.799338 -235.909204) (xy 450.776848 -235.927392) (xy 450.768046 -235.935003) (xy 450.757861 -235.955901)
			(xy 450.75729 -235.967524) (xy 450.75729 -236.04728) (xy 450.757859 -236.058908) (xy 450.768027 -236.079818)
			(xy 450.776848 -236.087412) (xy 450.799347 -236.105584) (xy 450.839079 -236.147609) (xy 450.872015 -236.195149)
			(xy 450.8974 -236.247113) (xy 450.914654 -236.302313) (xy 450.921397 -236.346492) (xy 454.16038 -236.346492)
			(xy 454.164451 -236.29087) (xy 454.176577 -236.236433) (xy 454.1965 -236.184342) (xy 454.223796 -236.135707)
			(xy 454.257882 -236.091564) (xy 454.298031 -236.052855) (xy 454.343389 -236.020404) (xy 454.392989 -235.994903)
			(xy 454.445773 -235.976896) (xy 454.500616 -235.966766) (xy 454.55635 -235.964729) (xy 454.611787 -235.970829)
			(xy 454.665744 -235.984935) (xy 454.717073 -236.006747) (xy 454.764679 -236.035801) (xy 454.807547 -236.071476)
			(xy 454.844764 -236.113013) (xy 454.875537 -236.159526) (xy 454.899209 -236.210023) (xy 454.915277 -236.26343)
			(xy 454.922866 -236.314996) (xy 455.160378 -236.314996) (xy 455.164449 -236.259374) (xy 455.176575 -236.204937)
			(xy 455.196498 -236.152846) (xy 455.223794 -236.104211) (xy 455.25788 -236.060068) (xy 455.298029 -236.021359)
			(xy 455.343387 -235.988908) (xy 455.392987 -235.963407) (xy 455.445771 -235.9454) (xy 455.500614 -235.93527)
			(xy 455.556348 -235.933233) (xy 455.611785 -235.939333) (xy 455.665742 -235.953439) (xy 455.717071 -235.975251)
			(xy 455.764677 -236.004305) (xy 455.807545 -236.03998) (xy 455.844762 -236.081517) (xy 455.875535 -236.12803)
			(xy 455.899207 -236.178527) (xy 455.915275 -236.231934) (xy 455.923395 -236.28711) (xy 455.923904 -236.314996)
			(xy 455.923395 -236.342882) (xy 455.915275 -236.398058) (xy 455.910691 -236.413294) (xy 456.148692 -236.413294)
			(xy 456.152763 -236.357672) (xy 456.164889 -236.303235) (xy 456.184812 -236.251144) (xy 456.212108 -236.202509)
			(xy 456.246194 -236.158366) (xy 456.286343 -236.119657) (xy 456.331701 -236.087206) (xy 456.381301 -236.061705)
			(xy 456.434085 -236.043698) (xy 456.488928 -236.033568) (xy 456.544662 -236.031531) (xy 456.600099 -236.037631)
			(xy 456.654056 -236.051737) (xy 456.705385 -236.073549) (xy 456.752991 -236.102603) (xy 456.795859 -236.138278)
			(xy 456.833076 -236.179815) (xy 456.863849 -236.226328) (xy 456.887521 -236.276825) (xy 456.903589 -236.330232)
			(xy 456.911709 -236.385408) (xy 456.912218 -236.413294) (xy 456.911709 -236.44118) (xy 456.903589 -236.496356)
			(xy 456.887521 -236.549763) (xy 456.863849 -236.60026) (xy 456.833076 -236.646773) (xy 456.795859 -236.68831)
			(xy 456.752991 -236.723985) (xy 456.705385 -236.753039) (xy 456.654056 -236.774851) (xy 456.600099 -236.788957)
			(xy 456.544662 -236.795057) (xy 456.488928 -236.79302) (xy 456.434085 -236.78289) (xy 456.381301 -236.764883)
			(xy 456.331701 -236.739382) (xy 456.286343 -236.706931) (xy 456.246194 -236.668222) (xy 456.212108 -236.624079)
			(xy 456.184812 -236.575444) (xy 456.164889 -236.523353) (xy 456.152763 -236.468916) (xy 456.148692 -236.413294)
			(xy 455.910691 -236.413294) (xy 455.899207 -236.451465) (xy 455.875535 -236.501962) (xy 455.844762 -236.548475)
			(xy 455.807545 -236.590012) (xy 455.764677 -236.625687) (xy 455.717071 -236.654741) (xy 455.665742 -236.676553)
			(xy 455.611785 -236.690659) (xy 455.556348 -236.696759) (xy 455.500614 -236.694722) (xy 455.445771 -236.684592)
			(xy 455.392987 -236.666585) (xy 455.343387 -236.641084) (xy 455.298029 -236.608633) (xy 455.25788 -236.569924)
			(xy 455.223794 -236.525781) (xy 455.196498 -236.477146) (xy 455.176575 -236.425055) (xy 455.164449 -236.370618)
			(xy 455.160378 -236.314996) (xy 454.922866 -236.314996) (xy 454.923397 -236.318606) (xy 454.923906 -236.346492)
			(xy 454.923397 -236.374378) (xy 454.915277 -236.429554) (xy 454.899209 -236.482961) (xy 454.875537 -236.533458)
			(xy 454.844764 -236.579971) (xy 454.807547 -236.621508) (xy 454.764679 -236.657183) (xy 454.717073 -236.686237)
			(xy 454.665744 -236.708049) (xy 454.611787 -236.722155) (xy 454.55635 -236.728255) (xy 454.500616 -236.726218)
			(xy 454.445773 -236.716088) (xy 454.392989 -236.698081) (xy 454.343389 -236.67258) (xy 454.298031 -236.640129)
			(xy 454.257882 -236.60142) (xy 454.223796 -236.557277) (xy 454.1965 -236.508642) (xy 454.176577 -236.456551)
			(xy 454.164451 -236.402114) (xy 454.16038 -236.346492) (xy 450.921397 -236.346492) (xy 450.92338 -236.359485)
			(xy 450.923914 -236.388402) (xy 450.923428 -236.415653) (xy 450.915672 -236.469601) (xy 450.900317 -236.521896)
			(xy 450.877675 -236.571473) (xy 450.848209 -236.617323) (xy 450.812518 -236.658514) (xy 450.771327 -236.694205)
			(xy 450.725477 -236.723671) (xy 450.6759 -236.746313) (xy 450.623605 -236.761668) (xy 450.569657 -236.769424)
			(xy 450.515155 -236.769424) (xy 450.461207 -236.761668) (xy 450.408912 -236.746313) (xy 450.359335 -236.723671)
			(xy 450.313485 -236.694205) (xy 450.272294 -236.658514) (xy 450.236603 -236.617323) (xy 450.207137 -236.571473)
			(xy 450.184495 -236.521896) (xy 450.16914 -236.469601) (xy 450.161384 -236.415653) (xy 450.160898 -236.388402)
			(xy 445.169274 -236.388402) (xy 445.177679 -236.416338) (xy 445.185799 -236.471514) (xy 445.186308 -236.4994)
			(xy 445.185799 -236.527286) (xy 445.177679 -236.582462) (xy 445.161611 -236.635869) (xy 445.137939 -236.686366)
			(xy 445.107166 -236.732879) (xy 445.069949 -236.774416) (xy 445.027081 -236.810091) (xy 444.979475 -236.839145)
			(xy 444.928146 -236.860957) (xy 444.874189 -236.875063) (xy 444.818752 -236.881163) (xy 444.763018 -236.879126)
			(xy 444.708175 -236.868996) (xy 444.655391 -236.850989) (xy 444.605791 -236.825488) (xy 444.560433 -236.793037)
			(xy 444.520284 -236.754328) (xy 444.486198 -236.710185) (xy 444.458902 -236.66155) (xy 444.438979 -236.609459)
			(xy 444.426853 -236.555022) (xy 444.422782 -236.4994) (xy 437.263657 -236.4994) (xy 437.352317 -237.5154)
			(xy 443.254382 -237.5154) (xy 443.258453 -237.459778) (xy 443.270579 -237.405341) (xy 443.290502 -237.35325)
			(xy 443.317798 -237.304615) (xy 443.351884 -237.260472) (xy 443.392033 -237.221763) (xy 443.437391 -237.189312)
			(xy 443.486991 -237.163811) (xy 443.539775 -237.145804) (xy 443.594618 -237.135674) (xy 443.650352 -237.133637)
			(xy 443.705789 -237.139737) (xy 443.759746 -237.153843) (xy 443.811075 -237.175655) (xy 443.858681 -237.204709)
			(xy 443.901549 -237.240384) (xy 443.938766 -237.281921) (xy 443.969539 -237.328434) (xy 443.993211 -237.378931)
			(xy 444.009279 -237.432338) (xy 444.017399 -237.487514) (xy 444.017908 -237.5154) (xy 444.017399 -237.543286)
			(xy 444.009279 -237.598462) (xy 443.993211 -237.651869) (xy 443.969539 -237.702366) (xy 443.938766 -237.748879)
			(xy 443.901549 -237.790416) (xy 443.858681 -237.826091) (xy 443.811075 -237.855145) (xy 443.759746 -237.876957)
			(xy 443.705789 -237.891063) (xy 443.650352 -237.897163) (xy 443.594618 -237.895126) (xy 443.539775 -237.884996)
			(xy 443.486991 -237.866989) (xy 443.437391 -237.841488) (xy 443.392033 -237.809037) (xy 443.351884 -237.770328)
			(xy 443.317798 -237.726185) (xy 443.290502 -237.67755) (xy 443.270579 -237.625459) (xy 443.258453 -237.571022)
			(xy 443.254382 -237.5154) (xy 437.352317 -237.5154) (xy 437.817673 -242.84813) (xy 451.778624 -242.84813)
			(xy 451.779037 -242.821814) (xy 451.786282 -242.769683) (xy 451.800611 -242.719039) (xy 451.821754 -242.67084)
			(xy 451.84931 -242.625998) (xy 451.882758 -242.585361) (xy 451.901814 -242.567206) (xy 451.909217 -242.559686)
			(xy 451.91774 -242.540405) (xy 451.918324 -242.529868) (xy 451.918324 -242.455192) (xy 451.917806 -242.444641)
			(xy 451.909262 -242.425346) (xy 451.901814 -242.417854) (xy 451.882746 -242.399711) (xy 451.849289 -242.359079)
			(xy 451.821732 -242.314236) (xy 451.800595 -242.266033) (xy 451.786281 -242.215383) (xy 451.77906 -242.163247)
			(xy 451.778624 -242.13693) (xy 451.779083 -242.109676) (xy 451.786837 -242.055724) (xy 451.802191 -242.003424)
			(xy 451.824832 -241.953842) (xy 451.8543 -241.907987) (xy 451.889994 -241.866793) (xy 451.931188 -241.831099)
			(xy 451.977043 -241.801631) (xy 452.026626 -241.77899) (xy 452.078926 -241.763637) (xy 452.132878 -241.755883)
			(xy 452.160132 -241.755422) (xy 452.186447 -241.755861) (xy 452.238577 -241.763101) (xy 452.289221 -241.777425)
			(xy 452.33742 -241.798563) (xy 452.382262 -241.826114) (xy 452.4229 -241.859558) (xy 452.441056 -241.878612)
			(xy 452.44859 -241.885998) (xy 452.467861 -241.894531) (xy 452.478394 -241.895122) (xy 452.55307 -241.895122)
			(xy 452.563618 -241.894583) (xy 452.582913 -241.886054) (xy 452.590408 -241.878612) (xy 452.610228 -241.857824)
			(xy 452.655 -241.821849) (xy 452.704658 -241.792989) (xy 452.75808 -241.771896) (xy 452.814059 -241.759047)
			(xy 452.871332 -241.754732) (xy 452.928605 -241.759047) (xy 452.984584 -241.771896) (xy 453.038006 -241.792989)
			(xy 453.087664 -241.821849) (xy 453.132436 -241.857824) (xy 453.152256 -241.878612) (xy 453.15979 -241.885998)
			(xy 453.179061 -241.894531) (xy 453.189594 -241.895122) (xy 453.26427 -241.895122) (xy 453.274818 -241.894583)
			(xy 453.294113 -241.886054) (xy 453.301608 -241.878612) (xy 453.319769 -241.859562) (xy 453.360397 -241.826104)
			(xy 453.405236 -241.798544) (xy 453.453436 -241.777404) (xy 453.504083 -241.763086) (xy 453.556216 -241.755861)
			(xy 453.582532 -241.755422) (xy 453.609785 -241.755848) (xy 453.663737 -241.76361) (xy 453.716035 -241.77897)
			(xy 453.765614 -241.801618) (xy 453.811466 -241.83109) (xy 453.852656 -241.866788) (xy 453.888347 -241.907984)
			(xy 453.917812 -241.953841) (xy 453.940451 -242.003424) (xy 453.955803 -242.055724) (xy 453.963556 -242.109677)
			(xy 453.96404 -242.13693) (xy 453.963612 -242.163246) (xy 453.956372 -242.215376) (xy 453.942046 -242.266021)
			(xy 453.920906 -242.31422) (xy 453.893352 -242.359062) (xy 453.859906 -242.399699) (xy 453.84085 -242.417854)
			(xy 453.83343 -242.42536) (xy 453.824915 -242.444652) (xy 453.82434 -242.455192) (xy 453.82434 -242.529868)
			(xy 453.824861 -242.540419) (xy 453.833401 -242.559715) (xy 453.84085 -242.567206) (xy 453.859911 -242.585356)
			(xy 453.893366 -242.625988) (xy 453.920923 -242.67083) (xy 453.94206 -242.719031) (xy 453.956377 -242.769679)
			(xy 453.963601 -242.821814) (xy 453.96404 -242.84813) (xy 453.96355 -242.875381) (xy 453.95579 -242.929326)
			(xy 453.940433 -242.981619) (xy 453.917791 -243.031194) (xy 453.888324 -243.077043) (xy 453.852634 -243.118232)
			(xy 453.811445 -243.153923) (xy 453.765596 -243.18339) (xy 453.716021 -243.206032) (xy 453.663728 -243.22139)
			(xy 453.609783 -243.22915) (xy 453.582532 -243.229638) (xy 453.556216 -243.229236) (xy 453.504083 -243.22199)
			(xy 453.453439 -243.20766) (xy 453.40524 -243.186515) (xy 453.360398 -243.158957) (xy 453.319762 -243.125506)
			(xy 453.301608 -243.106448) (xy 453.294079 -243.099055) (xy 453.274805 -243.090524) (xy 453.26427 -243.089938)
			(xy 453.189594 -243.089938) (xy 453.179041 -243.090439) (xy 453.159745 -243.098993) (xy 453.152256 -243.106448)
			(xy 453.132436 -243.127236) (xy 453.087664 -243.163211) (xy 453.038006 -243.192071) (xy 452.984584 -243.213164)
			(xy 452.928605 -243.226013) (xy 452.871332 -243.230328) (xy 452.814059 -243.226013) (xy 452.75808 -243.213164)
			(xy 452.704658 -243.192071) (xy 452.655 -243.163211) (xy 452.610228 -243.127236) (xy 452.590408 -243.106448)
			(xy 452.582879 -243.099055) (xy 452.563605 -243.090524) (xy 452.55307 -243.089938) (xy 452.478394 -243.089938)
			(xy 452.467841 -243.090439) (xy 452.448545 -243.098993) (xy 452.441056 -243.106448) (xy 452.422924 -243.125527)
			(xy 452.382288 -243.15898) (xy 452.337443 -243.186535) (xy 452.289237 -243.207669) (xy 452.238586 -243.221982)
			(xy 452.186449 -243.229202) (xy 452.160132 -243.229638) (xy 452.132881 -243.229115) (xy 452.078934 -243.221363)
			(xy 452.026639 -243.206013) (xy 451.977061 -243.183376) (xy 451.931209 -243.153914) (xy 451.890017 -243.118227)
			(xy 451.854323 -243.07704) (xy 451.824854 -243.031193) (xy 451.802209 -242.981619) (xy 451.78685 -242.929327)
			(xy 451.779089 -242.875381) (xy 451.778624 -242.84813) (xy 437.817673 -242.84813) (xy 438.051847 -245.53164)
			(xy 458.764894 -245.53164) (xy 458.765323 -245.505325) (xy 458.772566 -245.453195) (xy 458.786893 -245.402551)
			(xy 458.808033 -245.354353) (xy 458.835585 -245.30951) (xy 458.86903 -245.268872) (xy 458.888084 -245.250716)
			(xy 458.895478 -245.243188) (xy 458.904007 -245.223913) (xy 458.904594 -245.213378) (xy 458.904594 -245.138702)
			(xy 458.904079 -245.128151) (xy 458.895534 -245.108855) (xy 458.888084 -245.101364) (xy 458.869015 -245.083222)
			(xy 458.83556 -245.042589) (xy 458.808003 -244.997746) (xy 458.786867 -244.949542) (xy 458.772552 -244.898893)
			(xy 458.765331 -244.846757) (xy 458.764894 -244.82044) (xy 458.76538 -244.793189) (xy 458.773136 -244.739241)
			(xy 458.788491 -244.686946) (xy 458.811133 -244.637369) (xy 458.840599 -244.591519) (xy 458.87629 -244.550328)
			(xy 458.917481 -244.514637) (xy 458.963331 -244.485171) (xy 459.012908 -244.462529) (xy 459.065203 -244.447174)
			(xy 459.119151 -244.439418) (xy 459.173653 -244.439418) (xy 459.227601 -244.447174) (xy 459.279896 -244.462529)
			(xy 459.329473 -244.485171) (xy 459.375323 -244.514637) (xy 459.416514 -244.550328) (xy 459.452205 -244.591519)
			(xy 459.481671 -244.637369) (xy 459.504313 -244.686946) (xy 459.519668 -244.739241) (xy 459.527424 -244.793189)
			(xy 459.52791 -244.82044) (xy 459.527466 -244.846755) (xy 459.520226 -244.898884) (xy 459.505902 -244.949527)
			(xy 459.484765 -244.997726) (xy 459.457215 -245.042569) (xy 459.423773 -245.083208) (xy 459.40472 -245.101364)
			(xy 459.397335 -245.1089) (xy 459.3888 -245.128169) (xy 459.38821 -245.138702) (xy 459.38821 -245.213378)
			(xy 459.388735 -245.223928) (xy 459.397273 -245.243224) (xy 459.40472 -245.250716) (xy 459.42378 -245.268867)
			(xy 459.457236 -245.309498) (xy 459.484794 -245.354339) (xy 459.505932 -245.402541) (xy 459.520248 -245.453189)
			(xy 459.527472 -245.505324) (xy 459.52791 -245.53164) (xy 459.527424 -245.558891) (xy 459.519668 -245.612839)
			(xy 459.504313 -245.665134) (xy 459.481671 -245.714711) (xy 459.452205 -245.760561) (xy 459.416514 -245.801752)
			(xy 459.375323 -245.837443) (xy 459.329473 -245.866909) (xy 459.279896 -245.889551) (xy 459.227601 -245.904906)
			(xy 459.173653 -245.912662) (xy 459.119151 -245.912662) (xy 459.065203 -245.904906) (xy 459.012908 -245.889551)
			(xy 458.963331 -245.866909) (xy 458.917481 -245.837443) (xy 458.87629 -245.801752) (xy 458.840599 -245.760561)
			(xy 458.811133 -245.714711) (xy 458.788491 -245.665134) (xy 458.773136 -245.612839) (xy 458.76538 -245.558891)
			(xy 458.764894 -245.53164) (xy 438.051847 -245.53164) (xy 438.10726 -246.16664) (xy 454.116184 -246.16664)
			(xy 454.120255 -246.111018) (xy 454.132381 -246.056581) (xy 454.152304 -246.00449) (xy 454.1796 -245.955855)
			(xy 454.213686 -245.911712) (xy 454.253835 -245.873003) (xy 454.299193 -245.840552) (xy 454.348793 -245.815051)
			(xy 454.401577 -245.797044) (xy 454.45642 -245.786914) (xy 454.512154 -245.784877) (xy 454.567591 -245.790977)
			(xy 454.621548 -245.805083) (xy 454.672877 -245.826895) (xy 454.720483 -245.855949) (xy 454.763351 -245.891624)
			(xy 454.800568 -245.933161) (xy 454.831341 -245.979674) (xy 454.855013 -246.030171) (xy 454.871081 -246.083578)
			(xy 454.879201 -246.138754) (xy 454.87971 -246.16664) (xy 457.316584 -246.16664) (xy 457.320655 -246.111018)
			(xy 457.332781 -246.056581) (xy 457.352704 -246.00449) (xy 457.38 -245.955855) (xy 457.414086 -245.911712)
			(xy 457.454235 -245.873003) (xy 457.499593 -245.840552) (xy 457.549193 -245.815051) (xy 457.601977 -245.797044)
			(xy 457.65682 -245.786914) (xy 457.712554 -245.784877) (xy 457.767991 -245.790977) (xy 457.821948 -245.805083)
			(xy 457.873277 -245.826895) (xy 457.920883 -245.855949) (xy 457.963751 -245.891624) (xy 458.000968 -245.933161)
			(xy 458.031741 -245.979674) (xy 458.055413 -246.030171) (xy 458.071481 -246.083578) (xy 458.079601 -246.138754)
			(xy 458.08011 -246.16664) (xy 458.079646 -246.19204) (xy 458.205584 -246.19204) (xy 458.209655 -246.136418)
			(xy 458.221781 -246.081981) (xy 458.241704 -246.02989) (xy 458.269 -245.981255) (xy 458.303086 -245.937112)
			(xy 458.343235 -245.898403) (xy 458.388593 -245.865952) (xy 458.438193 -245.840451) (xy 458.490977 -245.822444)
			(xy 458.54582 -245.812314) (xy 458.601554 -245.810277) (xy 458.656991 -245.816377) (xy 458.710948 -245.830483)
			(xy 458.762277 -245.852295) (xy 458.809883 -245.881349) (xy 458.852751 -245.917024) (xy 458.889968 -245.958561)
			(xy 458.920741 -246.005074) (xy 458.944413 -246.055571) (xy 458.960481 -246.108978) (xy 458.968601 -246.164154)
			(xy 458.96911 -246.19204) (xy 458.968601 -246.219926) (xy 458.960481 -246.275102) (xy 458.944413 -246.328509)
			(xy 458.920741 -246.379006) (xy 458.889968 -246.425519) (xy 458.852751 -246.467056) (xy 458.809883 -246.502731)
			(xy 458.762277 -246.531785) (xy 458.710948 -246.553597) (xy 458.656991 -246.567703) (xy 458.601554 -246.573803)
			(xy 458.54582 -246.571766) (xy 458.490977 -246.561636) (xy 458.438193 -246.543629) (xy 458.388593 -246.518128)
			(xy 458.343235 -246.485677) (xy 458.303086 -246.446968) (xy 458.269 -246.402825) (xy 458.241704 -246.35419)
			(xy 458.221781 -246.302099) (xy 458.209655 -246.247662) (xy 458.205584 -246.19204) (xy 458.079646 -246.19204)
			(xy 458.079601 -246.194526) (xy 458.071481 -246.249702) (xy 458.055413 -246.303109) (xy 458.031741 -246.353606)
			(xy 458.000968 -246.400119) (xy 457.963751 -246.441656) (xy 457.920883 -246.477331) (xy 457.873277 -246.506385)
			(xy 457.821948 -246.528197) (xy 457.767991 -246.542303) (xy 457.712554 -246.548403) (xy 457.65682 -246.546366)
			(xy 457.601977 -246.536236) (xy 457.549193 -246.518229) (xy 457.499593 -246.492728) (xy 457.454235 -246.460277)
			(xy 457.414086 -246.421568) (xy 457.38 -246.377425) (xy 457.352704 -246.32879) (xy 457.332781 -246.276699)
			(xy 457.320655 -246.222262) (xy 457.316584 -246.16664) (xy 454.87971 -246.16664) (xy 454.879201 -246.194526)
			(xy 454.871081 -246.249702) (xy 454.855013 -246.303109) (xy 454.831341 -246.353606) (xy 454.800568 -246.400119)
			(xy 454.763351 -246.441656) (xy 454.720483 -246.477331) (xy 454.672877 -246.506385) (xy 454.621548 -246.528197)
			(xy 454.567591 -246.542303) (xy 454.512154 -246.548403) (xy 454.45642 -246.546366) (xy 454.401577 -246.536236)
			(xy 454.348793 -246.518229) (xy 454.299193 -246.492728) (xy 454.253835 -246.460277) (xy 454.213686 -246.421568)
			(xy 454.1796 -246.377425) (xy 454.152304 -246.32879) (xy 454.132381 -246.276699) (xy 454.120255 -246.222262)
			(xy 454.116184 -246.16664) (xy 438.10726 -246.16664) (xy 438.342368 -248.86085) (xy 451.577195 -248.86085)
			(xy 451.577195 -248.80635) (xy 451.584951 -248.752404) (xy 451.600306 -248.700112) (xy 451.622946 -248.650537)
			(xy 451.652411 -248.604688) (xy 451.688101 -248.5635) (xy 451.72929 -248.52781) (xy 451.775139 -248.498345)
			(xy 451.824714 -248.475705) (xy 451.877006 -248.460351) (xy 451.930952 -248.452595) (xy 451.958202 -248.452132)
			(xy 451.985446 -248.45261) (xy 452.03938 -248.460367) (xy 452.091659 -248.475724) (xy 452.14122 -248.498367)
			(xy 452.187053 -248.527835) (xy 452.228223 -248.563527) (xy 452.263893 -248.604718) (xy 452.279004 -248.627392)
			(xy 452.283877 -248.634398) (xy 452.297271 -248.644952) (xy 452.313402 -248.650485) (xy 452.32193 -248.65076)
			(xy 452.407274 -248.65076) (xy 452.415794 -248.650449) (xy 452.431903 -248.644892) (xy 452.445314 -248.634379)
			(xy 452.4502 -248.627392) (xy 452.46533 -248.60473) (xy 452.500993 -248.563533) (xy 452.542158 -248.527834)
			(xy 452.587987 -248.498361) (xy 452.637546 -248.475714) (xy 452.689825 -248.460354) (xy 452.743758 -248.452595)
			(xy 452.771002 -248.452132) (xy 452.796977 -248.45258) (xy 452.848448 -248.459623) (xy 452.898485 -248.473591)
			(xy 452.946161 -248.494226) (xy 452.990592 -248.521146) (xy 453.030956 -248.55385) (xy 453.066503 -248.591734)
			(xy 453.081898 -248.61266) (xy 453.089508 -248.622172) (xy 453.111137 -248.633305) (xy 453.1233 -248.633996)
			(xy 453.206104 -248.633996) (xy 453.218266 -248.633301) (xy 453.23989 -248.622167) (xy 453.247506 -248.61266)
			(xy 453.262889 -248.591726) (xy 453.298445 -248.553849) (xy 453.338813 -248.521149) (xy 453.383246 -248.494232)
			(xy 453.430922 -248.473596) (xy 453.480957 -248.459623) (xy 453.532427 -248.452571) (xy 453.558402 -248.452132)
			(xy 453.585656 -248.452538) (xy 453.639609 -248.460296) (xy 453.691909 -248.475652) (xy 453.741491 -248.498296)
			(xy 453.787346 -248.527766) (xy 453.828541 -248.563461) (xy 453.864236 -248.604655) (xy 453.893705 -248.65051)
			(xy 453.916348 -248.700093) (xy 453.931705 -248.752393) (xy 453.939462 -248.806346) (xy 453.939462 -248.860854)
			(xy 453.931705 -248.914807) (xy 453.916348 -248.967107) (xy 453.893705 -249.01669) (xy 453.864236 -249.062545)
			(xy 453.828541 -249.103739) (xy 453.787346 -249.139434) (xy 453.741491 -249.168904) (xy 453.691909 -249.191548)
			(xy 453.639609 -249.206904) (xy 453.585656 -249.214662) (xy 453.558402 -249.215148) (xy 453.532427 -249.214705)
			(xy 453.480956 -249.207663) (xy 453.430918 -249.193694) (xy 453.383242 -249.173058) (xy 453.33881 -249.146138)
			(xy 453.298447 -249.113432) (xy 453.2629 -249.075547) (xy 453.247506 -249.05462) (xy 453.239898 -249.045106)
			(xy 453.218267 -249.033975) (xy 453.206104 -249.033284) (xy 453.1233 -249.033284) (xy 453.111139 -249.03399)
			(xy 453.089516 -249.045117) (xy 453.081898 -249.05462) (xy 453.066507 -249.075548) (xy 453.030953 -249.113426)
			(xy 452.990587 -249.146127) (xy 452.946155 -249.173045) (xy 452.89848 -249.193682) (xy 452.848446 -249.207656)
			(xy 452.796977 -249.214709) (xy 452.771002 -249.215148) (xy 452.743757 -249.214676) (xy 452.689823 -249.206919)
			(xy 452.637543 -249.191562) (xy 452.587982 -249.168918) (xy 452.54215 -249.139449) (xy 452.500979 -249.103755)
			(xy 452.46531 -249.062563) (xy 452.4502 -249.039888) (xy 452.445331 -249.03288) (xy 452.431934 -249.022327)
			(xy 452.415803 -249.016795) (xy 452.407274 -249.01652) (xy 452.32193 -249.01652) (xy 452.313406 -249.016798)
			(xy 452.297293 -249.022364) (xy 452.283885 -249.032893) (xy 452.279004 -249.039888) (xy 452.263898 -249.062566)
			(xy 452.228228 -249.103759) (xy 452.187058 -249.139454) (xy 452.141225 -249.168924) (xy 452.091663 -249.191569)
			(xy 452.039382 -249.206926) (xy 451.985447 -249.214684) (xy 451.958202 -249.215148) (xy 451.930952 -249.214605)
			(xy 451.877006 -249.206849) (xy 451.824714 -249.191495) (xy 451.775139 -249.168855) (xy 451.72929 -249.13939)
			(xy 451.688101 -249.1037) (xy 451.652411 -249.062512) (xy 451.622946 -249.016663) (xy 451.600306 -248.967088)
			(xy 451.584951 -248.914796) (xy 451.577195 -248.86085) (xy 438.342368 -248.86085) (xy 438.342786 -248.865644)
			(xy 438.343538 -248.871856) (xy 438.347654 -248.88367) (xy 438.350914 -248.889012) (xy 439.218809 -250.20524)
			(xy 453.481184 -250.20524) (xy 453.485255 -250.149618) (xy 453.497381 -250.095181) (xy 453.517304 -250.04309)
			(xy 453.5446 -249.994455) (xy 453.578686 -249.950312) (xy 453.618835 -249.911603) (xy 453.664193 -249.879152)
			(xy 453.713793 -249.853651) (xy 453.766577 -249.835644) (xy 453.82142 -249.825514) (xy 453.877154 -249.823477)
			(xy 453.932591 -249.829577) (xy 453.986548 -249.843683) (xy 454.037877 -249.865495) (xy 454.085483 -249.894549)
			(xy 454.128351 -249.930224) (xy 454.165568 -249.971761) (xy 454.196341 -250.018274) (xy 454.220013 -250.068771)
			(xy 454.236081 -250.122178) (xy 454.239782 -250.147328) (xy 458.853538 -250.147328) (xy 458.857609 -250.091706)
			(xy 458.869735 -250.037269) (xy 458.889658 -249.985178) (xy 458.916954 -249.936543) (xy 458.95104 -249.8924)
			(xy 458.991189 -249.853691) (xy 459.036547 -249.82124) (xy 459.086147 -249.795739) (xy 459.138931 -249.777732)
			(xy 459.193774 -249.767602) (xy 459.249508 -249.765565) (xy 459.304945 -249.771665) (xy 459.358902 -249.785771)
			(xy 459.410231 -249.807583) (xy 459.457837 -249.836637) (xy 459.500705 -249.872312) (xy 459.537922 -249.913849)
			(xy 459.568695 -249.960362) (xy 459.592367 -250.010859) (xy 459.608435 -250.064266) (xy 459.616555 -250.119442)
			(xy 459.617064 -250.147328) (xy 459.616555 -250.175214) (xy 459.608435 -250.23039) (xy 459.592367 -250.283797)
			(xy 459.568695 -250.334294) (xy 459.537922 -250.380807) (xy 459.500705 -250.422344) (xy 459.457837 -250.458019)
			(xy 459.410231 -250.487073) (xy 459.358902 -250.508885) (xy 459.304945 -250.522991) (xy 459.249508 -250.529091)
			(xy 459.193774 -250.527054) (xy 459.138931 -250.516924) (xy 459.086147 -250.498917) (xy 459.036547 -250.473416)
			(xy 458.991189 -250.440965) (xy 458.95104 -250.402256) (xy 458.916954 -250.358113) (xy 458.889658 -250.309478)
			(xy 458.869735 -250.257387) (xy 458.857609 -250.20295) (xy 458.853538 -250.147328) (xy 454.239782 -250.147328)
			(xy 454.244201 -250.177354) (xy 454.24471 -250.20524) (xy 454.244201 -250.233126) (xy 454.236081 -250.288302)
			(xy 454.220013 -250.341709) (xy 454.196341 -250.392206) (xy 454.165568 -250.438719) (xy 454.128351 -250.480256)
			(xy 454.085483 -250.515931) (xy 454.037877 -250.544985) (xy 453.986548 -250.566797) (xy 453.932591 -250.580903)
			(xy 453.877154 -250.587003) (xy 453.82142 -250.584966) (xy 453.766577 -250.574836) (xy 453.713793 -250.556829)
			(xy 453.664193 -250.531328) (xy 453.618835 -250.498877) (xy 453.578686 -250.460168) (xy 453.5446 -250.416025)
			(xy 453.517304 -250.36739) (xy 453.497381 -250.315299) (xy 453.485255 -250.260862) (xy 453.481184 -250.20524)
			(xy 439.218809 -250.20524) (xy 439.553439 -250.712732) (xy 443.057278 -250.712732) (xy 443.061349 -250.65711)
			(xy 443.073475 -250.602673) (xy 443.093398 -250.550582) (xy 443.120694 -250.501947) (xy 443.15478 -250.457804)
			(xy 443.194929 -250.419095) (xy 443.240287 -250.386644) (xy 443.289887 -250.361143) (xy 443.342671 -250.343136)
			(xy 443.397514 -250.333006) (xy 443.453248 -250.330969) (xy 443.508685 -250.337069) (xy 443.562642 -250.351175)
			(xy 443.613971 -250.372987) (xy 443.661577 -250.402041) (xy 443.704445 -250.437716) (xy 443.741662 -250.479253)
			(xy 443.772435 -250.525766) (xy 443.796107 -250.576263) (xy 443.812175 -250.62967) (xy 443.820295 -250.684846)
			(xy 443.820804 -250.712732) (xy 443.820295 -250.740618) (xy 443.812175 -250.795794) (xy 443.796107 -250.849201)
			(xy 443.772435 -250.899698) (xy 443.753964 -250.927616) (xy 443.943738 -250.927616) (xy 443.947809 -250.871994)
			(xy 443.959935 -250.817557) (xy 443.979858 -250.765466) (xy 444.007154 -250.716831) (xy 444.04124 -250.672688)
			(xy 444.081389 -250.633979) (xy 444.126747 -250.601528) (xy 444.176347 -250.576027) (xy 444.229131 -250.55802)
			(xy 444.283974 -250.54789) (xy 444.339708 -250.545853) (xy 444.395145 -250.551953) (xy 444.449102 -250.566059)
			(xy 444.500431 -250.587871) (xy 444.548037 -250.616925) (xy 444.590905 -250.6526) (xy 444.628122 -250.694137)
			(xy 444.658895 -250.74065) (xy 444.682567 -250.791147) (xy 444.698635 -250.844554) (xy 444.706755 -250.89973)
			(xy 444.707264 -250.927616) (xy 444.706755 -250.955502) (xy 444.698635 -251.010678) (xy 444.682567 -251.064085)
			(xy 444.658895 -251.114582) (xy 444.628122 -251.161095) (xy 444.590905 -251.202632) (xy 444.548037 -251.238307)
			(xy 444.500431 -251.267361) (xy 444.449102 -251.289173) (xy 444.395145 -251.303279) (xy 444.339708 -251.309379)
			(xy 444.283974 -251.307342) (xy 444.229131 -251.297212) (xy 444.176347 -251.279205) (xy 444.126747 -251.253704)
			(xy 444.081389 -251.221253) (xy 444.04124 -251.182544) (xy 444.007154 -251.138401) (xy 443.979858 -251.089766)
			(xy 443.959935 -251.037675) (xy 443.947809 -250.983238) (xy 443.943738 -250.927616) (xy 443.753964 -250.927616)
			(xy 443.741662 -250.946211) (xy 443.704445 -250.987748) (xy 443.661577 -251.023423) (xy 443.613971 -251.052477)
			(xy 443.562642 -251.074289) (xy 443.508685 -251.088395) (xy 443.453248 -251.094495) (xy 443.397514 -251.092458)
			(xy 443.342671 -251.082328) (xy 443.289887 -251.064321) (xy 443.240287 -251.03882) (xy 443.194929 -251.006369)
			(xy 443.15478 -250.96766) (xy 443.120694 -250.923517) (xy 443.093398 -250.874882) (xy 443.073475 -250.822791)
			(xy 443.061349 -250.768354) (xy 443.057278 -250.712732) (xy 439.553439 -250.712732) (xy 440.263397 -251.789438)
			(xy 444.588898 -251.789438) (xy 444.592969 -251.733816) (xy 444.605095 -251.679379) (xy 444.625018 -251.627288)
			(xy 444.652314 -251.578653) (xy 444.6864 -251.53451) (xy 444.726549 -251.495801) (xy 444.771907 -251.46335)
			(xy 444.821507 -251.437849) (xy 444.874291 -251.419842) (xy 444.929134 -251.409712) (xy 444.984868 -251.407675)
			(xy 445.040305 -251.413775) (xy 445.094262 -251.427881) (xy 445.145591 -251.449693) (xy 445.193197 -251.478747)
			(xy 445.236065 -251.514422) (xy 445.273282 -251.555959) (xy 445.304055 -251.602472) (xy 445.327727 -251.652969)
			(xy 445.343795 -251.706376) (xy 445.351915 -251.761552) (xy 445.352424 -251.789438) (xy 445.351915 -251.817324)
			(xy 445.343795 -251.8725) (xy 445.327727 -251.925907) (xy 445.304055 -251.976404) (xy 445.273282 -252.022917)
			(xy 445.23872 -252.061491) (xy 446.710002 -252.061491) (xy 446.717753 -252.007532) (xy 446.733105 -251.955225)
			(xy 446.755744 -251.905635) (xy 446.78521 -251.859772) (xy 446.820904 -251.81857) (xy 446.862098 -251.782866)
			(xy 446.907953 -251.753389) (xy 446.957537 -251.730737) (xy 447.00984 -251.715373) (xy 447.063798 -251.707608)
			(xy 447.091054 -251.707142) (xy 447.112189 -251.707444) (xy 447.154196 -251.712159) (xy 447.174874 -251.71654)
			(xy 447.189052 -251.719147) (xy 447.217804 -251.71737) (xy 447.244913 -251.707622) (xy 447.268213 -251.690682)
			(xy 447.285847 -251.667901) (xy 447.296405 -251.641098) (xy 447.299046 -251.612412) (xy 447.296794 -251.598176)
			(xy 447.293599 -251.580377) (xy 447.290162 -251.544376) (xy 447.289936 -251.526294) (xy 447.289936 -251.52604)
			(xy 447.290335 -251.498786) (xy 447.298087 -251.444832) (xy 447.313438 -251.39253) (xy 447.336076 -251.342945)
			(xy 447.36554 -251.297087) (xy 447.401231 -251.255889) (xy 447.442422 -251.220189) (xy 447.488274 -251.190715)
			(xy 447.537854 -251.168066) (xy 447.590152 -251.152704) (xy 447.644105 -251.144941) (xy 447.698613 -251.144935)
			(xy 447.752567 -251.152686) (xy 447.804869 -251.168037) (xy 447.854453 -251.190675) (xy 447.900312 -251.22014)
			(xy 447.94151 -251.25583) (xy 447.97721 -251.297021) (xy 448.006684 -251.342873) (xy 448.029333 -251.392453)
			(xy 448.044696 -251.444751) (xy 448.052459 -251.498703) (xy 448.052465 -251.553211) (xy 448.044714 -251.607166)
			(xy 448.029363 -251.659467) (xy 448.025223 -251.668534) (xy 450.165722 -251.668534) (xy 450.169793 -251.612912)
			(xy 450.181919 -251.558475) (xy 450.201842 -251.506384) (xy 450.229138 -251.457749) (xy 450.263224 -251.413606)
			(xy 450.303373 -251.374897) (xy 450.348731 -251.342446) (xy 450.398331 -251.316945) (xy 450.451115 -251.298938)
			(xy 450.505958 -251.288808) (xy 450.561692 -251.286771) (xy 450.617129 -251.292871) (xy 450.671086 -251.306977)
			(xy 450.722415 -251.328789) (xy 450.770021 -251.357843) (xy 450.789003 -251.37364) (xy 457.418184 -251.37364)
			(xy 457.422255 -251.318018) (xy 457.434381 -251.263581) (xy 457.454304 -251.21149) (xy 457.4816 -251.162855)
			(xy 457.515686 -251.118712) (xy 457.555835 -251.080003) (xy 457.601193 -251.047552) (xy 457.650793 -251.022051)
			(xy 457.703577 -251.004044) (xy 457.75842 -250.993914) (xy 457.814154 -250.991877) (xy 457.869591 -250.997977)
			(xy 457.923548 -251.012083) (xy 457.974877 -251.033895) (xy 458.022483 -251.062949) (xy 458.065351 -251.098624)
			(xy 458.102568 -251.140161) (xy 458.133341 -251.186674) (xy 458.157013 -251.237171) (xy 458.173081 -251.290578)
			(xy 458.181201 -251.345754) (xy 458.18171 -251.37364) (xy 458.181201 -251.401526) (xy 458.173081 -251.456702)
			(xy 458.157013 -251.510109) (xy 458.133341 -251.560606) (xy 458.102568 -251.607119) (xy 458.065351 -251.648656)
			(xy 458.022483 -251.684331) (xy 457.974877 -251.713385) (xy 457.923548 -251.735197) (xy 457.869591 -251.749303)
			(xy 457.814154 -251.755403) (xy 457.75842 -251.753366) (xy 457.703577 -251.743236) (xy 457.650793 -251.725229)
			(xy 457.601193 -251.699728) (xy 457.555835 -251.667277) (xy 457.515686 -251.628568) (xy 457.4816 -251.584425)
			(xy 457.454304 -251.53579) (xy 457.434381 -251.483699) (xy 457.422255 -251.429262) (xy 457.418184 -251.37364)
			(xy 450.789003 -251.37364) (xy 450.812889 -251.393518) (xy 450.850106 -251.435055) (xy 450.880879 -251.481568)
			(xy 450.904551 -251.532065) (xy 450.920619 -251.585472) (xy 450.928739 -251.640648) (xy 450.929248 -251.668534)
			(xy 450.928739 -251.69642) (xy 450.920619 -251.751596) (xy 450.904551 -251.805003) (xy 450.880879 -251.8555)
			(xy 450.850106 -251.902013) (xy 450.812889 -251.94355) (xy 450.770021 -251.979225) (xy 450.722415 -252.008279)
			(xy 450.671086 -252.030091) (xy 450.617129 -252.044197) (xy 450.561692 -252.050297) (xy 450.505958 -252.04826)
			(xy 450.451115 -252.03813) (xy 450.398331 -252.020123) (xy 450.348731 -251.994622) (xy 450.303373 -251.962171)
			(xy 450.263224 -251.923462) (xy 450.229138 -251.879319) (xy 450.201842 -251.830684) (xy 450.181919 -251.778593)
			(xy 450.169793 -251.724156) (xy 450.165722 -251.668534) (xy 448.025223 -251.668534) (xy 448.006725 -251.709052)
			(xy 447.977261 -251.754911) (xy 447.941571 -251.796109) (xy 447.90038 -251.831809) (xy 447.854528 -251.861284)
			(xy 447.804949 -251.883933) (xy 447.75265 -251.899295) (xy 447.698698 -251.907059) (xy 447.671444 -251.907548)
			(xy 447.650309 -251.907246) (xy 447.608302 -251.902531) (xy 447.587624 -251.89815) (xy 447.57346 -251.895435)
			(xy 447.544687 -251.897213) (xy 447.51756 -251.906971) (xy 447.494248 -251.923929) (xy 447.476612 -251.946733)
			(xy 447.466061 -251.973561) (xy 447.463439 -252.00227) (xy 447.465704 -252.016514) (xy 447.468898 -252.034313)
			(xy 447.472335 -252.070314) (xy 447.472562 -252.088396) (xy 447.472562 -252.08865) (xy 447.472199 -252.115907)
			(xy 447.464448 -252.169866) (xy 447.449096 -252.222173) (xy 447.426457 -252.271762) (xy 447.396991 -252.317625)
			(xy 447.361298 -252.358828) (xy 447.320105 -252.394532) (xy 447.274249 -252.42401) (xy 447.224665 -252.446662)
			(xy 447.172362 -252.462027) (xy 447.118405 -252.469792) (xy 447.063892 -252.469799) (xy 447.009933 -252.462047)
			(xy 446.957626 -252.446696) (xy 446.908036 -252.424057) (xy 446.862173 -252.39459) (xy 446.820971 -252.358897)
			(xy 446.785267 -252.317704) (xy 446.755789 -252.271848) (xy 446.733138 -252.222264) (xy 446.717773 -252.169961)
			(xy 446.710008 -252.116004) (xy 446.710002 -252.061491) (xy 445.23872 -252.061491) (xy 445.236065 -252.064454)
			(xy 445.193197 -252.100129) (xy 445.145591 -252.129183) (xy 445.094262 -252.150995) (xy 445.040305 -252.165101)
			(xy 444.984868 -252.171201) (xy 444.929134 -252.169164) (xy 444.874291 -252.159034) (xy 444.821507 -252.141027)
			(xy 444.771907 -252.115526) (xy 444.726549 -252.083075) (xy 444.6864 -252.044366) (xy 444.652314 -252.000223)
			(xy 444.625018 -251.951588) (xy 444.605095 -251.899497) (xy 444.592969 -251.84506) (xy 444.588898 -251.789438)
			(xy 440.263397 -251.789438) (xy 440.713758 -252.472444) (xy 443.78194 -252.472444) (xy 443.786011 -252.416822)
			(xy 443.798137 -252.362385) (xy 443.81806 -252.310294) (xy 443.845356 -252.261659) (xy 443.879442 -252.217516)
			(xy 443.919591 -252.178807) (xy 443.964949 -252.146356) (xy 444.014549 -252.120855) (xy 444.067333 -252.102848)
			(xy 444.122176 -252.092718) (xy 444.17791 -252.090681) (xy 444.233347 -252.096781) (xy 444.287304 -252.110887)
			(xy 444.338633 -252.132699) (xy 444.386239 -252.161753) (xy 444.429107 -252.197428) (xy 444.466324 -252.238965)
			(xy 444.497097 -252.285478) (xy 444.520769 -252.335975) (xy 444.536837 -252.389382) (xy 444.544957 -252.444558)
			(xy 444.545466 -252.472444) (xy 444.544957 -252.50033) (xy 444.536837 -252.555506) (xy 444.520769 -252.608913)
			(xy 444.497097 -252.65941) (xy 444.466324 -252.705923) (xy 444.429107 -252.74746) (xy 444.386239 -252.783135)
			(xy 444.338633 -252.812189) (xy 444.287304 -252.834001) (xy 444.233347 -252.848107) (xy 444.17791 -252.854207)
			(xy 444.122176 -252.85217) (xy 444.067333 -252.84204) (xy 444.014549 -252.824033) (xy 443.964949 -252.798532)
			(xy 443.919591 -252.766081) (xy 443.879442 -252.727372) (xy 443.845356 -252.683229) (xy 443.81806 -252.634594)
			(xy 443.798137 -252.582503) (xy 443.786011 -252.528066) (xy 443.78194 -252.472444) (xy 440.713758 -252.472444)
			(xy 440.989602 -252.890782) (xy 446.373756 -252.890782) (xy 446.377827 -252.83516) (xy 446.389953 -252.780723)
			(xy 446.409876 -252.728632) (xy 446.437172 -252.679997) (xy 446.471258 -252.635854) (xy 446.511407 -252.597145)
			(xy 446.556765 -252.564694) (xy 446.606365 -252.539193) (xy 446.659149 -252.521186) (xy 446.713992 -252.511056)
			(xy 446.769726 -252.509019) (xy 446.825163 -252.515119) (xy 446.87912 -252.529225) (xy 446.930449 -252.551037)
			(xy 446.978055 -252.580091) (xy 447.020923 -252.615766) (xy 447.05814 -252.657303) (xy 447.088913 -252.703816)
			(xy 447.107022 -252.742446) (xy 450.334886 -252.742446) (xy 450.338957 -252.686824) (xy 450.351083 -252.632387)
			(xy 450.371006 -252.580296) (xy 450.398302 -252.531661) (xy 450.432388 -252.487518) (xy 450.472537 -252.448809)
			(xy 450.517895 -252.416358) (xy 450.567495 -252.390857) (xy 450.620279 -252.37285) (xy 450.675122 -252.36272)
			(xy 450.730856 -252.360683) (xy 450.786293 -252.366783) (xy 450.84025 -252.380889) (xy 450.891579 -252.402701)
			(xy 450.939185 -252.431755) (xy 450.982053 -252.46743) (xy 451.01927 -252.508967) (xy 451.050043 -252.55548)
			(xy 451.073715 -252.605977) (xy 451.089783 -252.659384) (xy 451.097903 -252.71456) (xy 451.098412 -252.742446)
			(xy 451.097903 -252.770332) (xy 451.09625 -252.781562) (xy 451.520304 -252.781562) (xy 451.524375 -252.72594)
			(xy 451.536501 -252.671503) (xy 451.556424 -252.619412) (xy 451.58372 -252.570777) (xy 451.617806 -252.526634)
			(xy 451.657955 -252.487925) (xy 451.703313 -252.455474) (xy 451.752913 -252.429973) (xy 451.805697 -252.411966)
			(xy 451.86054 -252.401836) (xy 451.916274 -252.399799) (xy 451.971711 -252.405899) (xy 452.025668 -252.420005)
			(xy 452.076997 -252.441817) (xy 452.124603 -252.470871) (xy 452.167471 -252.506546) (xy 452.204688 -252.548083)
			(xy 452.235461 -252.594596) (xy 452.259133 -252.645093) (xy 452.275201 -252.6985) (xy 452.283321 -252.753676)
			(xy 452.28383 -252.781562) (xy 452.283321 -252.809448) (xy 452.275201 -252.864624) (xy 452.259133 -252.918031)
			(xy 452.235461 -252.968528) (xy 452.204688 -253.015041) (xy 452.167471 -253.056578) (xy 452.124603 -253.092253)
			(xy 452.076997 -253.121307) (xy 452.025668 -253.143119) (xy 451.971711 -253.157225) (xy 451.916274 -253.163325)
			(xy 451.86054 -253.161288) (xy 451.805697 -253.151158) (xy 451.752913 -253.133151) (xy 451.703313 -253.10765)
			(xy 451.657955 -253.075199) (xy 451.617806 -253.03649) (xy 451.58372 -252.992347) (xy 451.556424 -252.943712)
			(xy 451.536501 -252.891621) (xy 451.524375 -252.837184) (xy 451.520304 -252.781562) (xy 451.09625 -252.781562)
			(xy 451.089783 -252.825508) (xy 451.073715 -252.878915) (xy 451.050043 -252.929412) (xy 451.01927 -252.975925)
			(xy 450.982053 -253.017462) (xy 450.939185 -253.053137) (xy 450.891579 -253.082191) (xy 450.84025 -253.104003)
			(xy 450.786293 -253.118109) (xy 450.730856 -253.124209) (xy 450.675122 -253.122172) (xy 450.620279 -253.112042)
			(xy 450.567495 -253.094035) (xy 450.517895 -253.068534) (xy 450.472537 -253.036083) (xy 450.432388 -252.997374)
			(xy 450.398302 -252.953231) (xy 450.371006 -252.904596) (xy 450.351083 -252.852505) (xy 450.338957 -252.798068)
			(xy 450.334886 -252.742446) (xy 447.107022 -252.742446) (xy 447.112585 -252.754313) (xy 447.128653 -252.80772)
			(xy 447.136773 -252.862896) (xy 447.137282 -252.890782) (xy 447.136773 -252.918668) (xy 447.128653 -252.973844)
			(xy 447.112585 -253.027251) (xy 447.088913 -253.077748) (xy 447.05814 -253.124261) (xy 447.020923 -253.165798)
			(xy 446.978055 -253.201473) (xy 446.930449 -253.230527) (xy 446.87912 -253.252339) (xy 446.825163 -253.266445)
			(xy 446.769726 -253.272545) (xy 446.713992 -253.270508) (xy 446.659149 -253.260378) (xy 446.606365 -253.242371)
			(xy 446.556765 -253.21687) (xy 446.511407 -253.184419) (xy 446.471258 -253.14571) (xy 446.437172 -253.101567)
			(xy 446.409876 -253.052932) (xy 446.389953 -253.000841) (xy 446.377827 -252.946404) (xy 446.373756 -252.890782)
			(xy 440.989602 -252.890782) (xy 441.263938 -253.306834) (xy 445.098422 -253.306834) (xy 445.102493 -253.251212)
			(xy 445.114619 -253.196775) (xy 445.134542 -253.144684) (xy 445.161838 -253.096049) (xy 445.195924 -253.051906)
			(xy 445.236073 -253.013197) (xy 445.281431 -252.980746) (xy 445.331031 -252.955245) (xy 445.383815 -252.937238)
			(xy 445.438658 -252.927108) (xy 445.494392 -252.925071) (xy 445.549829 -252.931171) (xy 445.603786 -252.945277)
			(xy 445.655115 -252.967089) (xy 445.702721 -252.996143) (xy 445.745589 -253.031818) (xy 445.782806 -253.073355)
			(xy 445.813579 -253.119868) (xy 445.837251 -253.170365) (xy 445.853319 -253.223772) (xy 445.861439 -253.278948)
			(xy 445.861948 -253.306834) (xy 445.861439 -253.33472) (xy 445.853319 -253.389896) (xy 445.837251 -253.443303)
			(xy 445.813579 -253.4938) (xy 445.782806 -253.540313) (xy 445.745589 -253.58185) (xy 445.702721 -253.617525)
			(xy 445.655115 -253.646579) (xy 445.603786 -253.668391) (xy 445.549829 -253.682497) (xy 445.494392 -253.688597)
			(xy 445.438658 -253.68656) (xy 445.383815 -253.67643) (xy 445.331031 -253.658423) (xy 445.281431 -253.632922)
			(xy 445.236073 -253.600471) (xy 445.195924 -253.561762) (xy 445.161838 -253.517619) (xy 445.134542 -253.468984)
			(xy 445.114619 -253.416893) (xy 445.102493 -253.362456) (xy 445.098422 -253.306834) (xy 441.263938 -253.306834)
			(xy 441.33897 -253.420626) (xy 441.33897 -253.421134) (xy 445.017967 -258.92633) (xy 448.944998 -258.92633)
			(xy 448.949069 -258.870708) (xy 448.961195 -258.816271) (xy 448.981118 -258.76418) (xy 449.008414 -258.715545)
			(xy 449.0425 -258.671402) (xy 449.082649 -258.632693) (xy 449.128007 -258.600242) (xy 449.177607 -258.574741)
			(xy 449.230391 -258.556734) (xy 449.285234 -258.546604) (xy 449.340968 -258.544567) (xy 449.396405 -258.550667)
			(xy 449.450362 -258.564773) (xy 449.501691 -258.586585) (xy 449.549297 -258.615639) (xy 449.592165 -258.651314)
			(xy 449.629382 -258.692851) (xy 449.660155 -258.739364) (xy 449.683827 -258.789861) (xy 449.699895 -258.843268)
			(xy 449.706213 -258.886198) (xy 450.433184 -258.886198) (xy 450.437255 -258.830576) (xy 450.449381 -258.776139)
			(xy 450.469304 -258.724048) (xy 450.4966 -258.675413) (xy 450.530686 -258.63127) (xy 450.570835 -258.592561)
			(xy 450.616193 -258.56011) (xy 450.665793 -258.534609) (xy 450.718577 -258.516602) (xy 450.77342 -258.506472)
			(xy 450.829154 -258.504435) (xy 450.884591 -258.510535) (xy 450.938548 -258.524641) (xy 450.989877 -258.546453)
			(xy 451.037483 -258.575507) (xy 451.080351 -258.611182) (xy 451.117568 -258.652719) (xy 451.148341 -258.699232)
			(xy 451.172013 -258.749729) (xy 451.188081 -258.803136) (xy 451.196201 -258.858312) (xy 451.19671 -258.886198)
			(xy 451.196201 -258.914084) (xy 451.191446 -258.946396) (xy 451.94169 -258.946396) (xy 451.945761 -258.890774)
			(xy 451.957887 -258.836337) (xy 451.97781 -258.784246) (xy 452.005106 -258.735611) (xy 452.039192 -258.691468)
			(xy 452.079341 -258.652759) (xy 452.124699 -258.620308) (xy 452.174299 -258.594807) (xy 452.227083 -258.5768)
			(xy 452.281926 -258.56667) (xy 452.33766 -258.564633) (xy 452.393097 -258.570733) (xy 452.447054 -258.584839)
			(xy 452.498383 -258.606651) (xy 452.545989 -258.635705) (xy 452.588857 -258.67138) (xy 452.626074 -258.712917)
			(xy 452.656847 -258.75943) (xy 452.680519 -258.809927) (xy 452.696587 -258.863334) (xy 452.699952 -258.886198)
			(xy 453.449942 -258.886198) (xy 453.454013 -258.830576) (xy 453.466139 -258.776139) (xy 453.486062 -258.724048)
			(xy 453.513358 -258.675413) (xy 453.547444 -258.63127) (xy 453.587593 -258.592561) (xy 453.632951 -258.56011)
			(xy 453.682551 -258.534609) (xy 453.735335 -258.516602) (xy 453.790178 -258.506472) (xy 453.845912 -258.504435)
			(xy 453.901349 -258.510535) (xy 453.955306 -258.524641) (xy 454.006635 -258.546453) (xy 454.054241 -258.575507)
			(xy 454.097109 -258.611182) (xy 454.134326 -258.652719) (xy 454.165099 -258.699232) (xy 454.188771 -258.749729)
			(xy 454.19353 -258.765548) (xy 455.159362 -258.765548) (xy 455.163433 -258.709926) (xy 455.175559 -258.655489)
			(xy 455.195482 -258.603398) (xy 455.222778 -258.554763) (xy 455.256864 -258.51062) (xy 455.297013 -258.471911)
			(xy 455.342371 -258.43946) (xy 455.391971 -258.413959) (xy 455.444755 -258.395952) (xy 455.499598 -258.385822)
			(xy 455.555332 -258.383785) (xy 455.610769 -258.389885) (xy 455.664726 -258.403991) (xy 455.716055 -258.425803)
			(xy 455.763661 -258.454857) (xy 455.806529 -258.490532) (xy 455.843746 -258.532069) (xy 455.874519 -258.578582)
			(xy 455.898191 -258.629079) (xy 455.914259 -258.682486) (xy 455.922379 -258.737662) (xy 455.922888 -258.765548)
			(xy 455.922379 -258.793434) (xy 455.917624 -258.825746) (xy 456.728066 -258.825746) (xy 456.732137 -258.770124)
			(xy 456.744263 -258.715687) (xy 456.764186 -258.663596) (xy 456.791482 -258.614961) (xy 456.825568 -258.570818)
			(xy 456.865717 -258.532109) (xy 456.911075 -258.499658) (xy 456.960675 -258.474157) (xy 457.013459 -258.45615)
			(xy 457.068302 -258.44602) (xy 457.124036 -258.443983) (xy 457.179473 -258.450083) (xy 457.23343 -258.464189)
			(xy 457.284759 -258.486001) (xy 457.332365 -258.515055) (xy 457.375233 -258.55073) (xy 457.41245 -258.592267)
			(xy 457.443223 -258.63878) (xy 457.466895 -258.689277) (xy 457.482963 -258.742684) (xy 457.491083 -258.79786)
			(xy 457.491592 -258.825746) (xy 457.491226 -258.845812) (xy 458.135734 -258.845812) (xy 458.139805 -258.79019)
			(xy 458.151931 -258.735753) (xy 458.171854 -258.683662) (xy 458.19915 -258.635027) (xy 458.233236 -258.590884)
			(xy 458.273385 -258.552175) (xy 458.318743 -258.519724) (xy 458.368343 -258.494223) (xy 458.421127 -258.476216)
			(xy 458.47597 -258.466086) (xy 458.531704 -258.464049) (xy 458.587141 -258.470149) (xy 458.641098 -258.484255)
			(xy 458.692427 -258.506067) (xy 458.740033 -258.535121) (xy 458.782901 -258.570796) (xy 458.820118 -258.612333)
			(xy 458.850891 -258.658846) (xy 458.874563 -258.709343) (xy 458.890631 -258.76275) (xy 458.898751 -258.817926)
			(xy 458.89926 -258.845812) (xy 458.898751 -258.873698) (xy 458.890631 -258.928874) (xy 458.874563 -258.982281)
			(xy 458.850891 -259.032778) (xy 458.820118 -259.079291) (xy 458.782901 -259.120828) (xy 458.740033 -259.156503)
			(xy 458.692427 -259.185557) (xy 458.641098 -259.207369) (xy 458.587141 -259.221475) (xy 458.531704 -259.227575)
			(xy 458.47597 -259.225538) (xy 458.421127 -259.215408) (xy 458.368343 -259.197401) (xy 458.318743 -259.1719)
			(xy 458.273385 -259.139449) (xy 458.233236 -259.10074) (xy 458.19915 -259.056597) (xy 458.171854 -259.007962)
			(xy 458.151931 -258.955871) (xy 458.139805 -258.901434) (xy 458.135734 -258.845812) (xy 457.491226 -258.845812)
			(xy 457.491083 -258.853632) (xy 457.482963 -258.908808) (xy 457.466895 -258.962215) (xy 457.443223 -259.012712)
			(xy 457.41245 -259.059225) (xy 457.375233 -259.100762) (xy 457.332365 -259.136437) (xy 457.284759 -259.165491)
			(xy 457.23343 -259.187303) (xy 457.179473 -259.201409) (xy 457.124036 -259.207509) (xy 457.068302 -259.205472)
			(xy 457.013459 -259.195342) (xy 456.960675 -259.177335) (xy 456.911075 -259.151834) (xy 456.865717 -259.119383)
			(xy 456.825568 -259.080674) (xy 456.791482 -259.036531) (xy 456.764186 -258.987896) (xy 456.744263 -258.935805)
			(xy 456.732137 -258.881368) (xy 456.728066 -258.825746) (xy 455.917624 -258.825746) (xy 455.914259 -258.84861)
			(xy 455.898191 -258.902017) (xy 455.874519 -258.952514) (xy 455.843746 -258.999027) (xy 455.806529 -259.040564)
			(xy 455.763661 -259.076239) (xy 455.716055 -259.105293) (xy 455.664726 -259.127105) (xy 455.610769 -259.141211)
			(xy 455.555332 -259.147311) (xy 455.499598 -259.145274) (xy 455.444755 -259.135144) (xy 455.391971 -259.117137)
			(xy 455.342371 -259.091636) (xy 455.297013 -259.059185) (xy 455.256864 -259.020476) (xy 455.222778 -258.976333)
			(xy 455.195482 -258.927698) (xy 455.175559 -258.875607) (xy 455.163433 -258.82117) (xy 455.159362 -258.765548)
			(xy 454.19353 -258.765548) (xy 454.204839 -258.803136) (xy 454.212959 -258.858312) (xy 454.213468 -258.886198)
			(xy 454.212959 -258.914084) (xy 454.204839 -258.96926) (xy 454.188771 -259.022667) (xy 454.165099 -259.073164)
			(xy 454.134326 -259.119677) (xy 454.097109 -259.161214) (xy 454.054241 -259.196889) (xy 454.006635 -259.225943)
			(xy 453.955306 -259.247755) (xy 453.901349 -259.261861) (xy 453.845912 -259.267961) (xy 453.790178 -259.265924)
			(xy 453.735335 -259.255794) (xy 453.682551 -259.237787) (xy 453.632951 -259.212286) (xy 453.587593 -259.179835)
			(xy 453.547444 -259.141126) (xy 453.513358 -259.096983) (xy 453.486062 -259.048348) (xy 453.466139 -258.996257)
			(xy 453.454013 -258.94182) (xy 453.449942 -258.886198) (xy 452.699952 -258.886198) (xy 452.704707 -258.91851)
			(xy 452.705216 -258.946396) (xy 452.704707 -258.974282) (xy 452.696587 -259.029458) (xy 452.680519 -259.082865)
			(xy 452.656847 -259.133362) (xy 452.626074 -259.179875) (xy 452.588857 -259.221412) (xy 452.545989 -259.257087)
			(xy 452.498383 -259.286141) (xy 452.447054 -259.307953) (xy 452.393097 -259.322059) (xy 452.33766 -259.328159)
			(xy 452.281926 -259.326122) (xy 452.227083 -259.315992) (xy 452.174299 -259.297985) (xy 452.124699 -259.272484)
			(xy 452.079341 -259.240033) (xy 452.039192 -259.201324) (xy 452.005106 -259.157181) (xy 451.97781 -259.108546)
			(xy 451.957887 -259.056455) (xy 451.945761 -259.002018) (xy 451.94169 -258.946396) (xy 451.191446 -258.946396)
			(xy 451.188081 -258.96926) (xy 451.172013 -259.022667) (xy 451.148341 -259.073164) (xy 451.117568 -259.119677)
			(xy 451.080351 -259.161214) (xy 451.037483 -259.196889) (xy 450.989877 -259.225943) (xy 450.938548 -259.247755)
			(xy 450.884591 -259.261861) (xy 450.829154 -259.267961) (xy 450.77342 -259.265924) (xy 450.718577 -259.255794)
			(xy 450.665793 -259.237787) (xy 450.616193 -259.212286) (xy 450.570835 -259.179835) (xy 450.530686 -259.141126)
			(xy 450.4966 -259.096983) (xy 450.469304 -259.048348) (xy 450.449381 -258.996257) (xy 450.437255 -258.94182)
			(xy 450.433184 -258.886198) (xy 449.706213 -258.886198) (xy 449.708015 -258.898444) (xy 449.708524 -258.92633)
			(xy 449.708015 -258.954216) (xy 449.699895 -259.009392) (xy 449.683827 -259.062799) (xy 449.660155 -259.113296)
			(xy 449.629382 -259.159809) (xy 449.592165 -259.201346) (xy 449.549297 -259.237021) (xy 449.501691 -259.266075)
			(xy 449.450362 -259.287887) (xy 449.396405 -259.301993) (xy 449.340968 -259.308093) (xy 449.285234 -259.306056)
			(xy 449.230391 -259.295926) (xy 449.177607 -259.277919) (xy 449.128007 -259.252418) (xy 449.082649 -259.219967)
			(xy 449.0425 -259.181258) (xy 449.008414 -259.137115) (xy 448.981118 -259.08848) (xy 448.961195 -259.036389)
			(xy 448.949069 -258.981952) (xy 448.944998 -258.92633) (xy 445.017967 -258.92633) (xy 445.45064 -259.573776)
			(xy 446.548508 -259.573776) (xy 446.552579 -259.518154) (xy 446.564705 -259.463717) (xy 446.584628 -259.411626)
			(xy 446.611924 -259.362991) (xy 446.64601 -259.318848) (xy 446.686159 -259.280139) (xy 446.731517 -259.247688)
			(xy 446.781117 -259.222187) (xy 446.833901 -259.20418) (xy 446.888744 -259.19405) (xy 446.944478 -259.192013)
			(xy 446.999915 -259.198113) (xy 447.053872 -259.212219) (xy 447.105201 -259.234031) (xy 447.152807 -259.263085)
			(xy 447.195675 -259.29876) (xy 447.232892 -259.340297) (xy 447.242842 -259.355336) (xy 459.730854 -259.355336)
			(xy 459.734925 -259.299714) (xy 459.747051 -259.245277) (xy 459.766974 -259.193186) (xy 459.79427 -259.144551)
			(xy 459.828356 -259.100408) (xy 459.868505 -259.061699) (xy 459.913863 -259.029248) (xy 459.963463 -259.003747)
			(xy 460.016247 -258.98574) (xy 460.07109 -258.97561) (xy 460.126824 -258.973573) (xy 460.182261 -258.979673)
			(xy 460.236218 -258.993779) (xy 460.287547 -259.015591) (xy 460.335153 -259.044645) (xy 460.378021 -259.08032)
			(xy 460.415238 -259.121857) (xy 460.446011 -259.16837) (xy 460.469683 -259.218867) (xy 460.485751 -259.272274)
			(xy 460.493871 -259.32745) (xy 460.49438 -259.355336) (xy 460.493871 -259.383222) (xy 460.485751 -259.438398)
			(xy 460.469683 -259.491805) (xy 460.446011 -259.542302) (xy 460.415238 -259.588815) (xy 460.378021 -259.630352)
			(xy 460.335153 -259.666027) (xy 460.287547 -259.695081) (xy 460.236218 -259.716893) (xy 460.182261 -259.730999)
			(xy 460.126824 -259.737099) (xy 460.07109 -259.735062) (xy 460.016247 -259.724932) (xy 459.963463 -259.706925)
			(xy 459.913863 -259.681424) (xy 459.868505 -259.648973) (xy 459.828356 -259.610264) (xy 459.79427 -259.566121)
			(xy 459.766974 -259.517486) (xy 459.747051 -259.465395) (xy 459.734925 -259.410958) (xy 459.730854 -259.355336)
			(xy 447.242842 -259.355336) (xy 447.263665 -259.38681) (xy 447.287337 -259.437307) (xy 447.303405 -259.490714)
			(xy 447.311525 -259.54589) (xy 447.312034 -259.573776) (xy 447.311525 -259.601662) (xy 447.303405 -259.656838)
			(xy 447.287337 -259.710245) (xy 447.263665 -259.760742) (xy 447.232892 -259.807255) (xy 447.195675 -259.848792)
			(xy 447.152807 -259.884467) (xy 447.105201 -259.913521) (xy 447.053872 -259.935333) (xy 446.999915 -259.949439)
			(xy 446.944478 -259.955539) (xy 446.888744 -259.953502) (xy 446.833901 -259.943372) (xy 446.781117 -259.925365)
			(xy 446.731517 -259.899864) (xy 446.686159 -259.867413) (xy 446.64601 -259.828704) (xy 446.611924 -259.784561)
			(xy 446.584628 -259.735926) (xy 446.564705 -259.683835) (xy 446.552579 -259.629398) (xy 446.548508 -259.573776)
			(xy 445.45064 -259.573776) (xy 445.747689 -260.018276) (xy 448.904358 -260.018276) (xy 448.908429 -259.962654)
			(xy 448.920555 -259.908217) (xy 448.940478 -259.856126) (xy 448.967774 -259.807491) (xy 449.00186 -259.763348)
			(xy 449.042009 -259.724639) (xy 449.087367 -259.692188) (xy 449.136967 -259.666687) (xy 449.189751 -259.64868)
			(xy 449.244594 -259.63855) (xy 449.300328 -259.636513) (xy 449.355765 -259.642613) (xy 449.409722 -259.656719)
			(xy 449.461051 -259.678531) (xy 449.508657 -259.707585) (xy 449.551525 -259.74326) (xy 449.588742 -259.784797)
			(xy 449.619515 -259.83131) (xy 449.643187 -259.881807) (xy 449.659255 -259.935214) (xy 449.667375 -259.99039)
			(xy 449.667884 -260.018276) (xy 450.428358 -260.018276) (xy 450.432429 -259.962654) (xy 450.444555 -259.908217)
			(xy 450.464478 -259.856126) (xy 450.491774 -259.807491) (xy 450.52586 -259.763348) (xy 450.566009 -259.724639)
			(xy 450.611367 -259.692188) (xy 450.660967 -259.666687) (xy 450.713751 -259.64868) (xy 450.768594 -259.63855)
			(xy 450.824328 -259.636513) (xy 450.879765 -259.642613) (xy 450.933722 -259.656719) (xy 450.985051 -259.678531)
			(xy 451.032657 -259.707585) (xy 451.075525 -259.74326) (xy 451.112742 -259.784797) (xy 451.143515 -259.83131)
			(xy 451.167187 -259.881807) (xy 451.183255 -259.935214) (xy 451.185685 -259.951728) (xy 451.492364 -259.951728)
			(xy 451.496435 -259.896106) (xy 451.508561 -259.841669) (xy 451.528484 -259.789578) (xy 451.55578 -259.740943)
			(xy 451.589866 -259.6968) (xy 451.630015 -259.658091) (xy 451.675373 -259.62564) (xy 451.724973 -259.600139)
			(xy 451.777757 -259.582132) (xy 451.8326 -259.572002) (xy 451.888334 -259.569965) (xy 451.943771 -259.576065)
			(xy 451.997728 -259.590171) (xy 452.049057 -259.611983) (xy 452.096663 -259.641037) (xy 452.139531 -259.676712)
			(xy 452.176748 -259.718249) (xy 452.207521 -259.764762) (xy 452.231193 -259.815259) (xy 452.247261 -259.868666)
			(xy 452.255381 -259.923842) (xy 452.25589 -259.951728) (xy 452.255381 -259.979614) (xy 452.249691 -260.018276)
			(xy 452.714358 -260.018276) (xy 452.718429 -259.962654) (xy 452.730555 -259.908217) (xy 452.750478 -259.856126)
			(xy 452.777774 -259.807491) (xy 452.81186 -259.763348) (xy 452.852009 -259.724639) (xy 452.897367 -259.692188)
			(xy 452.946967 -259.666687) (xy 452.999751 -259.64868) (xy 453.054594 -259.63855) (xy 453.110328 -259.636513)
			(xy 453.165765 -259.642613) (xy 453.219722 -259.656719) (xy 453.271051 -259.678531) (xy 453.318657 -259.707585)
			(xy 453.361525 -259.74326) (xy 453.398742 -259.784797) (xy 453.429515 -259.83131) (xy 453.453187 -259.881807)
			(xy 453.469255 -259.935214) (xy 453.477375 -259.99039) (xy 453.477884 -260.018276) (xy 454.238358 -260.018276)
			(xy 454.242429 -259.962654) (xy 454.254555 -259.908217) (xy 454.274478 -259.856126) (xy 454.301774 -259.807491)
			(xy 454.33586 -259.763348) (xy 454.376009 -259.724639) (xy 454.421367 -259.692188) (xy 454.470967 -259.666687)
			(xy 454.523751 -259.64868) (xy 454.578594 -259.63855) (xy 454.634328 -259.636513) (xy 454.689765 -259.642613)
			(xy 454.743722 -259.656719) (xy 454.795051 -259.678531) (xy 454.842657 -259.707585) (xy 454.885525 -259.74326)
			(xy 454.922742 -259.784797) (xy 454.953515 -259.83131) (xy 454.977187 -259.881807) (xy 454.993255 -259.935214)
			(xy 455.001375 -259.99039) (xy 455.001884 -260.018276) (xy 455.762358 -260.018276) (xy 455.766429 -259.962654)
			(xy 455.778555 -259.908217) (xy 455.798478 -259.856126) (xy 455.825774 -259.807491) (xy 455.85986 -259.763348)
			(xy 455.900009 -259.724639) (xy 455.945367 -259.692188) (xy 455.994967 -259.666687) (xy 456.047751 -259.64868)
			(xy 456.102594 -259.63855) (xy 456.158328 -259.636513) (xy 456.213765 -259.642613) (xy 456.267722 -259.656719)
			(xy 456.319051 -259.678531) (xy 456.366657 -259.707585) (xy 456.409525 -259.74326) (xy 456.446742 -259.784797)
			(xy 456.477515 -259.83131) (xy 456.501187 -259.881807) (xy 456.517255 -259.935214) (xy 456.525375 -259.99039)
			(xy 456.525884 -260.018276) (xy 457.286358 -260.018276) (xy 457.290429 -259.962654) (xy 457.302555 -259.908217)
			(xy 457.322478 -259.856126) (xy 457.349774 -259.807491) (xy 457.38386 -259.763348) (xy 457.424009 -259.724639)
			(xy 457.469367 -259.692188) (xy 457.518967 -259.666687) (xy 457.571751 -259.64868) (xy 457.626594 -259.63855)
			(xy 457.682328 -259.636513) (xy 457.737765 -259.642613) (xy 457.791722 -259.656719) (xy 457.843051 -259.678531)
			(xy 457.890657 -259.707585) (xy 457.933525 -259.74326) (xy 457.970742 -259.784797) (xy 458.001515 -259.83131)
			(xy 458.025187 -259.881807) (xy 458.041255 -259.935214) (xy 458.049375 -259.99039) (xy 458.049884 -260.018276)
			(xy 458.810358 -260.018276) (xy 458.814429 -259.962654) (xy 458.826555 -259.908217) (xy 458.846478 -259.856126)
			(xy 458.873774 -259.807491) (xy 458.90786 -259.763348) (xy 458.948009 -259.724639) (xy 458.993367 -259.692188)
			(xy 459.042967 -259.666687) (xy 459.095751 -259.64868) (xy 459.150594 -259.63855) (xy 459.206328 -259.636513)
			(xy 459.261765 -259.642613) (xy 459.315722 -259.656719) (xy 459.367051 -259.678531) (xy 459.414657 -259.707585)
			(xy 459.457525 -259.74326) (xy 459.494742 -259.784797) (xy 459.525515 -259.83131) (xy 459.549187 -259.881807)
			(xy 459.565255 -259.935214) (xy 459.573375 -259.99039) (xy 459.573884 -260.018276) (xy 459.573375 -260.046162)
			(xy 459.565255 -260.101338) (xy 459.549187 -260.154745) (xy 459.525515 -260.205242) (xy 459.494742 -260.251755)
			(xy 459.457525 -260.293292) (xy 459.414657 -260.328967) (xy 459.367051 -260.358021) (xy 459.315722 -260.379833)
			(xy 459.261765 -260.393939) (xy 459.206328 -260.400039) (xy 459.150594 -260.398002) (xy 459.095751 -260.387872)
			(xy 459.042967 -260.369865) (xy 458.993367 -260.344364) (xy 458.948009 -260.311913) (xy 458.90786 -260.273204)
			(xy 458.873774 -260.229061) (xy 458.846478 -260.180426) (xy 458.826555 -260.128335) (xy 458.814429 -260.073898)
			(xy 458.810358 -260.018276) (xy 458.049884 -260.018276) (xy 458.049375 -260.046162) (xy 458.041255 -260.101338)
			(xy 458.025187 -260.154745) (xy 458.001515 -260.205242) (xy 457.970742 -260.251755) (xy 457.933525 -260.293292)
			(xy 457.890657 -260.328967) (xy 457.843051 -260.358021) (xy 457.791722 -260.379833) (xy 457.737765 -260.393939)
			(xy 457.682328 -260.400039) (xy 457.626594 -260.398002) (xy 457.571751 -260.387872) (xy 457.518967 -260.369865)
			(xy 457.469367 -260.344364) (xy 457.424009 -260.311913) (xy 457.38386 -260.273204) (xy 457.349774 -260.229061)
			(xy 457.322478 -260.180426) (xy 457.302555 -260.128335) (xy 457.290429 -260.073898) (xy 457.286358 -260.018276)
			(xy 456.525884 -260.018276) (xy 456.525375 -260.046162) (xy 456.517255 -260.101338) (xy 456.501187 -260.154745)
			(xy 456.477515 -260.205242) (xy 456.446742 -260.251755) (xy 456.409525 -260.293292) (xy 456.366657 -260.328967)
			(xy 456.319051 -260.358021) (xy 456.267722 -260.379833) (xy 456.213765 -260.393939) (xy 456.158328 -260.400039)
			(xy 456.102594 -260.398002) (xy 456.047751 -260.387872) (xy 455.994967 -260.369865) (xy 455.945367 -260.344364)
			(xy 455.900009 -260.311913) (xy 455.85986 -260.273204) (xy 455.825774 -260.229061) (xy 455.798478 -260.180426)
			(xy 455.778555 -260.128335) (xy 455.766429 -260.073898) (xy 455.762358 -260.018276) (xy 455.001884 -260.018276)
			(xy 455.001375 -260.046162) (xy 454.993255 -260.101338) (xy 454.977187 -260.154745) (xy 454.953515 -260.205242)
			(xy 454.922742 -260.251755) (xy 454.885525 -260.293292) (xy 454.842657 -260.328967) (xy 454.795051 -260.358021)
			(xy 454.743722 -260.379833) (xy 454.689765 -260.393939) (xy 454.634328 -260.400039) (xy 454.578594 -260.398002)
			(xy 454.523751 -260.387872) (xy 454.470967 -260.369865) (xy 454.421367 -260.344364) (xy 454.376009 -260.311913)
			(xy 454.33586 -260.273204) (xy 454.301774 -260.229061) (xy 454.274478 -260.180426) (xy 454.254555 -260.128335)
			(xy 454.242429 -260.073898) (xy 454.238358 -260.018276) (xy 453.477884 -260.018276) (xy 453.477375 -260.046162)
			(xy 453.469255 -260.101338) (xy 453.453187 -260.154745) (xy 453.429515 -260.205242) (xy 453.398742 -260.251755)
			(xy 453.361525 -260.293292) (xy 453.318657 -260.328967) (xy 453.271051 -260.358021) (xy 453.219722 -260.379833)
			(xy 453.165765 -260.393939) (xy 453.110328 -260.400039) (xy 453.054594 -260.398002) (xy 452.999751 -260.387872)
			(xy 452.946967 -260.369865) (xy 452.897367 -260.344364) (xy 452.852009 -260.311913) (xy 452.81186 -260.273204)
			(xy 452.777774 -260.229061) (xy 452.750478 -260.180426) (xy 452.730555 -260.128335) (xy 452.718429 -260.073898)
			(xy 452.714358 -260.018276) (xy 452.249691 -260.018276) (xy 452.247261 -260.03479) (xy 452.231193 -260.088197)
			(xy 452.207521 -260.138694) (xy 452.176748 -260.185207) (xy 452.139531 -260.226744) (xy 452.096663 -260.262419)
			(xy 452.049057 -260.291473) (xy 451.997728 -260.313285) (xy 451.943771 -260.327391) (xy 451.888334 -260.333491)
			(xy 451.8326 -260.331454) (xy 451.777757 -260.321324) (xy 451.724973 -260.303317) (xy 451.675373 -260.277816)
			(xy 451.630015 -260.245365) (xy 451.589866 -260.206656) (xy 451.55578 -260.162513) (xy 451.528484 -260.113878)
			(xy 451.508561 -260.061787) (xy 451.496435 -260.00735) (xy 451.492364 -259.951728) (xy 451.185685 -259.951728)
			(xy 451.191375 -259.99039) (xy 451.191884 -260.018276) (xy 451.191375 -260.046162) (xy 451.183255 -260.101338)
			(xy 451.167187 -260.154745) (xy 451.143515 -260.205242) (xy 451.112742 -260.251755) (xy 451.075525 -260.293292)
			(xy 451.032657 -260.328967) (xy 450.985051 -260.358021) (xy 450.933722 -260.379833) (xy 450.879765 -260.393939)
			(xy 450.824328 -260.400039) (xy 450.768594 -260.398002) (xy 450.713751 -260.387872) (xy 450.660967 -260.369865)
			(xy 450.611367 -260.344364) (xy 450.566009 -260.311913) (xy 450.52586 -260.273204) (xy 450.491774 -260.229061)
			(xy 450.464478 -260.180426) (xy 450.444555 -260.128335) (xy 450.432429 -260.073898) (xy 450.428358 -260.018276)
			(xy 449.667884 -260.018276) (xy 449.667375 -260.046162) (xy 449.659255 -260.101338) (xy 449.643187 -260.154745)
			(xy 449.619515 -260.205242) (xy 449.588742 -260.251755) (xy 449.551525 -260.293292) (xy 449.508657 -260.328967)
			(xy 449.461051 -260.358021) (xy 449.409722 -260.379833) (xy 449.355765 -260.393939) (xy 449.300328 -260.400039)
			(xy 449.244594 -260.398002) (xy 449.189751 -260.387872) (xy 449.136967 -260.369865) (xy 449.087367 -260.344364)
			(xy 449.042009 -260.311913) (xy 449.00186 -260.273204) (xy 448.967774 -260.229061) (xy 448.940478 -260.180426)
			(xy 448.920555 -260.128335) (xy 448.908429 -260.073898) (xy 448.904358 -260.018276) (xy 445.747689 -260.018276)
			(xy 446.36917 -260.948251) (xy 448.90537 -260.948251) (xy 448.90537 -260.893749) (xy 448.913126 -260.839803)
			(xy 448.92848 -260.787509) (xy 448.95112 -260.737932) (xy 448.980585 -260.692082) (xy 449.016274 -260.650891)
			(xy 449.057462 -260.615199) (xy 449.103311 -260.585731) (xy 449.152886 -260.563088) (xy 449.205179 -260.547731)
			(xy 449.259125 -260.539971) (xy 449.286376 -260.539484) (xy 449.313443 -260.539965) (xy 449.367035 -260.547614)
			(xy 449.419007 -260.562762) (xy 449.468316 -260.585105) (xy 449.513971 -260.614194) (xy 449.555056 -260.649444)
			(xy 449.590745 -260.690148) (xy 449.620323 -260.735488) (xy 449.643193 -260.784555) (xy 449.658898 -260.836361)
			(xy 449.667122 -260.889867) (xy 449.667884 -260.916928) (xy 449.668059 -260.920992) (xy 450.428358 -260.920992)
			(xy 450.432429 -260.86537) (xy 450.444555 -260.810933) (xy 450.464478 -260.758842) (xy 450.491774 -260.710207)
			(xy 450.52586 -260.666064) (xy 450.566009 -260.627355) (xy 450.611367 -260.594904) (xy 450.660967 -260.569403)
			(xy 450.713751 -260.551396) (xy 450.768594 -260.541266) (xy 450.824328 -260.539229) (xy 450.879765 -260.545329)
			(xy 450.933722 -260.559435) (xy 450.985051 -260.581247) (xy 451.032657 -260.610301) (xy 451.075525 -260.645976)
			(xy 451.112742 -260.687513) (xy 451.143515 -260.734026) (xy 451.167187 -260.784523) (xy 451.183255 -260.83793)
			(xy 451.191375 -260.893106) (xy 451.191884 -260.920992) (xy 451.952358 -260.920992) (xy 451.956429 -260.86537)
			(xy 451.968555 -260.810933) (xy 451.988478 -260.758842) (xy 452.015774 -260.710207) (xy 452.04986 -260.666064)
			(xy 452.090009 -260.627355) (xy 452.135367 -260.594904) (xy 452.184967 -260.569403) (xy 452.237751 -260.551396)
			(xy 452.292594 -260.541266) (xy 452.348328 -260.539229) (xy 452.403765 -260.545329) (xy 452.457722 -260.559435)
			(xy 452.509051 -260.581247) (xy 452.556657 -260.610301) (xy 452.599525 -260.645976) (xy 452.636742 -260.687513)
			(xy 452.667515 -260.734026) (xy 452.691187 -260.784523) (xy 452.707255 -260.83793) (xy 452.715375 -260.893106)
			(xy 452.715884 -260.920992) (xy 453.476358 -260.920992) (xy 453.480429 -260.86537) (xy 453.492555 -260.810933)
			(xy 453.512478 -260.758842) (xy 453.539774 -260.710207) (xy 453.57386 -260.666064) (xy 453.614009 -260.627355)
			(xy 453.659367 -260.594904) (xy 453.708967 -260.569403) (xy 453.761751 -260.551396) (xy 453.816594 -260.541266)
			(xy 453.872328 -260.539229) (xy 453.927765 -260.545329) (xy 453.981722 -260.559435) (xy 454.033051 -260.581247)
			(xy 454.080657 -260.610301) (xy 454.123525 -260.645976) (xy 454.160742 -260.687513) (xy 454.191515 -260.734026)
			(xy 454.215187 -260.784523) (xy 454.231255 -260.83793) (xy 454.239375 -260.893106) (xy 454.239884 -260.920992)
			(xy 455.000358 -260.920992) (xy 455.004429 -260.86537) (xy 455.016555 -260.810933) (xy 455.036478 -260.758842)
			(xy 455.063774 -260.710207) (xy 455.09786 -260.666064) (xy 455.138009 -260.627355) (xy 455.183367 -260.594904)
			(xy 455.232967 -260.569403) (xy 455.285751 -260.551396) (xy 455.340594 -260.541266) (xy 455.396328 -260.539229)
			(xy 455.451765 -260.545329) (xy 455.505722 -260.559435) (xy 455.557051 -260.581247) (xy 455.604657 -260.610301)
			(xy 455.647525 -260.645976) (xy 455.684742 -260.687513) (xy 455.715515 -260.734026) (xy 455.739187 -260.784523)
			(xy 455.755255 -260.83793) (xy 455.763375 -260.893106) (xy 455.763884 -260.920992) (xy 456.524358 -260.920992)
			(xy 456.528429 -260.86537) (xy 456.540555 -260.810933) (xy 456.560478 -260.758842) (xy 456.587774 -260.710207)
			(xy 456.62186 -260.666064) (xy 456.662009 -260.627355) (xy 456.707367 -260.594904) (xy 456.756967 -260.569403)
			(xy 456.809751 -260.551396) (xy 456.864594 -260.541266) (xy 456.920328 -260.539229) (xy 456.975765 -260.545329)
			(xy 457.029722 -260.559435) (xy 457.081051 -260.581247) (xy 457.128657 -260.610301) (xy 457.171525 -260.645976)
			(xy 457.208742 -260.687513) (xy 457.239515 -260.734026) (xy 457.263187 -260.784523) (xy 457.279255 -260.83793)
			(xy 457.287375 -260.893106) (xy 457.287884 -260.920992) (xy 457.287375 -260.948878) (xy 457.283143 -260.977634)
			(xy 457.669136 -260.977634) (xy 457.673207 -260.922012) (xy 457.685333 -260.867575) (xy 457.705256 -260.815484)
			(xy 457.732552 -260.766849) (xy 457.766638 -260.722706) (xy 457.806787 -260.683997) (xy 457.852145 -260.651546)
			(xy 457.901745 -260.626045) (xy 457.954529 -260.608038) (xy 458.009372 -260.597908) (xy 458.065106 -260.595871)
			(xy 458.120543 -260.601971) (xy 458.1745 -260.616077) (xy 458.225829 -260.637889) (xy 458.273435 -260.666943)
			(xy 458.316303 -260.702618) (xy 458.35352 -260.744155) (xy 458.384293 -260.790668) (xy 458.407965 -260.841165)
			(xy 458.424033 -260.894572) (xy 458.427921 -260.920992) (xy 458.810358 -260.920992) (xy 458.814429 -260.86537)
			(xy 458.826555 -260.810933) (xy 458.846478 -260.758842) (xy 458.873774 -260.710207) (xy 458.90786 -260.666064)
			(xy 458.948009 -260.627355) (xy 458.993367 -260.594904) (xy 459.042967 -260.569403) (xy 459.095751 -260.551396)
			(xy 459.150594 -260.541266) (xy 459.206328 -260.539229) (xy 459.261765 -260.545329) (xy 459.315722 -260.559435)
			(xy 459.367051 -260.581247) (xy 459.414657 -260.610301) (xy 459.457525 -260.645976) (xy 459.494742 -260.687513)
			(xy 459.525515 -260.734026) (xy 459.549187 -260.784523) (xy 459.560518 -260.822186) (xy 460.002634 -260.822186)
			(xy 460.006705 -260.766564) (xy 460.018831 -260.712127) (xy 460.038754 -260.660036) (xy 460.06605 -260.611401)
			(xy 460.100136 -260.567258) (xy 460.140285 -260.528549) (xy 460.185643 -260.496098) (xy 460.235243 -260.470597)
			(xy 460.288027 -260.45259) (xy 460.34287 -260.44246) (xy 460.398604 -260.440423) (xy 460.454041 -260.446523)
			(xy 460.507998 -260.460629) (xy 460.559327 -260.482441) (xy 460.606933 -260.511495) (xy 460.649801 -260.54717)
			(xy 460.687018 -260.588707) (xy 460.717791 -260.63522) (xy 460.741463 -260.685717) (xy 460.757531 -260.739124)
			(xy 460.765651 -260.7943) (xy 460.76616 -260.822186) (xy 460.765651 -260.850072) (xy 460.757531 -260.905248)
			(xy 460.741463 -260.958655) (xy 460.717791 -261.009152) (xy 460.687018 -261.055665) (xy 460.649801 -261.097202)
			(xy 460.606933 -261.132877) (xy 460.559327 -261.161931) (xy 460.507998 -261.183743) (xy 460.454041 -261.197849)
			(xy 460.398604 -261.203949) (xy 460.34287 -261.201912) (xy 460.288027 -261.191782) (xy 460.235243 -261.173775)
			(xy 460.185643 -261.148274) (xy 460.140285 -261.115823) (xy 460.100136 -261.077114) (xy 460.06605 -261.032971)
			(xy 460.038754 -260.984336) (xy 460.018831 -260.932245) (xy 460.006705 -260.877808) (xy 460.002634 -260.822186)
			(xy 459.560518 -260.822186) (xy 459.565255 -260.83793) (xy 459.573375 -260.893106) (xy 459.573884 -260.920992)
			(xy 459.573375 -260.948878) (xy 459.565255 -261.004054) (xy 459.549187 -261.057461) (xy 459.525515 -261.107958)
			(xy 459.494742 -261.154471) (xy 459.457525 -261.196008) (xy 459.414657 -261.231683) (xy 459.367051 -261.260737)
			(xy 459.315722 -261.282549) (xy 459.261765 -261.296655) (xy 459.206328 -261.302755) (xy 459.150594 -261.300718)
			(xy 459.095751 -261.290588) (xy 459.042967 -261.272581) (xy 458.993367 -261.24708) (xy 458.948009 -261.214629)
			(xy 458.90786 -261.17592) (xy 458.873774 -261.131777) (xy 458.846478 -261.083142) (xy 458.826555 -261.031051)
			(xy 458.814429 -260.976614) (xy 458.810358 -260.920992) (xy 458.427921 -260.920992) (xy 458.432153 -260.949748)
			(xy 458.432662 -260.977634) (xy 458.432153 -261.00552) (xy 458.424033 -261.060696) (xy 458.407965 -261.114103)
			(xy 458.384293 -261.1646) (xy 458.35352 -261.211113) (xy 458.316303 -261.25265) (xy 458.273435 -261.288325)
			(xy 458.225829 -261.317379) (xy 458.1745 -261.339191) (xy 458.120543 -261.353297) (xy 458.065106 -261.359397)
			(xy 458.009372 -261.35736) (xy 457.954529 -261.34723) (xy 457.901745 -261.329223) (xy 457.852145 -261.303722)
			(xy 457.806787 -261.271271) (xy 457.766638 -261.232562) (xy 457.732552 -261.188419) (xy 457.705256 -261.139784)
			(xy 457.685333 -261.087693) (xy 457.673207 -261.033256) (xy 457.669136 -260.977634) (xy 457.283143 -260.977634)
			(xy 457.279255 -261.004054) (xy 457.263187 -261.057461) (xy 457.239515 -261.107958) (xy 457.208742 -261.154471)
			(xy 457.171525 -261.196008) (xy 457.128657 -261.231683) (xy 457.081051 -261.260737) (xy 457.029722 -261.282549)
			(xy 456.975765 -261.296655) (xy 456.920328 -261.302755) (xy 456.864594 -261.300718) (xy 456.809751 -261.290588)
			(xy 456.756967 -261.272581) (xy 456.707367 -261.24708) (xy 456.662009 -261.214629) (xy 456.62186 -261.17592)
			(xy 456.587774 -261.131777) (xy 456.560478 -261.083142) (xy 456.540555 -261.031051) (xy 456.528429 -260.976614)
			(xy 456.524358 -260.920992) (xy 455.763884 -260.920992) (xy 455.763375 -260.948878) (xy 455.755255 -261.004054)
			(xy 455.739187 -261.057461) (xy 455.715515 -261.107958) (xy 455.684742 -261.154471) (xy 455.647525 -261.196008)
			(xy 455.604657 -261.231683) (xy 455.557051 -261.260737) (xy 455.505722 -261.282549) (xy 455.451765 -261.296655)
			(xy 455.396328 -261.302755) (xy 455.340594 -261.300718) (xy 455.285751 -261.290588) (xy 455.232967 -261.272581)
			(xy 455.183367 -261.24708) (xy 455.138009 -261.214629) (xy 455.09786 -261.17592) (xy 455.063774 -261.131777)
			(xy 455.036478 -261.083142) (xy 455.016555 -261.031051) (xy 455.004429 -260.976614) (xy 455.000358 -260.920992)
			(xy 454.239884 -260.920992) (xy 454.239375 -260.948878) (xy 454.231255 -261.004054) (xy 454.215187 -261.057461)
			(xy 454.191515 -261.107958) (xy 454.160742 -261.154471) (xy 454.123525 -261.196008) (xy 454.080657 -261.231683)
			(xy 454.033051 -261.260737) (xy 453.981722 -261.282549) (xy 453.927765 -261.296655) (xy 453.872328 -261.302755)
			(xy 453.816594 -261.300718) (xy 453.761751 -261.290588) (xy 453.708967 -261.272581) (xy 453.659367 -261.24708)
			(xy 453.614009 -261.214629) (xy 453.57386 -261.17592) (xy 453.539774 -261.131777) (xy 453.512478 -261.083142)
			(xy 453.492555 -261.031051) (xy 453.480429 -260.976614) (xy 453.476358 -260.920992) (xy 452.715884 -260.920992)
			(xy 452.715375 -260.948878) (xy 452.707255 -261.004054) (xy 452.691187 -261.057461) (xy 452.667515 -261.107958)
			(xy 452.636742 -261.154471) (xy 452.599525 -261.196008) (xy 452.556657 -261.231683) (xy 452.509051 -261.260737)
			(xy 452.457722 -261.282549) (xy 452.403765 -261.296655) (xy 452.348328 -261.302755) (xy 452.292594 -261.300718)
			(xy 452.237751 -261.290588) (xy 452.184967 -261.272581) (xy 452.135367 -261.24708) (xy 452.090009 -261.214629)
			(xy 452.04986 -261.17592) (xy 452.015774 -261.131777) (xy 451.988478 -261.083142) (xy 451.968555 -261.031051)
			(xy 451.956429 -260.976614) (xy 451.952358 -260.920992) (xy 451.191884 -260.920992) (xy 451.191375 -260.948878)
			(xy 451.183255 -261.004054) (xy 451.167187 -261.057461) (xy 451.143515 -261.107958) (xy 451.112742 -261.154471)
			(xy 451.075525 -261.196008) (xy 451.032657 -261.231683) (xy 450.985051 -261.260737) (xy 450.933722 -261.282549)
			(xy 450.879765 -261.296655) (xy 450.824328 -261.302755) (xy 450.768594 -261.300718) (xy 450.713751 -261.290588)
			(xy 450.660967 -261.272581) (xy 450.611367 -261.24708) (xy 450.566009 -261.214629) (xy 450.52586 -261.17592)
			(xy 450.491774 -261.131777) (xy 450.464478 -261.083142) (xy 450.444555 -261.031051) (xy 450.432429 -260.976614)
			(xy 450.428358 -260.920992) (xy 449.668059 -260.920992) (xy 449.668467 -260.930483) (xy 449.675847 -260.95658)
			(xy 449.68984 -260.979811) (xy 449.709457 -260.998537) (xy 449.733313 -261.011436) (xy 449.759724 -261.017597)
			(xy 449.786826 -261.016585) (xy 449.812703 -261.008471) (xy 449.824348 -261.00151) (xy 449.847502 -260.987199)
			(xy 449.89702 -260.964601) (xy 449.949249 -260.949277) (xy 450.003127 -260.94154) (xy 450.030342 -260.941058)
			(xy 450.057589 -260.941615) (xy 450.111527 -260.949376) (xy 450.163812 -260.964733) (xy 450.21338 -260.987375)
			(xy 450.259221 -261.016839) (xy 450.300402 -261.052528) (xy 450.336086 -261.093713) (xy 450.365546 -261.139557)
			(xy 450.388182 -261.189127) (xy 450.403533 -261.241414) (xy 450.411288 -261.295353) (xy 450.411288 -261.349847)
			(xy 450.403533 -261.403786) (xy 450.388182 -261.456073) (xy 450.365546 -261.505643) (xy 450.336086 -261.551487)
			(xy 450.300402 -261.592672) (xy 450.259221 -261.628361) (xy 450.21338 -261.657825) (xy 450.163812 -261.680467)
			(xy 450.111527 -261.695824) (xy 450.057589 -261.703585) (xy 450.030342 -261.704074) (xy 450.003273 -261.703617)
			(xy 449.949679 -261.695969) (xy 449.897704 -261.680821) (xy 449.848392 -261.658478) (xy 449.802735 -261.629387)
			(xy 449.761649 -261.594134) (xy 449.725959 -261.553427) (xy 449.696383 -261.508082) (xy 449.673514 -261.459012)
			(xy 449.657813 -261.407202) (xy 449.649593 -261.353692) (xy 449.648834 -261.32663) (xy 449.648254 -261.313076)
			(xy 449.640865 -261.286985) (xy 449.626869 -261.26376) (xy 449.607252 -261.245038) (xy 449.583398 -261.232141)
			(xy 449.556991 -261.225979) (xy 449.529893 -261.226986) (xy 449.504016 -261.235091) (xy 449.49237 -261.242048)
			(xy 449.469209 -261.256346) (xy 449.419694 -261.278949) (xy 449.367467 -261.294276) (xy 449.313591 -261.302016)
			(xy 449.286376 -261.3025) (xy 449.259125 -261.302029) (xy 449.205179 -261.294269) (xy 449.152886 -261.278912)
			(xy 449.103311 -261.256269) (xy 449.057462 -261.226801) (xy 449.016274 -261.191109) (xy 448.980585 -261.149918)
			(xy 448.95112 -261.104068) (xy 448.92848 -261.054491) (xy 448.913126 -261.002197) (xy 448.90537 -260.948251)
			(xy 446.36917 -260.948251) (xy 447.032639 -261.941056) (xy 459.446628 -261.941056) (xy 459.450699 -261.885434)
			(xy 459.462825 -261.830997) (xy 459.482748 -261.778906) (xy 459.510044 -261.730271) (xy 459.54413 -261.686128)
			(xy 459.584279 -261.647419) (xy 459.629637 -261.614968) (xy 459.679237 -261.589467) (xy 459.732021 -261.57146)
			(xy 459.786864 -261.56133) (xy 459.842598 -261.559293) (xy 459.898035 -261.565393) (xy 459.951992 -261.579499)
			(xy 460.003321 -261.601311) (xy 460.050927 -261.630365) (xy 460.093795 -261.66604) (xy 460.131012 -261.707577)
			(xy 460.161785 -261.75409) (xy 460.185457 -261.804587) (xy 460.201525 -261.857994) (xy 460.209645 -261.91317)
			(xy 460.210154 -261.941056) (xy 460.209645 -261.968942) (xy 460.201525 -262.024118) (xy 460.185457 -262.077525)
			(xy 460.161785 -262.128022) (xy 460.131012 -262.174535) (xy 460.093795 -262.216072) (xy 460.050927 -262.251747)
			(xy 460.003321 -262.280801) (xy 459.951992 -262.302613) (xy 459.898035 -262.316719) (xy 459.842598 -262.322819)
			(xy 459.786864 -262.320782) (xy 459.732021 -262.310652) (xy 459.679237 -262.292645) (xy 459.629637 -262.267144)
			(xy 459.584279 -262.234693) (xy 459.54413 -262.195984) (xy 459.510044 -262.151841) (xy 459.482748 -262.103206)
			(xy 459.462825 -262.051115) (xy 459.450699 -261.996678) (xy 459.446628 -261.941056) (xy 447.032639 -261.941056)
			(xy 447.978784 -263.356852) (xy 448.0055 -263.397909) (xy 448.051686 -263.484297) (xy 448.070986 -263.529318)
			(xy 448.181222 -263.795764) (xy 448.185794 -263.8044) (xy 448.584574 -264.409428) (xy 448.608309 -264.446263)
			(xy 448.6499 -264.523397) (xy 448.684495 -264.603914) (xy 448.69862 -264.645394) (xy 449.326508 -266.5603)
			(xy 449.327778 -266.563856) (xy 449.443348 -266.84224) (xy 449.461762 -266.888356) (xy 449.490416 -266.983438)
			(xy 449.509471 -267.080898) (xy 449.514722 -267.130276) (xy 449.51523 -267.13561) (xy 450.126862 -269.000986)
			(xy 450.141963 -269.049127) (xy 450.16343 -269.147716) (xy 450.174738 -269.247979) (xy 450.175884 -269.29842)
			(xy 450.21536 -272.975578) (xy 450.721984 -272.975578) (xy 450.722417 -272.948206) (xy 450.730239 -272.894025)
			(xy 450.745735 -272.841521) (xy 450.768585 -272.791774) (xy 450.798318 -272.74581) (xy 450.815964 -272.72488)
			(xy 450.816218 -272.724626) (xy 450.821802 -272.717538) (xy 450.82805 -272.700622) (xy 450.82841 -272.691606)
			(xy 450.82841 -272.62455) (xy 450.828027 -272.615536) (xy 450.821797 -272.598619) (xy 450.816218 -272.59153)
			(xy 450.815964 -272.59153) (xy 450.815964 -272.591276) (xy 450.798341 -272.570331) (xy 450.768628 -272.524361)
			(xy 450.74579 -272.474617) (xy 450.730295 -272.422119) (xy 450.722461 -272.367946) (xy 450.721984 -272.340578)
			(xy 450.722457 -272.313327) (xy 450.730217 -272.259379) (xy 450.745574 -272.207084) (xy 450.768217 -272.157508)
			(xy 450.797685 -272.111658) (xy 450.833378 -272.070468) (xy 450.874569 -272.034777) (xy 450.92042 -272.005311)
			(xy 450.969997 -271.982669) (xy 451.022293 -271.967314) (xy 451.076241 -271.959556) (xy 451.103492 -271.95907)
			(xy 451.13223 -271.959607) (xy 451.189057 -271.968227) (xy 451.243947 -271.985275) (xy 451.295659 -272.010363)
			(xy 451.343022 -272.042925) (xy 451.36435 -272.062194) (xy 451.371208 -272.068798) (xy 451.389242 -272.07591)
			(xy 451.478142 -272.07591) (xy 451.496176 -272.068798) (xy 451.503034 -272.062194) (xy 451.524361 -272.042924)
			(xy 451.571724 -272.010359) (xy 451.623435 -271.985268) (xy 451.678326 -271.968218) (xy 451.735153 -271.959596)
			(xy 451.792631 -271.959596) (xy 451.849458 -271.968218) (xy 451.904349 -271.985268) (xy 451.95606 -272.010359)
			(xy 452.003423 -272.042924) (xy 452.02475 -272.062194) (xy 452.031608 -272.068798) (xy 452.049642 -272.07591)
			(xy 452.138542 -272.07591) (xy 452.156576 -272.068798) (xy 452.163434 -272.062194) (xy 452.184761 -272.042924)
			(xy 452.232124 -272.010359) (xy 452.283835 -271.985268) (xy 452.338726 -271.968218) (xy 452.395553 -271.959596)
			(xy 452.453031 -271.959596) (xy 452.509858 -271.968218) (xy 452.564749 -271.985268) (xy 452.61646 -272.010359)
			(xy 452.663823 -272.042924) (xy 452.68515 -272.062194) (xy 452.692008 -272.068798) (xy 452.710042 -272.07591)
			(xy 452.798942 -272.07591) (xy 452.816976 -272.068798) (xy 452.823834 -272.062194) (xy 452.845173 -272.042937)
			(xy 452.892531 -272.010367) (xy 452.944239 -271.985271) (xy 452.999128 -271.968217) (xy 453.055954 -271.959592)
			(xy 453.084692 -271.95907) (xy 453.111942 -271.959585) (xy 453.165888 -271.96734) (xy 453.21818 -271.982693)
			(xy 453.267756 -272.005332) (xy 453.313606 -272.034795) (xy 453.354795 -272.070483) (xy 453.390487 -272.11167)
			(xy 453.419954 -272.157517) (xy 453.442596 -272.207091) (xy 453.457954 -272.259383) (xy 453.465713 -272.313328)
			(xy 453.4662 -272.340578) (xy 453.465721 -272.367948) (xy 453.457906 -272.422126) (xy 453.44242 -272.474629)
			(xy 453.419581 -272.524376) (xy 453.38986 -272.570344) (xy 453.37222 -272.591276) (xy 453.371966 -272.59153)
			(xy 453.366399 -272.59863) (xy 453.360142 -272.615537) (xy 453.359774 -272.62455) (xy 453.359774 -272.691606)
			(xy 453.360134 -272.700622) (xy 453.36638 -272.717539) (xy 453.371966 -272.724626) (xy 453.37222 -272.724626)
			(xy 453.37222 -272.72488) (xy 453.389866 -272.745806) (xy 453.419576 -272.791781) (xy 453.442411 -272.84153)
			(xy 453.4579 -272.894032) (xy 453.465388 -272.94586) (xy 454.465436 -272.94586) (xy 454.465928 -272.918491)
			(xy 454.473739 -272.864312) (xy 454.489221 -272.811809) (xy 454.512057 -272.762062) (xy 454.541777 -272.716094)
			(xy 454.559416 -272.695162) (xy 454.55967 -272.694908) (xy 454.565268 -272.687829) (xy 454.571506 -272.670906)
			(xy 454.571862 -272.661888) (xy 454.571862 -272.594832) (xy 454.571498 -272.585816) (xy 454.565256 -272.568898)
			(xy 454.55967 -272.561812) (xy 454.559416 -272.561812) (xy 454.559416 -272.561558) (xy 454.541793 -272.540613)
			(xy 454.512078 -272.494644) (xy 454.489239 -272.4449) (xy 454.473744 -272.392402) (xy 454.465912 -272.338228)
			(xy 454.465436 -272.31086) (xy 454.465818 -272.283604) (xy 454.473581 -272.229648) (xy 454.488945 -272.177346)
			(xy 454.511595 -272.127763) (xy 454.541071 -272.081907) (xy 454.576774 -272.040714) (xy 454.617975 -272.005021)
			(xy 454.663836 -271.975555) (xy 454.713425 -271.952915) (xy 454.76573 -271.937563) (xy 454.819688 -271.929812)
			(xy 454.846944 -271.929352) (xy 454.875683 -271.929862) (xy 454.932511 -271.93849) (xy 454.987401 -271.955544)
			(xy 455.039113 -271.980638) (xy 455.086475 -272.013205) (xy 455.107802 -272.032476) (xy 455.11466 -272.03908)
			(xy 455.132694 -272.046192) (xy 455.221594 -272.046192) (xy 455.239628 -272.03908) (xy 455.246486 -272.032476)
			(xy 455.267813 -272.013206) (xy 455.315176 -271.980641) (xy 455.366887 -271.95555) (xy 455.421778 -271.9385)
			(xy 455.478605 -271.929878) (xy 455.536083 -271.929878) (xy 455.59291 -271.9385) (xy 455.647801 -271.95555)
			(xy 455.699512 -271.980641) (xy 455.746875 -272.013206) (xy 455.768202 -272.032476) (xy 455.77506 -272.03908)
			(xy 455.793094 -272.046192) (xy 455.881994 -272.046192) (xy 455.900028 -272.03908) (xy 455.906886 -272.032476)
			(xy 455.928213 -272.013206) (xy 455.975576 -271.980641) (xy 456.027287 -271.95555) (xy 456.082178 -271.9385)
			(xy 456.139005 -271.929878) (xy 456.196483 -271.929878) (xy 456.25331 -271.9385) (xy 456.308201 -271.95555)
			(xy 456.359912 -271.980641) (xy 456.407275 -272.013206) (xy 456.428602 -272.032476) (xy 456.43546 -272.03908)
			(xy 456.453494 -272.046192) (xy 456.542394 -272.046192) (xy 456.560428 -272.03908) (xy 456.567286 -272.032476)
			(xy 456.588601 -272.013191) (xy 456.635965 -271.980625) (xy 456.68768 -271.955535) (xy 456.742574 -271.938488)
			(xy 456.799404 -271.92987) (xy 456.828144 -271.929352) (xy 456.855395 -271.929837) (xy 456.90934 -271.937598)
			(xy 456.961632 -271.952957) (xy 457.011207 -271.9756) (xy 457.057055 -272.005067) (xy 457.098244 -272.040759)
			(xy 457.133935 -272.081948) (xy 457.163402 -272.127796) (xy 457.186044 -272.177371) (xy 457.201403 -272.229664)
			(xy 457.209164 -272.283609) (xy 457.209652 -272.31086) (xy 457.209174 -272.33823) (xy 457.201361 -272.392409)
			(xy 457.185875 -272.444912) (xy 457.163036 -272.49466) (xy 457.133313 -272.540626) (xy 457.115672 -272.561558)
			(xy 457.115418 -272.561812) (xy 457.109823 -272.568893) (xy 457.103581 -272.585814) (xy 457.103226 -272.594832)
			(xy 457.103226 -272.661888) (xy 457.103583 -272.670905) (xy 457.10983 -272.687822) (xy 457.115418 -272.694908)
			(xy 457.115672 -272.694908) (xy 457.115672 -272.695162) (xy 457.133302 -272.716101) (xy 457.163016 -272.762072)
			(xy 457.185855 -272.811817) (xy 457.201348 -272.864317) (xy 457.209177 -272.918491) (xy 457.209652 -272.94586)
			(xy 457.209085 -272.973108) (xy 457.201335 -273.027051) (xy 457.185987 -273.079341) (xy 457.163354 -273.128915)
			(xy 457.133896 -273.174764) (xy 457.098213 -273.215953) (xy 457.057031 -273.251645) (xy 457.011189 -273.281113)
			(xy 456.96162 -273.303758) (xy 456.909333 -273.319117) (xy 456.855392 -273.326879) (xy 456.828144 -273.327368)
			(xy 456.799405 -273.32686) (xy 456.742577 -273.318231) (xy 456.687687 -273.301176) (xy 456.635976 -273.276082)
			(xy 456.588613 -273.243515) (xy 456.567286 -273.224244) (xy 456.560428 -273.21764) (xy 456.542394 -273.210528)
			(xy 456.453494 -273.210528) (xy 456.43546 -273.21764) (xy 456.428602 -273.224244) (xy 456.407275 -273.243514)
			(xy 456.359912 -273.276079) (xy 456.308201 -273.30117) (xy 456.25331 -273.31822) (xy 456.196483 -273.326842)
			(xy 456.139005 -273.326842) (xy 456.082178 -273.31822) (xy 456.027287 -273.30117) (xy 455.975576 -273.276079)
			(xy 455.928213 -273.243514) (xy 455.906886 -273.224244) (xy 455.900028 -273.21764) (xy 455.881994 -273.210528)
			(xy 455.793094 -273.210528) (xy 455.77506 -273.21764) (xy 455.768202 -273.224244) (xy 455.746875 -273.243514)
			(xy 455.699512 -273.276079) (xy 455.647801 -273.30117) (xy 455.59291 -273.31822) (xy 455.536083 -273.326842)
			(xy 455.478605 -273.326842) (xy 455.421778 -273.31822) (xy 455.366887 -273.30117) (xy 455.315176 -273.276079)
			(xy 455.267813 -273.243514) (xy 455.246486 -273.224244) (xy 455.239628 -273.21764) (xy 455.221594 -273.210528)
			(xy 455.132694 -273.210528) (xy 455.11466 -273.21764) (xy 455.107802 -273.224244) (xy 455.086495 -273.243538)
			(xy 455.039128 -273.276102) (xy 454.987411 -273.30119) (xy 454.932516 -273.318235) (xy 454.875684 -273.326851)
			(xy 454.846944 -273.327368) (xy 454.81969 -273.326904) (xy 454.765737 -273.319152) (xy 454.713437 -273.303799)
			(xy 454.663855 -273.281159) (xy 454.617999 -273.251692) (xy 454.576805 -273.215998) (xy 454.541111 -273.174804)
			(xy 454.511643 -273.128949) (xy 454.489002 -273.079367) (xy 454.473649 -273.027066) (xy 454.465897 -272.973114)
			(xy 454.465436 -272.94586) (xy 453.465388 -272.94586) (xy 453.465727 -272.948208) (xy 453.4662 -272.975578)
			(xy 453.465724 -273.002831) (xy 453.45797 -273.056782) (xy 453.442616 -273.10908) (xy 453.419976 -273.15866)
			(xy 453.390509 -273.204514) (xy 453.354817 -273.245707) (xy 453.313625 -273.281401) (xy 453.267773 -273.310869)
			(xy 453.218193 -273.333511) (xy 453.165895 -273.348867) (xy 453.111945 -273.356623) (xy 453.084692 -273.357086)
			(xy 453.055954 -273.356544) (xy 452.999129 -273.347922) (xy 452.944239 -273.330875) (xy 452.892527 -273.305788)
			(xy 452.845163 -273.273229) (xy 452.823834 -273.253962) (xy 452.816976 -273.247358) (xy 452.798942 -273.240246)
			(xy 452.710042 -273.240246) (xy 452.692008 -273.247358) (xy 452.68515 -273.253962) (xy 452.663823 -273.273232)
			(xy 452.61646 -273.305797) (xy 452.564749 -273.330888) (xy 452.509858 -273.347938) (xy 452.453031 -273.35656)
			(xy 452.395553 -273.35656) (xy 452.338726 -273.347938) (xy 452.283835 -273.330888) (xy 452.232124 -273.305797)
			(xy 452.184761 -273.273232) (xy 452.163434 -273.253962) (xy 452.156576 -273.247358) (xy 452.138542 -273.240246)
			(xy 452.049642 -273.240246) (xy 452.031608 -273.247358) (xy 452.02475 -273.253962) (xy 452.003423 -273.273232)
			(xy 451.95606 -273.305797) (xy 451.904349 -273.330888) (xy 451.849458 -273.347938) (xy 451.792631 -273.35656)
			(xy 451.735153 -273.35656) (xy 451.678326 -273.347938) (xy 451.623435 -273.330888) (xy 451.571724 -273.305797)
			(xy 451.524361 -273.273232) (xy 451.503034 -273.253962) (xy 451.496176 -273.247358) (xy 451.478142 -273.240246)
			(xy 451.389242 -273.240246) (xy 451.371208 -273.247358) (xy 451.36435 -273.253962) (xy 451.343026 -273.273236)
			(xy 451.295663 -273.305802) (xy 451.243951 -273.330894) (xy 451.189059 -273.347944) (xy 451.132231 -273.356566)
			(xy 451.103492 -273.357086) (xy 451.076238 -273.356652) (xy 451.022285 -273.348893) (xy 450.969985 -273.333535)
			(xy 450.920403 -273.31089) (xy 450.874549 -273.281419) (xy 450.833356 -273.245723) (xy 450.797663 -273.204527)
			(xy 450.768195 -273.15867) (xy 450.745554 -273.109087) (xy 450.7302 -273.056786) (xy 450.722446 -273.002832)
			(xy 450.721984 -272.975578) (xy 450.21536 -272.975578) (xy 450.219826 -273.39163) (xy 450.219826 -273.396202)
			(xy 450.220588 -273.422618) (xy 450.220588 -273.423126) (xy 450.22008 -273.449288) (xy 450.22008 -273.494754)
			(xy 450.219516 -273.541639) (xy 450.214441 -273.59483) (xy 463.155028 -273.59483) (xy 463.159099 -273.539208)
			(xy 463.171225 -273.484771) (xy 463.191148 -273.43268) (xy 463.218444 -273.384045) (xy 463.25253 -273.339902)
			(xy 463.292679 -273.301193) (xy 463.338037 -273.268742) (xy 463.387637 -273.243241) (xy 463.440421 -273.225234)
			(xy 463.495264 -273.215104) (xy 463.550998 -273.213067) (xy 463.606435 -273.219167) (xy 463.660392 -273.233273)
			(xy 463.711721 -273.255085) (xy 463.759327 -273.284139) (xy 463.802195 -273.319814) (xy 463.839412 -273.361351)
			(xy 463.870185 -273.407864) (xy 463.893857 -273.458361) (xy 463.909925 -273.511768) (xy 463.918045 -273.566944)
			(xy 463.918554 -273.59483) (xy 463.918045 -273.622716) (xy 463.909925 -273.677892) (xy 463.893857 -273.731299)
			(xy 463.870185 -273.781796) (xy 463.839412 -273.828309) (xy 463.802195 -273.869846) (xy 463.759327 -273.905521)
			(xy 463.711721 -273.934575) (xy 463.660392 -273.956387) (xy 463.606435 -273.970493) (xy 463.550998 -273.976593)
			(xy 463.495264 -273.974556) (xy 463.440421 -273.964426) (xy 463.387637 -273.946419) (xy 463.338037 -273.920918)
			(xy 463.292679 -273.888467) (xy 463.25253 -273.849758) (xy 463.218444 -273.805615) (xy 463.191148 -273.75698)
			(xy 463.171225 -273.704889) (xy 463.159099 -273.650452) (xy 463.155028 -273.59483) (xy 450.214441 -273.59483)
			(xy 450.21061 -273.634987) (xy 450.192902 -273.727071) (xy 450.16655 -273.817063) (xy 450.131793 -273.904155)
			(xy 450.11086 -273.946112) (xy 449.245806 -275.628608) (xy 454.42378 -275.628608) (xy 454.424296 -275.599308)
			(xy 454.433244 -275.541395) (xy 454.450947 -275.485532) (xy 454.476987 -275.433036) (xy 454.510752 -275.385141)
			(xy 454.530714 -275.363686) (xy 454.537318 -275.357082) (xy 454.544684 -275.339556) (xy 454.54697 -275.251672)
			(xy 454.54062 -275.233892) (xy 454.53427 -275.22678) (xy 454.516712 -275.205871) (xy 454.487157 -275.159963)
			(xy 454.464446 -275.110312) (xy 454.449043 -275.057931) (xy 454.441263 -275.003889) (xy 454.440798 -274.97659)
			(xy 454.441284 -274.949339) (xy 454.44904 -274.895391) (xy 454.464395 -274.843096) (xy 454.487037 -274.793519)
			(xy 454.516503 -274.747669) (xy 454.552194 -274.706478) (xy 454.593385 -274.670787) (xy 454.639235 -274.641321)
			(xy 454.688812 -274.618679) (xy 454.741107 -274.603324) (xy 454.795055 -274.595568) (xy 454.849557 -274.595568)
			(xy 454.903505 -274.603324) (xy 454.9558 -274.618679) (xy 455.005377 -274.641321) (xy 455.051227 -274.670787)
			(xy 455.092418 -274.706478) (xy 455.128109 -274.747669) (xy 455.133539 -274.756118) (xy 457.316076 -274.756118)
			(xy 457.320147 -274.700496) (xy 457.332273 -274.646059) (xy 457.352196 -274.593968) (xy 457.379492 -274.545333)
			(xy 457.413578 -274.50119) (xy 457.453727 -274.462481) (xy 457.499085 -274.43003) (xy 457.548685 -274.404529)
			(xy 457.601469 -274.386522) (xy 457.656312 -274.376392) (xy 457.712046 -274.374355) (xy 457.767483 -274.380455)
			(xy 457.82144 -274.394561) (xy 457.872769 -274.416373) (xy 457.920375 -274.445427) (xy 457.963243 -274.481102)
			(xy 458.00046 -274.522639) (xy 458.031233 -274.569152) (xy 458.054905 -274.619649) (xy 458.070973 -274.673056)
			(xy 458.079093 -274.728232) (xy 458.079602 -274.756118) (xy 458.079093 -274.784004) (xy 458.070973 -274.83918)
			(xy 458.055232 -274.8915) (xy 459.445866 -274.8915) (xy 459.449937 -274.835878) (xy 459.462063 -274.781441)
			(xy 459.481986 -274.72935) (xy 459.509282 -274.680715) (xy 459.543368 -274.636572) (xy 459.583517 -274.597863)
			(xy 459.628875 -274.565412) (xy 459.678475 -274.539911) (xy 459.731259 -274.521904) (xy 459.786102 -274.511774)
			(xy 459.841836 -274.509737) (xy 459.897273 -274.515837) (xy 459.95123 -274.529943) (xy 460.002559 -274.551755)
			(xy 460.050165 -274.580809) (xy 460.093033 -274.616484) (xy 460.13025 -274.658021) (xy 460.161023 -274.704534)
			(xy 460.184695 -274.755031) (xy 460.200763 -274.808438) (xy 460.208883 -274.863614) (xy 460.209392 -274.8915)
			(xy 460.208883 -274.919386) (xy 460.200763 -274.974562) (xy 460.184695 -275.027969) (xy 460.161023 -275.078466)
			(xy 460.13025 -275.124979) (xy 460.093033 -275.166516) (xy 460.050165 -275.202191) (xy 460.002559 -275.231245)
			(xy 459.95123 -275.253057) (xy 459.897273 -275.267163) (xy 459.841836 -275.273263) (xy 459.786102 -275.271226)
			(xy 459.731259 -275.261096) (xy 459.678475 -275.243089) (xy 459.628875 -275.217588) (xy 459.583517 -275.185137)
			(xy 459.543368 -275.146428) (xy 459.509282 -275.102285) (xy 459.481986 -275.05365) (xy 459.462063 -275.001559)
			(xy 459.449937 -274.947122) (xy 459.445866 -274.8915) (xy 458.055232 -274.8915) (xy 458.054905 -274.892587)
			(xy 458.031233 -274.943084) (xy 458.00046 -274.989597) (xy 457.963243 -275.031134) (xy 457.920375 -275.066809)
			(xy 457.872769 -275.095863) (xy 457.82144 -275.117675) (xy 457.767483 -275.131781) (xy 457.712046 -275.137881)
			(xy 457.656312 -275.135844) (xy 457.601469 -275.125714) (xy 457.548685 -275.107707) (xy 457.499085 -275.082206)
			(xy 457.453727 -275.049755) (xy 457.413578 -275.011046) (xy 457.379492 -274.966903) (xy 457.352196 -274.918268)
			(xy 457.332273 -274.866177) (xy 457.320147 -274.81174) (xy 457.316076 -274.756118) (xy 455.133539 -274.756118)
			(xy 455.157575 -274.793519) (xy 455.180217 -274.843096) (xy 455.195572 -274.895391) (xy 455.203328 -274.949339)
			(xy 455.203814 -274.97659) (xy 455.203299 -275.00589) (xy 455.19435 -275.063803) (xy 455.176648 -275.119666)
			(xy 455.150607 -275.172162) (xy 455.116842 -275.220057) (xy 455.09688 -275.241512) (xy 455.090276 -275.248116)
			(xy 455.08291 -275.265642) (xy 455.081278 -275.32838) (xy 460.941672 -275.32838) (xy 460.945743 -275.272758)
			(xy 460.957869 -275.218321) (xy 460.977792 -275.16623) (xy 461.005088 -275.117595) (xy 461.039174 -275.073452)
			(xy 461.079323 -275.034743) (xy 461.124681 -275.002292) (xy 461.174281 -274.976791) (xy 461.227065 -274.958784)
			(xy 461.281908 -274.948654) (xy 461.337642 -274.946617) (xy 461.393079 -274.952717) (xy 461.447036 -274.966823)
			(xy 461.498365 -274.988635) (xy 461.545971 -275.017689) (xy 461.588839 -275.053364) (xy 461.626056 -275.094901)
			(xy 461.656829 -275.141414) (xy 461.680501 -275.191911) (xy 461.696569 -275.245318) (xy 461.704689 -275.300494)
			(xy 461.705198 -275.32838) (xy 461.704689 -275.356266) (xy 461.696569 -275.411442) (xy 461.680501 -275.464849)
			(xy 461.656829 -275.515346) (xy 461.626056 -275.561859) (xy 461.588839 -275.603396) (xy 461.56068 -275.62683)
			(xy 463.093306 -275.62683) (xy 463.097377 -275.571208) (xy 463.109503 -275.516771) (xy 463.129426 -275.46468)
			(xy 463.156722 -275.416045) (xy 463.190808 -275.371902) (xy 463.230957 -275.333193) (xy 463.276315 -275.300742)
			(xy 463.325915 -275.275241) (xy 463.378699 -275.257234) (xy 463.433542 -275.247104) (xy 463.489276 -275.245067)
			(xy 463.544713 -275.251167) (xy 463.59867 -275.265273) (xy 463.649999 -275.287085) (xy 463.697605 -275.316139)
			(xy 463.740473 -275.351814) (xy 463.77769 -275.393351) (xy 463.808463 -275.439864) (xy 463.832135 -275.490361)
			(xy 463.848203 -275.543768) (xy 463.856323 -275.598944) (xy 463.856832 -275.62683) (xy 463.856323 -275.654716)
			(xy 463.848203 -275.709892) (xy 463.832135 -275.763299) (xy 463.808463 -275.813796) (xy 463.77769 -275.860309)
			(xy 463.740473 -275.901846) (xy 463.697605 -275.937521) (xy 463.649999 -275.966575) (xy 463.59867 -275.988387)
			(xy 463.544713 -276.002493) (xy 463.489276 -276.008593) (xy 463.433542 -276.006556) (xy 463.378699 -275.996426)
			(xy 463.325915 -275.978419) (xy 463.276315 -275.952918) (xy 463.230957 -275.920467) (xy 463.190808 -275.881758)
			(xy 463.156722 -275.837615) (xy 463.129426 -275.78898) (xy 463.109503 -275.736889) (xy 463.097377 -275.682452)
			(xy 463.093306 -275.62683) (xy 461.56068 -275.62683) (xy 461.545971 -275.639071) (xy 461.498365 -275.668125)
			(xy 461.447036 -275.689937) (xy 461.393079 -275.704043) (xy 461.337642 -275.710143) (xy 461.281908 -275.708106)
			(xy 461.227065 -275.697976) (xy 461.174281 -275.679969) (xy 461.124681 -275.654468) (xy 461.079323 -275.622017)
			(xy 461.039174 -275.583308) (xy 461.005088 -275.539165) (xy 460.977792 -275.49053) (xy 460.957869 -275.438439)
			(xy 460.945743 -275.384002) (xy 460.941672 -275.32838) (xy 455.081278 -275.32838) (xy 455.080624 -275.353526)
			(xy 455.086974 -275.371306) (xy 455.093324 -275.378418) (xy 455.11088 -275.399329) (xy 455.140436 -275.445236)
			(xy 455.163147 -275.494886) (xy 455.17855 -275.547267) (xy 455.186331 -275.601309) (xy 455.186796 -275.628608)
			(xy 455.18631 -275.655859) (xy 455.178554 -275.709807) (xy 455.163199 -275.762102) (xy 455.140557 -275.811679)
			(xy 455.111091 -275.857529) (xy 455.0754 -275.89872) (xy 455.034209 -275.934411) (xy 454.988359 -275.963877)
			(xy 454.938782 -275.986519) (xy 454.886487 -276.001874) (xy 454.832539 -276.00963) (xy 454.778037 -276.00963)
			(xy 454.724089 -276.001874) (xy 454.671794 -275.986519) (xy 454.622217 -275.963877) (xy 454.576367 -275.934411)
			(xy 454.535176 -275.89872) (xy 454.499485 -275.857529) (xy 454.470019 -275.811679) (xy 454.447377 -275.762102)
			(xy 454.432022 -275.709807) (xy 454.424266 -275.655859) (xy 454.42378 -275.628608) (xy 449.245806 -275.628608)
			(xy 448.30566 -277.457154) (xy 450.500496 -277.457154) (xy 450.500995 -277.429785) (xy 450.508805 -277.375607)
			(xy 450.524286 -277.323105) (xy 450.547121 -277.273357) (xy 450.576838 -277.227389) (xy 450.594476 -277.206456)
			(xy 450.59473 -277.206202) (xy 450.600325 -277.199121) (xy 450.606566 -277.1822) (xy 450.606922 -277.173182)
			(xy 450.606922 -277.106126) (xy 450.606548 -277.097111) (xy 450.600312 -277.080194) (xy 450.59473 -277.073106)
			(xy 450.594476 -277.073106) (xy 450.594476 -277.072852) (xy 450.576844 -277.051914) (xy 450.547132 -277.005943)
			(xy 450.524295 -276.956197) (xy 450.508802 -276.903697) (xy 450.500972 -276.849523) (xy 450.500496 -276.822154)
			(xy 450.500935 -276.794901) (xy 450.508698 -276.740952) (xy 450.524059 -276.688656) (xy 450.546706 -276.639078)
			(xy 450.576177 -276.593228) (xy 450.611874 -276.552038) (xy 450.653068 -276.516347) (xy 450.698922 -276.486882)
			(xy 450.748503 -276.464242) (xy 450.800801 -276.448887) (xy 450.854751 -276.441131) (xy 450.882004 -276.440646)
			(xy 450.910742 -276.441182) (xy 450.967568 -276.449804) (xy 451.022458 -276.466852) (xy 451.07417 -276.49194)
			(xy 451.121534 -276.524501) (xy 451.142862 -276.54377) (xy 451.14972 -276.550374) (xy 451.167754 -276.557486)
			(xy 451.256654 -276.557486) (xy 451.274688 -276.550374) (xy 451.281546 -276.54377) (xy 451.302873 -276.5245)
			(xy 451.350236 -276.491935) (xy 451.401947 -276.466844) (xy 451.456838 -276.449794) (xy 451.513665 -276.441172)
			(xy 451.571143 -276.441172) (xy 451.62797 -276.449794) (xy 451.682861 -276.466844) (xy 451.734572 -276.491935)
			(xy 451.781935 -276.5245) (xy 451.803262 -276.54377) (xy 451.81012 -276.550374) (xy 451.828154 -276.557486)
			(xy 451.917054 -276.557486) (xy 451.935088 -276.550374) (xy 451.941946 -276.54377) (xy 451.963273 -276.5245)
			(xy 452.010636 -276.491935) (xy 452.062347 -276.466844) (xy 452.117238 -276.449794) (xy 452.174065 -276.441172)
			(xy 452.231543 -276.441172) (xy 452.28837 -276.449794) (xy 452.343261 -276.466844) (xy 452.394972 -276.491935)
			(xy 452.442335 -276.5245) (xy 452.463662 -276.54377) (xy 452.47052 -276.550374) (xy 452.488554 -276.557486)
			(xy 452.577454 -276.557486) (xy 452.595488 -276.550374) (xy 452.602346 -276.54377) (xy 452.623676 -276.524503)
			(xy 452.671037 -276.491935) (xy 452.722747 -276.466841) (xy 452.777638 -276.44979) (xy 452.834465 -276.441167)
			(xy 452.863204 -276.440646) (xy 452.890453 -276.441174) (xy 452.944397 -276.44893) (xy 452.996688 -276.464283)
			(xy 453.046262 -276.486921) (xy 453.054885 -276.492462) (xy 455.756008 -276.492462) (xy 455.760079 -276.43684)
			(xy 455.772205 -276.382403) (xy 455.792128 -276.330312) (xy 455.819424 -276.281677) (xy 455.85351 -276.237534)
			(xy 455.893659 -276.198825) (xy 455.939017 -276.166374) (xy 455.988617 -276.140873) (xy 456.041401 -276.122866)
			(xy 456.096244 -276.112736) (xy 456.151978 -276.110699) (xy 456.207415 -276.116799) (xy 456.261372 -276.130905)
			(xy 456.312701 -276.152717) (xy 456.360307 -276.181771) (xy 456.403175 -276.217446) (xy 456.440392 -276.258983)
			(xy 456.471165 -276.305496) (xy 456.494837 -276.355993) (xy 456.510905 -276.4094) (xy 456.519025 -276.464576)
			(xy 456.519534 -276.492462) (xy 456.519025 -276.520348) (xy 456.510905 -276.575524) (xy 456.494837 -276.628931)
			(xy 456.488321 -276.64283) (xy 461.074006 -276.64283) (xy 461.078077 -276.587208) (xy 461.090203 -276.532771)
			(xy 461.110126 -276.48068) (xy 461.137422 -276.432045) (xy 461.171508 -276.387902) (xy 461.211657 -276.349193)
			(xy 461.257015 -276.316742) (xy 461.306615 -276.291241) (xy 461.359399 -276.273234) (xy 461.414242 -276.263104)
			(xy 461.469976 -276.261067) (xy 461.525413 -276.267167) (xy 461.57937 -276.281273) (xy 461.630699 -276.303085)
			(xy 461.678305 -276.332139) (xy 461.721173 -276.367814) (xy 461.75839 -276.409351) (xy 461.789163 -276.455864)
			(xy 461.812835 -276.506361) (xy 461.828903 -276.559768) (xy 461.837023 -276.614944) (xy 461.837532 -276.64283)
			(xy 461.837023 -276.670716) (xy 461.828903 -276.725892) (xy 461.812835 -276.779299) (xy 461.789163 -276.829796)
			(xy 461.75839 -276.876309) (xy 461.721173 -276.917846) (xy 461.678305 -276.953521) (xy 461.630699 -276.982575)
			(xy 461.57937 -277.004387) (xy 461.525413 -277.018493) (xy 461.469976 -277.024593) (xy 461.414242 -277.022556)
			(xy 461.359399 -277.012426) (xy 461.306615 -276.994419) (xy 461.257015 -276.968918) (xy 461.211657 -276.936467)
			(xy 461.171508 -276.897758) (xy 461.137422 -276.853615) (xy 461.110126 -276.80498) (xy 461.090203 -276.752889)
			(xy 461.078077 -276.698452) (xy 461.074006 -276.64283) (xy 456.488321 -276.64283) (xy 456.471165 -276.679428)
			(xy 456.440392 -276.725941) (xy 456.403175 -276.767478) (xy 456.360307 -276.803153) (xy 456.312701 -276.832207)
			(xy 456.261372 -276.854019) (xy 456.207415 -276.868125) (xy 456.151978 -276.874225) (xy 456.096244 -276.872188)
			(xy 456.041401 -276.862058) (xy 455.988617 -276.844051) (xy 455.939017 -276.81855) (xy 455.893659 -276.786099)
			(xy 455.85351 -276.74739) (xy 455.819424 -276.703247) (xy 455.792128 -276.654612) (xy 455.772205 -276.602521)
			(xy 455.760079 -276.548084) (xy 455.756008 -276.492462) (xy 453.054885 -276.492462) (xy 453.092111 -276.516384)
			(xy 453.1333 -276.552071) (xy 453.168991 -276.593256) (xy 453.198458 -276.639101) (xy 453.221102 -276.688672)
			(xy 453.236461 -276.740962) (xy 453.244223 -276.794905) (xy 453.244712 -276.822154) (xy 453.244216 -276.849523)
			(xy 453.236405 -276.903701) (xy 453.220923 -276.956203) (xy 453.198088 -277.005951) (xy 453.16837 -277.051919)
			(xy 453.150732 -277.072852) (xy 453.150478 -277.073106) (xy 453.14488 -277.080185) (xy 453.138641 -277.097108)
			(xy 453.138286 -277.106126) (xy 453.138286 -277.173182) (xy 453.138655 -277.182198) (xy 453.144894 -277.199115)
			(xy 453.150478 -277.206202) (xy 453.150732 -277.206202) (xy 453.150732 -277.206456) (xy 453.168369 -277.22739)
			(xy 453.19808 -277.273363) (xy 453.220916 -277.32311) (xy 453.236408 -277.37561) (xy 453.244237 -277.429785)
			(xy 453.244712 -277.457154) (xy 453.244202 -277.484406) (xy 453.236451 -277.538355) (xy 453.221101 -277.590651)
			(xy 453.198464 -277.640231) (xy 453.169002 -277.686084) (xy 453.133313 -277.727277) (xy 453.092124 -277.762972)
			(xy 453.046275 -277.79244) (xy 452.996698 -277.815084) (xy 452.944404 -277.830441) (xy 452.890455 -277.838198)
			(xy 452.863204 -277.838662) (xy 452.834466 -277.838119) (xy 452.77764 -277.829499) (xy 452.72275 -277.812452)
			(xy 452.671038 -277.787365) (xy 452.623674 -277.754806) (xy 452.602346 -277.735538) (xy 452.595488 -277.728934)
			(xy 452.577454 -277.721822) (xy 452.488554 -277.721822) (xy 452.47052 -277.728934) (xy 452.463662 -277.735538)
			(xy 452.442335 -277.754808) (xy 452.394972 -277.787373) (xy 452.343261 -277.812464) (xy 452.28837 -277.829514)
			(xy 452.231543 -277.838136) (xy 452.174065 -277.838136) (xy 452.117238 -277.829514) (xy 452.062347 -277.812464)
			(xy 452.010636 -277.787373) (xy 451.963273 -277.754808) (xy 451.941946 -277.735538) (xy 451.935088 -277.728934)
			(xy 451.917054 -277.721822) (xy 451.828154 -277.721822) (xy 451.81012 -277.728934) (xy 451.803262 -277.735538)
			(xy 451.781935 -277.754808) (xy 451.734572 -277.787373) (xy 451.682861 -277.812464) (xy 451.62797 -277.829514)
			(xy 451.571143 -277.838136) (xy 451.513665 -277.838136) (xy 451.456838 -277.829514) (xy 451.401947 -277.812464)
			(xy 451.350236 -277.787373) (xy 451.302873 -277.754808) (xy 451.281546 -277.735538) (xy 451.274688 -277.728934)
			(xy 451.256654 -277.721822) (xy 451.167754 -277.721822) (xy 451.14972 -277.728934) (xy 451.142862 -277.735538)
			(xy 451.12153 -277.754803) (xy 451.07417 -277.787371) (xy 451.022459 -277.812465) (xy 450.96757 -277.829517)
			(xy 450.910743 -277.838141) (xy 450.882004 -277.838662) (xy 450.854749 -277.838241) (xy 450.800794 -277.830483)
			(xy 450.748493 -277.815125) (xy 450.69891 -277.79248) (xy 450.653054 -277.763008) (xy 450.61186 -277.72731)
			(xy 450.576167 -277.686112) (xy 450.5467 -277.640253) (xy 450.52406 -277.590668) (xy 450.508708 -277.538365)
			(xy 450.500956 -277.484409) (xy 450.500496 -277.457154) (xy 448.30566 -277.457154) (xy 447.951098 -278.146764)
			(xy 447.931901 -278.183183) (xy 447.888301 -278.253023) (xy 447.839043 -278.318996) (xy 447.784471 -278.380644)
			(xy 447.75501 -278.4094) (xy 447.477322 -278.67483) (xy 461.074516 -278.67483) (xy 461.07505 -278.645914)
			(xy 461.083775 -278.588743) (xy 461.101029 -278.533544) (xy 461.126418 -278.481582) (xy 461.159359 -278.434048)
			(xy 461.199098 -278.39203) (xy 461.221582 -278.37384) (xy 461.230375 -278.36622) (xy 461.240563 -278.345328)
			(xy 461.24114 -278.333708) (xy 461.24114 -278.253952) (xy 461.240635 -278.242315) (xy 461.230424 -278.221405)
			(xy 461.221582 -278.21382) (xy 461.199104 -278.195622) (xy 461.15937 -278.153603) (xy 461.12643 -278.10607)
			(xy 461.101041 -278.05411) (xy 461.083783 -277.998914) (xy 461.075052 -277.941746) (xy 461.074516 -277.91283)
			(xy 461.075002 -277.885579) (xy 461.082758 -277.831631) (xy 461.098113 -277.779336) (xy 461.120755 -277.729759)
			(xy 461.150221 -277.683909) (xy 461.185912 -277.642718) (xy 461.227103 -277.607027) (xy 461.272953 -277.577561)
			(xy 461.32253 -277.554919) (xy 461.374825 -277.539564) (xy 461.428773 -277.531808) (xy 461.483275 -277.531808)
			(xy 461.537223 -277.539564) (xy 461.589518 -277.554919) (xy 461.639095 -277.577561) (xy 461.684945 -277.607027)
			(xy 461.726136 -277.642718) (xy 461.741197 -277.6601) (xy 463.093306 -277.6601) (xy 463.097377 -277.604478)
			(xy 463.109503 -277.550041) (xy 463.129426 -277.49795) (xy 463.156722 -277.449315) (xy 463.190808 -277.405172)
			(xy 463.230957 -277.366463) (xy 463.276315 -277.334012) (xy 463.325915 -277.308511) (xy 463.378699 -277.290504)
			(xy 463.433542 -277.280374) (xy 463.489276 -277.278337) (xy 463.544713 -277.284437) (xy 463.59867 -277.298543)
			(xy 463.649999 -277.320355) (xy 463.697605 -277.349409) (xy 463.740473 -277.385084) (xy 463.77769 -277.426621)
			(xy 463.808463 -277.473134) (xy 463.832135 -277.523631) (xy 463.848203 -277.577038) (xy 463.856323 -277.632214)
			(xy 463.856832 -277.6601) (xy 463.856323 -277.687986) (xy 463.848203 -277.743162) (xy 463.832135 -277.796569)
			(xy 463.808463 -277.847066) (xy 463.77769 -277.893579) (xy 463.740473 -277.935116) (xy 463.697605 -277.970791)
			(xy 463.649999 -277.999845) (xy 463.59867 -278.021657) (xy 463.544713 -278.035763) (xy 463.489276 -278.041863)
			(xy 463.433542 -278.039826) (xy 463.378699 -278.029696) (xy 463.325915 -278.011689) (xy 463.276315 -277.986188)
			(xy 463.230957 -277.953737) (xy 463.190808 -277.915028) (xy 463.156722 -277.870885) (xy 463.129426 -277.82225)
			(xy 463.109503 -277.770159) (xy 463.097377 -277.715722) (xy 463.093306 -277.6601) (xy 461.741197 -277.6601)
			(xy 461.761827 -277.683909) (xy 461.791293 -277.729759) (xy 461.813935 -277.779336) (xy 461.82929 -277.831631)
			(xy 461.837046 -277.885579) (xy 461.837532 -277.91283) (xy 461.836989 -277.941746) (xy 461.828269 -277.998917)
			(xy 461.811017 -278.054117) (xy 461.78563 -278.106079) (xy 461.75269 -278.153614) (xy 461.712951 -278.19563)
			(xy 461.690466 -278.21382) (xy 461.681654 -278.221422) (xy 461.671474 -278.242327) (xy 461.670908 -278.253952)
			(xy 461.670908 -278.333708) (xy 461.671454 -278.345339) (xy 461.681638 -278.366249) (xy 461.690466 -278.37384)
			(xy 461.692981 -278.375872) (xy 463.99907 -278.375872) (xy 464.003141 -278.32025) (xy 464.015267 -278.265813)
			(xy 464.03519 -278.213722) (xy 464.062486 -278.165087) (xy 464.096572 -278.120944) (xy 464.136721 -278.082235)
			(xy 464.182079 -278.049784) (xy 464.231679 -278.024283) (xy 464.284463 -278.006276) (xy 464.339306 -277.996146)
			(xy 464.39504 -277.994109) (xy 464.450477 -278.000209) (xy 464.504434 -278.014315) (xy 464.555763 -278.036127)
			(xy 464.603369 -278.065181) (xy 464.646237 -278.100856) (xy 464.683454 -278.142393) (xy 464.714227 -278.188906)
			(xy 464.737899 -278.239403) (xy 464.753967 -278.29281) (xy 464.762087 -278.347986) (xy 464.762596 -278.375872)
			(xy 464.762087 -278.403758) (xy 464.753967 -278.458934) (xy 464.737899 -278.512341) (xy 464.714227 -278.562838)
			(xy 464.683454 -278.609351) (xy 464.646237 -278.650888) (xy 464.603369 -278.686563) (xy 464.555763 -278.715617)
			(xy 464.504434 -278.737429) (xy 464.450477 -278.751535) (xy 464.39504 -278.757635) (xy 464.339306 -278.755598)
			(xy 464.284463 -278.745468) (xy 464.231679 -278.727461) (xy 464.182079 -278.70196) (xy 464.136721 -278.669509)
			(xy 464.096572 -278.6308) (xy 464.062486 -278.586657) (xy 464.03519 -278.538022) (xy 464.015267 -278.485931)
			(xy 464.003141 -278.431494) (xy 463.99907 -278.375872) (xy 461.692981 -278.375872) (xy 461.712962 -278.392017)
			(xy 461.752698 -278.434039) (xy 461.785636 -278.481576) (xy 461.811023 -278.53354) (xy 461.828276 -278.588741)
			(xy 461.837 -278.645913) (xy 461.837532 -278.67483) (xy 461.837046 -278.702081) (xy 461.82929 -278.756029)
			(xy 461.813935 -278.808324) (xy 461.791293 -278.857901) (xy 461.761827 -278.903751) (xy 461.726136 -278.944942)
			(xy 461.684945 -278.980633) (xy 461.639095 -279.010099) (xy 461.589518 -279.032741) (xy 461.537223 -279.048096)
			(xy 461.483275 -279.055852) (xy 461.428773 -279.055852) (xy 461.374825 -279.048096) (xy 461.32253 -279.032741)
			(xy 461.272953 -279.010099) (xy 461.227103 -278.980633) (xy 461.185912 -278.944942) (xy 461.150221 -278.903751)
			(xy 461.120755 -278.857901) (xy 461.098113 -278.808324) (xy 461.082758 -278.756029) (xy 461.075002 -278.702081)
			(xy 461.074516 -278.67483) (xy 447.477322 -278.67483) (xy 446.4144 -279.69083) (xy 461.074006 -279.69083)
			(xy 461.078077 -279.635208) (xy 461.090203 -279.580771) (xy 461.110126 -279.52868) (xy 461.137422 -279.480045)
			(xy 461.171508 -279.435902) (xy 461.211657 -279.397193) (xy 461.257015 -279.364742) (xy 461.306615 -279.339241)
			(xy 461.359399 -279.321234) (xy 461.414242 -279.311104) (xy 461.469976 -279.309067) (xy 461.525413 -279.315167)
			(xy 461.57937 -279.329273) (xy 461.630699 -279.351085) (xy 461.678305 -279.380139) (xy 461.721173 -279.415814)
			(xy 461.749107 -279.44699) (xy 463.093306 -279.44699) (xy 463.097377 -279.391368) (xy 463.109503 -279.336931)
			(xy 463.129426 -279.28484) (xy 463.156722 -279.236205) (xy 463.190808 -279.192062) (xy 463.230957 -279.153353)
			(xy 463.276315 -279.120902) (xy 463.325915 -279.095401) (xy 463.378699 -279.077394) (xy 463.433542 -279.067264)
			(xy 463.489276 -279.065227) (xy 463.544713 -279.071327) (xy 463.59867 -279.085433) (xy 463.649999 -279.107245)
			(xy 463.697605 -279.136299) (xy 463.740473 -279.171974) (xy 463.77769 -279.213511) (xy 463.808463 -279.260024)
			(xy 463.832135 -279.310521) (xy 463.848203 -279.363928) (xy 463.856323 -279.419104) (xy 463.856832 -279.44699)
			(xy 463.856323 -279.474876) (xy 463.848203 -279.530052) (xy 463.832135 -279.583459) (xy 463.808463 -279.633956)
			(xy 463.77769 -279.680469) (xy 463.740473 -279.722006) (xy 463.697605 -279.757681) (xy 463.649999 -279.786735)
			(xy 463.59867 -279.808547) (xy 463.544713 -279.822653) (xy 463.489276 -279.828753) (xy 463.433542 -279.826716)
			(xy 463.378699 -279.816586) (xy 463.325915 -279.798579) (xy 463.276315 -279.773078) (xy 463.230957 -279.740627)
			(xy 463.190808 -279.701918) (xy 463.156722 -279.657775) (xy 463.129426 -279.60914) (xy 463.109503 -279.557049)
			(xy 463.097377 -279.502612) (xy 463.093306 -279.44699) (xy 461.749107 -279.44699) (xy 461.75839 -279.457351)
			(xy 461.789163 -279.503864) (xy 461.812835 -279.554361) (xy 461.828903 -279.607768) (xy 461.837023 -279.662944)
			(xy 461.837532 -279.69083) (xy 461.837023 -279.718716) (xy 461.828903 -279.773892) (xy 461.812835 -279.827299)
			(xy 461.789163 -279.877796) (xy 461.75839 -279.924309) (xy 461.721173 -279.965846) (xy 461.678305 -280.001521)
			(xy 461.630699 -280.030575) (xy 461.57937 -280.052387) (xy 461.525413 -280.066493) (xy 461.469976 -280.072593)
			(xy 461.414242 -280.070556) (xy 461.359399 -280.060426) (xy 461.306615 -280.042419) (xy 461.257015 -280.016918)
			(xy 461.211657 -279.984467) (xy 461.171508 -279.945758) (xy 461.137422 -279.901615) (xy 461.110126 -279.85298)
			(xy 461.090203 -279.800889) (xy 461.078077 -279.746452) (xy 461.074006 -279.69083) (xy 446.4144 -279.69083)
			(xy 445.856101 -280.224484) (xy 457.024484 -280.224484) (xy 457.028555 -280.168862) (xy 457.040681 -280.114425)
			(xy 457.060604 -280.062334) (xy 457.0879 -280.013699) (xy 457.121986 -279.969556) (xy 457.162135 -279.930847)
			(xy 457.207493 -279.898396) (xy 457.257093 -279.872895) (xy 457.309877 -279.854888) (xy 457.36472 -279.844758)
			(xy 457.420454 -279.842721) (xy 457.475891 -279.848821) (xy 457.529848 -279.862927) (xy 457.581177 -279.884739)
			(xy 457.628783 -279.913793) (xy 457.671651 -279.949468) (xy 457.708868 -279.991005) (xy 457.739641 -280.037518)
			(xy 457.763313 -280.088015) (xy 457.779381 -280.141422) (xy 457.787501 -280.196598) (xy 457.78801 -280.224484)
			(xy 457.787501 -280.25237) (xy 457.779381 -280.307546) (xy 457.763313 -280.360953) (xy 457.739641 -280.41145)
			(xy 457.708868 -280.457963) (xy 457.671651 -280.4995) (xy 457.628783 -280.535175) (xy 457.581177 -280.564229)
			(xy 457.529848 -280.586041) (xy 457.475891 -280.600147) (xy 457.420454 -280.606247) (xy 457.36472 -280.60421)
			(xy 457.309877 -280.59408) (xy 457.257093 -280.576073) (xy 457.207493 -280.550572) (xy 457.162135 -280.518121)
			(xy 457.121986 -280.479412) (xy 457.0879 -280.435269) (xy 457.060604 -280.386634) (xy 457.040681 -280.334543)
			(xy 457.028555 -280.280106) (xy 457.024484 -280.224484) (xy 445.856101 -280.224484) (xy 445.438107 -280.624026)
			(xy 459.436722 -280.624026) (xy 459.440793 -280.568404) (xy 459.452919 -280.513967) (xy 459.472842 -280.461876)
			(xy 459.500138 -280.413241) (xy 459.534224 -280.369098) (xy 459.574373 -280.330389) (xy 459.619731 -280.297938)
			(xy 459.669331 -280.272437) (xy 459.722115 -280.25443) (xy 459.776958 -280.2443) (xy 459.832692 -280.242263)
			(xy 459.888129 -280.248363) (xy 459.942086 -280.262469) (xy 459.993415 -280.284281) (xy 460.041021 -280.313335)
			(xy 460.083889 -280.34901) (xy 460.121106 -280.390547) (xy 460.151879 -280.43706) (xy 460.175551 -280.487557)
			(xy 460.191619 -280.540964) (xy 460.199739 -280.59614) (xy 460.200248 -280.624026) (xy 460.199739 -280.651912)
			(xy 460.191619 -280.707088) (xy 460.175551 -280.760495) (xy 460.151879 -280.810992) (xy 460.121106 -280.857505)
			(xy 460.083889 -280.899042) (xy 460.041021 -280.934717) (xy 459.998234 -280.96083) (xy 463.093306 -280.96083)
			(xy 463.097377 -280.905208) (xy 463.109503 -280.850771) (xy 463.129426 -280.79868) (xy 463.156722 -280.750045)
			(xy 463.190808 -280.705902) (xy 463.230957 -280.667193) (xy 463.276315 -280.634742) (xy 463.325915 -280.609241)
			(xy 463.378699 -280.591234) (xy 463.433542 -280.581104) (xy 463.489276 -280.579067) (xy 463.544713 -280.585167)
			(xy 463.59867 -280.599273) (xy 463.649999 -280.621085) (xy 463.697605 -280.650139) (xy 463.740473 -280.685814)
			(xy 463.77769 -280.727351) (xy 463.808463 -280.773864) (xy 463.832135 -280.824361) (xy 463.848203 -280.877768)
			(xy 463.856323 -280.932944) (xy 463.856832 -280.96083) (xy 463.856323 -280.988716) (xy 463.848203 -281.043892)
			(xy 463.832135 -281.097299) (xy 463.808463 -281.147796) (xy 463.77769 -281.194309) (xy 463.740473 -281.235846)
			(xy 463.697605 -281.271521) (xy 463.649999 -281.300575) (xy 463.59867 -281.322387) (xy 463.544713 -281.336493)
			(xy 463.489276 -281.342593) (xy 463.433542 -281.340556) (xy 463.378699 -281.330426) (xy 463.325915 -281.312419)
			(xy 463.276315 -281.286918) (xy 463.230957 -281.254467) (xy 463.190808 -281.215758) (xy 463.156722 -281.171615)
			(xy 463.129426 -281.12298) (xy 463.109503 -281.070889) (xy 463.097377 -281.016452) (xy 463.093306 -280.96083)
			(xy 459.998234 -280.96083) (xy 459.993415 -280.963771) (xy 459.942086 -280.985583) (xy 459.888129 -280.999689)
			(xy 459.832692 -281.005789) (xy 459.776958 -281.003752) (xy 459.722115 -280.993622) (xy 459.669331 -280.975615)
			(xy 459.619731 -280.950114) (xy 459.574373 -280.917663) (xy 459.534224 -280.878954) (xy 459.500138 -280.834811)
			(xy 459.472842 -280.786176) (xy 459.452919 -280.734085) (xy 459.440793 -280.679648) (xy 459.436722 -280.624026)
			(xy 445.438107 -280.624026) (xy 443.78553 -282.203652) (xy 450.561456 -282.203652) (xy 450.561883 -282.178253)
			(xy 450.568618 -282.127905) (xy 450.581977 -282.078896) (xy 450.601722 -282.032094) (xy 450.627505 -281.988326)
			(xy 450.658869 -281.948369) (xy 450.676772 -281.930348) (xy 450.683528 -281.923238) (xy 450.691485 -281.905328)
			(xy 450.692266 -281.89555) (xy 450.69506 -281.816048) (xy 450.688456 -281.797506) (xy 450.681852 -281.79014)
			(xy 450.663878 -281.769091) (xy 450.633518 -281.722813) (xy 450.610173 -281.672629) (xy 450.594333 -281.619596)
			(xy 450.586332 -281.56483) (xy 450.58584 -281.537156) (xy 450.58584 -281.536902) (xy 450.586257 -281.509647)
			(xy 450.594015 -281.455692) (xy 450.609373 -281.40339) (xy 450.632019 -281.353807) (xy 450.661492 -281.307952)
			(xy 450.69719 -281.266758) (xy 450.738388 -281.231064) (xy 450.784247 -281.201597) (xy 450.833833 -281.178957)
			(xy 450.886137 -281.163605) (xy 450.940093 -281.155854) (xy 450.967348 -281.155394) (xy 450.996088 -281.15589)
			(xy 451.052916 -281.16452) (xy 451.107807 -281.181576) (xy 451.159519 -281.206674) (xy 451.20688 -281.239245)
			(xy 451.228206 -281.258518) (xy 451.235064 -281.265122) (xy 451.253098 -281.272234) (xy 451.341998 -281.272234)
			(xy 451.360032 -281.265122) (xy 451.36689 -281.258518) (xy 451.388217 -281.239248) (xy 451.43558 -281.206683)
			(xy 451.487291 -281.181592) (xy 451.542182 -281.164542) (xy 451.599009 -281.15592) (xy 451.656487 -281.15592)
			(xy 451.713314 -281.164542) (xy 451.768205 -281.181592) (xy 451.819916 -281.206683) (xy 451.867279 -281.239248)
			(xy 451.888606 -281.258518) (xy 451.895464 -281.265122) (xy 451.913498 -281.272234) (xy 452.002398 -281.272234)
			(xy 452.020432 -281.265122) (xy 452.02729 -281.258518) (xy 452.048617 -281.239248) (xy 452.09598 -281.206683)
			(xy 452.147691 -281.181592) (xy 452.202582 -281.164542) (xy 452.259409 -281.15592) (xy 452.316887 -281.15592)
			(xy 452.373714 -281.164542) (xy 452.428605 -281.181592) (xy 452.480316 -281.206683) (xy 452.527679 -281.239248)
			(xy 452.549006 -281.258518) (xy 452.555864 -281.265122) (xy 452.573898 -281.272234) (xy 452.662798 -281.272234)
			(xy 452.680832 -281.265122) (xy 452.68769 -281.258518) (xy 452.708994 -281.239221) (xy 452.756363 -281.206659)
			(xy 452.80808 -281.181572) (xy 452.862976 -281.164528) (xy 452.919807 -281.155911) (xy 452.948548 -281.155394)
			(xy 452.975801 -281.155833) (xy 453.02975 -281.163596) (xy 453.082046 -281.178958) (xy 453.131623 -281.201604)
			(xy 453.177474 -281.231076) (xy 453.218663 -281.266772) (xy 453.254354 -281.307967) (xy 453.28382 -281.353821)
			(xy 453.30646 -281.403401) (xy 453.321814 -281.455699) (xy 453.32957 -281.509649) (xy 453.330056 -281.536902)
			(xy 453.329661 -281.562302) (xy 453.322919 -281.612651) (xy 453.309553 -281.661661) (xy 453.289802 -281.708463)
			(xy 453.281187 -281.723084) (xy 464.670392 -281.723084) (xy 464.674463 -281.667462) (xy 464.686589 -281.613025)
			(xy 464.706512 -281.560934) (xy 464.733808 -281.512299) (xy 464.767894 -281.468156) (xy 464.808043 -281.429447)
			(xy 464.853401 -281.396996) (xy 464.903001 -281.371495) (xy 464.955785 -281.353488) (xy 465.010628 -281.343358)
			(xy 465.066362 -281.341321) (xy 465.121799 -281.347421) (xy 465.175756 -281.361527) (xy 465.227085 -281.383339)
			(xy 465.274691 -281.412393) (xy 465.317559 -281.448068) (xy 465.354776 -281.489605) (xy 465.385549 -281.536118)
			(xy 465.409221 -281.586615) (xy 465.425289 -281.640022) (xy 465.433409 -281.695198) (xy 465.433918 -281.723084)
			(xy 465.433409 -281.75097) (xy 465.425289 -281.806146) (xy 465.409221 -281.859553) (xy 465.385549 -281.91005)
			(xy 465.354776 -281.956563) (xy 465.317559 -281.9981) (xy 465.274691 -282.033775) (xy 465.227085 -282.062829)
			(xy 465.175756 -282.084641) (xy 465.121799 -282.098747) (xy 465.066362 -282.104847) (xy 465.010628 -282.10281)
			(xy 464.955785 -282.09268) (xy 464.903001 -282.074673) (xy 464.853401 -282.049172) (xy 464.808043 -282.016721)
			(xy 464.767894 -281.978012) (xy 464.733808 -281.933869) (xy 464.706512 -281.885234) (xy 464.686589 -281.833143)
			(xy 464.674463 -281.778706) (xy 464.670392 -281.723084) (xy 453.281187 -281.723084) (xy 453.264014 -281.752229)
			(xy 453.232645 -281.792186) (xy 453.21474 -281.810206) (xy 453.208005 -281.817333) (xy 453.200035 -281.83523)
			(xy 453.199246 -281.845004) (xy 453.196452 -281.924506) (xy 453.203056 -281.943048) (xy 453.20966 -281.950414)
			(xy 453.227661 -281.971441) (xy 453.258016 -282.017725) (xy 453.281356 -282.067914) (xy 453.29719 -282.120952)
			(xy 453.305184 -282.175723) (xy 453.305672 -282.203398) (xy 453.305672 -282.203652) (xy 453.3052 -282.230905)
			(xy 453.297449 -282.284858) (xy 453.282097 -282.337158) (xy 453.259457 -282.38674) (xy 453.229991 -282.432595)
			(xy 453.194298 -282.473789) (xy 453.153105 -282.509484) (xy 453.107251 -282.538951) (xy 453.057669 -282.561593)
			(xy 453.00537 -282.576946) (xy 452.951417 -282.584699) (xy 452.924164 -282.58516) (xy 452.895425 -282.584642)
			(xy 452.838598 -282.576016) (xy 452.783708 -282.558963) (xy 452.731996 -282.533871) (xy 452.684633 -282.501306)
			(xy 452.663306 -282.482036) (xy 452.656448 -282.475432) (xy 452.638414 -282.46832) (xy 452.549514 -282.46832)
			(xy 452.53148 -282.475432) (xy 452.524622 -282.482036) (xy 452.503295 -282.501306) (xy 452.455932 -282.533871)
			(xy 452.404221 -282.558962) (xy 452.34933 -282.576012) (xy 452.292503 -282.584634) (xy 452.235025 -282.584634)
			(xy 452.178198 -282.576012) (xy 452.123307 -282.558962) (xy 452.071596 -282.533871) (xy 452.024233 -282.501306)
			(xy 452.002906 -282.482036) (xy 451.996048 -282.475432) (xy 451.978014 -282.46832) (xy 451.889114 -282.46832)
			(xy 451.87108 -282.475432) (xy 451.864222 -282.482036) (xy 451.842895 -282.501306) (xy 451.795532 -282.533871)
			(xy 451.743821 -282.558962) (xy 451.68893 -282.576012) (xy 451.632103 -282.584634) (xy 451.574625 -282.584634)
			(xy 451.517798 -282.576012) (xy 451.462907 -282.558962) (xy 451.411196 -282.533871) (xy 451.363833 -282.501306)
			(xy 451.342506 -282.482036) (xy 451.335648 -282.475432) (xy 451.317614 -282.46832) (xy 451.228714 -282.46832)
			(xy 451.21068 -282.475432) (xy 451.203822 -282.482036) (xy 451.182506 -282.501319) (xy 451.135141 -282.533885)
			(xy 451.083427 -282.558975) (xy 451.028534 -282.576023) (xy 450.971704 -282.584642) (xy 450.942964 -282.58516)
			(xy 450.915708 -282.584778) (xy 450.861752 -282.577015) (xy 450.809449 -282.561652) (xy 450.759866 -282.539002)
			(xy 450.71401 -282.509526) (xy 450.672817 -282.473824) (xy 450.637124 -282.432622) (xy 450.607658 -282.38676)
			(xy 450.585018 -282.337172) (xy 450.569667 -282.284866) (xy 450.561916 -282.230908) (xy 450.561456 -282.203652)
			(xy 443.78553 -282.203652) (xy 442.813415 -283.132854) (xy 456.388661 -283.132854) (xy 456.388661 -283.078346)
			(xy 456.396419 -283.024394) (xy 456.411776 -282.972095) (xy 456.43442 -282.922514) (xy 456.46389 -282.876661)
			(xy 456.499585 -282.835468) (xy 456.54078 -282.799775) (xy 456.586636 -282.770308) (xy 456.636218 -282.747667)
			(xy 456.688518 -282.732314) (xy 456.74247 -282.72456) (xy 456.769724 -282.724098) (xy 456.798463 -282.724608)
			(xy 456.855291 -282.733234) (xy 456.910182 -282.750287) (xy 456.961894 -282.775382) (xy 457.009256 -282.80795)
			(xy 457.030582 -282.827222) (xy 457.03744 -282.833826) (xy 457.055474 -282.840938) (xy 457.144374 -282.840938)
			(xy 457.162408 -282.833826) (xy 457.169266 -282.827222) (xy 457.190593 -282.807952) (xy 457.237956 -282.775387)
			(xy 457.289667 -282.750296) (xy 457.344558 -282.733246) (xy 457.401385 -282.724624) (xy 457.458863 -282.724624)
			(xy 457.51569 -282.733246) (xy 457.570581 -282.750296) (xy 457.622292 -282.775387) (xy 457.669655 -282.807952)
			(xy 457.690982 -282.827222) (xy 457.69784 -282.833826) (xy 457.715874 -282.840938) (xy 457.804774 -282.840938)
			(xy 457.822808 -282.833826) (xy 457.829666 -282.827222) (xy 457.850981 -282.807937) (xy 457.898346 -282.775373)
			(xy 457.950061 -282.750284) (xy 458.004955 -282.733237) (xy 458.061784 -282.724617) (xy 458.090524 -282.724098)
			(xy 458.120649 -282.724639) (xy 458.180147 -282.734126) (xy 458.237416 -282.752843) (xy 458.291033 -282.780325)
			(xy 458.339665 -282.815891) (xy 458.361288 -282.836874) (xy 458.368701 -282.843697) (xy 458.38729 -282.851428)
			(xy 458.397356 -282.85186) (xy 458.469492 -282.85186) (xy 458.479562 -282.851441) (xy 458.498161 -282.843717)
			(xy 458.50556 -282.836874) (xy 458.527192 -282.815901) (xy 458.575817 -282.780329) (xy 458.629432 -282.752846)
			(xy 458.686701 -282.734137) (xy 458.7462 -282.724666) (xy 458.776324 -282.724098) (xy 458.803575 -282.724573)
			(xy 458.857521 -282.732333) (xy 458.909813 -282.74769) (xy 458.959388 -282.770333) (xy 459.005236 -282.799801)
			(xy 459.046424 -282.835493) (xy 459.082114 -282.876683) (xy 459.111578 -282.922533) (xy 459.134218 -282.972109)
			(xy 459.149572 -283.024403) (xy 459.157328 -283.078349) (xy 459.157328 -283.132851) (xy 459.149572 -283.186797)
			(xy 459.134218 -283.239091) (xy 459.111578 -283.288667) (xy 459.082114 -283.334517) (xy 459.046424 -283.375707)
			(xy 459.005236 -283.411399) (xy 458.959388 -283.440867) (xy 458.909813 -283.46351) (xy 458.857521 -283.478867)
			(xy 458.803575 -283.486627) (xy 458.776324 -283.487114) (xy 458.746201 -283.486538) (xy 458.686704 -283.47706)
			(xy 458.629436 -283.458351) (xy 458.575819 -283.430876) (xy 458.527185 -283.395317) (xy 458.50556 -283.374338)
			(xy 458.498163 -283.367493) (xy 458.479562 -283.359775) (xy 458.469492 -283.359352) (xy 458.397356 -283.359352)
			(xy 458.387282 -283.359741) (xy 458.368684 -283.367486) (xy 458.361288 -283.374338) (xy 458.339681 -283.395338)
			(xy 458.291049 -283.430906) (xy 458.237428 -283.458384) (xy 458.180153 -283.477087) (xy 458.12065 -283.486551)
			(xy 458.090524 -283.487114) (xy 458.061786 -283.486572) (xy 458.004959 -283.477953) (xy 457.950069 -283.460907)
			(xy 457.898357 -283.43582) (xy 457.850994 -283.403259) (xy 457.829666 -283.38399) (xy 457.822808 -283.377386)
			(xy 457.804774 -283.370274) (xy 457.715874 -283.370274) (xy 457.69784 -283.377386) (xy 457.690982 -283.38399)
			(xy 457.669655 -283.40326) (xy 457.622292 -283.435825) (xy 457.570581 -283.460916) (xy 457.51569 -283.477966)
			(xy 457.458863 -283.486588) (xy 457.401385 -283.486588) (xy 457.344558 -283.477966) (xy 457.289667 -283.460916)
			(xy 457.237956 -283.435825) (xy 457.190593 -283.40326) (xy 457.169266 -283.38399) (xy 457.162408 -283.377386)
			(xy 457.144374 -283.370274) (xy 457.055474 -283.370274) (xy 457.03744 -283.377386) (xy 457.030582 -283.38399)
			(xy 457.009249 -283.403254) (xy 456.961888 -283.43582) (xy 456.910178 -283.460913) (xy 456.855289 -283.477966)
			(xy 456.798463 -283.486591) (xy 456.769724 -283.487114) (xy 456.74247 -283.48664) (xy 456.688518 -283.478886)
			(xy 456.636218 -283.463533) (xy 456.586636 -283.440892) (xy 456.54078 -283.411425) (xy 456.499585 -283.375732)
			(xy 456.46389 -283.334539) (xy 456.43442 -283.288686) (xy 456.411776 -283.239105) (xy 456.396419 -283.186806)
			(xy 456.388661 -283.132854) (xy 442.813415 -283.132854) (xy 442.760608 -283.18333) (xy 442.757615 -283.18674)
			(xy 442.752762 -283.194407) (xy 442.750956 -283.19857) (xy 442.749432 -283.20238) (xy 442.748349 -283.206161)
			(xy 442.747205 -283.213941) (xy 442.747146 -283.217874) (xy 442.747146 -283.218128) (xy 442.747571 -283.228142)
			(xy 442.755248 -283.246642) (xy 442.769421 -283.260794) (xy 442.787931 -283.268443) (xy 442.797946 -283.268928)
			(xy 442.808868 -283.268928) (xy 442.835538 -283.258006) (xy 442.839348 -283.255466) (xy 442.85027 -283.248608)
			(xy 442.853572 -283.24556) (xy 442.874764 -283.226977) (xy 442.921589 -283.195605) (xy 442.972515 -283.171455)
			(xy 443.026437 -283.155051) (xy 443.082185 -283.146749) (xy 443.110366 -283.146246) (xy 443.137624 -283.146707)
			(xy 443.191585 -283.154461) (xy 443.243893 -283.169816) (xy 443.293484 -283.192459) (xy 443.339347 -283.22193)
			(xy 443.380548 -283.257628) (xy 443.41625 -283.298826) (xy 443.445725 -283.344686) (xy 443.468373 -283.394275)
			(xy 443.483732 -283.446582) (xy 443.491491 -283.500542) (xy 443.491491 -283.555058) (xy 443.483732 -283.609018)
			(xy 443.468373 -283.661325) (xy 443.445725 -283.710914) (xy 443.41625 -283.756774) (xy 443.380548 -283.797972)
			(xy 443.339347 -283.83367) (xy 443.293484 -283.863141) (xy 443.243893 -283.885784) (xy 443.191585 -283.901139)
			(xy 443.137624 -283.908893) (xy 443.110366 -283.909262) (xy 443.109858 -283.909262) (xy 443.079535 -283.908612)
			(xy 443.019671 -283.898894) (xy 442.962095 -283.879835) (xy 442.908256 -283.851916) (xy 442.883544 -283.834332)
			(xy 442.883036 -283.834332) (xy 442.87059 -283.82468) (xy 442.870082 -283.824172) (xy 442.865256 -283.821378)
			(xy 442.859687 -283.818575) (xy 442.847611 -283.815486) (xy 442.84138 -283.815282) (xy 442.819536 -283.815282)
			(xy 442.814097 -283.815136) (xy 442.803469 -283.812821) (xy 442.798454 -283.81071) (xy 442.78423 -283.804106)
			(xy 442.775967 -283.800673) (xy 442.758142 -283.799256) (xy 442.749432 -283.801312) (xy 442.727519 -283.822496)
			(xy 442.678264 -283.85839) (xy 442.623988 -283.886112) (xy 442.566034 -283.904977) (xy 442.505839 -283.914517)
			(xy 442.475366 -283.915104) (xy 442.449217 -283.914652) (xy 442.397399 -283.907575) (xy 442.347003 -283.893595)
			(xy 442.298944 -283.872965) (xy 442.254096 -283.84606) (xy 442.213274 -283.813368) (xy 442.19495 -283.794708)
			(xy 442.186349 -283.786557) (xy 442.164104 -283.77847) (xy 442.152278 -283.779214) (xy 442.144135 -283.780466)
			(xy 442.129229 -283.78746) (xy 442.123068 -283.79293) (xy 441.077639 -284.792255) (xy 453.090443 -284.792255)
			(xy 453.090443 -284.737745) (xy 453.098201 -284.683789) (xy 453.113559 -284.631487) (xy 453.136205 -284.581903)
			(xy 453.165677 -284.536047) (xy 453.201376 -284.494852) (xy 453.242574 -284.459157) (xy 453.288433 -284.429689)
			(xy 453.338019 -284.407047) (xy 453.390322 -284.391694) (xy 453.444279 -284.383941) (xy 453.471534 -284.38348)
			(xy 453.500273 -284.383988) (xy 453.557101 -284.392616) (xy 453.611992 -284.409669) (xy 453.663703 -284.434764)
			(xy 453.711065 -284.467332) (xy 453.732392 -284.486604) (xy 453.73925 -284.493208) (xy 453.757284 -284.50032)
			(xy 453.846184 -284.50032) (xy 453.864218 -284.493208) (xy 453.871076 -284.486604) (xy 453.892403 -284.467334)
			(xy 453.939766 -284.434769) (xy 453.991477 -284.409678) (xy 454.046368 -284.392628) (xy 454.103195 -284.384006)
			(xy 454.160673 -284.384006) (xy 454.2175 -284.392628) (xy 454.272391 -284.409678) (xy 454.324102 -284.434769)
			(xy 454.371465 -284.467334) (xy 454.392792 -284.486604) (xy 454.39965 -284.493208) (xy 454.417684 -284.50032)
			(xy 454.506584 -284.50032) (xy 454.524618 -284.493208) (xy 454.531476 -284.486604) (xy 454.552799 -284.467328)
			(xy 454.600161 -284.43476) (xy 454.651873 -284.409668) (xy 454.706766 -284.392619) (xy 454.763595 -284.383999)
			(xy 454.792334 -284.38348) (xy 454.822459 -284.38402) (xy 454.881957 -284.393508) (xy 454.939226 -284.412225)
			(xy 454.992842 -284.439708) (xy 455.041475 -284.475274) (xy 455.063098 -284.496256) (xy 455.07051 -284.503082)
			(xy 455.0891 -284.510811) (xy 455.099166 -284.511242) (xy 455.171302 -284.511242) (xy 455.181373 -284.510833)
			(xy 455.199972 -284.503102) (xy 455.20737 -284.496256) (xy 455.228994 -284.475275) (xy 455.277622 -284.439704)
			(xy 455.331239 -284.412223) (xy 455.388509 -284.393516) (xy 455.44801 -284.384047) (xy 455.478134 -284.38348)
			(xy 455.505383 -284.383993) (xy 455.559325 -284.391753) (xy 455.611614 -284.40711) (xy 455.661185 -284.429753)
			(xy 455.70703 -284.459219) (xy 455.748215 -284.494909) (xy 455.783901 -284.536097) (xy 455.813364 -284.581945)
			(xy 455.836002 -284.631518) (xy 455.851354 -284.683808) (xy 455.85911 -284.737751) (xy 455.85911 -284.792249)
			(xy 455.851354 -284.846192) (xy 455.836002 -284.898482) (xy 455.813364 -284.948055) (xy 455.783901 -284.993903)
			(xy 455.748215 -285.035091) (xy 455.70703 -285.070781) (xy 455.661185 -285.100247) (xy 455.611614 -285.12289)
			(xy 455.559325 -285.138247) (xy 455.505383 -285.146007) (xy 455.478134 -285.146496) (xy 455.448011 -285.145919)
			(xy 455.388514 -285.136442) (xy 455.331245 -285.117733) (xy 455.277628 -285.090258) (xy 455.228994 -285.054699)
			(xy 455.20737 -285.03372) (xy 455.199972 -285.026877) (xy 455.181371 -285.019158) (xy 455.171302 -285.018734)
			(xy 455.099166 -285.018734) (xy 455.089094 -285.019133) (xy 455.070496 -285.026871) (xy 455.063098 -285.03372)
			(xy 455.041501 -285.05473) (xy 454.992864 -285.090293) (xy 454.939241 -285.117768) (xy 454.881964 -285.136469)
			(xy 454.82246 -285.145932) (xy 454.792334 -285.146496) (xy 454.763594 -285.146013) (xy 454.706764 -285.137381)
			(xy 454.651873 -285.120321) (xy 454.600162 -285.095221) (xy 454.552801 -285.062647) (xy 454.531476 -285.043372)
			(xy 454.524618 -285.036768) (xy 454.506584 -285.029656) (xy 454.417684 -285.029656) (xy 454.39965 -285.036768)
			(xy 454.392792 -285.043372) (xy 454.371465 -285.062642) (xy 454.324102 -285.095207) (xy 454.272391 -285.120298)
			(xy 454.2175 -285.137348) (xy 454.160673 -285.14597) (xy 454.103195 -285.14597) (xy 454.046368 -285.137348)
			(xy 453.991477 -285.120298) (xy 453.939766 -285.095207) (xy 453.892403 -285.062642) (xy 453.871076 -285.043372)
			(xy 453.864218 -285.036768) (xy 453.846184 -285.029656) (xy 453.757284 -285.029656) (xy 453.73925 -285.036768)
			(xy 453.732392 -285.043372) (xy 453.711052 -285.062628) (xy 453.663694 -285.095196) (xy 453.611985 -285.120291)
			(xy 453.557097 -285.137345) (xy 453.500272 -285.145973) (xy 453.471534 -285.146496) (xy 453.444279 -285.146059)
			(xy 453.390322 -285.138306) (xy 453.338019 -285.122953) (xy 453.288433 -285.100311) (xy 453.242574 -285.070843)
			(xy 453.201376 -285.035148) (xy 453.165677 -284.993953) (xy 453.136205 -284.948097) (xy 453.113559 -284.898513)
			(xy 453.098201 -284.846211) (xy 453.090443 -284.792255) (xy 441.077639 -284.792255) (xy 440.225774 -285.606552)
			(xy 456.489267 -285.606552) (xy 456.489267 -285.552048) (xy 456.497024 -285.498098) (xy 456.51238 -285.445801)
			(xy 456.535023 -285.396222) (xy 456.56449 -285.35037) (xy 456.600184 -285.309178) (xy 456.641376 -285.273486)
			(xy 456.687229 -285.244019) (xy 456.736808 -285.221377) (xy 456.789106 -285.206023) (xy 456.843056 -285.198267)
			(xy 456.870308 -285.197804) (xy 456.899047 -285.198322) (xy 456.955875 -285.206946) (xy 457.010766 -285.223997)
			(xy 457.062477 -285.24909) (xy 457.109839 -285.281657) (xy 457.131166 -285.300928) (xy 457.138024 -285.307532)
			(xy 457.156058 -285.314644) (xy 457.244958 -285.314644) (xy 457.262992 -285.307532) (xy 457.26985 -285.300928)
			(xy 457.291177 -285.281658) (xy 457.33854 -285.249093) (xy 457.390251 -285.224002) (xy 457.445142 -285.206952)
			(xy 457.501969 -285.19833) (xy 457.559447 -285.19833) (xy 457.616274 -285.206952) (xy 457.671165 -285.224002)
			(xy 457.722876 -285.249093) (xy 457.770239 -285.281658) (xy 457.791566 -285.300928) (xy 457.798424 -285.307532)
			(xy 457.816458 -285.314644) (xy 457.905358 -285.314644) (xy 457.923392 -285.307532) (xy 457.93025 -285.300928)
			(xy 457.951572 -285.281652) (xy 457.998936 -285.249087) (xy 458.050649 -285.223995) (xy 458.10554 -285.206946)
			(xy 458.162369 -285.198324) (xy 458.191108 -285.197804) (xy 458.221232 -285.198354) (xy 458.280731 -285.207838)
			(xy 458.337999 -285.226552) (xy 458.391616 -285.254033) (xy 458.440249 -285.289598) (xy 458.461872 -285.31058)
			(xy 458.46929 -285.317398) (xy 458.487875 -285.325131) (xy 458.49794 -285.325566) (xy 458.570076 -285.325566)
			(xy 458.580145 -285.325137) (xy 458.598743 -285.31742) (xy 458.606144 -285.31058) (xy 458.627767 -285.289598)
			(xy 458.676397 -285.254031) (xy 458.730014 -285.226551) (xy 458.787284 -285.207844) (xy 458.846784 -285.198372)
			(xy 458.876908 -285.197804) (xy 458.90416 -285.198266) (xy 458.958108 -285.206024) (xy 459.010404 -285.22138)
			(xy 459.059982 -285.244023) (xy 459.105832 -285.27349) (xy 459.147023 -285.309183) (xy 459.182715 -285.350374)
			(xy 459.212181 -285.396226) (xy 459.234822 -285.445804) (xy 459.250178 -285.4981) (xy 459.257934 -285.552048)
			(xy 459.257934 -285.606552) (xy 459.250178 -285.6605) (xy 459.234822 -285.712796) (xy 459.212181 -285.762374)
			(xy 459.182715 -285.808226) (xy 459.147023 -285.849417) (xy 459.105832 -285.88511) (xy 459.059982 -285.914577)
			(xy 459.010404 -285.93722) (xy 458.958108 -285.952576) (xy 458.90416 -285.960334) (xy 458.876908 -285.96082)
			(xy 458.846784 -285.960253) (xy 458.787287 -285.950772) (xy 458.730019 -285.932061) (xy 458.676402 -285.904584)
			(xy 458.627768 -285.869024) (xy 458.606144 -285.848044) (xy 458.598718 -285.841237) (xy 458.580139 -285.833497)
			(xy 458.570076 -285.833058) (xy 458.49794 -285.833058) (xy 458.487871 -285.833489) (xy 458.469272 -285.841204)
			(xy 458.461872 -285.848044) (xy 458.440229 -285.869005) (xy 458.391606 -285.904578) (xy 458.337995 -285.932063)
			(xy 458.280728 -285.950775) (xy 458.221231 -285.96025) (xy 458.191108 -285.96082) (xy 458.16237 -285.960286)
			(xy 458.105543 -285.951665) (xy 458.050652 -285.934617) (xy 457.998941 -285.909528) (xy 457.951577 -285.876965)
			(xy 457.93025 -285.857696) (xy 457.923392 -285.851092) (xy 457.905358 -285.84398) (xy 457.816458 -285.84398)
			(xy 457.798424 -285.851092) (xy 457.791566 -285.857696) (xy 457.770239 -285.876966) (xy 457.722876 -285.909531)
			(xy 457.671165 -285.934622) (xy 457.616274 -285.951672) (xy 457.559447 -285.960294) (xy 457.501969 -285.960294)
			(xy 457.445142 -285.951672) (xy 457.390251 -285.934622) (xy 457.33854 -285.909531) (xy 457.291177 -285.876966)
			(xy 457.26985 -285.857696) (xy 457.262992 -285.851092) (xy 457.244958 -285.84398) (xy 457.156058 -285.84398)
			(xy 457.138024 -285.851092) (xy 457.131166 -285.857696) (xy 457.109826 -285.876952) (xy 457.062468 -285.909522)
			(xy 457.01076 -285.934619) (xy 456.955872 -285.951673) (xy 456.899046 -285.960298) (xy 456.870308 -285.96082)
			(xy 456.843056 -285.960333) (xy 456.789106 -285.952577) (xy 456.736808 -285.937223) (xy 456.687229 -285.914581)
			(xy 456.641376 -285.885114) (xy 456.600184 -285.849422) (xy 456.56449 -285.80823) (xy 456.535023 -285.762378)
			(xy 456.51238 -285.712799) (xy 456.497024 -285.660502) (xy 456.489267 -285.606552) (xy 440.225774 -285.606552)
			(xy 438.50017 -287.256055) (xy 453.090443 -287.256055) (xy 453.090443 -287.201545) (xy 453.098201 -287.147589)
			(xy 453.113559 -287.095287) (xy 453.136205 -287.045703) (xy 453.165677 -286.999847) (xy 453.201376 -286.958652)
			(xy 453.242574 -286.922957) (xy 453.288433 -286.893489) (xy 453.338019 -286.870847) (xy 453.390322 -286.855494)
			(xy 453.444279 -286.847741) (xy 453.471534 -286.84728) (xy 453.500273 -286.847788) (xy 453.557101 -286.856416)
			(xy 453.611992 -286.873469) (xy 453.663703 -286.898564) (xy 453.711065 -286.931132) (xy 453.732392 -286.950404)
			(xy 453.73925 -286.957008) (xy 453.757284 -286.96412) (xy 453.846184 -286.96412) (xy 453.864218 -286.957008)
			(xy 453.871076 -286.950404) (xy 453.892403 -286.931134) (xy 453.939766 -286.898569) (xy 453.991477 -286.873478)
			(xy 454.046368 -286.856428) (xy 454.103195 -286.847806) (xy 454.160673 -286.847806) (xy 454.2175 -286.856428)
			(xy 454.272391 -286.873478) (xy 454.324102 -286.898569) (xy 454.371465 -286.931134) (xy 454.392792 -286.950404)
			(xy 454.39965 -286.957008) (xy 454.417684 -286.96412) (xy 454.506584 -286.96412) (xy 454.524618 -286.957008)
			(xy 454.531476 -286.950404) (xy 454.552799 -286.931128) (xy 454.600161 -286.89856) (xy 454.651873 -286.873468)
			(xy 454.706766 -286.856419) (xy 454.763595 -286.847799) (xy 454.792334 -286.84728) (xy 454.822459 -286.84782)
			(xy 454.881957 -286.857308) (xy 454.939226 -286.876025) (xy 454.992842 -286.903508) (xy 455.041475 -286.939074)
			(xy 455.063098 -286.960056) (xy 455.07051 -286.966882) (xy 455.0891 -286.974611) (xy 455.099166 -286.975042)
			(xy 455.171302 -286.975042) (xy 455.181373 -286.974633) (xy 455.199972 -286.966902) (xy 455.20737 -286.960056)
			(xy 455.228994 -286.939075) (xy 455.277622 -286.903504) (xy 455.331239 -286.876023) (xy 455.388509 -286.857316)
			(xy 455.44801 -286.847847) (xy 455.478134 -286.84728) (xy 455.505383 -286.847793) (xy 455.559325 -286.855553)
			(xy 455.611614 -286.87091) (xy 455.661185 -286.893553) (xy 455.70703 -286.923019) (xy 455.748215 -286.958709)
			(xy 455.783901 -286.999897) (xy 455.813364 -287.045745) (xy 455.836002 -287.095318) (xy 455.851354 -287.147608)
			(xy 455.85911 -287.201551) (xy 455.85911 -287.256049) (xy 455.851354 -287.309992) (xy 455.836002 -287.362282)
			(xy 455.813364 -287.411855) (xy 455.783901 -287.457703) (xy 455.748215 -287.498891) (xy 455.70703 -287.534581)
			(xy 455.661185 -287.564047) (xy 455.611614 -287.58669) (xy 455.559325 -287.602047) (xy 455.505383 -287.609807)
			(xy 455.478134 -287.610296) (xy 455.448011 -287.609719) (xy 455.388514 -287.600242) (xy 455.331245 -287.581533)
			(xy 455.277628 -287.554058) (xy 455.228994 -287.518499) (xy 455.20737 -287.49752) (xy 455.199972 -287.490677)
			(xy 455.181371 -287.482958) (xy 455.171302 -287.482534) (xy 455.099166 -287.482534) (xy 455.089094 -287.482933)
			(xy 455.070496 -287.490671) (xy 455.063098 -287.49752) (xy 455.041501 -287.51853) (xy 454.992864 -287.554093)
			(xy 454.939241 -287.581568) (xy 454.881964 -287.600269) (xy 454.82246 -287.609732) (xy 454.792334 -287.610296)
			(xy 454.763594 -287.609813) (xy 454.706764 -287.601181) (xy 454.651873 -287.584121) (xy 454.600162 -287.559021)
			(xy 454.552801 -287.526447) (xy 454.531476 -287.507172) (xy 454.524618 -287.500568) (xy 454.506584 -287.493456)
			(xy 454.417684 -287.493456) (xy 454.39965 -287.500568) (xy 454.392792 -287.507172) (xy 454.371465 -287.526442)
			(xy 454.324102 -287.559007) (xy 454.272391 -287.584098) (xy 454.2175 -287.601148) (xy 454.160673 -287.60977)
			(xy 454.103195 -287.60977) (xy 454.046368 -287.601148) (xy 453.991477 -287.584098) (xy 453.939766 -287.559007)
			(xy 453.892403 -287.526442) (xy 453.871076 -287.507172) (xy 453.864218 -287.500568) (xy 453.846184 -287.493456)
			(xy 453.757284 -287.493456) (xy 453.73925 -287.500568) (xy 453.732392 -287.507172) (xy 453.711052 -287.526428)
			(xy 453.663694 -287.558996) (xy 453.611985 -287.584091) (xy 453.557097 -287.601145) (xy 453.500272 -287.609773)
			(xy 453.471534 -287.610296) (xy 453.444279 -287.609859) (xy 453.390322 -287.602106) (xy 453.338019 -287.586753)
			(xy 453.288433 -287.564111) (xy 453.242574 -287.534643) (xy 453.201376 -287.498948) (xy 453.165677 -287.457753)
			(xy 453.136205 -287.411897) (xy 453.113559 -287.362313) (xy 453.098201 -287.310011) (xy 453.090443 -287.256055)
			(xy 438.50017 -287.256055) (xy 438.11444 -287.624774) (xy 438.100978 -287.637474) (xy 438.093358 -287.644586)
			(xy 438.089294 -287.653984) (xy 438.087287 -287.658698) (xy 438.084989 -287.66868) (xy 438.084722 -287.673796)
			(xy 438.084214 -287.707832) (xy 438.083452 -287.746948) (xy 438.083498 -287.75293) (xy 438.08607 -287.76461)
			(xy 438.088532 -287.770062) (xy 438.092342 -287.777936) (xy 438.11571 -287.801304) (xy 438.119326 -287.804741)
			(xy 438.127641 -287.810248) (xy 438.13222 -287.812226) (xy 438.141364 -287.816036) (xy 438.151524 -287.816036)
			(xy 438.1783 -287.816455) (xy 438.231335 -287.823876) (xy 438.282811 -287.83864) (xy 438.331717 -287.860457)
			(xy 438.377092 -287.888898) (xy 438.418045 -287.923403) (xy 438.436258 -287.943036) (xy 438.443728 -287.950375)
			(xy 438.462883 -287.958783) (xy 438.473342 -287.959292) (xy 438.869582 -287.959292) (xy 438.878753 -287.958957)
			(xy 438.895948 -287.952583) (xy 438.90311 -287.946846) (xy 438.922573 -287.92865) (xy 438.965666 -287.897315)
			(xy 439.012702 -287.872286) (xy 439.062766 -287.854052) (xy 439.114881 -287.842967) (xy 439.168032 -287.839248)
			(xy 439.221183 -287.842967) (xy 439.273298 -287.854052) (xy 439.323362 -287.872286) (xy 439.370398 -287.897315)
			(xy 439.413491 -287.92865) (xy 439.432954 -287.946846) (xy 439.440133 -287.952552) (xy 439.457318 -287.958919)
			(xy 439.466482 -287.959292) (xy 439.853324 -287.959292) (xy 439.862492 -287.95895) (xy 439.879677 -287.952565)
			(xy 439.886852 -287.946846) (xy 439.906315 -287.92865) (xy 439.949408 -287.897315) (xy 439.996444 -287.872286)
			(xy 440.046508 -287.854052) (xy 440.098623 -287.842967) (xy 440.151774 -287.839248) (xy 440.204925 -287.842967)
			(xy 440.25704 -287.854052) (xy 440.307104 -287.872286) (xy 440.35414 -287.897315) (xy 440.357354 -287.899652)
			(xy 457.970079 -287.899652) (xy 457.970079 -287.845148) (xy 457.977837 -287.791198) (xy 457.993193 -287.738901)
			(xy 458.015836 -287.689322) (xy 458.045305 -287.64347) (xy 458.080999 -287.60228) (xy 458.122193 -287.566588)
			(xy 458.168047 -287.537123) (xy 458.217627 -287.514483) (xy 458.269925 -287.499131) (xy 458.323876 -287.491377)
			(xy 458.351128 -287.490916) (xy 458.381252 -287.491479) (xy 458.440748 -287.500963) (xy 458.498016 -287.519677)
			(xy 458.551632 -287.547154) (xy 458.600267 -287.582713) (xy 458.621892 -287.603692) (xy 458.629302 -287.61052)
			(xy 458.647893 -287.618247) (xy 458.65796 -287.618678) (xy 458.730096 -287.618678) (xy 458.740166 -287.618256)
			(xy 458.758764 -287.610534) (xy 458.766164 -287.603692) (xy 458.78778 -287.582702) (xy 458.836412 -287.547136)
			(xy 458.89003 -287.519658) (xy 458.947302 -287.500952) (xy 459.006803 -287.491483) (xy 459.036928 -287.490916)
			(xy 459.06418 -287.491356) (xy 459.118128 -287.499116) (xy 459.170422 -287.514475) (xy 459.219999 -287.537119)
			(xy 459.265849 -287.566588) (xy 459.307038 -287.602281) (xy 459.342729 -287.643473) (xy 459.372195 -287.689325)
			(xy 459.394835 -287.738904) (xy 459.41019 -287.7912) (xy 459.417946 -287.845148) (xy 459.417946 -287.899652)
			(xy 459.41019 -287.9536) (xy 459.394835 -288.005896) (xy 459.372195 -288.055475) (xy 459.342729 -288.101327)
			(xy 459.307038 -288.142519) (xy 459.265849 -288.178212) (xy 459.219999 -288.207681) (xy 459.170422 -288.230325)
			(xy 459.118128 -288.245684) (xy 459.06418 -288.253444) (xy 459.036928 -288.253932) (xy 459.006805 -288.253349)
			(xy 458.947309 -288.243872) (xy 458.890041 -288.225164) (xy 458.836424 -288.197691) (xy 458.787789 -288.162134)
			(xy 458.766164 -288.141156) (xy 458.758776 -288.134302) (xy 458.740167 -288.126592) (xy 458.730096 -288.12617)
			(xy 458.65796 -288.12617) (xy 458.647886 -288.126556) (xy 458.629287 -288.134302) (xy 458.621892 -288.141156)
			(xy 458.600287 -288.162158) (xy 458.551653 -288.197725) (xy 458.498032 -288.225202) (xy 458.440757 -288.243905)
			(xy 458.381254 -288.253368) (xy 458.351128 -288.253932) (xy 458.323876 -288.253423) (xy 458.269925 -288.245669)
			(xy 458.217627 -288.230317) (xy 458.168047 -288.207677) (xy 458.122193 -288.178212) (xy 458.080999 -288.14252)
			(xy 458.045305 -288.10133) (xy 458.015836 -288.055478) (xy 457.993193 -288.005899) (xy 457.977837 -287.953602)
			(xy 457.970079 -287.899652) (xy 440.357354 -287.899652) (xy 440.397233 -287.92865) (xy 440.416696 -287.946846)
			(xy 440.423873 -287.952561) (xy 440.441057 -287.958947) (xy 440.450224 -287.959292) (xy 443.512448 -287.959292)
			(xy 443.522515 -287.959723) (xy 443.541107 -287.967449) (xy 443.548516 -287.974278) (xy 444.377085 -288.802847)
			(xy 458.605926 -288.802847) (xy 458.605926 -288.748353) (xy 458.613681 -288.694413) (xy 458.629034 -288.642125)
			(xy 458.651672 -288.592555) (xy 458.681133 -288.546711) (xy 458.716819 -288.505526) (xy 458.758003 -288.469839)
			(xy 458.803846 -288.440376) (xy 458.853416 -288.417738) (xy 458.905703 -288.402384) (xy 458.959643 -288.394627)
			(xy 458.98689 -288.39414) (xy 459.01426 -288.394602) (xy 459.06844 -288.402419) (xy 459.120944 -288.417909)
			(xy 459.17069 -288.440752) (xy 459.216657 -288.470478) (xy 459.237588 -288.48812) (xy 459.237842 -288.488374)
			(xy 459.244935 -288.493951) (xy 459.261847 -288.500202) (xy 459.270862 -288.500566) (xy 459.337918 -288.500566)
			(xy 459.346937 -288.500225) (xy 459.363854 -288.493967) (xy 459.370938 -288.488374) (xy 459.370938 -288.48812)
			(xy 459.371192 -288.48812) (xy 459.392119 -288.470474) (xy 459.438093 -288.440763) (xy 459.487842 -288.417928)
			(xy 459.540344 -288.402438) (xy 459.59452 -288.394613) (xy 459.62189 -288.39414) (xy 459.649147 -288.394506)
			(xy 459.703106 -288.402263) (xy 459.755411 -288.41762) (xy 459.804999 -288.440265) (xy 459.850859 -288.469736)
			(xy 459.892058 -288.505435) (xy 459.927758 -288.546633) (xy 459.95723 -288.592492) (xy 459.979876 -288.642079)
			(xy 459.995235 -288.694385) (xy 460.002993 -288.748343) (xy 460.002993 -288.802857) (xy 459.995235 -288.856815)
			(xy 459.979876 -288.909121) (xy 459.95723 -288.958708) (xy 459.927758 -289.004567) (xy 459.892058 -289.045765)
			(xy 459.850859 -289.081464) (xy 459.804999 -289.110935) (xy 459.755411 -289.13358) (xy 459.703106 -289.148937)
			(xy 459.649147 -289.156694) (xy 459.62189 -289.157156) (xy 459.594519 -289.156707) (xy 459.540339 -289.148886)
			(xy 459.487835 -289.133394) (xy 459.438088 -289.110548) (xy 459.392123 -289.080819) (xy 459.371192 -289.063176)
			(xy 459.370938 -289.062922) (xy 459.363851 -289.057336) (xy 459.346934 -289.051091) (xy 459.337918 -289.05073)
			(xy 459.270862 -289.05073) (xy 459.261842 -289.051062) (xy 459.244925 -289.057326) (xy 459.237842 -289.062922)
			(xy 459.237842 -289.063176) (xy 459.237588 -289.063176) (xy 459.21663 -289.080784) (xy 459.170665 -289.110501)
			(xy 459.120924 -289.133343) (xy 459.068429 -289.148842) (xy 459.014257 -289.156678) (xy 458.98689 -289.157156)
			(xy 458.959643 -289.156573) (xy 458.905703 -289.148816) (xy 458.853416 -289.133462) (xy 458.803846 -289.110824)
			(xy 458.758003 -289.081361) (xy 458.716819 -289.045674) (xy 458.681133 -289.004489) (xy 458.651672 -288.958645)
			(xy 458.629034 -288.909075) (xy 458.613681 -288.856787) (xy 458.605926 -288.802847) (xy 444.377085 -288.802847)
			(xy 445.11629 -289.542052) (xy 452.214966 -289.542052) (xy 452.214966 -289.487548) (xy 452.222722 -289.433599)
			(xy 452.238078 -289.381303) (xy 452.260719 -289.331724) (xy 452.290186 -289.285873) (xy 452.325878 -289.244681)
			(xy 452.36707 -289.208989) (xy 452.412921 -289.179521) (xy 452.462499 -289.156879) (xy 452.514795 -289.141523)
			(xy 452.568744 -289.133766) (xy 452.595996 -289.13328) (xy 452.623367 -289.133729) (xy 452.677548 -289.141548)
			(xy 452.730052 -289.15704) (xy 452.779798 -289.179886) (xy 452.825764 -289.209616) (xy 452.846694 -289.22726)
			(xy 452.846948 -289.227514) (xy 452.854044 -289.233087) (xy 452.870954 -289.239341) (xy 452.879968 -289.239706)
			(xy 452.947024 -289.239706) (xy 452.956042 -289.239359) (xy 452.972959 -289.233104) (xy 452.980044 -289.227514)
			(xy 452.980044 -289.22726) (xy 452.980298 -289.22726) (xy 453.001215 -289.209602) (xy 453.047192 -289.179894)
			(xy 453.096944 -289.157062) (xy 453.149448 -289.141576) (xy 453.203626 -289.133751) (xy 453.230996 -289.13328)
			(xy 453.258248 -289.133767) (xy 453.312198 -289.141523) (xy 453.364495 -289.156879) (xy 453.414074 -289.17952)
			(xy 453.459926 -289.208987) (xy 453.501118 -289.24468) (xy 453.536811 -289.285871) (xy 453.566278 -289.331723)
			(xy 453.58892 -289.381302) (xy 453.604276 -289.433598) (xy 453.612033 -289.487548) (xy 453.612033 -289.542052)
			(xy 453.604276 -289.596002) (xy 453.58892 -289.648298) (xy 453.566278 -289.697877) (xy 453.536811 -289.743729)
			(xy 453.501118 -289.78492) (xy 453.459926 -289.820613) (xy 453.414074 -289.85008) (xy 453.364495 -289.872721)
			(xy 453.312198 -289.888077) (xy 453.258248 -289.895833) (xy 453.230996 -289.896296) (xy 453.203626 -289.895833)
			(xy 453.149446 -289.888015) (xy 453.096943 -289.872525) (xy 453.047196 -289.849683) (xy 453.00123 -289.819957)
			(xy 452.980298 -289.802316) (xy 452.980044 -289.802062) (xy 452.972952 -289.796483) (xy 452.956039 -289.790233)
			(xy 452.947024 -289.78987) (xy 452.879968 -289.78987) (xy 452.87095 -289.790218) (xy 452.854034 -289.796472)
			(xy 452.846948 -289.802062) (xy 452.846948 -289.802316) (xy 452.846694 -289.802316) (xy 452.825777 -289.819974)
			(xy 452.7798 -289.849682) (xy 452.730048 -289.872514) (xy 452.677545 -289.888001) (xy 452.623366 -289.895825)
			(xy 452.595996 -289.896296) (xy 452.568744 -289.895834) (xy 452.514795 -289.888077) (xy 452.462499 -289.872721)
			(xy 452.412921 -289.850079) (xy 452.36707 -289.820611) (xy 452.325878 -289.784919) (xy 452.290186 -289.743727)
			(xy 452.260719 -289.697876) (xy 452.238078 -289.648297) (xy 452.222722 -289.596001) (xy 452.214966 -289.542052)
			(xy 445.11629 -289.542052) (xy 446.409085 -290.834847) (xy 458.605926 -290.834847) (xy 458.605926 -290.780353)
			(xy 458.613681 -290.726413) (xy 458.629034 -290.674125) (xy 458.651672 -290.624555) (xy 458.681133 -290.578711)
			(xy 458.716819 -290.537526) (xy 458.758003 -290.501839) (xy 458.803846 -290.472376) (xy 458.853416 -290.449738)
			(xy 458.905703 -290.434384) (xy 458.959643 -290.426627) (xy 458.98689 -290.42614) (xy 459.01426 -290.426602)
			(xy 459.06844 -290.434419) (xy 459.120944 -290.449909) (xy 459.17069 -290.472752) (xy 459.216657 -290.502478)
			(xy 459.237588 -290.52012) (xy 459.237842 -290.520374) (xy 459.244935 -290.525951) (xy 459.261847 -290.532202)
			(xy 459.270862 -290.532566) (xy 459.337918 -290.532566) (xy 459.346937 -290.532225) (xy 459.363854 -290.525967)
			(xy 459.370938 -290.520374) (xy 459.370938 -290.52012) (xy 459.371192 -290.52012) (xy 459.392119 -290.502474)
			(xy 459.438093 -290.472763) (xy 459.487842 -290.449928) (xy 459.540344 -290.434438) (xy 459.59452 -290.426613)
			(xy 459.62189 -290.42614) (xy 459.649147 -290.426506) (xy 459.703106 -290.434263) (xy 459.755411 -290.44962)
			(xy 459.804999 -290.472265) (xy 459.850859 -290.501736) (xy 459.892058 -290.537435) (xy 459.927758 -290.578633)
			(xy 459.95723 -290.624492) (xy 459.979876 -290.674079) (xy 459.995235 -290.726385) (xy 460.002993 -290.780343)
			(xy 460.002993 -290.834857) (xy 459.995235 -290.888815) (xy 459.979876 -290.941121) (xy 459.95723 -290.990708)
			(xy 459.927758 -291.036567) (xy 459.892058 -291.077765) (xy 459.850859 -291.113464) (xy 459.804999 -291.142935)
			(xy 459.755411 -291.16558) (xy 459.703106 -291.180937) (xy 459.649147 -291.188694) (xy 459.62189 -291.189156)
			(xy 459.594519 -291.188707) (xy 459.540339 -291.180886) (xy 459.487835 -291.165394) (xy 459.438088 -291.142548)
			(xy 459.392123 -291.112819) (xy 459.371192 -291.095176) (xy 459.370938 -291.094922) (xy 459.363851 -291.089336)
			(xy 459.346934 -291.083091) (xy 459.337918 -291.08273) (xy 459.270862 -291.08273) (xy 459.261842 -291.083062)
			(xy 459.244925 -291.089326) (xy 459.237842 -291.094922) (xy 459.237842 -291.095176) (xy 459.237588 -291.095176)
			(xy 459.21663 -291.112784) (xy 459.170665 -291.142501) (xy 459.120924 -291.165343) (xy 459.068429 -291.180842)
			(xy 459.014257 -291.188678) (xy 458.98689 -291.189156) (xy 458.959643 -291.188573) (xy 458.905703 -291.180816)
			(xy 458.853416 -291.165462) (xy 458.803846 -291.142824) (xy 458.758003 -291.113361) (xy 458.716819 -291.077674)
			(xy 458.681133 -291.036489) (xy 458.651672 -290.990645) (xy 458.629034 -290.941075) (xy 458.613681 -290.888787)
			(xy 458.605926 -290.834847) (xy 446.409085 -290.834847) (xy 447.148292 -291.574054) (xy 452.196643 -291.574054)
			(xy 452.196643 -291.519546) (xy 452.2044 -291.465593) (xy 452.219757 -291.413292) (xy 452.242401 -291.36371)
			(xy 452.271871 -291.317855) (xy 452.307566 -291.276661) (xy 452.348761 -291.240966) (xy 452.394617 -291.211497)
			(xy 452.4442 -291.188854) (xy 452.4965 -291.173499) (xy 452.550454 -291.165742) (xy 452.577708 -291.16528)
			(xy 452.605079 -291.165722) (xy 452.65926 -291.173543) (xy 452.711764 -291.189036) (xy 452.761511 -291.211884)
			(xy 452.807476 -291.241615) (xy 452.828406 -291.25926) (xy 452.82866 -291.259514) (xy 452.835753 -291.265092)
			(xy 452.852665 -291.271343) (xy 452.86168 -291.271706) (xy 452.928736 -291.271706) (xy 452.937754 -291.271365)
			(xy 452.954671 -291.265106) (xy 452.961756 -291.259514) (xy 452.961756 -291.25926) (xy 452.96201 -291.25926)
			(xy 452.982922 -291.241596) (xy 453.028901 -291.211889) (xy 453.078654 -291.189059) (xy 453.131158 -291.173573)
			(xy 453.185338 -291.165751) (xy 453.212708 -291.16528) (xy 453.239958 -291.165791) (xy 453.293903 -291.173548)
			(xy 453.346195 -291.188903) (xy 453.39577 -291.211544) (xy 453.441618 -291.24101) (xy 453.482806 -291.2767)
			(xy 453.518495 -291.317889) (xy 453.54796 -291.363737) (xy 453.5706 -291.413312) (xy 453.585954 -291.465605)
			(xy 453.59371 -291.51955) (xy 453.59371 -291.57405) (xy 453.585954 -291.627995) (xy 453.5706 -291.680288)
			(xy 453.54796 -291.729863) (xy 453.518495 -291.775711) (xy 453.482806 -291.8169) (xy 453.441618 -291.85259)
			(xy 453.39577 -291.882056) (xy 453.346195 -291.904697) (xy 453.293903 -291.920052) (xy 453.239958 -291.927809)
			(xy 453.212708 -291.928296) (xy 453.185338 -291.927826) (xy 453.131159 -291.920009) (xy 453.078656 -291.904521)
			(xy 453.028909 -291.88168) (xy 452.982942 -291.851957) (xy 452.96201 -291.834316) (xy 452.961756 -291.834062)
			(xy 452.954661 -291.828488) (xy 452.93775 -291.822235) (xy 452.928736 -291.82187) (xy 452.86168 -291.82187)
			(xy 452.852663 -291.822224) (xy 452.835746 -291.828474) (xy 452.82866 -291.834062) (xy 452.82866 -291.834316)
			(xy 452.828406 -291.834316) (xy 452.807485 -291.851968) (xy 452.761509 -291.881678) (xy 452.711758 -291.904511)
			(xy 452.659255 -291.919999) (xy 452.605078 -291.927824) (xy 452.577708 -291.928296) (xy 452.550454 -291.927858)
			(xy 452.4965 -291.920101) (xy 452.4442 -291.904746) (xy 452.394617 -291.882103) (xy 452.348761 -291.852634)
			(xy 452.307566 -291.816939) (xy 452.271871 -291.775745) (xy 452.242401 -291.72989) (xy 452.219757 -291.680308)
			(xy 452.2044 -291.628007) (xy 452.196643 -291.574054) (xy 447.148292 -291.574054) (xy 448.831208 -293.25697)
			(xy 448.838043 -293.264373) (xy 448.84575 -293.282971) (xy 448.846194 -293.293038) (xy 448.846194 -305.485038)
			(xy 448.848226 -305.499008) (xy 448.850004 -305.505358) (xy 448.86753 -305.533806) (xy 448.869507 -305.536894)
			(xy 448.874225 -305.542505) (xy 448.876928 -305.544982) (xy 448.8815 -305.5493) (xy 448.888866 -305.552856)
			(xy 448.963816 -305.588688) (xy 449.110486 -305.666742) (xy 449.253142 -305.751911) (xy 449.391439 -305.843989)
			(xy 449.525043 -305.942754) (xy 449.653632 -306.047966) (xy 449.776091 -306.158646) (xy 459.899002 -306.158646)
			(xy 459.903073 -306.103024) (xy 459.915199 -306.048587) (xy 459.935122 -305.996496) (xy 459.962418 -305.947861)
			(xy 459.996504 -305.903718) (xy 460.036653 -305.865009) (xy 460.082011 -305.832558) (xy 460.131611 -305.807057)
			(xy 460.184395 -305.78905) (xy 460.239238 -305.77892) (xy 460.294972 -305.776883) (xy 460.350409 -305.782983)
			(xy 460.404366 -305.797089) (xy 460.455695 -305.818901) (xy 460.503301 -305.847955) (xy 460.546169 -305.88363)
			(xy 460.583386 -305.925167) (xy 460.614159 -305.97168) (xy 460.637831 -306.022177) (xy 460.653899 -306.075584)
			(xy 460.662019 -306.13076) (xy 460.662528 -306.158646) (xy 460.662019 -306.186532) (xy 460.653899 -306.241708)
			(xy 460.637831 -306.295115) (xy 460.614159 -306.345612) (xy 460.583386 -306.392125) (xy 460.546169 -306.433662)
			(xy 460.503301 -306.469337) (xy 460.455695 -306.498391) (xy 460.404366 -306.520203) (xy 460.350409 -306.534309)
			(xy 460.294972 -306.540409) (xy 460.239238 -306.538372) (xy 460.184395 -306.528242) (xy 460.131611 -306.510235)
			(xy 460.082011 -306.484734) (xy 460.036653 -306.452283) (xy 459.996504 -306.413574) (xy 459.962418 -306.369431)
			(xy 459.935122 -306.320796) (xy 459.915199 -306.268705) (xy 459.903073 -306.214268) (xy 459.899002 -306.158646)
			(xy 449.776091 -306.158646) (xy 449.776893 -306.159371) (xy 449.89453 -306.2767) (xy 450.006257 -306.39967)
			(xy 450.111806 -306.527982) (xy 450.21092 -306.661327) (xy 450.303359 -306.799383) (xy 450.344305 -306.86756)
			(xy 452.570594 -306.86756) (xy 452.574665 -306.811938) (xy 452.586791 -306.757501) (xy 452.606714 -306.70541)
			(xy 452.63401 -306.656775) (xy 452.668096 -306.612632) (xy 452.708245 -306.573923) (xy 452.753603 -306.541472)
			(xy 452.803203 -306.515971) (xy 452.855987 -306.497964) (xy 452.91083 -306.487834) (xy 452.966564 -306.485797)
			(xy 453.022001 -306.491897) (xy 453.075958 -306.506003) (xy 453.127287 -306.527815) (xy 453.174893 -306.556869)
			(xy 453.217761 -306.592544) (xy 453.254978 -306.634081) (xy 453.285751 -306.680594) (xy 453.309423 -306.731091)
			(xy 453.325491 -306.784498) (xy 453.333611 -306.839674) (xy 453.33412 -306.86756) (xy 453.333611 -306.895446)
			(xy 453.325491 -306.950622) (xy 453.309423 -307.004029) (xy 453.285751 -307.054526) (xy 453.254978 -307.101039)
			(xy 453.217761 -307.142576) (xy 453.174893 -307.178251) (xy 453.127287 -307.207305) (xy 453.075958 -307.229117)
			(xy 453.022001 -307.243223) (xy 452.966564 -307.249323) (xy 452.91083 -307.247286) (xy 452.855987 -307.237156)
			(xy 452.803203 -307.219149) (xy 452.753603 -307.193648) (xy 452.708245 -307.161197) (xy 452.668096 -307.122488)
			(xy 452.63401 -307.078345) (xy 452.606714 -307.02971) (xy 452.586791 -306.977619) (xy 452.574665 -306.923182)
			(xy 452.570594 -306.86756) (xy 450.344305 -306.86756) (xy 450.388902 -306.941816) (xy 450.46734 -307.088281)
			(xy 450.538484 -307.238424) (xy 450.602162 -307.391883) (xy 450.65822 -307.548286) (xy 450.664778 -307.56987)
			(xy 457.496162 -307.56987) (xy 457.500233 -307.514248) (xy 457.512359 -307.459811) (xy 457.532282 -307.40772)
			(xy 457.559578 -307.359085) (xy 457.593664 -307.314942) (xy 457.633813 -307.276233) (xy 457.679171 -307.243782)
			(xy 457.728771 -307.218281) (xy 457.781555 -307.200274) (xy 457.836398 -307.190144) (xy 457.892132 -307.188107)
			(xy 457.947569 -307.194207) (xy 458.001526 -307.208313) (xy 458.052855 -307.230125) (xy 458.100461 -307.259179)
			(xy 458.143329 -307.294854) (xy 458.180546 -307.336391) (xy 458.211319 -307.382904) (xy 458.234991 -307.433401)
			(xy 458.251059 -307.486808) (xy 458.259179 -307.541984) (xy 458.259688 -307.56987) (xy 458.259179 -307.597756)
			(xy 458.257713 -307.607716) (xy 462.556604 -307.607716) (xy 462.560677 -307.552057) (xy 462.572812 -307.497584)
			(xy 462.592748 -307.445458) (xy 462.620062 -307.39679) (xy 462.65417 -307.352618) (xy 462.694347 -307.313883)
			(xy 462.739735 -307.281411) (xy 462.789367 -307.255893) (xy 462.842187 -307.237874) (xy 462.897066 -307.227737)
			(xy 462.952837 -307.225699) (xy 463.008311 -307.231802) (xy 463.062304 -307.245918) (xy 463.113667 -307.267745)
			(xy 463.161305 -307.296818) (xy 463.204201 -307.332517) (xy 463.241443 -307.374081) (xy 463.272237 -307.420625)
			(xy 463.295925 -307.471156) (xy 463.312003 -307.524598) (xy 463.320129 -307.579812) (xy 463.320638 -307.607716)
			(xy 463.320129 -307.63562) (xy 463.312003 -307.690834) (xy 463.295925 -307.744276) (xy 463.272237 -307.794807)
			(xy 463.241443 -307.841351) (xy 463.204201 -307.882915) (xy 463.161305 -307.918614) (xy 463.113667 -307.947687)
			(xy 463.062304 -307.969514) (xy 463.008311 -307.98363) (xy 462.952837 -307.989733) (xy 462.897066 -307.987695)
			(xy 462.842187 -307.977558) (xy 462.789367 -307.959539) (xy 462.739735 -307.934021) (xy 462.694347 -307.901549)
			(xy 462.65417 -307.862814) (xy 462.620062 -307.818642) (xy 462.592748 -307.769974) (xy 462.572812 -307.717848)
			(xy 462.560677 -307.663375) (xy 462.556604 -307.607716) (xy 458.257713 -307.607716) (xy 458.251059 -307.652932)
			(xy 458.234991 -307.706339) (xy 458.211319 -307.756836) (xy 458.180546 -307.803349) (xy 458.143329 -307.844886)
			(xy 458.100461 -307.880561) (xy 458.052855 -307.909615) (xy 458.001526 -307.931427) (xy 457.947569 -307.945533)
			(xy 457.892132 -307.951633) (xy 457.836398 -307.949596) (xy 457.781555 -307.939466) (xy 457.728771 -307.921459)
			(xy 457.679171 -307.895958) (xy 457.633813 -307.863507) (xy 457.593664 -307.824798) (xy 457.559578 -307.780655)
			(xy 457.532282 -307.73202) (xy 457.512359 -307.679929) (xy 457.500233 -307.625492) (xy 457.496162 -307.56987)
			(xy 450.664778 -307.56987) (xy 450.706523 -307.707256) (xy 450.746954 -307.868408) (xy 450.779415 -308.031352)
			(xy 450.803828 -308.195695) (xy 450.820134 -308.361039) (xy 450.828228 -308.525672) (xy 458.554072 -308.525672)
			(xy 458.558143 -308.47005) (xy 458.570269 -308.415613) (xy 458.590192 -308.363522) (xy 458.617488 -308.314887)
			(xy 458.651574 -308.270744) (xy 458.691723 -308.232035) (xy 458.737081 -308.199584) (xy 458.786681 -308.174083)
			(xy 458.839465 -308.156076) (xy 458.894308 -308.145946) (xy 458.950042 -308.143909) (xy 459.005479 -308.150009)
			(xy 459.054046 -308.162706) (xy 465.622892 -308.162706) (xy 465.626963 -308.107084) (xy 465.639089 -308.052647)
			(xy 465.659012 -308.000556) (xy 465.686308 -307.951921) (xy 465.720394 -307.907778) (xy 465.760543 -307.869069)
			(xy 465.805901 -307.836618) (xy 465.855501 -307.811117) (xy 465.908285 -307.79311) (xy 465.963128 -307.78298)
			(xy 466.018862 -307.780943) (xy 466.074299 -307.787043) (xy 466.128256 -307.801149) (xy 466.179585 -307.822961)
			(xy 466.227191 -307.852015) (xy 466.270059 -307.88769) (xy 466.307276 -307.929227) (xy 466.338049 -307.97574)
			(xy 466.361721 -308.026237) (xy 466.377789 -308.079644) (xy 466.385909 -308.13482) (xy 466.386418 -308.162706)
			(xy 466.385909 -308.190592) (xy 466.377789 -308.245768) (xy 466.361721 -308.299175) (xy 466.338049 -308.349672)
			(xy 466.307276 -308.396185) (xy 466.270059 -308.437722) (xy 466.227191 -308.473397) (xy 466.179585 -308.502451)
			(xy 466.128256 -308.524263) (xy 466.074299 -308.538369) (xy 466.018862 -308.544469) (xy 465.963128 -308.542432)
			(xy 465.908285 -308.532302) (xy 465.855501 -308.514295) (xy 465.805901 -308.488794) (xy 465.760543 -308.456343)
			(xy 465.720394 -308.417634) (xy 465.686308 -308.373491) (xy 465.659012 -308.324856) (xy 465.639089 -308.272765)
			(xy 465.626963 -308.218328) (xy 465.622892 -308.162706) (xy 459.054046 -308.162706) (xy 459.059436 -308.164115)
			(xy 459.110765 -308.185927) (xy 459.158371 -308.214981) (xy 459.201239 -308.250656) (xy 459.238456 -308.292193)
			(xy 459.269229 -308.338706) (xy 459.292901 -308.389203) (xy 459.308969 -308.44261) (xy 459.317089 -308.497786)
			(xy 459.317598 -308.525672) (xy 459.317089 -308.553558) (xy 459.308969 -308.608734) (xy 459.292901 -308.662141)
			(xy 459.278765 -308.692296) (xy 462.556604 -308.692296) (xy 462.560677 -308.636637) (xy 462.572812 -308.582164)
			(xy 462.592748 -308.530038) (xy 462.620062 -308.48137) (xy 462.65417 -308.437198) (xy 462.694347 -308.398463)
			(xy 462.739735 -308.365991) (xy 462.789367 -308.340473) (xy 462.842187 -308.322454) (xy 462.897066 -308.312317)
			(xy 462.952837 -308.310279) (xy 463.008311 -308.316382) (xy 463.062304 -308.330498) (xy 463.113667 -308.352325)
			(xy 463.161305 -308.381398) (xy 463.204201 -308.417097) (xy 463.241443 -308.458661) (xy 463.272237 -308.505205)
			(xy 463.295925 -308.555736) (xy 463.312003 -308.609178) (xy 463.320129 -308.664392) (xy 463.320638 -308.692296)
			(xy 463.320129 -308.7202) (xy 463.312003 -308.775414) (xy 463.295925 -308.828856) (xy 463.272237 -308.879387)
			(xy 463.241443 -308.925931) (xy 463.204201 -308.967495) (xy 463.161305 -309.003194) (xy 463.113667 -309.032267)
			(xy 463.062304 -309.054094) (xy 463.008311 -309.06821) (xy 462.952837 -309.074313) (xy 462.897066 -309.072275)
			(xy 462.842187 -309.062138) (xy 462.789367 -309.044119) (xy 462.739735 -309.018601) (xy 462.694347 -308.986129)
			(xy 462.65417 -308.947394) (xy 462.620062 -308.903222) (xy 462.592748 -308.854554) (xy 462.572812 -308.802428)
			(xy 462.560677 -308.747955) (xy 462.556604 -308.692296) (xy 459.278765 -308.692296) (xy 459.269229 -308.712638)
			(xy 459.238456 -308.759151) (xy 459.201239 -308.800688) (xy 459.158371 -308.836363) (xy 459.110765 -308.865417)
			(xy 459.059436 -308.887229) (xy 459.005479 -308.901335) (xy 458.950042 -308.907435) (xy 458.894308 -308.905398)
			(xy 458.839465 -308.895268) (xy 458.786681 -308.877261) (xy 458.737081 -308.85176) (xy 458.691723 -308.819309)
			(xy 458.651574 -308.7806) (xy 458.617488 -308.736457) (xy 458.590192 -308.687822) (xy 458.570269 -308.635731)
			(xy 458.558143 -308.581294) (xy 458.554072 -308.525672) (xy 450.828228 -308.525672) (xy 450.828292 -308.526984)
			(xy 450.828285 -308.693131) (xy 450.820111 -308.859075) (xy 450.80379 -309.024418) (xy 450.786368 -309.141622)
			(xy 460.562196 -309.141622) (xy 460.566267 -309.086) (xy 460.578393 -309.031563) (xy 460.598316 -308.979472)
			(xy 460.625612 -308.930837) (xy 460.659698 -308.886694) (xy 460.699847 -308.847985) (xy 460.745205 -308.815534)
			(xy 460.794805 -308.790033) (xy 460.847589 -308.772026) (xy 460.902432 -308.761896) (xy 460.958166 -308.759859)
			(xy 461.013603 -308.765959) (xy 461.06756 -308.780065) (xy 461.118889 -308.801877) (xy 461.166495 -308.830931)
			(xy 461.209363 -308.866606) (xy 461.24658 -308.908143) (xy 461.277353 -308.954656) (xy 461.301025 -309.005153)
			(xy 461.317093 -309.05856) (xy 461.325213 -309.113736) (xy 461.325722 -309.141622) (xy 461.325213 -309.169508)
			(xy 461.317093 -309.224684) (xy 461.301025 -309.278091) (xy 461.277353 -309.328588) (xy 461.24658 -309.375101)
			(xy 461.209363 -309.416638) (xy 461.166495 -309.452313) (xy 461.118889 -309.481367) (xy 461.06756 -309.503179)
			(xy 461.013603 -309.517285) (xy 460.958166 -309.523385) (xy 460.902432 -309.521348) (xy 460.847589 -309.511218)
			(xy 460.794805 -309.493211) (xy 460.745205 -309.46771) (xy 460.699847 -309.435259) (xy 460.659698 -309.39655)
			(xy 460.625612 -309.352407) (xy 460.598316 -309.303772) (xy 460.578393 -309.251681) (xy 460.566267 -309.197244)
			(xy 460.562196 -309.141622) (xy 450.786368 -309.141622) (xy 450.779362 -309.188758) (xy 450.746885 -309.3517)
			(xy 450.706439 -309.512848) (xy 450.658121 -309.671813) (xy 450.602048 -309.828211) (xy 450.538356 -309.981664)
			(xy 450.51455 -310.031892) (xy 456.942188 -310.031892) (xy 456.946259 -309.97627) (xy 456.958385 -309.921833)
			(xy 456.978308 -309.869742) (xy 457.005604 -309.821107) (xy 457.03969 -309.776964) (xy 457.079839 -309.738255)
			(xy 457.125197 -309.705804) (xy 457.174797 -309.680303) (xy 457.227581 -309.662296) (xy 457.282424 -309.652166)
			(xy 457.338158 -309.650129) (xy 457.393595 -309.656229) (xy 457.447552 -309.670335) (xy 457.498881 -309.692147)
			(xy 457.546487 -309.721201) (xy 457.589355 -309.756876) (xy 457.626572 -309.798413) (xy 457.657345 -309.844926)
			(xy 457.668429 -309.86857) (xy 458.657704 -309.86857) (xy 458.661775 -309.812948) (xy 458.673901 -309.758511)
			(xy 458.693824 -309.70642) (xy 458.72112 -309.657785) (xy 458.755206 -309.613642) (xy 458.795355 -309.574933)
			(xy 458.840713 -309.542482) (xy 458.890313 -309.516981) (xy 458.943097 -309.498974) (xy 458.99794 -309.488844)
			(xy 459.053674 -309.486807) (xy 459.109111 -309.492907) (xy 459.163068 -309.507013) (xy 459.214397 -309.528825)
			(xy 459.262003 -309.557879) (xy 459.304871 -309.593554) (xy 459.342088 -309.635091) (xy 459.372861 -309.681604)
			(xy 459.396533 -309.732101) (xy 459.412601 -309.785508) (xy 459.420721 -309.840684) (xy 459.42123 -309.86857)
			(xy 459.420721 -309.896456) (xy 459.412601 -309.951632) (xy 459.396533 -310.005039) (xy 459.372861 -310.055536)
			(xy 459.342088 -310.102049) (xy 459.304871 -310.143586) (xy 459.262003 -310.179261) (xy 459.214397 -310.208315)
			(xy 459.163068 -310.230127) (xy 459.109111 -310.244233) (xy 459.053674 -310.250333) (xy 458.99794 -310.248296)
			(xy 458.943097 -310.238166) (xy 458.890313 -310.220159) (xy 458.840713 -310.194658) (xy 458.795355 -310.162207)
			(xy 458.755206 -310.123498) (xy 458.72112 -310.079355) (xy 458.693824 -310.03072) (xy 458.673901 -309.978629)
			(xy 458.661775 -309.924192) (xy 458.657704 -309.86857) (xy 457.668429 -309.86857) (xy 457.681017 -309.895423)
			(xy 457.697085 -309.94883) (xy 457.705205 -310.004006) (xy 457.705714 -310.031892) (xy 457.705205 -310.059778)
			(xy 457.697085 -310.114954) (xy 457.681017 -310.168361) (xy 457.657345 -310.218858) (xy 457.626572 -310.265371)
			(xy 457.589355 -310.306908) (xy 457.546487 -310.342583) (xy 457.498881 -310.371637) (xy 457.447552 -310.393449)
			(xy 457.393595 -310.407555) (xy 457.338158 -310.413655) (xy 457.282424 -310.411618) (xy 457.227581 -310.401488)
			(xy 457.174797 -310.383481) (xy 457.125197 -310.35798) (xy 457.079839 -310.325529) (xy 457.03969 -310.28682)
			(xy 457.005604 -310.242677) (xy 456.978308 -310.194042) (xy 456.958385 -310.141951) (xy 456.946259 -310.087514)
			(xy 456.942188 -310.031892) (xy 450.51455 -310.031892) (xy 450.467198 -310.1318) (xy 450.388746 -310.278258)
			(xy 450.303191 -310.420683) (xy 450.210738 -310.55873) (xy 450.111612 -310.692066) (xy 450.006051 -310.820369)
			(xy 449.894312 -310.943328) (xy 449.776665 -311.060646) (xy 449.653393 -311.17204) (xy 449.524795 -311.27724)
			(xy 449.440921 -311.33923) (xy 458.119986 -311.33923) (xy 458.124057 -311.283608) (xy 458.136183 -311.229171)
			(xy 458.156106 -311.17708) (xy 458.183402 -311.128445) (xy 458.217488 -311.084302) (xy 458.257637 -311.045593)
			(xy 458.302995 -311.013142) (xy 458.352595 -310.987641) (xy 458.405379 -310.969634) (xy 458.460222 -310.959504)
			(xy 458.515956 -310.957467) (xy 458.571393 -310.963567) (xy 458.62535 -310.977673) (xy 458.676679 -310.999485)
			(xy 458.724285 -311.028539) (xy 458.767153 -311.064214) (xy 458.80437 -311.105751) (xy 458.835143 -311.152264)
			(xy 458.858815 -311.202761) (xy 458.874883 -311.256168) (xy 458.883003 -311.311344) (xy 458.883512 -311.33923)
			(xy 458.883003 -311.367116) (xy 458.874883 -311.422292) (xy 458.858815 -311.475699) (xy 458.842059 -311.511442)
			(xy 459.73441 -311.511442) (xy 459.738481 -311.45582) (xy 459.750607 -311.401383) (xy 459.77053 -311.349292)
			(xy 459.797826 -311.300657) (xy 459.831912 -311.256514) (xy 459.872061 -311.217805) (xy 459.917419 -311.185354)
			(xy 459.967019 -311.159853) (xy 460.019803 -311.141846) (xy 460.074646 -311.131716) (xy 460.13038 -311.129679)
			(xy 460.185817 -311.135779) (xy 460.239774 -311.149885) (xy 460.291103 -311.171697) (xy 460.338709 -311.200751)
			(xy 460.381577 -311.236426) (xy 460.418794 -311.277963) (xy 460.449567 -311.324476) (xy 460.473239 -311.374973)
			(xy 460.489307 -311.42838) (xy 460.497427 -311.483556) (xy 460.497936 -311.511442) (xy 460.497427 -311.539328)
			(xy 460.489307 -311.594504) (xy 460.473239 -311.647911) (xy 460.449567 -311.698408) (xy 460.418794 -311.744921)
			(xy 460.381577 -311.786458) (xy 460.338709 -311.822133) (xy 460.291103 -311.851187) (xy 460.239774 -311.872999)
			(xy 460.185817 -311.887105) (xy 460.13038 -311.893205) (xy 460.074646 -311.891168) (xy 460.019803 -311.881038)
			(xy 459.967019 -311.863031) (xy 459.917419 -311.83753) (xy 459.872061 -311.805079) (xy 459.831912 -311.76637)
			(xy 459.797826 -311.722227) (xy 459.77053 -311.673592) (xy 459.750607 -311.621501) (xy 459.738481 -311.567064)
			(xy 459.73441 -311.511442) (xy 458.842059 -311.511442) (xy 458.835143 -311.526196) (xy 458.80437 -311.572709)
			(xy 458.767153 -311.614246) (xy 458.724285 -311.649921) (xy 458.676679 -311.678975) (xy 458.62535 -311.700787)
			(xy 458.571393 -311.714893) (xy 458.515956 -311.720993) (xy 458.460222 -311.718956) (xy 458.405379 -311.708826)
			(xy 458.352595 -311.690819) (xy 458.302995 -311.665318) (xy 458.257637 -311.632867) (xy 458.217488 -311.594158)
			(xy 458.183402 -311.550015) (xy 458.156106 -311.50138) (xy 458.136183 -311.449289) (xy 458.124057 -311.394852)
			(xy 458.119986 -311.33923) (xy 449.440921 -311.33923) (xy 449.391181 -311.375992) (xy 449.252875 -311.468057)
			(xy 449.110211 -311.553213) (xy 448.963534 -311.631253) (xy 448.888612 -311.667144) (xy 448.882008 -311.670446)
			(xy 448.876166 -311.675526) (xy 448.86753 -311.685432) (xy 448.853814 -311.708038) (xy 448.85033 -311.714153)
			(xy 448.846459 -311.727676) (xy 448.846194 -311.734708) (xy 448.846194 -320.940176) (xy 455.509122 -320.940176)
			(xy 455.509569 -320.912805) (xy 455.51739 -320.858625) (xy 455.532884 -320.806121) (xy 455.55573 -320.756375)
			(xy 455.585459 -320.710409) (xy 455.603102 -320.689478) (xy 455.603356 -320.689224) (xy 455.608945 -320.68214)
			(xy 455.615189 -320.665221) (xy 455.615548 -320.656204) (xy 455.615548 -320.589148) (xy 455.615179 -320.580132)
			(xy 455.608941 -320.563214) (xy 455.603356 -320.556128) (xy 455.603102 -320.556128) (xy 455.603102 -320.555874)
			(xy 455.585484 -320.534925) (xy 455.555769 -320.488957) (xy 455.532929 -320.439213) (xy 455.517433 -320.386717)
			(xy 455.509599 -320.332544) (xy 455.509122 -320.305176) (xy 455.509533 -320.277921) (xy 455.517294 -320.223967)
			(xy 455.532654 -320.171666) (xy 455.555302 -320.122084) (xy 455.584775 -320.076229) (xy 455.620474 -320.035036)
			(xy 455.661673 -319.999343) (xy 455.707531 -319.969876) (xy 455.757117 -319.947235) (xy 455.80942 -319.931882)
			(xy 455.863375 -319.924129) (xy 455.89063 -319.923668) (xy 455.918002 -319.9241) (xy 455.972183 -319.931923)
			(xy 456.024687 -319.94742) (xy 456.074433 -319.970269) (xy 456.120398 -320.000002) (xy 456.141328 -320.017648)
			(xy 456.141582 -320.017902) (xy 456.148669 -320.023487) (xy 456.165586 -320.029735) (xy 456.174602 -320.030094)
			(xy 456.241658 -320.030094) (xy 456.250673 -320.029718) (xy 456.26759 -320.023484) (xy 456.274678 -320.017902)
			(xy 456.274678 -320.017648) (xy 456.274932 -320.017648) (xy 456.295865 -320.000007) (xy 456.341833 -319.970283)
			(xy 456.391579 -319.947437) (xy 456.444081 -319.931941) (xy 456.498259 -319.924112) (xy 456.553001 -319.924112)
			(xy 456.607179 -319.931941) (xy 456.659681 -319.947437) (xy 456.709427 -319.970283) (xy 456.755395 -320.000007)
			(xy 456.776328 -320.017648) (xy 456.776582 -320.017902) (xy 456.783669 -320.023487) (xy 456.800586 -320.029735)
			(xy 456.809602 -320.030094) (xy 456.876658 -320.030094) (xy 456.885673 -320.029718) (xy 456.90259 -320.023484)
			(xy 456.909678 -320.017902) (xy 456.909678 -320.017648) (xy 456.909932 -320.017648) (xy 456.930885 -320.000035)
			(xy 456.976851 -319.970317) (xy 457.026593 -319.947476) (xy 457.07909 -319.931979) (xy 457.133262 -319.924145)
			(xy 457.16063 -319.923668) (xy 457.187881 -319.92415) (xy 457.241828 -319.93191) (xy 457.294121 -319.947268)
			(xy 457.343697 -319.96991) (xy 457.389546 -319.999378) (xy 457.430735 -320.035069) (xy 457.466426 -320.076259)
			(xy 457.495892 -320.122109) (xy 457.518535 -320.171685) (xy 457.533891 -320.223978) (xy 457.541651 -320.277925)
			(xy 457.542138 -320.305176) (xy 457.541673 -320.332546) (xy 457.533857 -320.386726) (xy 457.518369 -320.43923)
			(xy 457.495526 -320.488977) (xy 457.4658 -320.534943) (xy 457.448158 -320.555874) (xy 457.447904 -320.556128)
			(xy 457.442342 -320.563231) (xy 457.43608 -320.580135) (xy 457.435712 -320.589148) (xy 457.435712 -320.656204)
			(xy 457.436064 -320.665221) (xy 457.442315 -320.682138) (xy 457.447904 -320.689224) (xy 457.448158 -320.689224)
			(xy 457.448158 -320.689478) (xy 457.465794 -320.710413) (xy 457.495507 -320.756384) (xy 457.518345 -320.806131)
			(xy 457.533836 -320.858631) (xy 457.541664 -320.912807) (xy 457.542138 -320.940176) (xy 457.5416 -320.967425)
			(xy 457.533847 -321.021369) (xy 457.518496 -321.073661) (xy 457.49586 -321.123236) (xy 457.466399 -321.169085)
			(xy 457.430713 -321.210275) (xy 457.389529 -321.245967) (xy 457.343684 -321.275434) (xy 457.294112 -321.298078)
			(xy 457.241822 -321.313436) (xy 457.187879 -321.321196) (xy 457.16063 -321.321684) (xy 457.13326 -321.321204)
			(xy 457.079082 -321.31339) (xy 457.026578 -321.297905) (xy 456.976831 -321.275066) (xy 456.930864 -321.245344)
			(xy 456.909932 -321.227704) (xy 456.909678 -321.22745) (xy 456.902606 -321.221842) (xy 456.885678 -321.215609)
			(xy 456.876658 -321.215258) (xy 456.809602 -321.215258) (xy 456.800584 -321.215604) (xy 456.783666 -321.221858)
			(xy 456.776582 -321.22745) (xy 456.776328 -321.227704) (xy 456.755395 -321.245345) (xy 456.709427 -321.275069)
			(xy 456.659681 -321.297915) (xy 456.607179 -321.313411) (xy 456.553001 -321.32124) (xy 456.498259 -321.32124)
			(xy 456.444081 -321.313411) (xy 456.391579 -321.297915) (xy 456.341833 -321.275069) (xy 456.295865 -321.245345)
			(xy 456.274932 -321.227704) (xy 456.274678 -321.22745) (xy 456.267606 -321.221842) (xy 456.250678 -321.215609)
			(xy 456.241658 -321.215258) (xy 456.174602 -321.215258) (xy 456.165584 -321.215604) (xy 456.148666 -321.221858)
			(xy 456.141582 -321.22745) (xy 456.141582 -321.227704) (xy 456.141328 -321.227704) (xy 456.120397 -321.245344)
			(xy 456.074424 -321.275056) (xy 456.024676 -321.297891) (xy 455.972175 -321.313382) (xy 455.917999 -321.32121)
			(xy 455.89063 -321.321684) (xy 455.863377 -321.321217) (xy 455.809425 -321.313463) (xy 455.757126 -321.29811)
			(xy 455.707544 -321.275469) (xy 455.661689 -321.246002) (xy 455.620496 -321.210308) (xy 455.584802 -321.169115)
			(xy 455.555334 -321.123261) (xy 455.532692 -321.07368) (xy 455.517338 -321.021381) (xy 455.509584 -320.967429)
			(xy 455.509122 -320.940176) (xy 448.846194 -320.940176) (xy 448.846194 -322.416678) (xy 448.84721 -322.426584)
			(xy 448.848915 -322.433743) (xy 448.855749 -322.446768) (xy 448.860672 -322.452238) (xy 451.243954 -324.83552)
			(xy 451.249455 -324.840503) (xy 451.262624 -324.847337) (xy 451.269862 -324.848982) (xy 451.279514 -324.849998)
			(xy 466.72754 -324.849998)
		)
		(stroke
			(width 0)
			(type solid)
		)
		(fill yes)
		(layer "In9.Cu")
		(net "GND")
	)
	(gr_poly
		(pts
			(xy 446.717674 -416.954462) (xy 446.729264 -416.95331) (xy 446.749632 -416.942061) (xy 446.75679 -416.932872)
			(xy 446.803526 -416.856672) (xy 446.807737 -416.848318) (xy 446.810458 -416.829824) (xy 446.80886 -416.820604)
			(xy 446.805558 -416.807142) (xy 446.803272 -416.802316) (xy 446.802764 -416.8013) (xy 446.791201 -416.775901)
			(xy 446.774793 -416.722562) (xy 446.766331 -416.667401) (xy 446.76568 -416.639502) (xy 446.76568 -416.634422)
			(xy 446.766338 -416.607289) (xy 446.774387 -416.553616) (xy 446.789961 -416.501626) (xy 446.812746 -416.452367)
			(xy 446.842281 -416.406834) (xy 446.877971 -416.365947) (xy 446.919095 -416.33053) (xy 446.964824 -416.301298)
			(xy 447.014233 -416.278842) (xy 447.066326 -416.263614) (xy 447.120051 -416.255923) (xy 447.174325 -416.255923)
			(xy 447.22805 -416.263614) (xy 447.280143 -416.278842) (xy 447.329552 -416.301298) (xy 447.375281 -416.33053)
			(xy 447.416405 -416.365947) (xy 447.452095 -416.406834) (xy 447.48163 -416.452367) (xy 447.504415 -416.501626)
			(xy 447.519989 -416.553616) (xy 447.528038 -416.607289) (xy 447.528696 -416.634422) (xy 447.528696 -416.639502)
			(xy 447.528042 -416.667401) (xy 447.519577 -416.72256) (xy 447.503164 -416.775897) (xy 447.491612 -416.8013)
			(xy 447.491104 -416.802316) (xy 447.488818 -416.807142) (xy 447.485516 -416.820604) (xy 447.4838 -416.829964)
			(xy 447.486663 -416.848764) (xy 447.491104 -416.85718) (xy 447.536062 -416.930078) (xy 447.539622 -416.935526)
			(xy 447.549008 -416.944536) (xy 447.554604 -416.947858) (xy 447.554858 -416.948112) (xy 447.560581 -416.951075)
			(xy 447.573054 -416.954299) (xy 447.579496 -416.954462) (xy 448.747134 -416.954462) (xy 448.749674 -416.954462)
			(xy 448.761264 -416.95331) (xy 448.781632 -416.942061) (xy 448.78879 -416.932872) (xy 448.835526 -416.856672)
			(xy 448.839737 -416.848318) (xy 448.842458 -416.829824) (xy 448.84086 -416.820604) (xy 448.837558 -416.807142)
			(xy 448.835272 -416.802316) (xy 448.834764 -416.8013) (xy 448.823201 -416.775901) (xy 448.806793 -416.722562)
			(xy 448.798331 -416.667401) (xy 448.79768 -416.639502) (xy 448.79768 -416.634422) (xy 448.798338 -416.607289)
			(xy 448.806387 -416.553616) (xy 448.821961 -416.501626) (xy 448.844746 -416.452367) (xy 448.874281 -416.406834)
			(xy 448.909971 -416.365947) (xy 448.951095 -416.33053) (xy 448.996824 -416.301298) (xy 449.046233 -416.278842)
			(xy 449.098326 -416.263614) (xy 449.152051 -416.255923) (xy 449.206325 -416.255923) (xy 449.26005 -416.263614)
			(xy 449.312143 -416.278842) (xy 449.361552 -416.301298) (xy 449.407281 -416.33053) (xy 449.448405 -416.365947)
			(xy 449.484095 -416.406834) (xy 449.51363 -416.452367) (xy 449.536415 -416.501626) (xy 449.551989 -416.553616)
			(xy 449.560038 -416.607289) (xy 449.560696 -416.634422) (xy 449.560696 -416.639502) (xy 449.560042 -416.667401)
			(xy 449.551577 -416.72256) (xy 449.535164 -416.775897) (xy 449.523612 -416.8013) (xy 449.523104 -416.802316)
			(xy 449.520818 -416.807142) (xy 449.517516 -416.820604) (xy 449.5158 -416.829964) (xy 449.518663 -416.848764)
			(xy 449.523104 -416.85718) (xy 449.568062 -416.930078) (xy 449.571622 -416.935526) (xy 449.581008 -416.944536)
			(xy 449.586604 -416.947858) (xy 449.586858 -416.948112) (xy 449.592581 -416.951075) (xy 449.605054 -416.954299)
			(xy 449.611496 -416.954462) (xy 449.763134 -416.954462) (xy 449.765674 -416.954462) (xy 449.777264 -416.95331)
			(xy 449.797632 -416.942061) (xy 449.80479 -416.932872) (xy 449.851526 -416.856672) (xy 449.855737 -416.848318)
			(xy 449.858458 -416.829824) (xy 449.85686 -416.820604) (xy 449.853558 -416.807142) (xy 449.851272 -416.802316)
			(xy 449.850764 -416.8013) (xy 449.839201 -416.775901) (xy 449.822793 -416.722562) (xy 449.814331 -416.667401)
			(xy 449.81368 -416.639502) (xy 449.81368 -416.634422) (xy 449.814338 -416.607289) (xy 449.822387 -416.553616)
			(xy 449.837961 -416.501626) (xy 449.860746 -416.452367) (xy 449.890281 -416.406834) (xy 449.925971 -416.365947)
			(xy 449.967095 -416.33053) (xy 450.012824 -416.301298) (xy 450.062233 -416.278842) (xy 450.114326 -416.263614)
			(xy 450.168051 -416.255923) (xy 450.222325 -416.255923) (xy 450.27605 -416.263614) (xy 450.328143 -416.278842)
			(xy 450.377552 -416.301298) (xy 450.423281 -416.33053) (xy 450.464405 -416.365947) (xy 450.500095 -416.406834)
			(xy 450.52963 -416.452367) (xy 450.552415 -416.501626) (xy 450.567989 -416.553616) (xy 450.576038 -416.607289)
			(xy 450.576696 -416.634422) (xy 450.576696 -416.639502) (xy 450.576042 -416.667401) (xy 450.567577 -416.72256)
			(xy 450.551164 -416.775897) (xy 450.539612 -416.8013) (xy 450.539104 -416.802316) (xy 450.536818 -416.807142)
			(xy 450.533516 -416.820604) (xy 450.531802 -416.82982) (xy 450.534529 -416.848354) (xy 450.53885 -416.856672)
			(xy 450.585586 -416.932872) (xy 450.592732 -416.942074) (xy 450.613108 -416.953319) (xy 450.624702 -416.954462)
			(xy 464.785456 -416.954462) (xy 464.795521 -416.954028) (xy 464.814107 -416.946295) (xy 464.821524 -416.939476)
			(xy 466.303614 -415.457386) (xy 466.310468 -415.449991) (xy 466.31821 -415.431392) (xy 466.3186 -415.421318)
			(xy 466.3186 -334.405986) (xy 466.318174 -334.395917) (xy 466.310456 -334.377316) (xy 466.303614 -334.369918)
			(xy 464.688428 -332.754732) (xy 464.681027 -332.747893) (xy 464.662429 -332.74018) (xy 464.65236 -332.739746)
			(xy 463.619088 -332.739746) (xy 463.60902 -332.740173) (xy 463.590423 -332.747895) (xy 463.58302 -332.754732)
			(xy 463.569558 -332.768194) (xy 463.562157 -332.775035) (xy 463.543559 -332.782755) (xy 463.53349 -332.78318)
			(xy 437.66486 -332.78318) (xy 437.654793 -332.782749) (xy 437.636201 -332.775022) (xy 437.628792 -332.768194)
			(xy 432.008026 -327.147428) (xy 432.001188 -327.140027) (xy 431.993476 -327.121428) (xy 431.99304 -327.11136)
			(xy 431.99304 -317.982092) (xy 431.993128 -317.977072) (xy 431.995038 -317.967216) (xy 431.99685 -317.962534)
			(xy 432.004216 -317.945262) (xy 432.00601 -317.940575) (xy 432.00792 -317.930722) (xy 432.008026 -317.925704)
			(xy 432.008026 -289.965384) (xy 432.007933 -289.960506) (xy 432.00615 -289.950914) (xy 432.00447 -289.946334)
			(xy 432.00066 -289.93719) (xy 431.466498 -289.403028) (xy 431.463647 -289.400322) (xy 431.457268 -289.39573)
			(xy 431.453798 -289.393884) (xy 431.448372 -289.391297) (xy 431.436692 -289.388465) (xy 431.430684 -289.388296)
			(xy 428.706788 -289.388296) (xy 428.697888 -289.388734) (xy 428.681189 -289.39491) (xy 428.6676 -289.406414)
			(xy 428.662846 -289.41395) (xy 428.61865 -289.499548) (xy 428.613824 -289.508692) (xy 428.61484 -289.522916)
			(xy 428.615535 -289.529703) (xy 428.620041 -289.542577) (xy 428.62373 -289.548316) (xy 428.623984 -289.54857)
			(xy 428.637224 -289.568) (xy 428.658202 -289.610077) (xy 428.672468 -289.654878) (xy 428.679682 -289.701338)
			(xy 428.680118 -289.724846) (xy 428.679596 -289.750101) (xy 428.671283 -289.799923) (xy 428.654882 -289.847697)
			(xy 428.630841 -289.89212) (xy 428.599817 -289.93198) (xy 428.562655 -289.96619) (xy 428.520369 -289.993816)
			(xy 428.474113 -290.014106) (xy 428.425148 -290.026506) (xy 428.37481 -290.030677) (xy 428.324472 -290.026506)
			(xy 428.275507 -290.014106) (xy 428.229251 -289.993816) (xy 428.186965 -289.96619) (xy 428.149803 -289.93198)
			(xy 428.118779 -289.89212) (xy 428.094738 -289.847697) (xy 428.078337 -289.799923) (xy 428.070024 -289.750101)
			(xy 428.069502 -289.724846) (xy 428.069949 -289.70137) (xy 428.077182 -289.654977) (xy 428.091453 -289.610245)
			(xy 428.112424 -289.568235) (xy 428.125636 -289.548824) (xy 428.125636 -289.548316) (xy 428.12589 -289.548316)
			(xy 428.129586 -289.54258) (xy 428.134085 -289.529704) (xy 428.13478 -289.522916) (xy 428.135796 -289.508692)
			(xy 428.13097 -289.499548) (xy 428.086774 -289.41395) (xy 428.08207 -289.40637) (xy 428.068474 -289.394837)
			(xy 428.051745 -289.388672) (xy 428.042832 -289.388296) (xy 427.756828 -289.388296) (xy 427.747925 -289.388727)
			(xy 427.731215 -289.394895) (xy 427.717615 -289.406396) (xy 427.712886 -289.41395) (xy 427.66869 -289.499548)
			(xy 427.663864 -289.508692) (xy 427.66488 -289.522916) (xy 427.665576 -289.529703) (xy 427.670084 -289.542574)
			(xy 427.67377 -289.548316) (xy 427.674024 -289.54857) (xy 427.687263 -289.568001) (xy 427.708238 -289.610079)
			(xy 427.722501 -289.654879) (xy 427.729715 -289.701338) (xy 427.730158 -289.724846) (xy 427.729636 -289.750101)
			(xy 427.721323 -289.799923) (xy 427.704922 -289.847697) (xy 427.680881 -289.89212) (xy 427.649857 -289.93198)
			(xy 427.612695 -289.96619) (xy 427.570409 -289.993816) (xy 427.524153 -290.014106) (xy 427.475188 -290.026506)
			(xy 427.42485 -290.030677) (xy 427.374512 -290.026506) (xy 427.325547 -290.014106) (xy 427.279291 -289.993816)
			(xy 427.237005 -289.96619) (xy 427.199843 -289.93198) (xy 427.168819 -289.89212) (xy 427.144778 -289.847697)
			(xy 427.128377 -289.799923) (xy 427.120064 -289.750101) (xy 427.119542 -289.724846) (xy 427.121066 -289.695382)
			(xy 427.121066 -289.69462) (xy 427.121453 -289.687759) (xy 427.119 -289.674244) (xy 427.11624 -289.66795)
			(xy 427.112941 -289.66174) (xy 427.103538 -289.651292) (xy 427.097698 -289.647376) (xy 427.023022 -289.599878)
			(xy 427.015656 -289.596068) (xy 427.007677 -289.593088) (xy 426.990696 -289.591927) (xy 426.982382 -289.593782)
			(xy 426.974254 -289.596068) (xy 426.96384 -289.600132) (xy 426.961808 -289.601402) (xy 426.931643 -289.618802)
			(xy 426.869223 -289.649692) (xy 426.837094 -289.663124) (xy 426.828966 -289.667188) (xy 426.822362 -289.672014)
			(xy 426.814338 -289.679922) (xy 426.805525 -289.700625) (xy 426.805344 -289.711892) (xy 426.805598 -289.724846)
			(xy 426.805085 -289.750831) (xy 426.796949 -289.802159) (xy 426.780883 -289.851583) (xy 426.757285 -289.897885)
			(xy 426.726734 -289.939926) (xy 426.689983 -289.976671) (xy 426.647937 -290.007214) (xy 426.601631 -290.030805)
			(xy 426.552204 -290.046862) (xy 426.500875 -290.054989) (xy 426.47489 -290.055554) (xy 426.46214 -290.055463)
			(xy 426.436711 -290.053557) (xy 426.42409 -290.051744) (xy 426.39825 -290.047219) (xy 426.348336 -290.031081)
			(xy 426.301596 -290.007266) (xy 426.259201 -289.976373) (xy 426.222212 -289.939175) (xy 426.191559 -289.896606)
			(xy 426.168009 -289.849732) (xy 426.152153 -289.799728) (xy 426.147738 -289.773868) (xy 426.146001 -289.764542)
			(xy 426.136628 -289.748066) (xy 426.121872 -289.736168) (xy 426.11294 -289.732974) (xy 426.102018 -289.730688)
			(xy 426.052742 -289.7251) (xy 426.052488 -289.7251) (xy 426.011086 -289.718496) (xy 426.005244 -289.71748)
			(xy 425.993306 -289.71748) (xy 425.947332 -289.7251) (xy 425.947078 -289.7251) (xy 425.943776 -289.725608)
			(xy 425.898056 -289.730688) (xy 425.893866 -289.731111) (xy 425.885693 -289.733146) (xy 425.8818 -289.734752)
			(xy 425.874102 -289.738527) (xy 425.861608 -289.750252) (xy 425.853681 -289.765443) (xy 425.852082 -289.773868)
			(xy 425.847719 -289.799653) (xy 425.83193 -289.849506) (xy 425.808489 -289.896253) (xy 425.777982 -289.938726)
			(xy 425.74117 -289.975868) (xy 425.69897 -290.006752) (xy 425.652434 -290.030608) (xy 425.602724 -290.046841)
			(xy 425.551077 -290.055046) (xy 425.52493 -290.055554) (xy 425.521628 -290.055554) (xy 425.507577 -290.055271)
			(xy 425.479598 -290.052603) (xy 425.465748 -290.05022) (xy 425.464224 -290.049966) (xy 425.46016 -290.049458)
			(xy 425.449349 -290.048869) (xy 425.428824 -290.0557) (xy 425.420536 -290.062666) (xy 425.420282 -290.06292)
			(xy 425.41295 -290.070393) (xy 425.404563 -290.089548) (xy 425.404026 -290.100004) (xy 425.404026 -290.268152)
			(xy 425.404459 -290.278217) (xy 425.41219 -290.296806) (xy 425.419012 -290.30422) (xy 425.419266 -290.304474)
			(xy 425.47286 -290.355782) (xy 425.479964 -290.362032) (xy 425.49745 -290.369223) (xy 425.506896 -290.369752)
			(xy 425.510452 -290.369752) (xy 425.524422 -290.369498) (xy 425.525184 -290.369498) (xy 425.550423 -290.370042)
			(xy 425.600208 -290.378392) (xy 425.64794 -290.394818) (xy 425.692321 -290.418872) (xy 425.73214 -290.449899)
			(xy 425.766313 -290.487053) (xy 425.793908 -290.529322) (xy 425.814174 -290.575555) (xy 425.826559 -290.624492)
			(xy 425.830725 -290.6748) (xy 425.830725 -290.674806) (xy 426.169086 -290.674806) (xy 426.173046 -290.625752)
			(xy 426.184823 -290.577968) (xy 426.204114 -290.532692) (xy 426.230417 -290.491096) (xy 426.263052 -290.454259)
			(xy 426.301173 -290.423134) (xy 426.343794 -290.398527) (xy 426.38981 -290.381075) (xy 426.438029 -290.371231)
			(xy 426.487204 -290.36925) (xy 426.536059 -290.375182) (xy 426.58333 -290.388874) (xy 426.627792 -290.409972)
			(xy 426.668295 -290.437928) (xy 426.703788 -290.47202) (xy 426.733353 -290.511364) (xy 426.756224 -290.554941)
			(xy 426.771808 -290.601622) (xy 426.779703 -290.650199) (xy 426.780198 -290.674806) (xy 429.96918 -290.674806)
			(xy 429.97314 -290.625752) (xy 429.984917 -290.577968) (xy 430.004208 -290.532692) (xy 430.030511 -290.491096)
			(xy 430.063146 -290.454259) (xy 430.101267 -290.423134) (xy 430.143888 -290.398527) (xy 430.189904 -290.381075)
			(xy 430.238123 -290.371231) (xy 430.287298 -290.36925) (xy 430.336153 -290.375182) (xy 430.383424 -290.388874)
			(xy 430.427886 -290.409972) (xy 430.468389 -290.437928) (xy 430.503882 -290.47202) (xy 430.533447 -290.511364)
			(xy 430.556318 -290.554941) (xy 430.571902 -290.601622) (xy 430.579797 -290.650199) (xy 430.580292 -290.674806)
			(xy 430.91914 -290.674806) (xy 430.9231 -290.625752) (xy 430.934877 -290.577968) (xy 430.954168 -290.532692)
			(xy 430.980471 -290.491096) (xy 431.013106 -290.454259) (xy 431.051227 -290.423134) (xy 431.093848 -290.398527)
			(xy 431.139864 -290.381075) (xy 431.188083 -290.371231) (xy 431.237258 -290.36925) (xy 431.286113 -290.375182)
			(xy 431.333384 -290.388874) (xy 431.377846 -290.409972) (xy 431.418349 -290.437928) (xy 431.453842 -290.47202)
			(xy 431.483407 -290.511364) (xy 431.506278 -290.554941) (xy 431.521862 -290.601622) (xy 431.529757 -290.650199)
			(xy 431.530252 -290.674806) (xy 431.529757 -290.699413) (xy 431.521862 -290.74799) (xy 431.506278 -290.794671)
			(xy 431.483407 -290.838248) (xy 431.453842 -290.877592) (xy 431.418349 -290.911684) (xy 431.377846 -290.93964)
			(xy 431.333384 -290.960738) (xy 431.286113 -290.97443) (xy 431.237258 -290.980362) (xy 431.188083 -290.978381)
			(xy 431.139864 -290.968537) (xy 431.093848 -290.951085) (xy 431.051227 -290.926478) (xy 431.013106 -290.895353)
			(xy 430.980471 -290.858516) (xy 430.954168 -290.81692) (xy 430.934877 -290.771644) (xy 430.9231 -290.72386)
			(xy 430.91914 -290.674806) (xy 430.580292 -290.674806) (xy 430.579797 -290.699413) (xy 430.571902 -290.74799)
			(xy 430.556318 -290.794671) (xy 430.533447 -290.838248) (xy 430.503882 -290.877592) (xy 430.468389 -290.911684)
			(xy 430.427886 -290.93964) (xy 430.383424 -290.960738) (xy 430.336153 -290.97443) (xy 430.287298 -290.980362)
			(xy 430.238123 -290.978381) (xy 430.189904 -290.968537) (xy 430.143888 -290.951085) (xy 430.101267 -290.926478)
			(xy 430.063146 -290.895353) (xy 430.030511 -290.858516) (xy 430.004208 -290.81692) (xy 429.984917 -290.771644)
			(xy 429.97314 -290.72386) (xy 429.96918 -290.674806) (xy 426.780198 -290.674806) (xy 426.779703 -290.699413)
			(xy 426.771808 -290.74799) (xy 426.756224 -290.794671) (xy 426.733353 -290.838248) (xy 426.703788 -290.877592)
			(xy 426.668295 -290.911684) (xy 426.627792 -290.93964) (xy 426.58333 -290.960738) (xy 426.536059 -290.97443)
			(xy 426.487204 -290.980362) (xy 426.438029 -290.978381) (xy 426.38981 -290.968537) (xy 426.343794 -290.951085)
			(xy 426.301173 -290.926478) (xy 426.263052 -290.895353) (xy 426.230417 -290.858516) (xy 426.204114 -290.81692)
			(xy 426.184823 -290.771644) (xy 426.173046 -290.72386) (xy 426.169086 -290.674806) (xy 425.830725 -290.674806)
			(xy 425.826559 -290.725108) (xy 425.814174 -290.774045) (xy 425.793908 -290.820278) (xy 425.766313 -290.862547)
			(xy 425.73214 -290.899701) (xy 425.692321 -290.930728) (xy 425.64794 -290.954782) (xy 425.600208 -290.971208)
			(xy 425.550423 -290.979558) (xy 425.525184 -290.980114) (xy 425.524422 -290.980114) (xy 425.510198 -290.97986)
			(xy 425.499784 -290.979352) (xy 425.490132 -290.983162) (xy 425.485451 -290.985081) (xy 425.476883 -290.990456)
			(xy 425.473114 -290.99383) (xy 425.419774 -291.04463) (xy 425.412652 -291.052053) (xy 425.404525 -291.070931)
			(xy 425.404026 -291.081206) (xy 425.404026 -291.624766) (xy 427.119046 -291.624766) (xy 427.123006 -291.575712)
			(xy 427.134783 -291.527928) (xy 427.154074 -291.482652) (xy 427.180377 -291.441056) (xy 427.213012 -291.404219)
			(xy 427.251133 -291.373094) (xy 427.293754 -291.348487) (xy 427.33977 -291.331035) (xy 427.387989 -291.321191)
			(xy 427.437164 -291.31921) (xy 427.486019 -291.325142) (xy 427.53329 -291.338834) (xy 427.577752 -291.359932)
			(xy 427.618255 -291.387888) (xy 427.653748 -291.42198) (xy 427.683313 -291.461324) (xy 427.706184 -291.504901)
			(xy 427.721768 -291.551582) (xy 427.729663 -291.600159) (xy 427.730158 -291.624766) (xy 428.069006 -291.624766)
			(xy 428.072966 -291.575712) (xy 428.084743 -291.527928) (xy 428.104034 -291.482652) (xy 428.130337 -291.441056)
			(xy 428.162972 -291.404219) (xy 428.201093 -291.373094) (xy 428.243714 -291.348487) (xy 428.28973 -291.331035)
			(xy 428.337949 -291.321191) (xy 428.387124 -291.31921) (xy 428.435979 -291.325142) (xy 428.48325 -291.338834)
			(xy 428.527712 -291.359932) (xy 428.568215 -291.387888) (xy 428.603708 -291.42198) (xy 428.633273 -291.461324)
			(xy 428.656144 -291.504901) (xy 428.671728 -291.551582) (xy 428.679623 -291.600159) (xy 428.680118 -291.624766)
			(xy 428.679623 -291.649373) (xy 428.671728 -291.69795) (xy 428.656144 -291.744631) (xy 428.633273 -291.788208)
			(xy 428.603708 -291.827552) (xy 428.568215 -291.861644) (xy 428.527712 -291.8896) (xy 428.48325 -291.910698)
			(xy 428.435979 -291.92439) (xy 428.387124 -291.930322) (xy 428.337949 -291.928341) (xy 428.28973 -291.918497)
			(xy 428.243714 -291.901045) (xy 428.201093 -291.876438) (xy 428.162972 -291.845313) (xy 428.130337 -291.808476)
			(xy 428.104034 -291.76688) (xy 428.084743 -291.721604) (xy 428.072966 -291.67382) (xy 428.069006 -291.624766)
			(xy 427.730158 -291.624766) (xy 427.729663 -291.649373) (xy 427.721768 -291.69795) (xy 427.706184 -291.744631)
			(xy 427.683313 -291.788208) (xy 427.653748 -291.827552) (xy 427.618255 -291.861644) (xy 427.577752 -291.8896)
			(xy 427.53329 -291.910698) (xy 427.486019 -291.92439) (xy 427.437164 -291.930322) (xy 427.387989 -291.928341)
			(xy 427.33977 -291.918497) (xy 427.293754 -291.901045) (xy 427.251133 -291.876438) (xy 427.213012 -291.845313)
			(xy 427.180377 -291.808476) (xy 427.154074 -291.76688) (xy 427.134783 -291.721604) (xy 427.123006 -291.67382)
			(xy 427.119046 -291.624766) (xy 425.404026 -291.624766) (xy 425.404026 -292.168072) (xy 425.404463 -292.178136)
			(xy 425.412199 -292.196719) (xy 425.419012 -292.20414) (xy 425.419266 -292.204394) (xy 425.47286 -292.255702)
			(xy 425.479965 -292.26195) (xy 425.497451 -292.269138) (xy 425.506896 -292.269672) (xy 425.510452 -292.269672)
			(xy 425.524422 -292.269418) (xy 425.525184 -292.269418) (xy 425.550422 -292.269962) (xy 425.600203 -292.278311)
			(xy 425.647932 -292.294736) (xy 425.69231 -292.318789) (xy 425.732126 -292.349813) (xy 425.766297 -292.386965)
			(xy 425.79389 -292.429232) (xy 425.814155 -292.475462) (xy 425.826539 -292.524396) (xy 425.830705 -292.5747)
			(xy 425.830703 -292.574726) (xy 426.169086 -292.574726) (xy 426.173046 -292.525672) (xy 426.184823 -292.477888)
			(xy 426.204114 -292.432612) (xy 426.230417 -292.391016) (xy 426.263052 -292.354179) (xy 426.301173 -292.323054)
			(xy 426.343794 -292.298447) (xy 426.38981 -292.280995) (xy 426.438029 -292.271151) (xy 426.487204 -292.26917)
			(xy 426.536059 -292.275102) (xy 426.58333 -292.288794) (xy 426.627792 -292.309892) (xy 426.668295 -292.337848)
			(xy 426.703788 -292.37194) (xy 426.733353 -292.411284) (xy 426.756224 -292.454861) (xy 426.771808 -292.501542)
			(xy 426.779703 -292.550119) (xy 426.780198 -292.574726) (xy 426.780193 -292.57498) (xy 429.96918 -292.57498)
			(xy 429.97314 -292.525926) (xy 429.984917 -292.478142) (xy 430.004208 -292.432866) (xy 430.030511 -292.39127)
			(xy 430.063146 -292.354433) (xy 430.101267 -292.323308) (xy 430.143888 -292.298701) (xy 430.189904 -292.281249)
			(xy 430.238123 -292.271405) (xy 430.287298 -292.269424) (xy 430.336153 -292.275356) (xy 430.383424 -292.289048)
			(xy 430.427886 -292.310146) (xy 430.468389 -292.338102) (xy 430.503882 -292.372194) (xy 430.533447 -292.411538)
			(xy 430.556318 -292.455115) (xy 430.571902 -292.501796) (xy 430.579797 -292.550373) (xy 430.580292 -292.57498)
			(xy 430.91914 -292.57498) (xy 430.9231 -292.525926) (xy 430.934877 -292.478142) (xy 430.954168 -292.432866)
			(xy 430.980471 -292.39127) (xy 431.013106 -292.354433) (xy 431.051227 -292.323308) (xy 431.093848 -292.298701)
			(xy 431.139864 -292.281249) (xy 431.188083 -292.271405) (xy 431.237258 -292.269424) (xy 431.286113 -292.275356)
			(xy 431.333384 -292.289048) (xy 431.377846 -292.310146) (xy 431.418349 -292.338102) (xy 431.453842 -292.372194)
			(xy 431.483407 -292.411538) (xy 431.506278 -292.455115) (xy 431.521862 -292.501796) (xy 431.529757 -292.550373)
			(xy 431.530252 -292.57498) (xy 431.529757 -292.599587) (xy 431.521862 -292.648164) (xy 431.506278 -292.694845)
			(xy 431.483407 -292.738422) (xy 431.453842 -292.777766) (xy 431.418349 -292.811858) (xy 431.377846 -292.839814)
			(xy 431.333384 -292.860912) (xy 431.286113 -292.874604) (xy 431.237258 -292.880536) (xy 431.188083 -292.878555)
			(xy 431.139864 -292.868711) (xy 431.093848 -292.851259) (xy 431.051227 -292.826652) (xy 431.013106 -292.795527)
			(xy 430.980471 -292.75869) (xy 430.954168 -292.717094) (xy 430.934877 -292.671818) (xy 430.9231 -292.624034)
			(xy 430.91914 -292.57498) (xy 430.580292 -292.57498) (xy 430.579797 -292.599587) (xy 430.571902 -292.648164)
			(xy 430.556318 -292.694845) (xy 430.533447 -292.738422) (xy 430.503882 -292.777766) (xy 430.468389 -292.811858)
			(xy 430.427886 -292.839814) (xy 430.383424 -292.860912) (xy 430.336153 -292.874604) (xy 430.287298 -292.880536)
			(xy 430.238123 -292.878555) (xy 430.189904 -292.868711) (xy 430.143888 -292.851259) (xy 430.101267 -292.826652)
			(xy 430.063146 -292.795527) (xy 430.030511 -292.75869) (xy 430.004208 -292.717094) (xy 429.984917 -292.671818)
			(xy 429.97314 -292.624034) (xy 429.96918 -292.57498) (xy 426.780193 -292.57498) (xy 426.779703 -292.599333)
			(xy 426.771808 -292.64791) (xy 426.756224 -292.694591) (xy 426.733353 -292.738168) (xy 426.703788 -292.777512)
			(xy 426.668295 -292.811604) (xy 426.627792 -292.83956) (xy 426.58333 -292.860658) (xy 426.536059 -292.87435)
			(xy 426.487204 -292.880282) (xy 426.438029 -292.878301) (xy 426.38981 -292.868457) (xy 426.343794 -292.851005)
			(xy 426.301173 -292.826398) (xy 426.263052 -292.795273) (xy 426.230417 -292.758436) (xy 426.204114 -292.71684)
			(xy 426.184823 -292.671564) (xy 426.173046 -292.62378) (xy 426.169086 -292.574726) (xy 425.830703 -292.574726)
			(xy 425.826539 -292.625004) (xy 425.814155 -292.673938) (xy 425.79389 -292.720168) (xy 425.766297 -292.762435)
			(xy 425.732126 -292.799587) (xy 425.69231 -292.830612) (xy 425.647932 -292.854664) (xy 425.600203 -292.871089)
			(xy 425.550422 -292.879438) (xy 425.525184 -292.880034) (xy 425.524422 -292.880034) (xy 425.510198 -292.87978)
			(xy 425.499784 -292.879272) (xy 425.490132 -292.883082) (xy 425.485452 -292.885002) (xy 425.476885 -292.890378)
			(xy 425.473114 -292.89375) (xy 425.419774 -292.94455) (xy 425.412655 -292.951975) (xy 425.404536 -292.970852)
			(xy 425.404026 -292.981126) (xy 425.404026 -293.52494) (xy 427.119046 -293.52494) (xy 427.123006 -293.475886)
			(xy 427.134783 -293.428102) (xy 427.154074 -293.382826) (xy 427.180377 -293.34123) (xy 427.213012 -293.304393)
			(xy 427.251133 -293.273268) (xy 427.293754 -293.248661) (xy 427.33977 -293.231209) (xy 427.387989 -293.221365)
			(xy 427.437164 -293.219384) (xy 427.486019 -293.225316) (xy 427.53329 -293.239008) (xy 427.577752 -293.260106)
			(xy 427.618255 -293.288062) (xy 427.653748 -293.322154) (xy 427.683313 -293.361498) (xy 427.706184 -293.405075)
			(xy 427.721768 -293.451756) (xy 427.729663 -293.500333) (xy 427.730158 -293.52494) (xy 428.069006 -293.52494)
			(xy 428.072966 -293.475886) (xy 428.084743 -293.428102) (xy 428.104034 -293.382826) (xy 428.130337 -293.34123)
			(xy 428.162972 -293.304393) (xy 428.201093 -293.273268) (xy 428.243714 -293.248661) (xy 428.28973 -293.231209)
			(xy 428.337949 -293.221365) (xy 428.387124 -293.219384) (xy 428.435979 -293.225316) (xy 428.48325 -293.239008)
			(xy 428.527712 -293.260106) (xy 428.568215 -293.288062) (xy 428.603708 -293.322154) (xy 428.633273 -293.361498)
			(xy 428.656144 -293.405075) (xy 428.671728 -293.451756) (xy 428.679623 -293.500333) (xy 428.680118 -293.52494)
			(xy 428.679623 -293.549547) (xy 428.671728 -293.598124) (xy 428.656144 -293.644805) (xy 428.633273 -293.688382)
			(xy 428.603708 -293.727726) (xy 428.568215 -293.761818) (xy 428.527712 -293.789774) (xy 428.48325 -293.810872)
			(xy 428.435979 -293.824564) (xy 428.387124 -293.830496) (xy 428.337949 -293.828515) (xy 428.28973 -293.818671)
			(xy 428.243714 -293.801219) (xy 428.201093 -293.776612) (xy 428.162972 -293.745487) (xy 428.130337 -293.70865)
			(xy 428.104034 -293.667054) (xy 428.084743 -293.621778) (xy 428.072966 -293.573994) (xy 428.069006 -293.52494)
			(xy 427.730158 -293.52494) (xy 427.729663 -293.549547) (xy 427.721768 -293.598124) (xy 427.706184 -293.644805)
			(xy 427.683313 -293.688382) (xy 427.653748 -293.727726) (xy 427.618255 -293.761818) (xy 427.577752 -293.789774)
			(xy 427.53329 -293.810872) (xy 427.486019 -293.824564) (xy 427.437164 -293.830496) (xy 427.387989 -293.828515)
			(xy 427.33977 -293.818671) (xy 427.293754 -293.801219) (xy 427.251133 -293.776612) (xy 427.213012 -293.745487)
			(xy 427.180377 -293.70865) (xy 427.154074 -293.667054) (xy 427.134783 -293.621778) (xy 427.123006 -293.573994)
			(xy 427.119046 -293.52494) (xy 425.404026 -293.52494) (xy 425.404026 -294.068246) (xy 425.404458 -294.078312)
			(xy 425.412187 -294.096902) (xy 425.419012 -294.104314) (xy 425.419266 -294.104568) (xy 425.47286 -294.155876)
			(xy 425.479963 -294.162126) (xy 425.49745 -294.169319) (xy 425.506896 -294.169846) (xy 425.510452 -294.169846)
			(xy 425.524422 -294.169592) (xy 425.525184 -294.169592) (xy 425.550424 -294.170136) (xy 425.600209 -294.178486)
			(xy 425.647943 -294.194912) (xy 425.692324 -294.218967) (xy 425.732144 -294.249994) (xy 425.766317 -294.287149)
			(xy 425.793913 -294.329419) (xy 425.81418 -294.375653) (xy 425.826565 -294.424591) (xy 425.830731 -294.4749)
			(xy 429.96918 -294.4749) (xy 429.97314 -294.425846) (xy 429.984917 -294.378062) (xy 430.004208 -294.332786)
			(xy 430.030511 -294.29119) (xy 430.063146 -294.254353) (xy 430.101267 -294.223228) (xy 430.143888 -294.198621)
			(xy 430.189904 -294.181169) (xy 430.238123 -294.171325) (xy 430.287298 -294.169344) (xy 430.336153 -294.175276)
			(xy 430.383424 -294.188968) (xy 430.427886 -294.210066) (xy 430.468389 -294.238022) (xy 430.503882 -294.272114)
			(xy 430.533447 -294.311458) (xy 430.556318 -294.355035) (xy 430.571902 -294.401716) (xy 430.579797 -294.450293)
			(xy 430.580292 -294.4749) (xy 430.91914 -294.4749) (xy 430.9231 -294.425846) (xy 430.934877 -294.378062)
			(xy 430.954168 -294.332786) (xy 430.980471 -294.29119) (xy 431.013106 -294.254353) (xy 431.051227 -294.223228)
			(xy 431.093848 -294.198621) (xy 431.139864 -294.181169) (xy 431.188083 -294.171325) (xy 431.237258 -294.169344)
			(xy 431.286113 -294.175276) (xy 431.333384 -294.188968) (xy 431.377846 -294.210066) (xy 431.418349 -294.238022)
			(xy 431.453842 -294.272114) (xy 431.483407 -294.311458) (xy 431.506278 -294.355035) (xy 431.521862 -294.401716)
			(xy 431.529757 -294.450293) (xy 431.530252 -294.4749) (xy 431.529757 -294.499507) (xy 431.521862 -294.548084)
			(xy 431.506278 -294.594765) (xy 431.483407 -294.638342) (xy 431.453842 -294.677686) (xy 431.418349 -294.711778)
			(xy 431.377846 -294.739734) (xy 431.333384 -294.760832) (xy 431.286113 -294.774524) (xy 431.237258 -294.780456)
			(xy 431.188083 -294.778475) (xy 431.139864 -294.768631) (xy 431.093848 -294.751179) (xy 431.051227 -294.726572)
			(xy 431.013106 -294.695447) (xy 430.980471 -294.65861) (xy 430.954168 -294.617014) (xy 430.934877 -294.571738)
			(xy 430.9231 -294.523954) (xy 430.91914 -294.4749) (xy 430.580292 -294.4749) (xy 430.579797 -294.499507)
			(xy 430.571902 -294.548084) (xy 430.556318 -294.594765) (xy 430.533447 -294.638342) (xy 430.503882 -294.677686)
			(xy 430.468389 -294.711778) (xy 430.427886 -294.739734) (xy 430.383424 -294.760832) (xy 430.336153 -294.774524)
			(xy 430.287298 -294.780456) (xy 430.238123 -294.778475) (xy 430.189904 -294.768631) (xy 430.143888 -294.751179)
			(xy 430.101267 -294.726572) (xy 430.063146 -294.695447) (xy 430.030511 -294.65861) (xy 430.004208 -294.617014)
			(xy 429.984917 -294.571738) (xy 429.97314 -294.523954) (xy 429.96918 -294.4749) (xy 425.830731 -294.4749)
			(xy 425.826565 -294.525209) (xy 425.81418 -294.574147) (xy 425.793913 -294.620381) (xy 425.766317 -294.662651)
			(xy 425.732144 -294.699806) (xy 425.692324 -294.730833) (xy 425.647943 -294.754888) (xy 425.600209 -294.771314)
			(xy 425.550424 -294.779664) (xy 425.525184 -294.780208) (xy 425.524422 -294.780208) (xy 425.510198 -294.779954)
			(xy 425.499784 -294.779446) (xy 425.490132 -294.783256) (xy 425.485451 -294.785175) (xy 425.476883 -294.790549)
			(xy 425.473114 -294.793924) (xy 425.419774 -294.844724) (xy 425.412651 -294.852147) (xy 425.404522 -294.871024)
			(xy 425.404026 -294.8813) (xy 425.404026 -295.968166) (xy 425.404462 -295.97823) (xy 425.412196 -295.996815)
			(xy 425.419012 -296.004234) (xy 425.419266 -296.004488) (xy 425.47286 -296.055796) (xy 425.479964 -296.062044)
			(xy 425.497451 -296.069233) (xy 425.506896 -296.069766) (xy 425.510452 -296.069766) (xy 425.524422 -296.069512)
			(xy 425.525184 -296.069512) (xy 425.550422 -296.070056) (xy 425.600204 -296.078406) (xy 425.647935 -296.094831)
			(xy 425.692313 -296.118883) (xy 425.73213 -296.149909) (xy 425.766302 -296.187061) (xy 425.793896 -296.229329)
			(xy 425.814161 -296.27556) (xy 425.826545 -296.324495) (xy 425.830711 -296.3748) (xy 425.830709 -296.37482)
			(xy 426.169086 -296.37482) (xy 426.173046 -296.325766) (xy 426.184823 -296.277982) (xy 426.204114 -296.232706)
			(xy 426.230417 -296.19111) (xy 426.263052 -296.154273) (xy 426.301173 -296.123148) (xy 426.343794 -296.098541)
			(xy 426.38981 -296.081089) (xy 426.438029 -296.071245) (xy 426.487204 -296.069264) (xy 426.536059 -296.075196)
			(xy 426.58333 -296.088888) (xy 426.627792 -296.109986) (xy 426.668295 -296.137942) (xy 426.703788 -296.172034)
			(xy 426.733353 -296.211378) (xy 426.756224 -296.254955) (xy 426.771808 -296.301636) (xy 426.779703 -296.350213)
			(xy 426.780198 -296.37482) (xy 426.779703 -296.399427) (xy 426.771808 -296.448004) (xy 426.756224 -296.494685)
			(xy 426.733353 -296.538262) (xy 426.703788 -296.577606) (xy 426.668295 -296.611698) (xy 426.627792 -296.639654)
			(xy 426.58333 -296.660752) (xy 426.536059 -296.674444) (xy 426.487204 -296.680376) (xy 426.438029 -296.678395)
			(xy 426.38981 -296.668551) (xy 426.343794 -296.651099) (xy 426.301173 -296.626492) (xy 426.263052 -296.595367)
			(xy 426.230417 -296.55853) (xy 426.204114 -296.516934) (xy 426.184823 -296.471658) (xy 426.173046 -296.423874)
			(xy 426.169086 -296.37482) (xy 425.830709 -296.37482) (xy 425.826545 -296.425105) (xy 425.814161 -296.47404)
			(xy 425.793896 -296.520271) (xy 425.766301 -296.562539) (xy 425.73213 -296.599691) (xy 425.692313 -296.630717)
			(xy 425.647935 -296.654769) (xy 425.600204 -296.671194) (xy 425.550422 -296.679544) (xy 425.525184 -296.680128)
			(xy 425.524422 -296.680128) (xy 425.510198 -296.679874) (xy 425.499784 -296.679366) (xy 425.490132 -296.683176)
			(xy 425.485452 -296.685095) (xy 425.476885 -296.690471) (xy 425.473114 -296.693844) (xy 425.419774 -296.744644)
			(xy 425.412654 -296.752068) (xy 425.404533 -296.770946) (xy 425.404026 -296.78122) (xy 425.404026 -297.32478)
			(xy 427.119046 -297.32478) (xy 427.123006 -297.275726) (xy 427.134783 -297.227942) (xy 427.154074 -297.182666)
			(xy 427.180377 -297.14107) (xy 427.213012 -297.104233) (xy 427.251133 -297.073108) (xy 427.293754 -297.048501)
			(xy 427.33977 -297.031049) (xy 427.387989 -297.021205) (xy 427.437164 -297.019224) (xy 427.486019 -297.025156)
			(xy 427.53329 -297.038848) (xy 427.577752 -297.059946) (xy 427.618255 -297.087902) (xy 427.653748 -297.121994)
			(xy 427.683313 -297.161338) (xy 427.706184 -297.204915) (xy 427.721768 -297.251596) (xy 427.729663 -297.300173)
			(xy 427.730158 -297.32478) (xy 428.069006 -297.32478) (xy 428.072966 -297.275726) (xy 428.084743 -297.227942)
			(xy 428.104034 -297.182666) (xy 428.130337 -297.14107) (xy 428.162972 -297.104233) (xy 428.201093 -297.073108)
			(xy 428.243714 -297.048501) (xy 428.28973 -297.031049) (xy 428.337949 -297.021205) (xy 428.387124 -297.019224)
			(xy 428.435979 -297.025156) (xy 428.48325 -297.038848) (xy 428.527712 -297.059946) (xy 428.568215 -297.087902)
			(xy 428.603708 -297.121994) (xy 428.633273 -297.161338) (xy 428.656144 -297.204915) (xy 428.671728 -297.251596)
			(xy 428.679623 -297.300173) (xy 428.680118 -297.32478) (xy 428.679623 -297.349387) (xy 428.671728 -297.397964)
			(xy 428.656144 -297.444645) (xy 428.633273 -297.488222) (xy 428.603708 -297.527566) (xy 428.568215 -297.561658)
			(xy 428.527712 -297.589614) (xy 428.48325 -297.610712) (xy 428.435979 -297.624404) (xy 428.387124 -297.630336)
			(xy 428.337949 -297.628355) (xy 428.28973 -297.618511) (xy 428.243714 -297.601059) (xy 428.201093 -297.576452)
			(xy 428.162972 -297.545327) (xy 428.130337 -297.50849) (xy 428.104034 -297.466894) (xy 428.084743 -297.421618)
			(xy 428.072966 -297.373834) (xy 428.069006 -297.32478) (xy 427.730158 -297.32478) (xy 427.729663 -297.349387)
			(xy 427.721768 -297.397964) (xy 427.706184 -297.444645) (xy 427.683313 -297.488222) (xy 427.653748 -297.527566)
			(xy 427.618255 -297.561658) (xy 427.577752 -297.589614) (xy 427.53329 -297.610712) (xy 427.486019 -297.624404)
			(xy 427.437164 -297.630336) (xy 427.387989 -297.628355) (xy 427.33977 -297.618511) (xy 427.293754 -297.601059)
			(xy 427.251133 -297.576452) (xy 427.213012 -297.545327) (xy 427.180377 -297.50849) (xy 427.154074 -297.466894)
			(xy 427.134783 -297.421618) (xy 427.123006 -297.373834) (xy 427.119046 -297.32478) (xy 425.404026 -297.32478)
			(xy 425.404026 -297.868086) (xy 425.404465 -297.878149) (xy 425.412205 -297.896728) (xy 425.419012 -297.904154)
			(xy 425.419266 -297.904408) (xy 425.47286 -297.955716) (xy 425.479965 -297.961963) (xy 425.497451 -297.969149)
			(xy 425.506896 -297.969686) (xy 425.510452 -297.969686) (xy 425.524422 -297.969432) (xy 425.525184 -297.969432)
			(xy 425.550421 -297.969976) (xy 425.6002 -297.978325) (xy 425.647927 -297.994749) (xy 425.692302 -298.0188)
			(xy 425.732117 -298.049824) (xy 425.766286 -298.086974) (xy 425.793878 -298.129239) (xy 425.814142 -298.175466)
			(xy 425.826525 -298.224398) (xy 425.830691 -298.2747) (xy 425.830688 -298.27474) (xy 426.169086 -298.27474)
			(xy 426.173046 -298.225686) (xy 426.184823 -298.177902) (xy 426.204114 -298.132626) (xy 426.230417 -298.09103)
			(xy 426.263052 -298.054193) (xy 426.301173 -298.023068) (xy 426.343794 -297.998461) (xy 426.38981 -297.981009)
			(xy 426.438029 -297.971165) (xy 426.487204 -297.969184) (xy 426.536059 -297.975116) (xy 426.58333 -297.988808)
			(xy 426.627792 -298.009906) (xy 426.668295 -298.037862) (xy 426.703788 -298.071954) (xy 426.733353 -298.111298)
			(xy 426.756224 -298.154875) (xy 426.771808 -298.201556) (xy 426.779703 -298.250133) (xy 426.780198 -298.27474)
			(xy 429.96918 -298.27474) (xy 429.97314 -298.225686) (xy 429.984917 -298.177902) (xy 430.004208 -298.132626)
			(xy 430.030511 -298.09103) (xy 430.063146 -298.054193) (xy 430.101267 -298.023068) (xy 430.143888 -297.998461)
			(xy 430.189904 -297.981009) (xy 430.238123 -297.971165) (xy 430.287298 -297.969184) (xy 430.336153 -297.975116)
			(xy 430.383424 -297.988808) (xy 430.427886 -298.009906) (xy 430.468389 -298.037862) (xy 430.503882 -298.071954)
			(xy 430.533447 -298.111298) (xy 430.556318 -298.154875) (xy 430.571902 -298.201556) (xy 430.579797 -298.250133)
			(xy 430.580292 -298.27474) (xy 430.91914 -298.27474) (xy 430.9231 -298.225686) (xy 430.934877 -298.177902)
			(xy 430.954168 -298.132626) (xy 430.980471 -298.09103) (xy 431.013106 -298.054193) (xy 431.051227 -298.023068)
			(xy 431.093848 -297.998461) (xy 431.139864 -297.981009) (xy 431.188083 -297.971165) (xy 431.237258 -297.969184)
			(xy 431.286113 -297.975116) (xy 431.333384 -297.988808) (xy 431.377846 -298.009906) (xy 431.418349 -298.037862)
			(xy 431.453842 -298.071954) (xy 431.483407 -298.111298) (xy 431.506278 -298.154875) (xy 431.521862 -298.201556)
			(xy 431.529757 -298.250133) (xy 431.530252 -298.27474) (xy 431.529757 -298.299347) (xy 431.521862 -298.347924)
			(xy 431.506278 -298.394605) (xy 431.483407 -298.438182) (xy 431.453842 -298.477526) (xy 431.418349 -298.511618)
			(xy 431.377846 -298.539574) (xy 431.333384 -298.560672) (xy 431.286113 -298.574364) (xy 431.237258 -298.580296)
			(xy 431.188083 -298.578315) (xy 431.139864 -298.568471) (xy 431.093848 -298.551019) (xy 431.051227 -298.526412)
			(xy 431.013106 -298.495287) (xy 430.980471 -298.45845) (xy 430.954168 -298.416854) (xy 430.934877 -298.371578)
			(xy 430.9231 -298.323794) (xy 430.91914 -298.27474) (xy 430.580292 -298.27474) (xy 430.579797 -298.299347)
			(xy 430.571902 -298.347924) (xy 430.556318 -298.394605) (xy 430.533447 -298.438182) (xy 430.503882 -298.477526)
			(xy 430.468389 -298.511618) (xy 430.427886 -298.539574) (xy 430.383424 -298.560672) (xy 430.336153 -298.574364)
			(xy 430.287298 -298.580296) (xy 430.238123 -298.578315) (xy 430.189904 -298.568471) (xy 430.143888 -298.551019)
			(xy 430.101267 -298.526412) (xy 430.063146 -298.495287) (xy 430.030511 -298.45845) (xy 430.004208 -298.416854)
			(xy 429.984917 -298.371578) (xy 429.97314 -298.323794) (xy 429.96918 -298.27474) (xy 426.780198 -298.27474)
			(xy 426.779703 -298.299347) (xy 426.771808 -298.347924) (xy 426.756224 -298.394605) (xy 426.733353 -298.438182)
			(xy 426.703788 -298.477526) (xy 426.668295 -298.511618) (xy 426.627792 -298.539574) (xy 426.58333 -298.560672)
			(xy 426.536059 -298.574364) (xy 426.487204 -298.580296) (xy 426.438029 -298.578315) (xy 426.38981 -298.568471)
			(xy 426.343794 -298.551019) (xy 426.301173 -298.526412) (xy 426.263052 -298.495287) (xy 426.230417 -298.45845)
			(xy 426.204114 -298.416854) (xy 426.184823 -298.371578) (xy 426.173046 -298.323794) (xy 426.169086 -298.27474)
			(xy 425.830688 -298.27474) (xy 425.826525 -298.325002) (xy 425.814142 -298.373934) (xy 425.793878 -298.420162)
			(xy 425.766286 -298.462426) (xy 425.732117 -298.499576) (xy 425.692302 -298.5306) (xy 425.647927 -298.554651)
			(xy 425.600199 -298.571075) (xy 425.550421 -298.579424) (xy 425.525184 -298.580048) (xy 425.524422 -298.580048)
			(xy 425.510198 -298.579794) (xy 425.499784 -298.579286) (xy 425.490132 -298.583096) (xy 425.48545 -298.585012)
			(xy 425.476877 -298.590382) (xy 425.473114 -298.593764) (xy 425.419774 -298.644564) (xy 425.412658 -298.651989)
			(xy 425.404543 -298.670867) (xy 425.404026 -298.68114) (xy 425.404026 -299.224954) (xy 427.119046 -299.224954)
			(xy 427.123006 -299.1759) (xy 427.134783 -299.128116) (xy 427.154074 -299.08284) (xy 427.180377 -299.041244)
			(xy 427.213012 -299.004407) (xy 427.251133 -298.973282) (xy 427.293754 -298.948675) (xy 427.33977 -298.931223)
			(xy 427.387989 -298.921379) (xy 427.437164 -298.919398) (xy 427.486019 -298.92533) (xy 427.53329 -298.939022)
			(xy 427.577752 -298.96012) (xy 427.618255 -298.988076) (xy 427.653748 -299.022168) (xy 427.683313 -299.061512)
			(xy 427.706184 -299.105089) (xy 427.721768 -299.15177) (xy 427.729663 -299.200347) (xy 427.730158 -299.224954)
			(xy 428.069006 -299.224954) (xy 428.072966 -299.1759) (xy 428.084743 -299.128116) (xy 428.104034 -299.08284)
			(xy 428.130337 -299.041244) (xy 428.162972 -299.004407) (xy 428.201093 -298.973282) (xy 428.243714 -298.948675)
			(xy 428.28973 -298.931223) (xy 428.337949 -298.921379) (xy 428.387124 -298.919398) (xy 428.435979 -298.92533)
			(xy 428.48325 -298.939022) (xy 428.527712 -298.96012) (xy 428.568215 -298.988076) (xy 428.603708 -299.022168)
			(xy 428.633273 -299.061512) (xy 428.656144 -299.105089) (xy 428.671728 -299.15177) (xy 428.679623 -299.200347)
			(xy 428.680118 -299.224954) (xy 428.679623 -299.249561) (xy 428.671728 -299.298138) (xy 428.656144 -299.344819)
			(xy 428.633273 -299.388396) (xy 428.603708 -299.42774) (xy 428.568215 -299.461832) (xy 428.527712 -299.489788)
			(xy 428.48325 -299.510886) (xy 428.435979 -299.524578) (xy 428.387124 -299.53051) (xy 428.337949 -299.528529)
			(xy 428.28973 -299.518685) (xy 428.243714 -299.501233) (xy 428.201093 -299.476626) (xy 428.162972 -299.445501)
			(xy 428.130337 -299.408664) (xy 428.104034 -299.367068) (xy 428.084743 -299.321792) (xy 428.072966 -299.274008)
			(xy 428.069006 -299.224954) (xy 427.730158 -299.224954) (xy 427.729663 -299.249561) (xy 427.721768 -299.298138)
			(xy 427.706184 -299.344819) (xy 427.683313 -299.388396) (xy 427.653748 -299.42774) (xy 427.618255 -299.461832)
			(xy 427.577752 -299.489788) (xy 427.53329 -299.510886) (xy 427.486019 -299.524578) (xy 427.437164 -299.53051)
			(xy 427.387989 -299.528529) (xy 427.33977 -299.518685) (xy 427.293754 -299.501233) (xy 427.251133 -299.476626)
			(xy 427.213012 -299.445501) (xy 427.180377 -299.408664) (xy 427.154074 -299.367068) (xy 427.134783 -299.321792)
			(xy 427.123006 -299.274008) (xy 427.119046 -299.224954) (xy 425.404026 -299.224954) (xy 425.404026 -299.76826)
			(xy 425.404461 -299.778325) (xy 425.412193 -299.796911) (xy 425.419012 -299.804328) (xy 425.419266 -299.804582)
			(xy 425.47286 -299.85589) (xy 425.479964 -299.862139) (xy 425.497451 -299.869329) (xy 425.506896 -299.86986)
			(xy 425.510452 -299.86986) (xy 425.524422 -299.869606) (xy 425.525184 -299.869606) (xy 425.550423 -299.87015)
			(xy 425.600206 -299.8785) (xy 425.647937 -299.894925) (xy 425.692317 -299.918978) (xy 425.732134 -299.950004)
			(xy 425.766306 -299.987158) (xy 425.793901 -300.029426) (xy 425.814167 -300.075658) (xy 425.826551 -300.124594)
			(xy 425.830717 -300.1749) (xy 425.830716 -300.174914) (xy 426.169086 -300.174914) (xy 426.173046 -300.12586)
			(xy 426.184823 -300.078076) (xy 426.204114 -300.0328) (xy 426.230417 -299.991204) (xy 426.263052 -299.954367)
			(xy 426.301173 -299.923242) (xy 426.343794 -299.898635) (xy 426.38981 -299.881183) (xy 426.438029 -299.871339)
			(xy 426.487204 -299.869358) (xy 426.536059 -299.87529) (xy 426.58333 -299.888982) (xy 426.627792 -299.91008)
			(xy 426.668295 -299.938036) (xy 426.703788 -299.972128) (xy 426.733353 -300.011472) (xy 426.756224 -300.055049)
			(xy 426.771808 -300.10173) (xy 426.779703 -300.150307) (xy 426.780198 -300.174914) (xy 429.96918 -300.174914)
			(xy 429.97314 -300.12586) (xy 429.984917 -300.078076) (xy 430.004208 -300.0328) (xy 430.030511 -299.991204)
			(xy 430.063146 -299.954367) (xy 430.101267 -299.923242) (xy 430.143888 -299.898635) (xy 430.189904 -299.881183)
			(xy 430.238123 -299.871339) (xy 430.287298 -299.869358) (xy 430.336153 -299.87529) (xy 430.383424 -299.888982)
			(xy 430.427886 -299.91008) (xy 430.468389 -299.938036) (xy 430.503882 -299.972128) (xy 430.533447 -300.011472)
			(xy 430.556318 -300.055049) (xy 430.571902 -300.10173) (xy 430.579797 -300.150307) (xy 430.580292 -300.174914)
			(xy 430.91914 -300.174914) (xy 430.9231 -300.12586) (xy 430.934877 -300.078076) (xy 430.954168 -300.0328)
			(xy 430.980471 -299.991204) (xy 431.013106 -299.954367) (xy 431.051227 -299.923242) (xy 431.093848 -299.898635)
			(xy 431.139864 -299.881183) (xy 431.188083 -299.871339) (xy 431.237258 -299.869358) (xy 431.286113 -299.87529)
			(xy 431.333384 -299.888982) (xy 431.377846 -299.91008) (xy 431.418349 -299.938036) (xy 431.453842 -299.972128)
			(xy 431.483407 -300.011472) (xy 431.506278 -300.055049) (xy 431.521862 -300.10173) (xy 431.529757 -300.150307)
			(xy 431.530252 -300.174914) (xy 431.529757 -300.199521) (xy 431.521862 -300.248098) (xy 431.506278 -300.294779)
			(xy 431.483407 -300.338356) (xy 431.453842 -300.3777) (xy 431.418349 -300.411792) (xy 431.377846 -300.439748)
			(xy 431.333384 -300.460846) (xy 431.286113 -300.474538) (xy 431.237258 -300.48047) (xy 431.188083 -300.478489)
			(xy 431.139864 -300.468645) (xy 431.093848 -300.451193) (xy 431.051227 -300.426586) (xy 431.013106 -300.395461)
			(xy 430.980471 -300.358624) (xy 430.954168 -300.317028) (xy 430.934877 -300.271752) (xy 430.9231 -300.223968)
			(xy 430.91914 -300.174914) (xy 430.580292 -300.174914) (xy 430.579797 -300.199521) (xy 430.571902 -300.248098)
			(xy 430.556318 -300.294779) (xy 430.533447 -300.338356) (xy 430.503882 -300.3777) (xy 430.468389 -300.411792)
			(xy 430.427886 -300.439748) (xy 430.383424 -300.460846) (xy 430.336153 -300.474538) (xy 430.287298 -300.48047)
			(xy 430.238123 -300.478489) (xy 430.189904 -300.468645) (xy 430.143888 -300.451193) (xy 430.101267 -300.426586)
			(xy 430.063146 -300.395461) (xy 430.030511 -300.358624) (xy 430.004208 -300.317028) (xy 429.984917 -300.271752)
			(xy 429.97314 -300.223968) (xy 429.96918 -300.174914) (xy 426.780198 -300.174914) (xy 426.779703 -300.199521)
			(xy 426.771808 -300.248098) (xy 426.756224 -300.294779) (xy 426.733353 -300.338356) (xy 426.703788 -300.3777)
			(xy 426.668295 -300.411792) (xy 426.627792 -300.439748) (xy 426.58333 -300.460846) (xy 426.536059 -300.474538)
			(xy 426.487204 -300.48047) (xy 426.438029 -300.478489) (xy 426.38981 -300.468645) (xy 426.343794 -300.451193)
			(xy 426.301173 -300.426586) (xy 426.263052 -300.395461) (xy 426.230417 -300.358624) (xy 426.204114 -300.317028)
			(xy 426.184823 -300.271752) (xy 426.173046 -300.223968) (xy 426.169086 -300.174914) (xy 425.830716 -300.174914)
			(xy 425.826551 -300.225206) (xy 425.814167 -300.274142) (xy 425.793901 -300.320374) (xy 425.766306 -300.362642)
			(xy 425.732134 -300.399796) (xy 425.692316 -300.430822) (xy 425.647937 -300.454875) (xy 425.600206 -300.4713)
			(xy 425.550423 -300.47965) (xy 425.525184 -300.480222) (xy 425.524422 -300.480222) (xy 425.510198 -300.479968)
			(xy 425.499784 -300.47946) (xy 425.490132 -300.48327) (xy 425.485452 -300.485189) (xy 425.476884 -300.490565)
			(xy 425.473114 -300.493938) (xy 425.419774 -300.544738) (xy 425.412653 -300.552162) (xy 425.404529 -300.571039)
			(xy 425.404026 -300.581314) (xy 425.404026 -301.124874) (xy 427.119046 -301.124874) (xy 427.123006 -301.07582)
			(xy 427.134783 -301.028036) (xy 427.154074 -300.98276) (xy 427.180377 -300.941164) (xy 427.213012 -300.904327)
			(xy 427.251133 -300.873202) (xy 427.293754 -300.848595) (xy 427.33977 -300.831143) (xy 427.387989 -300.821299)
			(xy 427.437164 -300.819318) (xy 427.486019 -300.82525) (xy 427.53329 -300.838942) (xy 427.577752 -300.86004)
			(xy 427.618255 -300.887996) (xy 427.653748 -300.922088) (xy 427.683313 -300.961432) (xy 427.706184 -301.005009)
			(xy 427.721768 -301.05169) (xy 427.729663 -301.100267) (xy 427.730158 -301.124874) (xy 428.069006 -301.124874)
			(xy 428.072966 -301.07582) (xy 428.084743 -301.028036) (xy 428.104034 -300.98276) (xy 428.130337 -300.941164)
			(xy 428.162972 -300.904327) (xy 428.201093 -300.873202) (xy 428.243714 -300.848595) (xy 428.28973 -300.831143)
			(xy 428.337949 -300.821299) (xy 428.387124 -300.819318) (xy 428.435979 -300.82525) (xy 428.48325 -300.838942)
			(xy 428.527712 -300.86004) (xy 428.568215 -300.887996) (xy 428.603708 -300.922088) (xy 428.633273 -300.961432)
			(xy 428.656144 -301.005009) (xy 428.671728 -301.05169) (xy 428.679623 -301.100267) (xy 428.680118 -301.124874)
			(xy 428.679623 -301.149481) (xy 428.671728 -301.198058) (xy 428.656144 -301.244739) (xy 428.633273 -301.288316)
			(xy 428.603708 -301.32766) (xy 428.568215 -301.361752) (xy 428.527712 -301.389708) (xy 428.48325 -301.410806)
			(xy 428.435979 -301.424498) (xy 428.387124 -301.43043) (xy 428.337949 -301.428449) (xy 428.28973 -301.418605)
			(xy 428.243714 -301.401153) (xy 428.201093 -301.376546) (xy 428.162972 -301.345421) (xy 428.130337 -301.308584)
			(xy 428.104034 -301.266988) (xy 428.084743 -301.221712) (xy 428.072966 -301.173928) (xy 428.069006 -301.124874)
			(xy 427.730158 -301.124874) (xy 427.729663 -301.149481) (xy 427.721768 -301.198058) (xy 427.706184 -301.244739)
			(xy 427.683313 -301.288316) (xy 427.653748 -301.32766) (xy 427.618255 -301.361752) (xy 427.577752 -301.389708)
			(xy 427.53329 -301.410806) (xy 427.486019 -301.424498) (xy 427.437164 -301.43043) (xy 427.387989 -301.428449)
			(xy 427.33977 -301.418605) (xy 427.293754 -301.401153) (xy 427.251133 -301.376546) (xy 427.213012 -301.345421)
			(xy 427.180377 -301.308584) (xy 427.154074 -301.266988) (xy 427.134783 -301.221712) (xy 427.123006 -301.173928)
			(xy 427.119046 -301.124874) (xy 425.404026 -301.124874) (xy 425.404026 -301.66818) (xy 425.404464 -301.678243)
			(xy 425.412202 -301.696824) (xy 425.419012 -301.704248) (xy 425.419266 -301.704502) (xy 425.47286 -301.75581)
			(xy 425.479965 -301.762057) (xy 425.497451 -301.769244) (xy 425.506896 -301.76978) (xy 425.510452 -301.76978)
			(xy 425.524422 -301.769526) (xy 425.525184 -301.769526) (xy 425.550421 -301.77007) (xy 425.600201 -301.778419)
			(xy 425.647929 -301.794843) (xy 425.692306 -301.818895) (xy 425.732121 -301.849919) (xy 425.76629 -301.88707)
			(xy 425.793883 -301.929336) (xy 425.814148 -301.975565) (xy 425.826531 -302.024497) (xy 425.830697 -302.0748)
			(xy 425.830694 -302.074834) (xy 426.169086 -302.074834) (xy 426.173046 -302.02578) (xy 426.184823 -301.977996)
			(xy 426.204114 -301.93272) (xy 426.230417 -301.891124) (xy 426.263052 -301.854287) (xy 426.301173 -301.823162)
			(xy 426.343794 -301.798555) (xy 426.38981 -301.781103) (xy 426.438029 -301.771259) (xy 426.487204 -301.769278)
			(xy 426.536059 -301.77521) (xy 426.58333 -301.788902) (xy 426.627792 -301.81) (xy 426.668295 -301.837956)
			(xy 426.703788 -301.872048) (xy 426.733353 -301.911392) (xy 426.756224 -301.954969) (xy 426.771808 -302.00165)
			(xy 426.779703 -302.050227) (xy 426.780198 -302.074834) (xy 429.96918 -302.074834) (xy 429.97314 -302.02578)
			(xy 429.984917 -301.977996) (xy 430.004208 -301.93272) (xy 430.030511 -301.891124) (xy 430.063146 -301.854287)
			(xy 430.101267 -301.823162) (xy 430.143888 -301.798555) (xy 430.189904 -301.781103) (xy 430.238123 -301.771259)
			(xy 430.287298 -301.769278) (xy 430.336153 -301.77521) (xy 430.383424 -301.788902) (xy 430.427886 -301.81)
			(xy 430.468389 -301.837956) (xy 430.503882 -301.872048) (xy 430.533447 -301.911392) (xy 430.556318 -301.954969)
			(xy 430.571902 -302.00165) (xy 430.579797 -302.050227) (xy 430.580292 -302.074834) (xy 430.91914 -302.074834)
			(xy 430.9231 -302.02578) (xy 430.934877 -301.977996) (xy 430.954168 -301.93272) (xy 430.980471 -301.891124)
			(xy 431.013106 -301.854287) (xy 431.051227 -301.823162) (xy 431.093848 -301.798555) (xy 431.139864 -301.781103)
			(xy 431.188083 -301.771259) (xy 431.237258 -301.769278) (xy 431.286113 -301.77521) (xy 431.333384 -301.788902)
			(xy 431.377846 -301.81) (xy 431.418349 -301.837956) (xy 431.453842 -301.872048) (xy 431.483407 -301.911392)
			(xy 431.506278 -301.954969) (xy 431.521862 -302.00165) (xy 431.529757 -302.050227) (xy 431.530252 -302.074834)
			(xy 431.529757 -302.099441) (xy 431.521862 -302.148018) (xy 431.506278 -302.194699) (xy 431.483407 -302.238276)
			(xy 431.453842 -302.27762) (xy 431.418349 -302.311712) (xy 431.377846 -302.339668) (xy 431.333384 -302.360766)
			(xy 431.286113 -302.374458) (xy 431.237258 -302.38039) (xy 431.188083 -302.378409) (xy 431.139864 -302.368565)
			(xy 431.093848 -302.351113) (xy 431.051227 -302.326506) (xy 431.013106 -302.295381) (xy 430.980471 -302.258544)
			(xy 430.954168 -302.216948) (xy 430.934877 -302.171672) (xy 430.9231 -302.123888) (xy 430.91914 -302.074834)
			(xy 430.580292 -302.074834) (xy 430.579797 -302.099441) (xy 430.571902 -302.148018) (xy 430.556318 -302.194699)
			(xy 430.533447 -302.238276) (xy 430.503882 -302.27762) (xy 430.468389 -302.311712) (xy 430.427886 -302.339668)
			(xy 430.383424 -302.360766) (xy 430.336153 -302.374458) (xy 430.287298 -302.38039) (xy 430.238123 -302.378409)
			(xy 430.189904 -302.368565) (xy 430.143888 -302.351113) (xy 430.101267 -302.326506) (xy 430.063146 -302.295381)
			(xy 430.030511 -302.258544) (xy 430.004208 -302.216948) (xy 429.984917 -302.171672) (xy 429.97314 -302.123888)
			(xy 429.96918 -302.074834) (xy 426.780198 -302.074834) (xy 426.779703 -302.099441) (xy 426.771808 -302.148018)
			(xy 426.756224 -302.194699) (xy 426.733353 -302.238276) (xy 426.703788 -302.27762) (xy 426.668295 -302.311712)
			(xy 426.627792 -302.339668) (xy 426.58333 -302.360766) (xy 426.536059 -302.374458) (xy 426.487204 -302.38039)
			(xy 426.438029 -302.378409) (xy 426.38981 -302.368565) (xy 426.343794 -302.351113) (xy 426.301173 -302.326506)
			(xy 426.263052 -302.295381) (xy 426.230417 -302.258544) (xy 426.204114 -302.216948) (xy 426.184823 -302.171672)
			(xy 426.173046 -302.123888) (xy 426.169086 -302.074834) (xy 425.830694 -302.074834) (xy 425.826531 -302.125103)
			(xy 425.814148 -302.174036) (xy 425.793883 -302.220264) (xy 425.76629 -302.26253) (xy 425.732121 -302.299681)
			(xy 425.692306 -302.330705) (xy 425.647929 -302.354757) (xy 425.600201 -302.371181) (xy 425.550421 -302.37953)
			(xy 425.525184 -302.380142) (xy 425.524422 -302.380142) (xy 425.510198 -302.379888) (xy 425.499784 -302.37938)
			(xy 425.490132 -302.38319) (xy 425.48545 -302.385106) (xy 425.476876 -302.390476) (xy 425.473114 -302.393858)
			(xy 425.419774 -302.444658) (xy 425.412657 -302.452083) (xy 425.40454 -302.47096) (xy 425.404026 -302.481234)
			(xy 425.404026 -303.024794) (xy 427.119046 -303.024794) (xy 427.123006 -302.97574) (xy 427.134783 -302.927956)
			(xy 427.154074 -302.88268) (xy 427.180377 -302.841084) (xy 427.213012 -302.804247) (xy 427.251133 -302.773122)
			(xy 427.293754 -302.748515) (xy 427.33977 -302.731063) (xy 427.387989 -302.721219) (xy 427.437164 -302.719238)
			(xy 427.486019 -302.72517) (xy 427.53329 -302.738862) (xy 427.577752 -302.75996) (xy 427.618255 -302.787916)
			(xy 427.653748 -302.822008) (xy 427.683313 -302.861352) (xy 427.706184 -302.904929) (xy 427.721768 -302.95161)
			(xy 427.729663 -303.000187) (xy 427.730158 -303.024794) (xy 428.069006 -303.024794) (xy 428.072966 -302.97574)
			(xy 428.084743 -302.927956) (xy 428.104034 -302.88268) (xy 428.130337 -302.841084) (xy 428.162972 -302.804247)
			(xy 428.201093 -302.773122) (xy 428.243714 -302.748515) (xy 428.28973 -302.731063) (xy 428.337949 -302.721219)
			(xy 428.387124 -302.719238) (xy 428.435979 -302.72517) (xy 428.48325 -302.738862) (xy 428.527712 -302.75996)
			(xy 428.568215 -302.787916) (xy 428.603708 -302.822008) (xy 428.633273 -302.861352) (xy 428.656144 -302.904929)
			(xy 428.671728 -302.95161) (xy 428.679623 -303.000187) (xy 428.680118 -303.024794) (xy 428.679623 -303.049401)
			(xy 428.671728 -303.097978) (xy 428.656144 -303.144659) (xy 428.633273 -303.188236) (xy 428.603708 -303.22758)
			(xy 428.568215 -303.261672) (xy 428.527712 -303.289628) (xy 428.48325 -303.310726) (xy 428.435979 -303.324418)
			(xy 428.387124 -303.33035) (xy 428.337949 -303.328369) (xy 428.28973 -303.318525) (xy 428.243714 -303.301073)
			(xy 428.201093 -303.276466) (xy 428.162972 -303.245341) (xy 428.130337 -303.208504) (xy 428.104034 -303.166908)
			(xy 428.084743 -303.121632) (xy 428.072966 -303.073848) (xy 428.069006 -303.024794) (xy 427.730158 -303.024794)
			(xy 427.729663 -303.049401) (xy 427.721768 -303.097978) (xy 427.706184 -303.144659) (xy 427.683313 -303.188236)
			(xy 427.653748 -303.22758) (xy 427.618255 -303.261672) (xy 427.577752 -303.289628) (xy 427.53329 -303.310726)
			(xy 427.486019 -303.324418) (xy 427.437164 -303.33035) (xy 427.387989 -303.328369) (xy 427.33977 -303.318525)
			(xy 427.293754 -303.301073) (xy 427.251133 -303.276466) (xy 427.213012 -303.245341) (xy 427.180377 -303.208504)
			(xy 427.154074 -303.166908) (xy 427.134783 -303.121632) (xy 427.123006 -303.073848) (xy 427.119046 -303.024794)
			(xy 425.404026 -303.024794) (xy 425.404026 -303.5681) (xy 425.40445 -303.57817) (xy 425.412167 -303.596772)
			(xy 425.419012 -303.604168) (xy 425.419266 -303.604422) (xy 425.47286 -303.65573) (xy 425.479966 -303.661975)
			(xy 425.497452 -303.669159) (xy 425.506896 -303.6697) (xy 425.510452 -303.6697) (xy 425.524422 -303.669446)
			(xy 425.525184 -303.669446) (xy 425.550428 -303.669989) (xy 425.600221 -303.678341) (xy 425.647962 -303.69477)
			(xy 425.69235 -303.718828) (xy 425.732175 -303.74986) (xy 425.766354 -303.787021) (xy 425.793954 -303.829297)
			(xy 425.814224 -303.875538) (xy 425.826611 -303.924484) (xy 425.830778 -303.9748) (xy 425.826611 -304.025116)
			(xy 425.814224 -304.074062) (xy 425.793954 -304.120303) (xy 425.766354 -304.162579) (xy 425.732175 -304.19974)
			(xy 425.69235 -304.230772) (xy 425.647962 -304.25483) (xy 425.600221 -304.271259) (xy 425.550428 -304.279611)
			(xy 425.525184 -304.280062) (xy 425.524422 -304.280062) (xy 425.510198 -304.279808) (xy 425.499784 -304.2793)
			(xy 425.490132 -304.28311) (xy 425.48545 -304.285027) (xy 425.476878 -304.290398) (xy 425.473114 -304.293778)
			(xy 425.419774 -304.344578) (xy 425.412644 -304.351998) (xy 425.404498 -304.370875) (xy 425.404026 -304.381154)
			(xy 425.404026 -304.475442) (xy 429.473356 -304.475442) (xy 429.473356 -304.424026) (xy 429.481399 -304.373244)
			(xy 429.497287 -304.324345) (xy 429.52063 -304.278533) (xy 429.550851 -304.236937) (xy 429.587207 -304.200581)
			(xy 429.628803 -304.17036) (xy 429.674615 -304.147017) (xy 429.723514 -304.131129) (xy 429.774296 -304.123086)
			(xy 429.825712 -304.123086) (xy 429.876494 -304.131129) (xy 429.925393 -304.147017) (xy 429.971205 -304.17036)
			(xy 430.012801 -304.200581) (xy 430.049157 -304.236937) (xy 430.079378 -304.278533) (xy 430.102721 -304.324345)
			(xy 430.118609 -304.373244) (xy 430.126652 -304.424026) (xy 430.127156 -304.449734) (xy 430.126652 -304.475442)
			(xy 430.423316 -304.475442) (xy 430.423316 -304.424026) (xy 430.431359 -304.373244) (xy 430.447247 -304.324345)
			(xy 430.47059 -304.278533) (xy 430.500811 -304.236937) (xy 430.537167 -304.200581) (xy 430.578763 -304.17036)
			(xy 430.624575 -304.147017) (xy 430.673474 -304.131129) (xy 430.724256 -304.123086) (xy 430.775672 -304.123086)
			(xy 430.826454 -304.131129) (xy 430.875353 -304.147017) (xy 430.921165 -304.17036) (xy 430.962761 -304.200581)
			(xy 430.999117 -304.236937) (xy 431.029338 -304.278533) (xy 431.052681 -304.324345) (xy 431.068569 -304.373244)
			(xy 431.076612 -304.424026) (xy 431.077116 -304.449734) (xy 431.076612 -304.475442) (xy 431.068569 -304.526224)
			(xy 431.052681 -304.575123) (xy 431.029338 -304.620935) (xy 430.999117 -304.662531) (xy 430.962761 -304.698887)
			(xy 430.921165 -304.729108) (xy 430.875353 -304.752451) (xy 430.826454 -304.768339) (xy 430.775672 -304.776382)
			(xy 430.724256 -304.776382) (xy 430.673474 -304.768339) (xy 430.624575 -304.752451) (xy 430.578763 -304.729108)
			(xy 430.537167 -304.698887) (xy 430.500811 -304.662531) (xy 430.47059 -304.620935) (xy 430.447247 -304.575123)
			(xy 430.431359 -304.526224) (xy 430.423316 -304.475442) (xy 430.126652 -304.475442) (xy 430.118609 -304.526224)
			(xy 430.102721 -304.575123) (xy 430.079378 -304.620935) (xy 430.049157 -304.662531) (xy 430.012801 -304.698887)
			(xy 429.971205 -304.729108) (xy 429.925393 -304.752451) (xy 429.876494 -304.768339) (xy 429.825712 -304.776382)
			(xy 429.774296 -304.776382) (xy 429.723514 -304.768339) (xy 429.674615 -304.752451) (xy 429.628803 -304.729108)
			(xy 429.587207 -304.698887) (xy 429.550851 -304.662531) (xy 429.52063 -304.620935) (xy 429.497287 -304.575123)
			(xy 429.481399 -304.526224) (xy 429.473356 -304.475442) (xy 425.404026 -304.475442) (xy 425.404026 -305.44262)
			(xy 425.404108 -305.446829) (xy 425.405516 -305.455127) (xy 425.40682 -305.45913) (xy 425.408733 -305.464344)
			(xy 425.414497 -305.473833) (xy 425.41825 -305.477926) (xy 425.450762 -305.509168) (xy 425.472606 -305.53025)
			(xy 425.476364 -305.533687) (xy 425.484935 -305.539185) (xy 425.489624 -305.541172) (xy 425.499276 -305.544728)
			(xy 425.509944 -305.54422) (xy 425.515024 -305.543966) (xy 425.515532 -305.543966) (xy 425.52493 -305.543712)
			(xy 425.57319 -305.543712) (xy 425.583911 -305.543285) (xy 425.603504 -305.534591) (xy 425.611036 -305.526948)
			(xy 425.661582 -305.471068) (xy 425.668254 -305.462921) (xy 425.674949 -305.442981) (xy 425.674536 -305.43246)
			(xy 425.674536 -305.432206) (xy 425.673012 -305.399948) (xy 425.673516 -305.37426) (xy 425.681553 -305.323517)
			(xy 425.697429 -305.274656) (xy 425.720753 -305.22888) (xy 425.75095 -305.187316) (xy 425.787278 -305.150988)
			(xy 425.828842 -305.120791) (xy 425.874618 -305.097467) (xy 425.923479 -305.081591) (xy 425.974222 -305.073554)
			(xy 426.025598 -305.073554) (xy 426.076341 -305.081591) (xy 426.125202 -305.097467) (xy 426.170978 -305.120791)
			(xy 426.212542 -305.150988) (xy 426.24887 -305.187316) (xy 426.279067 -305.22888) (xy 426.302391 -305.274656)
			(xy 426.318267 -305.323517) (xy 426.326304 -305.37426) (xy 426.326808 -305.399948) (xy 426.325584 -305.425656)
			(xy 427.573182 -305.425656) (xy 427.573182 -305.37424) (xy 427.581225 -305.323458) (xy 427.597113 -305.274559)
			(xy 427.620456 -305.228747) (xy 427.650677 -305.187151) (xy 427.687033 -305.150795) (xy 427.728629 -305.120574)
			(xy 427.774441 -305.097231) (xy 427.82334 -305.081343) (xy 427.874122 -305.0733) (xy 427.925538 -305.0733)
			(xy 427.97632 -305.081343) (xy 428.025219 -305.097231) (xy 428.071031 -305.120574) (xy 428.112627 -305.150795)
			(xy 428.148983 -305.187151) (xy 428.179204 -305.228747) (xy 428.202547 -305.274559) (xy 428.218435 -305.323458)
			(xy 428.226478 -305.37424) (xy 428.226982 -305.399948) (xy 428.226478 -305.425656) (xy 428.523142 -305.425656)
			(xy 428.523142 -305.37424) (xy 428.531185 -305.323458) (xy 428.547073 -305.274559) (xy 428.570416 -305.228747)
			(xy 428.600637 -305.187151) (xy 428.636993 -305.150795) (xy 428.678589 -305.120574) (xy 428.724401 -305.097231)
			(xy 428.7733 -305.081343) (xy 428.824082 -305.0733) (xy 428.875498 -305.0733) (xy 428.92628 -305.081343)
			(xy 428.975179 -305.097231) (xy 429.020991 -305.120574) (xy 429.062587 -305.150795) (xy 429.098943 -305.187151)
			(xy 429.129164 -305.228747) (xy 429.152507 -305.274559) (xy 429.168395 -305.323458) (xy 429.176438 -305.37424)
			(xy 429.176942 -305.399948) (xy 429.176438 -305.425656) (xy 429.168395 -305.476438) (xy 429.152507 -305.525337)
			(xy 429.129164 -305.571149) (xy 429.098943 -305.612745) (xy 429.062587 -305.649101) (xy 429.020991 -305.679322)
			(xy 428.975179 -305.702665) (xy 428.92628 -305.718553) (xy 428.875498 -305.726596) (xy 428.824082 -305.726596)
			(xy 428.7733 -305.718553) (xy 428.724401 -305.702665) (xy 428.678589 -305.679322) (xy 428.636993 -305.649101)
			(xy 428.600637 -305.612745) (xy 428.570416 -305.571149) (xy 428.547073 -305.525337) (xy 428.531185 -305.476438)
			(xy 428.523142 -305.425656) (xy 428.226478 -305.425656) (xy 428.218435 -305.476438) (xy 428.202547 -305.525337)
			(xy 428.179204 -305.571149) (xy 428.148983 -305.612745) (xy 428.112627 -305.649101) (xy 428.071031 -305.679322)
			(xy 428.025219 -305.702665) (xy 427.97632 -305.718553) (xy 427.925538 -305.726596) (xy 427.874122 -305.726596)
			(xy 427.82334 -305.718553) (xy 427.774441 -305.702665) (xy 427.728629 -305.679322) (xy 427.687033 -305.649101)
			(xy 427.650677 -305.612745) (xy 427.620456 -305.571149) (xy 427.597113 -305.525337) (xy 427.581225 -305.476438)
			(xy 427.573182 -305.425656) (xy 426.325584 -305.425656) (xy 426.325284 -305.431952) (xy 426.325284 -305.43246)
			(xy 426.324846 -305.442988) (xy 426.331526 -305.462947) (xy 426.338238 -305.471068) (xy 426.388784 -305.526948)
			(xy 426.396379 -305.534498) (xy 426.415935 -305.543169) (xy 426.42663 -305.543712) (xy 426.47489 -305.543712)
			(xy 426.500902 -305.544195) (xy 426.552285 -305.552332) (xy 426.601763 -305.568407) (xy 426.648117 -305.592024)
			(xy 426.690205 -305.622602) (xy 426.726992 -305.659387) (xy 426.757571 -305.701475) (xy 426.78119 -305.747828)
			(xy 426.797266 -305.797305) (xy 426.805404 -305.848688) (xy 426.805404 -305.900712) (xy 426.797266 -305.952095)
			(xy 426.78119 -306.001572) (xy 426.757571 -306.047925) (xy 426.726992 -306.090013) (xy 426.690205 -306.126798)
			(xy 426.648117 -306.157376) (xy 426.601763 -306.180993) (xy 426.552285 -306.197068) (xy 426.500902 -306.205205)
			(xy 426.47489 -306.205636) (xy 425.52493 -306.205636) (xy 425.51858 -306.205382) (xy 425.517564 -306.205382)
			(xy 425.509944 -306.205128) (xy 425.499276 -306.20462) (xy 425.489624 -306.208176) (xy 425.484904 -306.210106)
			(xy 425.476317 -306.215602) (xy 425.472606 -306.219098) (xy 425.419774 -306.269898) (xy 425.412647 -306.27732)
			(xy 425.404509 -306.296197) (xy 425.404026 -306.306474) (xy 425.404026 -306.375616) (xy 429.473356 -306.375616)
			(xy 429.473356 -306.3242) (xy 429.481399 -306.273418) (xy 429.497287 -306.224519) (xy 429.52063 -306.178707)
			(xy 429.550851 -306.137111) (xy 429.587207 -306.100755) (xy 429.628803 -306.070534) (xy 429.674615 -306.047191)
			(xy 429.723514 -306.031303) (xy 429.774296 -306.02326) (xy 429.825712 -306.02326) (xy 429.876494 -306.031303)
			(xy 429.925393 -306.047191) (xy 429.971205 -306.070534) (xy 430.012801 -306.100755) (xy 430.049157 -306.137111)
			(xy 430.079378 -306.178707) (xy 430.102721 -306.224519) (xy 430.118609 -306.273418) (xy 430.126652 -306.3242)
			(xy 430.127156 -306.349908) (xy 430.126652 -306.375616) (xy 430.423316 -306.375616) (xy 430.423316 -306.3242)
			(xy 430.431359 -306.273418) (xy 430.447247 -306.224519) (xy 430.47059 -306.178707) (xy 430.500811 -306.137111)
			(xy 430.537167 -306.100755) (xy 430.578763 -306.070534) (xy 430.624575 -306.047191) (xy 430.673474 -306.031303)
			(xy 430.724256 -306.02326) (xy 430.775672 -306.02326) (xy 430.826454 -306.031303) (xy 430.875353 -306.047191)
			(xy 430.921165 -306.070534) (xy 430.962761 -306.100755) (xy 430.999117 -306.137111) (xy 431.029338 -306.178707)
			(xy 431.052681 -306.224519) (xy 431.068569 -306.273418) (xy 431.076612 -306.3242) (xy 431.077116 -306.349908)
			(xy 431.076612 -306.375616) (xy 431.068569 -306.426398) (xy 431.052681 -306.475297) (xy 431.029338 -306.521109)
			(xy 430.999117 -306.562705) (xy 430.962761 -306.599061) (xy 430.921165 -306.629282) (xy 430.875353 -306.652625)
			(xy 430.826454 -306.668513) (xy 430.775672 -306.676556) (xy 430.724256 -306.676556) (xy 430.673474 -306.668513)
			(xy 430.624575 -306.652625) (xy 430.578763 -306.629282) (xy 430.537167 -306.599061) (xy 430.500811 -306.562705)
			(xy 430.47059 -306.521109) (xy 430.447247 -306.475297) (xy 430.431359 -306.426398) (xy 430.423316 -306.375616)
			(xy 430.126652 -306.375616) (xy 430.118609 -306.426398) (xy 430.102721 -306.475297) (xy 430.079378 -306.521109)
			(xy 430.049157 -306.562705) (xy 430.012801 -306.599061) (xy 429.971205 -306.629282) (xy 429.925393 -306.652625)
			(xy 429.876494 -306.668513) (xy 429.825712 -306.676556) (xy 429.774296 -306.676556) (xy 429.723514 -306.668513)
			(xy 429.674615 -306.652625) (xy 429.628803 -306.629282) (xy 429.587207 -306.599061) (xy 429.550851 -306.562705)
			(xy 429.52063 -306.521109) (xy 429.497287 -306.475297) (xy 429.481399 -306.426398) (xy 429.473356 -306.375616)
			(xy 425.404026 -306.375616) (xy 425.404026 -307.34254) (xy 425.40411 -307.346748) (xy 425.405521 -307.355046)
			(xy 425.40682 -307.35905) (xy 425.408734 -307.364263) (xy 425.414501 -307.37375) (xy 425.41825 -307.377846)
			(xy 425.450762 -307.409088) (xy 425.472606 -307.43017) (xy 425.476365 -307.433606) (xy 425.484936 -307.439102)
			(xy 425.489624 -307.441092) (xy 425.499276 -307.444648) (xy 425.509944 -307.44414) (xy 425.515024 -307.443886)
			(xy 425.515532 -307.443886) (xy 425.52493 -307.443632) (xy 425.57319 -307.443632) (xy 425.583911 -307.443206)
			(xy 425.603507 -307.434514) (xy 425.611036 -307.426868) (xy 425.661582 -307.370988) (xy 425.668257 -307.362842)
			(xy 425.67496 -307.342902) (xy 425.674536 -307.33238) (xy 425.674536 -307.332126) (xy 425.673012 -307.299868)
			(xy 425.673516 -307.27418) (xy 425.681553 -307.223437) (xy 425.697429 -307.174576) (xy 425.720753 -307.1288)
			(xy 425.75095 -307.087236) (xy 425.787278 -307.050908) (xy 425.828842 -307.020711) (xy 425.874618 -306.997387)
			(xy 425.923479 -306.981511) (xy 425.974222 -306.973474) (xy 426.025598 -306.973474) (xy 426.076341 -306.981511)
			(xy 426.125202 -306.997387) (xy 426.170978 -307.020711) (xy 426.212542 -307.050908) (xy 426.24887 -307.087236)
			(xy 426.279067 -307.1288) (xy 426.302391 -307.174576) (xy 426.318267 -307.223437) (xy 426.326304 -307.27418)
			(xy 426.326808 -307.299868) (xy 426.325584 -307.325576) (xy 427.573182 -307.325576) (xy 427.573182 -307.27416)
			(xy 427.581225 -307.223378) (xy 427.597113 -307.174479) (xy 427.620456 -307.128667) (xy 427.650677 -307.087071)
			(xy 427.687033 -307.050715) (xy 427.728629 -307.020494) (xy 427.774441 -306.997151) (xy 427.82334 -306.981263)
			(xy 427.874122 -306.97322) (xy 427.925538 -306.97322) (xy 427.97632 -306.981263) (xy 428.025219 -306.997151)
			(xy 428.071031 -307.020494) (xy 428.112627 -307.050715) (xy 428.148983 -307.087071) (xy 428.179204 -307.128667)
			(xy 428.202547 -307.174479) (xy 428.218435 -307.223378) (xy 428.226478 -307.27416) (xy 428.226982 -307.299868)
			(xy 428.226478 -307.325576) (xy 428.523142 -307.325576) (xy 428.523142 -307.27416) (xy 428.531185 -307.223378)
			(xy 428.547073 -307.174479) (xy 428.570416 -307.128667) (xy 428.600637 -307.087071) (xy 428.636993 -307.050715)
			(xy 428.678589 -307.020494) (xy 428.724401 -306.997151) (xy 428.7733 -306.981263) (xy 428.824082 -306.97322)
			(xy 428.875498 -306.97322) (xy 428.92628 -306.981263) (xy 428.975179 -306.997151) (xy 429.020991 -307.020494)
			(xy 429.062587 -307.050715) (xy 429.098943 -307.087071) (xy 429.129164 -307.128667) (xy 429.152507 -307.174479)
			(xy 429.168395 -307.223378) (xy 429.176438 -307.27416) (xy 429.176942 -307.299868) (xy 429.176438 -307.325576)
			(xy 429.168395 -307.376358) (xy 429.152507 -307.425257) (xy 429.129164 -307.471069) (xy 429.098943 -307.512665)
			(xy 429.062587 -307.549021) (xy 429.020991 -307.579242) (xy 428.975179 -307.602585) (xy 428.92628 -307.618473)
			(xy 428.875498 -307.626516) (xy 428.824082 -307.626516) (xy 428.7733 -307.618473) (xy 428.724401 -307.602585)
			(xy 428.678589 -307.579242) (xy 428.636993 -307.549021) (xy 428.600637 -307.512665) (xy 428.570416 -307.471069)
			(xy 428.547073 -307.425257) (xy 428.531185 -307.376358) (xy 428.523142 -307.325576) (xy 428.226478 -307.325576)
			(xy 428.218435 -307.376358) (xy 428.202547 -307.425257) (xy 428.179204 -307.471069) (xy 428.148983 -307.512665)
			(xy 428.112627 -307.549021) (xy 428.071031 -307.579242) (xy 428.025219 -307.602585) (xy 427.97632 -307.618473)
			(xy 427.925538 -307.626516) (xy 427.874122 -307.626516) (xy 427.82334 -307.618473) (xy 427.774441 -307.602585)
			(xy 427.728629 -307.579242) (xy 427.687033 -307.549021) (xy 427.650677 -307.512665) (xy 427.620456 -307.471069)
			(xy 427.597113 -307.425257) (xy 427.581225 -307.376358) (xy 427.573182 -307.325576) (xy 426.325584 -307.325576)
			(xy 426.325284 -307.331872) (xy 426.325284 -307.33238) (xy 426.32485 -307.342907) (xy 426.331536 -307.36286)
			(xy 426.338238 -307.370988) (xy 426.388784 -307.426868) (xy 426.39638 -307.434416) (xy 426.415936 -307.443083)
			(xy 426.42663 -307.443632) (xy 426.47489 -307.443632) (xy 426.5009 -307.444115) (xy 426.55228 -307.452251)
			(xy 426.601755 -307.468325) (xy 426.648106 -307.491941) (xy 426.690192 -307.522517) (xy 426.726977 -307.5593)
			(xy 426.757554 -307.601385) (xy 426.781171 -307.647736) (xy 426.797247 -307.69721) (xy 426.805385 -307.74859)
			(xy 426.805385 -307.80061) (xy 426.797247 -307.85199) (xy 426.781171 -307.901464) (xy 426.757554 -307.947815)
			(xy 426.726977 -307.9899) (xy 426.690192 -308.026683) (xy 426.648106 -308.057259) (xy 426.601755 -308.080875)
			(xy 426.55228 -308.096949) (xy 426.5009 -308.105085) (xy 426.47489 -308.105556) (xy 425.52493 -308.105556)
			(xy 425.51858 -308.105302) (xy 425.517564 -308.105302) (xy 425.509944 -308.105048) (xy 425.499276 -308.10454)
			(xy 425.489624 -308.108096) (xy 425.484905 -308.110027) (xy 425.476319 -308.115524) (xy 425.472606 -308.119018)
			(xy 425.419774 -308.169818) (xy 425.41265 -308.177241) (xy 425.404519 -308.196118) (xy 425.404026 -308.206394)
			(xy 425.404026 -308.275536) (xy 429.473356 -308.275536) (xy 429.473356 -308.22412) (xy 429.481399 -308.173338)
			(xy 429.497287 -308.124439) (xy 429.52063 -308.078627) (xy 429.550851 -308.037031) (xy 429.587207 -308.000675)
			(xy 429.628803 -307.970454) (xy 429.674615 -307.947111) (xy 429.723514 -307.931223) (xy 429.774296 -307.92318)
			(xy 429.825712 -307.92318) (xy 429.876494 -307.931223) (xy 429.925393 -307.947111) (xy 429.971205 -307.970454)
			(xy 430.012801 -308.000675) (xy 430.049157 -308.037031) (xy 430.079378 -308.078627) (xy 430.102721 -308.124439)
			(xy 430.118609 -308.173338) (xy 430.126652 -308.22412) (xy 430.127156 -308.249828) (xy 430.126652 -308.275536)
			(xy 430.423316 -308.275536) (xy 430.423316 -308.22412) (xy 430.431359 -308.173338) (xy 430.447247 -308.124439)
			(xy 430.47059 -308.078627) (xy 430.500811 -308.037031) (xy 430.537167 -308.000675) (xy 430.578763 -307.970454)
			(xy 430.624575 -307.947111) (xy 430.673474 -307.931223) (xy 430.724256 -307.92318) (xy 430.775672 -307.92318)
			(xy 430.826454 -307.931223) (xy 430.875353 -307.947111) (xy 430.921165 -307.970454) (xy 430.962761 -308.000675)
			(xy 430.999117 -308.037031) (xy 431.029338 -308.078627) (xy 431.052681 -308.124439) (xy 431.068569 -308.173338)
			(xy 431.076612 -308.22412) (xy 431.077116 -308.249828) (xy 431.076612 -308.275536) (xy 431.068569 -308.326318)
			(xy 431.052681 -308.375217) (xy 431.029338 -308.421029) (xy 430.999117 -308.462625) (xy 430.962761 -308.498981)
			(xy 430.921165 -308.529202) (xy 430.875353 -308.552545) (xy 430.826454 -308.568433) (xy 430.775672 -308.576476)
			(xy 430.724256 -308.576476) (xy 430.673474 -308.568433) (xy 430.624575 -308.552545) (xy 430.578763 -308.529202)
			(xy 430.537167 -308.498981) (xy 430.500811 -308.462625) (xy 430.47059 -308.421029) (xy 430.447247 -308.375217)
			(xy 430.431359 -308.326318) (xy 430.423316 -308.275536) (xy 430.126652 -308.275536) (xy 430.118609 -308.326318)
			(xy 430.102721 -308.375217) (xy 430.079378 -308.421029) (xy 430.049157 -308.462625) (xy 430.012801 -308.498981)
			(xy 429.971205 -308.529202) (xy 429.925393 -308.552545) (xy 429.876494 -308.568433) (xy 429.825712 -308.576476)
			(xy 429.774296 -308.576476) (xy 429.723514 -308.568433) (xy 429.674615 -308.552545) (xy 429.628803 -308.529202)
			(xy 429.587207 -308.498981) (xy 429.550851 -308.462625) (xy 429.52063 -308.421029) (xy 429.497287 -308.375217)
			(xy 429.481399 -308.326318) (xy 429.473356 -308.275536) (xy 425.404026 -308.275536) (xy 425.404026 -309.242714)
			(xy 425.404108 -309.246923) (xy 425.405515 -309.255222) (xy 425.40682 -309.259224) (xy 425.408732 -309.264438)
			(xy 425.414495 -309.273928) (xy 425.41825 -309.27802) (xy 425.45381 -309.31231) (xy 425.472606 -309.330344)
			(xy 425.476346 -309.333758) (xy 425.484919 -309.339141) (xy 425.489624 -309.341012) (xy 425.499276 -309.344822)
			(xy 425.509944 -309.344314) (xy 425.524676 -309.34406) (xy 425.573444 -309.34406) (xy 425.584168 -309.343641)
			(xy 425.603769 -309.334952) (xy 425.61129 -309.327296) (xy 425.661582 -309.27167) (xy 425.668304 -309.263405)
			(xy 425.674978 -309.2432) (xy 425.674536 -309.232554) (xy 425.674536 -309.2323) (xy 425.673012 -309.199788)
			(xy 425.673516 -309.1741) (xy 425.681553 -309.123357) (xy 425.697429 -309.074496) (xy 425.720753 -309.02872)
			(xy 425.75095 -308.987156) (xy 425.787278 -308.950828) (xy 425.828842 -308.920631) (xy 425.874618 -308.897307)
			(xy 425.923479 -308.881431) (xy 425.974222 -308.873394) (xy 426.025598 -308.873394) (xy 426.076341 -308.881431)
			(xy 426.125202 -308.897307) (xy 426.170978 -308.920631) (xy 426.212542 -308.950828) (xy 426.24887 -308.987156)
			(xy 426.279067 -309.02872) (xy 426.302391 -309.074496) (xy 426.318267 -309.123357) (xy 426.326304 -309.1741)
			(xy 426.326808 -309.199788) (xy 426.325603 -309.225496) (xy 427.573182 -309.225496) (xy 427.573182 -309.17408)
			(xy 427.581225 -309.123298) (xy 427.597113 -309.074399) (xy 427.620456 -309.028587) (xy 427.650677 -308.986991)
			(xy 427.687033 -308.950635) (xy 427.728629 -308.920414) (xy 427.774441 -308.897071) (xy 427.82334 -308.881183)
			(xy 427.874122 -308.87314) (xy 427.925538 -308.87314) (xy 427.97632 -308.881183) (xy 428.025219 -308.897071)
			(xy 428.071031 -308.920414) (xy 428.112627 -308.950635) (xy 428.148983 -308.986991) (xy 428.179204 -309.028587)
			(xy 428.202547 -309.074399) (xy 428.218435 -309.123298) (xy 428.226478 -309.17408) (xy 428.226982 -309.199788)
			(xy 428.226478 -309.225496) (xy 428.523142 -309.225496) (xy 428.523142 -309.17408) (xy 428.531185 -309.123298)
			(xy 428.547073 -309.074399) (xy 428.570416 -309.028587) (xy 428.600637 -308.986991) (xy 428.636993 -308.950635)
			(xy 428.678589 -308.920414) (xy 428.724401 -308.897071) (xy 428.7733 -308.881183) (xy 428.824082 -308.87314)
			(xy 428.875498 -308.87314) (xy 428.92628 -308.881183) (xy 428.975179 -308.897071) (xy 429.020991 -308.920414)
			(xy 429.062587 -308.950635) (xy 429.098943 -308.986991) (xy 429.129164 -309.028587) (xy 429.152507 -309.074399)
			(xy 429.168395 -309.123298) (xy 429.176438 -309.17408) (xy 429.176942 -309.199788) (xy 429.176438 -309.225496)
			(xy 429.168395 -309.276278) (xy 429.152507 -309.325177) (xy 429.129164 -309.370989) (xy 429.098943 -309.412585)
			(xy 429.062587 -309.448941) (xy 429.020991 -309.479162) (xy 428.975179 -309.502505) (xy 428.92628 -309.518393)
			(xy 428.875498 -309.526436) (xy 428.824082 -309.526436) (xy 428.7733 -309.518393) (xy 428.724401 -309.502505)
			(xy 428.678589 -309.479162) (xy 428.636993 -309.448941) (xy 428.600637 -309.412585) (xy 428.570416 -309.370989)
			(xy 428.547073 -309.325177) (xy 428.531185 -309.276278) (xy 428.523142 -309.225496) (xy 428.226478 -309.225496)
			(xy 428.218435 -309.276278) (xy 428.202547 -309.325177) (xy 428.179204 -309.370989) (xy 428.148983 -309.412585)
			(xy 428.112627 -309.448941) (xy 428.071031 -309.479162) (xy 428.025219 -309.502505) (xy 427.97632 -309.518393)
			(xy 427.925538 -309.526436) (xy 427.874122 -309.526436) (xy 427.82334 -309.518393) (xy 427.774441 -309.502505)
			(xy 427.728629 -309.479162) (xy 427.687033 -309.448941) (xy 427.650677 -309.412585) (xy 427.620456 -309.370989)
			(xy 427.597113 -309.325177) (xy 427.581225 -309.276278) (xy 427.573182 -309.225496) (xy 426.325603 -309.225496)
			(xy 426.325284 -309.2323) (xy 426.325284 -309.232554) (xy 426.324673 -309.243219) (xy 426.331381 -309.26348)
			(xy 426.338238 -309.27167) (xy 426.38853 -309.327296) (xy 426.396131 -309.334833) (xy 426.415686 -309.343478)
			(xy 426.426376 -309.34406) (xy 426.47489 -309.34406) (xy 426.500882 -309.344542) (xy 426.552227 -309.352673)
			(xy 426.601668 -309.368736) (xy 426.647987 -309.392336) (xy 426.690044 -309.422891) (xy 426.726803 -309.459649)
			(xy 426.757359 -309.501705) (xy 426.78096 -309.548023) (xy 426.797024 -309.597463) (xy 426.805157 -309.648808)
			(xy 426.805157 -309.700792) (xy 426.797024 -309.752137) (xy 426.78096 -309.801577) (xy 426.757359 -309.847895)
			(xy 426.726803 -309.889951) (xy 426.690044 -309.926709) (xy 426.647987 -309.957264) (xy 426.601668 -309.980864)
			(xy 426.552227 -309.996927) (xy 426.500882 -310.005058) (xy 426.47489 -310.005476) (xy 425.525184 -310.005476)
			(xy 425.524676 -310.005476) (xy 425.509944 -310.005222) (xy 425.499276 -310.004714) (xy 425.489624 -310.00827)
			(xy 425.484907 -310.010203) (xy 425.476327 -310.015707) (xy 425.472606 -310.019192) (xy 425.419774 -310.069992)
			(xy 425.412646 -310.077413) (xy 425.404505 -310.09629) (xy 425.404026 -310.106568) (xy 425.404026 -310.175456)
			(xy 429.473356 -310.175456) (xy 429.473356 -310.12404) (xy 429.481399 -310.073258) (xy 429.497287 -310.024359)
			(xy 429.52063 -309.978547) (xy 429.550851 -309.936951) (xy 429.587207 -309.900595) (xy 429.628803 -309.870374)
			(xy 429.674615 -309.847031) (xy 429.723514 -309.831143) (xy 429.774296 -309.8231) (xy 429.825712 -309.8231)
			(xy 429.876494 -309.831143) (xy 429.925393 -309.847031) (xy 429.971205 -309.870374) (xy 430.012801 -309.900595)
			(xy 430.049157 -309.936951) (xy 430.079378 -309.978547) (xy 430.102721 -310.024359) (xy 430.118609 -310.073258)
			(xy 430.126652 -310.12404) (xy 430.127156 -310.149748) (xy 430.126652 -310.175456) (xy 430.423316 -310.175456)
			(xy 430.423316 -310.12404) (xy 430.431359 -310.073258) (xy 430.447247 -310.024359) (xy 430.47059 -309.978547)
			(xy 430.500811 -309.936951) (xy 430.537167 -309.900595) (xy 430.578763 -309.870374) (xy 430.624575 -309.847031)
			(xy 430.673474 -309.831143) (xy 430.724256 -309.8231) (xy 430.775672 -309.8231) (xy 430.826454 -309.831143)
			(xy 430.875353 -309.847031) (xy 430.921165 -309.870374) (xy 430.962761 -309.900595) (xy 430.999117 -309.936951)
			(xy 431.029338 -309.978547) (xy 431.052681 -310.024359) (xy 431.068569 -310.073258) (xy 431.076612 -310.12404)
			(xy 431.077116 -310.149748) (xy 431.076612 -310.175456) (xy 431.068569 -310.226238) (xy 431.052681 -310.275137)
			(xy 431.029338 -310.320949) (xy 430.999117 -310.362545) (xy 430.962761 -310.398901) (xy 430.921165 -310.429122)
			(xy 430.875353 -310.452465) (xy 430.826454 -310.468353) (xy 430.775672 -310.476396) (xy 430.724256 -310.476396)
			(xy 430.673474 -310.468353) (xy 430.624575 -310.452465) (xy 430.578763 -310.429122) (xy 430.537167 -310.398901)
			(xy 430.500811 -310.362545) (xy 430.47059 -310.320949) (xy 430.447247 -310.275137) (xy 430.431359 -310.226238)
			(xy 430.423316 -310.175456) (xy 430.126652 -310.175456) (xy 430.118609 -310.226238) (xy 430.102721 -310.275137)
			(xy 430.079378 -310.320949) (xy 430.049157 -310.362545) (xy 430.012801 -310.398901) (xy 429.971205 -310.429122)
			(xy 429.925393 -310.452465) (xy 429.876494 -310.468353) (xy 429.825712 -310.476396) (xy 429.774296 -310.476396)
			(xy 429.723514 -310.468353) (xy 429.674615 -310.452465) (xy 429.628803 -310.429122) (xy 429.587207 -310.398901)
			(xy 429.550851 -310.362545) (xy 429.52063 -310.320949) (xy 429.497287 -310.275137) (xy 429.481399 -310.226238)
			(xy 429.473356 -310.175456) (xy 425.404026 -310.175456) (xy 425.404026 -310.632938) (xy 427.11923 -310.632938)
			(xy 427.121924 -310.583378) (xy 427.1326 -310.534907) (xy 427.150977 -310.488802) (xy 427.176571 -310.446277)
			(xy 427.208708 -310.408453) (xy 427.24654 -310.376326) (xy 427.289072 -310.350743) (xy 427.335182 -310.332377)
			(xy 427.383655 -310.321713) (xy 427.433216 -310.319032) (xy 427.482557 -310.324404) (xy 427.530379 -310.337687)
			(xy 427.575422 -310.358533) (xy 427.6165 -310.38639) (xy 427.65253 -310.420527) (xy 427.682562 -310.460042)
			(xy 427.705806 -310.503896) (xy 427.72165 -310.550932) (xy 427.729675 -310.599912) (xy 427.730158 -310.624728)
			(xy 427.730158 -310.624982) (xy 427.730082 -310.634789) (xy 427.728808 -310.654363) (xy 427.727618 -310.664098)
			(xy 427.726186 -310.677618) (xy 427.729885 -310.704549) (xy 427.740551 -310.729552) (xy 427.75743 -310.75086)
			(xy 427.779329 -310.766965) (xy 427.804699 -310.776728) (xy 427.831744 -310.779459) (xy 427.84522 -310.777636)
			(xy 427.858707 -310.775496) (xy 427.885921 -310.773203) (xy 427.899576 -310.773064) (xy 427.89983 -310.773064)
			(xy 427.925518 -310.773612) (xy 427.976259 -310.781654) (xy 428.025119 -310.797534) (xy 428.070892 -310.820862)
			(xy 428.112453 -310.851064) (xy 428.148777 -310.887395) (xy 428.178971 -310.928961) (xy 428.20229 -310.974739)
			(xy 428.218161 -311.023602) (xy 428.226193 -311.074345) (xy 428.226188 -311.12572) (xy 428.218146 -311.176462)
			(xy 428.202265 -311.225321) (xy 428.178936 -311.271094) (xy 428.148735 -311.312655) (xy 428.112403 -311.348979)
			(xy 428.070836 -311.379172) (xy 428.025058 -311.402491) (xy 427.976196 -311.418362) (xy 427.925452 -311.426393)
			(xy 427.874077 -311.426387) (xy 427.823335 -311.418345) (xy 427.774476 -311.402464) (xy 427.728703 -311.379135)
			(xy 427.687143 -311.348933) (xy 427.65082 -311.312601) (xy 427.620627 -311.271034) (xy 427.597308 -311.225256)
			(xy 427.581438 -311.176393) (xy 427.573407 -311.12565) (xy 427.572932 -311.099962) (xy 427.572932 -311.099708)
			(xy 427.573084 -311.086053) (xy 427.575374 -311.05884) (xy 427.577504 -311.045352) (xy 427.579384 -311.031877)
			(xy 427.576757 -311.004807) (xy 427.567068 -310.979395) (xy 427.551005 -310.957449) (xy 427.529711 -310.94053)
			(xy 427.504703 -310.929842) (xy 427.477758 -310.926147) (xy 427.46422 -310.927496) (xy 427.454484 -310.928679)
			(xy 427.434911 -310.929949) (xy 427.425104 -310.930036) (xy 427.42485 -310.930036) (xy 427.400034 -310.929468)
			(xy 427.351056 -310.921431) (xy 427.304024 -310.905575) (xy 427.260176 -310.88232) (xy 427.220668 -310.852277)
			(xy 427.186541 -310.816239) (xy 427.158694 -310.775154) (xy 427.137861 -310.730106) (xy 427.124589 -310.68228)
			(xy 427.11923 -310.632938) (xy 425.404026 -310.632938) (xy 425.404026 -310.663844) (xy 425.403596 -310.673911)
			(xy 425.395873 -310.692507) (xy 425.38904 -310.699912) (xy 424.963513 -311.12567) (xy 425.673262 -311.12567)
			(xy 425.673262 -311.074254) (xy 425.681305 -311.023472) (xy 425.697193 -310.974573) (xy 425.720536 -310.928761)
			(xy 425.750757 -310.887165) (xy 425.787113 -310.850809) (xy 425.828709 -310.820588) (xy 425.874521 -310.797245)
			(xy 425.92342 -310.781357) (xy 425.974202 -310.773314) (xy 426.025618 -310.773314) (xy 426.0764 -310.781357)
			(xy 426.125299 -310.797245) (xy 426.171111 -310.820588) (xy 426.212707 -310.850809) (xy 426.249063 -310.887165)
			(xy 426.279284 -310.928761) (xy 426.302627 -310.974573) (xy 426.318515 -311.023472) (xy 426.326558 -311.074254)
			(xy 426.327062 -311.099962) (xy 426.326558 -311.12567) (xy 426.318515 -311.176452) (xy 426.302627 -311.225351)
			(xy 426.279284 -311.271163) (xy 426.249063 -311.312759) (xy 426.212707 -311.349115) (xy 426.171111 -311.379336)
			(xy 426.125299 -311.402679) (xy 426.0764 -311.418567) (xy 426.025618 -311.42661) (xy 425.974202 -311.42661)
			(xy 425.92342 -311.418567) (xy 425.874521 -311.402679) (xy 425.828709 -311.379336) (xy 425.787113 -311.349115)
			(xy 425.750757 -311.312759) (xy 425.720536 -311.271163) (xy 425.697193 -311.225351) (xy 425.681305 -311.176452)
			(xy 425.673262 -311.12567) (xy 424.963513 -311.12567) (xy 424.920664 -311.168542) (xy 424.917768 -311.171605)
			(xy 424.912915 -311.178497) (xy 424.911012 -311.182258) (xy 424.908667 -311.18748) (xy 424.9061 -311.198634)
			(xy 424.905932 -311.204356) (xy 424.905932 -311.574688) (xy 424.905471 -311.599443) (xy 424.898095 -311.648399)
			(xy 424.883505 -311.695709) (xy 424.862028 -311.740318) (xy 424.834144 -311.781227) (xy 424.800474 -311.817524)
			(xy 424.761771 -311.848399) (xy 424.740578 -311.8612) (xy 424.715207 -311.875084) (xy 424.660845 -311.894804)
			(xy 424.603885 -311.904787) (xy 424.57497 -311.905396) (xy 424.565616 -311.905355) (xy 424.546935 -311.904341)
			(xy 424.537632 -311.903364) (xy 424.526202 -311.902094) (xy 424.504358 -311.90946) (xy 424.439842 -311.973722)
			(xy 424.432218 -311.98215) (xy 424.424567 -312.003518) (xy 424.42511 -312.01487) (xy 424.42511 -312.015124)
			(xy 424.426888 -312.049922) (xy 424.426383 -312.075608) (xy 424.42638 -312.07563) (xy 425.673262 -312.07563)
			(xy 425.673262 -312.024214) (xy 425.681305 -311.973432) (xy 425.697193 -311.924533) (xy 425.720536 -311.878721)
			(xy 425.750757 -311.837125) (xy 425.787113 -311.800769) (xy 425.828709 -311.770548) (xy 425.874521 -311.747205)
			(xy 425.92342 -311.731317) (xy 425.974202 -311.723274) (xy 426.025618 -311.723274) (xy 426.0764 -311.731317)
			(xy 426.125299 -311.747205) (xy 426.171111 -311.770548) (xy 426.212707 -311.800769) (xy 426.249063 -311.837125)
			(xy 426.279284 -311.878721) (xy 426.302627 -311.924533) (xy 426.318515 -311.973432) (xy 426.326558 -312.024214)
			(xy 426.327062 -312.049922) (xy 426.326558 -312.07563) (xy 427.573182 -312.07563) (xy 427.573182 -312.024214)
			(xy 427.581225 -311.973432) (xy 427.597113 -311.924533) (xy 427.620456 -311.878721) (xy 427.650677 -311.837125)
			(xy 427.687033 -311.800769) (xy 427.728629 -311.770548) (xy 427.774441 -311.747205) (xy 427.82334 -311.731317)
			(xy 427.874122 -311.723274) (xy 427.925538 -311.723274) (xy 427.97632 -311.731317) (xy 428.025219 -311.747205)
			(xy 428.071031 -311.770548) (xy 428.112627 -311.800769) (xy 428.148983 -311.837125) (xy 428.179204 -311.878721)
			(xy 428.202547 -311.924533) (xy 428.218435 -311.973432) (xy 428.226478 -312.024214) (xy 428.226982 -312.049922)
			(xy 428.226478 -312.07563) (xy 429.473356 -312.07563) (xy 429.473356 -312.024214) (xy 429.481399 -311.973432)
			(xy 429.497287 -311.924533) (xy 429.52063 -311.878721) (xy 429.550851 -311.837125) (xy 429.587207 -311.800769)
			(xy 429.628803 -311.770548) (xy 429.674615 -311.747205) (xy 429.723514 -311.731317) (xy 429.774296 -311.723274)
			(xy 429.825712 -311.723274) (xy 429.876494 -311.731317) (xy 429.925393 -311.747205) (xy 429.971205 -311.770548)
			(xy 430.012801 -311.800769) (xy 430.049157 -311.837125) (xy 430.079378 -311.878721) (xy 430.102721 -311.924533)
			(xy 430.118609 -311.973432) (xy 430.126652 -312.024214) (xy 430.127156 -312.049922) (xy 430.126652 -312.07563)
			(xy 430.423316 -312.07563) (xy 430.423316 -312.024214) (xy 430.431359 -311.973432) (xy 430.447247 -311.924533)
			(xy 430.47059 -311.878721) (xy 430.500811 -311.837125) (xy 430.537167 -311.800769) (xy 430.578763 -311.770548)
			(xy 430.624575 -311.747205) (xy 430.673474 -311.731317) (xy 430.724256 -311.723274) (xy 430.775672 -311.723274)
			(xy 430.826454 -311.731317) (xy 430.875353 -311.747205) (xy 430.921165 -311.770548) (xy 430.962761 -311.800769)
			(xy 430.999117 -311.837125) (xy 431.029338 -311.878721) (xy 431.052681 -311.924533) (xy 431.068569 -311.973432)
			(xy 431.076612 -312.024214) (xy 431.077116 -312.049922) (xy 431.076612 -312.07563) (xy 431.068569 -312.126412)
			(xy 431.052681 -312.175311) (xy 431.029338 -312.221123) (xy 430.999117 -312.262719) (xy 430.962761 -312.299075)
			(xy 430.921165 -312.329296) (xy 430.875353 -312.352639) (xy 430.826454 -312.368527) (xy 430.775672 -312.37657)
			(xy 430.724256 -312.37657) (xy 430.673474 -312.368527) (xy 430.624575 -312.352639) (xy 430.578763 -312.329296)
			(xy 430.537167 -312.299075) (xy 430.500811 -312.262719) (xy 430.47059 -312.221123) (xy 430.447247 -312.175311)
			(xy 430.431359 -312.126412) (xy 430.423316 -312.07563) (xy 430.126652 -312.07563) (xy 430.118609 -312.126412)
			(xy 430.102721 -312.175311) (xy 430.079378 -312.221123) (xy 430.049157 -312.262719) (xy 430.012801 -312.299075)
			(xy 429.971205 -312.329296) (xy 429.925393 -312.352639) (xy 429.876494 -312.368527) (xy 429.825712 -312.37657)
			(xy 429.774296 -312.37657) (xy 429.723514 -312.368527) (xy 429.674615 -312.352639) (xy 429.628803 -312.329296)
			(xy 429.587207 -312.299075) (xy 429.550851 -312.262719) (xy 429.52063 -312.221123) (xy 429.497287 -312.175311)
			(xy 429.481399 -312.126412) (xy 429.473356 -312.07563) (xy 428.226478 -312.07563) (xy 428.218435 -312.126412)
			(xy 428.202547 -312.175311) (xy 428.179204 -312.221123) (xy 428.148983 -312.262719) (xy 428.112627 -312.299075)
			(xy 428.071031 -312.329296) (xy 428.025219 -312.352639) (xy 427.97632 -312.368527) (xy 427.925538 -312.37657)
			(xy 427.874122 -312.37657) (xy 427.82334 -312.368527) (xy 427.774441 -312.352639) (xy 427.728629 -312.329296)
			(xy 427.687033 -312.299075) (xy 427.650677 -312.262719) (xy 427.620456 -312.221123) (xy 427.597113 -312.175311)
			(xy 427.581225 -312.126412) (xy 427.573182 -312.07563) (xy 426.326558 -312.07563) (xy 426.318515 -312.126412)
			(xy 426.302627 -312.175311) (xy 426.279284 -312.221123) (xy 426.249063 -312.262719) (xy 426.212707 -312.299075)
			(xy 426.171111 -312.329296) (xy 426.125299 -312.352639) (xy 426.0764 -312.368527) (xy 426.025618 -312.37657)
			(xy 425.974202 -312.37657) (xy 425.92342 -312.368527) (xy 425.874521 -312.352639) (xy 425.828709 -312.329296)
			(xy 425.787113 -312.299075) (xy 425.750757 -312.262719) (xy 425.720536 -312.221123) (xy 425.697193 -312.175311)
			(xy 425.681305 -312.126412) (xy 425.673262 -312.07563) (xy 424.42638 -312.07563) (xy 424.418343 -312.126348)
			(xy 424.402465 -312.175206) (xy 424.37914 -312.220978) (xy 424.348941 -312.262538) (xy 424.312613 -312.298862)
			(xy 424.271051 -312.329056) (xy 424.225276 -312.352377) (xy 424.176417 -312.36825) (xy 424.125676 -312.376285)
			(xy 424.09999 -312.37682) (xy 424.074185 -312.376333) (xy 424.023215 -312.368228) (xy 423.974151 -312.352219)
			(xy 423.928209 -312.328705) (xy 423.886529 -312.298268) (xy 423.850146 -312.261664) (xy 423.819962 -312.219801)
			(xy 423.80789 -312.196988) (xy 423.80154 -312.184034) (xy 423.777156 -312.169048) (xy 423.477182 -312.169048)
			(xy 423.452544 -312.184288) (xy 423.446194 -312.197242) (xy 423.434054 -312.220483) (xy 423.403563 -312.263136)
			(xy 423.366727 -312.300447) (xy 423.324468 -312.331482) (xy 423.277844 -312.355465) (xy 423.22802 -312.371794)
			(xy 423.176245 -312.380063) (xy 423.123815 -312.380063) (xy 423.07204 -312.371794) (xy 423.022216 -312.355465)
			(xy 422.975592 -312.331482) (xy 422.933333 -312.300447) (xy 422.896497 -312.263136) (xy 422.866006 -312.220483)
			(xy 422.853866 -312.197242) (xy 422.847516 -312.184288) (xy 422.822878 -312.169048) (xy 422.52265 -312.169048)
			(xy 422.498266 -312.184034) (xy 422.491916 -312.196988) (xy 422.479862 -312.21981) (xy 422.449673 -312.261672)
			(xy 422.413286 -312.298273) (xy 422.371603 -312.328708) (xy 422.325659 -312.35222) (xy 422.276593 -312.368227)
			(xy 422.225622 -312.376331) (xy 422.17401 -312.376331) (xy 422.123039 -312.368227) (xy 422.073973 -312.35222)
			(xy 422.028029 -312.328708) (xy 421.986346 -312.298273) (xy 421.949959 -312.261672) (xy 421.91977 -312.21981)
			(xy 421.907716 -312.196988) (xy 421.901366 -312.184034) (xy 421.876982 -312.169048) (xy 421.577008 -312.169048)
			(xy 421.55237 -312.184288) (xy 421.54602 -312.197242) (xy 421.53388 -312.220483) (xy 421.503389 -312.263136)
			(xy 421.466553 -312.300447) (xy 421.424294 -312.331482) (xy 421.37767 -312.355465) (xy 421.327846 -312.371794)
			(xy 421.276071 -312.380063) (xy 421.223641 -312.380063) (xy 421.171866 -312.371794) (xy 421.122042 -312.355465)
			(xy 421.075418 -312.331482) (xy 421.033159 -312.300447) (xy 420.996323 -312.263136) (xy 420.965832 -312.220483)
			(xy 420.953692 -312.197242) (xy 420.947342 -312.184288) (xy 420.922704 -312.169048) (xy 420.612824 -312.169048)
			(xy 420.603681 -312.169425) (xy 420.586555 -312.17583) (xy 420.572765 -312.187836) (xy 420.56812 -312.195718)
			(xy 420.555625 -312.21762) (xy 420.524594 -312.257361) (xy 420.487455 -312.291463) (xy 420.445217 -312.318999)
			(xy 420.399028 -312.33922) (xy 420.350145 -312.351577) (xy 420.299896 -312.355733) (xy 420.249647 -312.351577)
			(xy 420.200764 -312.33922) (xy 420.154575 -312.318999) (xy 420.112337 -312.291463) (xy 420.075198 -312.257361)
			(xy 420.044167 -312.21762) (xy 420.031672 -312.195718) (xy 420.026998 -312.187855) (xy 420.013225 -312.175839)
			(xy 419.996107 -312.169428) (xy 419.986968 -312.169048) (xy 419.677088 -312.169048) (xy 419.65245 -312.184288)
			(xy 419.6461 -312.197242) (xy 419.63396 -312.220483) (xy 419.603469 -312.263136) (xy 419.566633 -312.300447)
			(xy 419.524374 -312.331482) (xy 419.47775 -312.355465) (xy 419.427926 -312.371794) (xy 419.376151 -312.380063)
			(xy 419.323721 -312.380063) (xy 419.271946 -312.371794) (xy 419.222122 -312.355465) (xy 419.175498 -312.331482)
			(xy 419.133239 -312.300447) (xy 419.096403 -312.263136) (xy 419.065912 -312.220483) (xy 419.053772 -312.197242)
			(xy 419.047422 -312.184288) (xy 419.022784 -312.169048) (xy 418.712904 -312.169048) (xy 418.703763 -312.169428)
			(xy 418.686643 -312.175838) (xy 418.672857 -312.187845) (xy 418.6682 -312.195718) (xy 418.655705 -312.21762)
			(xy 418.624674 -312.257361) (xy 418.587535 -312.291463) (xy 418.545297 -312.318999) (xy 418.499108 -312.33922)
			(xy 418.450225 -312.351577) (xy 418.399976 -312.355733) (xy 418.349727 -312.351577) (xy 418.300844 -312.33922)
			(xy 418.254655 -312.318999) (xy 418.212417 -312.291463) (xy 418.175278 -312.257361) (xy 418.144247 -312.21762)
			(xy 418.131752 -312.195718) (xy 418.127082 -312.187846) (xy 418.113312 -312.175808) (xy 418.096193 -312.169371)
			(xy 418.087048 -312.169048) (xy 417.777168 -312.169048) (xy 417.75253 -312.184288) (xy 417.74618 -312.197242)
			(xy 417.73404 -312.220483) (xy 417.703549 -312.263136) (xy 417.666713 -312.300447) (xy 417.624454 -312.331482)
			(xy 417.57783 -312.355465) (xy 417.528006 -312.371794) (xy 417.476231 -312.380063) (xy 417.423801 -312.380063)
			(xy 417.372026 -312.371794) (xy 417.322202 -312.355465) (xy 417.275578 -312.331482) (xy 417.233319 -312.300447)
			(xy 417.196483 -312.263136) (xy 417.165992 -312.220483) (xy 417.153852 -312.197242) (xy 417.147502 -312.184288)
			(xy 417.122864 -312.169048) (xy 416.81273 -312.169048) (xy 416.803587 -312.169424) (xy 416.786459 -312.175828)
			(xy 416.772667 -312.187834) (xy 416.768026 -312.195718) (xy 416.755531 -312.21762) (xy 416.7245 -312.257361)
			(xy 416.687361 -312.291463) (xy 416.645123 -312.318999) (xy 416.598934 -312.33922) (xy 416.550051 -312.351577)
			(xy 416.499802 -312.355733) (xy 416.449553 -312.351577) (xy 416.40067 -312.33922) (xy 416.354481 -312.318999)
			(xy 416.312243 -312.291463) (xy 416.275104 -312.257361) (xy 416.244073 -312.21762) (xy 416.231578 -312.195718)
			(xy 416.226904 -312.187854) (xy 416.213131 -312.175836) (xy 416.196014 -312.169423) (xy 416.186874 -312.169048)
			(xy 415.876994 -312.169048) (xy 415.852356 -312.184288) (xy 415.846006 -312.197242) (xy 415.833866 -312.220483)
			(xy 415.803375 -312.263136) (xy 415.766539 -312.300447) (xy 415.72428 -312.331482) (xy 415.677656 -312.355465)
			(xy 415.627832 -312.371794) (xy 415.576057 -312.380063) (xy 415.523627 -312.380063) (xy 415.471852 -312.371794)
			(xy 415.422028 -312.355465) (xy 415.375404 -312.331482) (xy 415.333145 -312.300447) (xy 415.296309 -312.263136)
			(xy 415.265818 -312.220483) (xy 415.253678 -312.197242) (xy 415.247328 -312.184288) (xy 415.22269 -312.169048)
			(xy 414.91281 -312.169048) (xy 414.903669 -312.169427) (xy 414.886546 -312.175836) (xy 414.87276 -312.187842)
			(xy 414.868106 -312.195718) (xy 414.855611 -312.21762) (xy 414.82458 -312.257361) (xy 414.787441 -312.291463)
			(xy 414.745203 -312.318999) (xy 414.699014 -312.33922) (xy 414.650131 -312.351577) (xy 414.599882 -312.355733)
			(xy 414.549633 -312.351577) (xy 414.50075 -312.33922) (xy 414.454561 -312.318999) (xy 414.412323 -312.291463)
			(xy 414.375184 -312.257361) (xy 414.344153 -312.21762) (xy 414.331658 -312.195718) (xy 414.326984 -312.187856)
			(xy 414.313209 -312.175844) (xy 414.296093 -312.169437) (xy 414.286954 -312.169048) (xy 413.977074 -312.169048)
			(xy 413.952436 -312.184288) (xy 413.946086 -312.197242) (xy 413.933946 -312.220483) (xy 413.903455 -312.263136)
			(xy 413.866619 -312.300447) (xy 413.82436 -312.331482) (xy 413.777736 -312.355465) (xy 413.727912 -312.371794)
			(xy 413.676137 -312.380063) (xy 413.623707 -312.380063) (xy 413.571932 -312.371794) (xy 413.522108 -312.355465)
			(xy 413.475484 -312.331482) (xy 413.433225 -312.300447) (xy 413.396389 -312.263136) (xy 413.365898 -312.220483)
			(xy 413.353758 -312.197242) (xy 413.347408 -312.184288) (xy 413.32277 -312.169048) (xy 413.022796 -312.169048)
			(xy 412.998412 -312.184034) (xy 412.992062 -312.196988) (xy 412.980008 -312.21981) (xy 412.949819 -312.261672)
			(xy 412.913432 -312.298273) (xy 412.871749 -312.328708) (xy 412.825805 -312.35222) (xy 412.776739 -312.368227)
			(xy 412.725768 -312.376331) (xy 412.674156 -312.376331) (xy 412.623185 -312.368227) (xy 412.574119 -312.35222)
			(xy 412.528175 -312.328708) (xy 412.486492 -312.298273) (xy 412.450105 -312.261672) (xy 412.419916 -312.21981)
			(xy 412.407862 -312.196988) (xy 412.401512 -312.184034) (xy 412.377128 -312.169048) (xy 412.077154 -312.169048)
			(xy 412.052516 -312.184288) (xy 412.046166 -312.197242) (xy 412.034026 -312.220483) (xy 412.003535 -312.263136)
			(xy 411.966699 -312.300447) (xy 411.92444 -312.331482) (xy 411.877816 -312.355465) (xy 411.827992 -312.371794)
			(xy 411.776217 -312.380063) (xy 411.723787 -312.380063) (xy 411.672012 -312.371794) (xy 411.622188 -312.355465)
			(xy 411.575564 -312.331482) (xy 411.533305 -312.300447) (xy 411.496469 -312.263136) (xy 411.465978 -312.220483)
			(xy 411.453838 -312.197242) (xy 411.447488 -312.184288) (xy 411.42285 -312.169048) (xy 411.122622 -312.169048)
			(xy 411.098238 -312.184034) (xy 411.091888 -312.196988) (xy 411.079834 -312.21981) (xy 411.049645 -312.261672)
			(xy 411.013258 -312.298273) (xy 410.971575 -312.328708) (xy 410.925631 -312.35222) (xy 410.876565 -312.368227)
			(xy 410.825594 -312.376331) (xy 410.773982 -312.376331) (xy 410.723011 -312.368227) (xy 410.673945 -312.35222)
			(xy 410.628001 -312.328708) (xy 410.586318 -312.298273) (xy 410.549931 -312.261672) (xy 410.519742 -312.21981)
			(xy 410.507688 -312.196988) (xy 410.501338 -312.184034) (xy 410.476954 -312.169048) (xy 410.17698 -312.169048)
			(xy 410.152342 -312.184288) (xy 410.145992 -312.197242) (xy 410.133852 -312.220483) (xy 410.103361 -312.263136)
			(xy 410.066525 -312.300447) (xy 410.024266 -312.331482) (xy 409.977642 -312.355465) (xy 409.927818 -312.371794)
			(xy 409.876043 -312.380063) (xy 409.823613 -312.380063) (xy 409.771838 -312.371794) (xy 409.722014 -312.355465)
			(xy 409.67539 -312.331482) (xy 409.633131 -312.300447) (xy 409.596295 -312.263136) (xy 409.565804 -312.220483)
			(xy 409.553664 -312.197242) (xy 409.547314 -312.184288) (xy 409.522676 -312.169048) (xy 409.222702 -312.169048)
			(xy 409.198318 -312.184034) (xy 409.191968 -312.196988) (xy 409.179914 -312.21981) (xy 409.149725 -312.261672)
			(xy 409.113338 -312.298273) (xy 409.071655 -312.328708) (xy 409.025711 -312.35222) (xy 408.976645 -312.368227)
			(xy 408.925674 -312.376331) (xy 408.874062 -312.376331) (xy 408.823091 -312.368227) (xy 408.774025 -312.35222)
			(xy 408.728081 -312.328708) (xy 408.686398 -312.298273) (xy 408.650011 -312.261672) (xy 408.619822 -312.21981)
			(xy 408.607768 -312.196988) (xy 408.601418 -312.184034) (xy 408.577034 -312.169048) (xy 408.27706 -312.169048)
			(xy 408.252422 -312.184288) (xy 408.246072 -312.197242) (xy 408.233932 -312.220483) (xy 408.203441 -312.263136)
			(xy 408.166605 -312.300447) (xy 408.124346 -312.331482) (xy 408.077722 -312.355465) (xy 408.027898 -312.371794)
			(xy 407.976123 -312.380063) (xy 407.923693 -312.380063) (xy 407.871918 -312.371794) (xy 407.822094 -312.355465)
			(xy 407.77547 -312.331482) (xy 407.733211 -312.300447) (xy 407.696375 -312.263136) (xy 407.665884 -312.220483)
			(xy 407.653744 -312.197242) (xy 407.647394 -312.184288) (xy 407.622756 -312.169048) (xy 407.322782 -312.169048)
			(xy 407.298398 -312.184034) (xy 407.292048 -312.196988) (xy 407.279994 -312.21981) (xy 407.249805 -312.261672)
			(xy 407.213418 -312.298273) (xy 407.171735 -312.328708) (xy 407.125791 -312.35222) (xy 407.076725 -312.368227)
			(xy 407.025754 -312.376331) (xy 406.974142 -312.376331) (xy 406.923171 -312.368227) (xy 406.874105 -312.35222)
			(xy 406.828161 -312.328708) (xy 406.786478 -312.298273) (xy 406.750091 -312.261672) (xy 406.719902 -312.21981)
			(xy 406.707848 -312.196988) (xy 406.701498 -312.184034) (xy 406.677114 -312.169048) (xy 406.37714 -312.169048)
			(xy 406.352502 -312.184288) (xy 406.346152 -312.197242) (xy 406.334012 -312.220483) (xy 406.303521 -312.263136)
			(xy 406.266685 -312.300447) (xy 406.224426 -312.331482) (xy 406.177802 -312.355465) (xy 406.127978 -312.371794)
			(xy 406.076203 -312.380063) (xy 406.023773 -312.380063) (xy 405.971998 -312.371794) (xy 405.922174 -312.355465)
			(xy 405.87555 -312.331482) (xy 405.833291 -312.300447) (xy 405.796455 -312.263136) (xy 405.765964 -312.220483)
			(xy 405.753824 -312.197242) (xy 405.747474 -312.184288) (xy 405.722836 -312.169048) (xy 405.422862 -312.169048)
			(xy 405.398478 -312.184034) (xy 405.392128 -312.196988) (xy 405.380074 -312.21981) (xy 405.349885 -312.261672)
			(xy 405.313498 -312.298273) (xy 405.271815 -312.328708) (xy 405.225871 -312.35222) (xy 405.176805 -312.368227)
			(xy 405.125834 -312.376331) (xy 405.074222 -312.376331) (xy 405.023251 -312.368227) (xy 404.974185 -312.35222)
			(xy 404.928241 -312.328708) (xy 404.886558 -312.298273) (xy 404.850171 -312.261672) (xy 404.819982 -312.21981)
			(xy 404.807928 -312.196988) (xy 404.801578 -312.184034) (xy 404.777194 -312.169048) (xy 404.476966 -312.169048)
			(xy 404.452328 -312.184288) (xy 404.445978 -312.197242) (xy 404.433838 -312.220483) (xy 404.403347 -312.263136)
			(xy 404.366511 -312.300447) (xy 404.324252 -312.331482) (xy 404.277628 -312.355465) (xy 404.227804 -312.371794)
			(xy 404.176029 -312.380063) (xy 404.123599 -312.380063) (xy 404.071824 -312.371794) (xy 404.022 -312.355465)
			(xy 403.975376 -312.331482) (xy 403.933117 -312.300447) (xy 403.896281 -312.263136) (xy 403.86579 -312.220483)
			(xy 403.85365 -312.197242) (xy 403.8473 -312.184288) (xy 403.822662 -312.169048) (xy 403.522688 -312.169048)
			(xy 403.498304 -312.184034) (xy 403.491954 -312.196988) (xy 403.4799 -312.21981) (xy 403.449711 -312.261672)
			(xy 403.413324 -312.298273) (xy 403.371641 -312.328708) (xy 403.325697 -312.35222) (xy 403.276631 -312.368227)
			(xy 403.22566 -312.376331) (xy 403.174048 -312.376331) (xy 403.123077 -312.368227) (xy 403.074011 -312.35222)
			(xy 403.028067 -312.328708) (xy 402.986384 -312.298273) (xy 402.949997 -312.261672) (xy 402.919808 -312.21981)
			(xy 402.907754 -312.196988) (xy 402.901404 -312.184034) (xy 402.87702 -312.169048) (xy 402.577046 -312.169048)
			(xy 402.552408 -312.184288) (xy 402.546058 -312.197242) (xy 402.533918 -312.220483) (xy 402.503427 -312.263136)
			(xy 402.466591 -312.300447) (xy 402.424332 -312.331482) (xy 402.377708 -312.355465) (xy 402.327884 -312.371794)
			(xy 402.276109 -312.380063) (xy 402.223679 -312.380063) (xy 402.171904 -312.371794) (xy 402.12208 -312.355465)
			(xy 402.075456 -312.331482) (xy 402.033197 -312.300447) (xy 401.996361 -312.263136) (xy 401.96587 -312.220483)
			(xy 401.95373 -312.197242) (xy 401.94738 -312.184288) (xy 401.922742 -312.169048) (xy 401.622768 -312.169048)
			(xy 401.598384 -312.184034) (xy 401.592034 -312.196988) (xy 401.57998 -312.21981) (xy 401.549791 -312.261672)
			(xy 401.513404 -312.298273) (xy 401.471721 -312.328708) (xy 401.425777 -312.35222) (xy 401.376711 -312.368227)
			(xy 401.32574 -312.376331) (xy 401.274128 -312.376331) (xy 401.223157 -312.368227) (xy 401.174091 -312.35222)
			(xy 401.128147 -312.328708) (xy 401.086464 -312.298273) (xy 401.050077 -312.261672) (xy 401.019888 -312.21981)
			(xy 401.007834 -312.196988) (xy 401.001484 -312.184034) (xy 400.9771 -312.169048) (xy 400.677126 -312.169048)
			(xy 400.652488 -312.184288) (xy 400.646138 -312.197242) (xy 400.633998 -312.220483) (xy 400.603507 -312.263136)
			(xy 400.566671 -312.300447) (xy 400.524412 -312.331482) (xy 400.477788 -312.355465) (xy 400.427964 -312.371794)
			(xy 400.376189 -312.380063) (xy 400.323759 -312.380063) (xy 400.271984 -312.371794) (xy 400.22216 -312.355465)
			(xy 400.175536 -312.331482) (xy 400.133277 -312.300447) (xy 400.096441 -312.263136) (xy 400.06595 -312.220483)
			(xy 400.05381 -312.197242) (xy 400.04746 -312.184288) (xy 400.022822 -312.169048) (xy 399.722848 -312.169048)
			(xy 399.698464 -312.184034) (xy 399.692114 -312.196988) (xy 399.68006 -312.21981) (xy 399.649871 -312.261672)
			(xy 399.613484 -312.298273) (xy 399.571801 -312.328708) (xy 399.525857 -312.35222) (xy 399.476791 -312.368227)
			(xy 399.42582 -312.376331) (xy 399.374208 -312.376331) (xy 399.323237 -312.368227) (xy 399.274171 -312.35222)
			(xy 399.228227 -312.328708) (xy 399.186544 -312.298273) (xy 399.150157 -312.261672) (xy 399.119968 -312.21981)
			(xy 399.107914 -312.196988) (xy 399.101564 -312.184034) (xy 399.07718 -312.169048) (xy 398.776952 -312.169048)
			(xy 398.752314 -312.184288) (xy 398.745964 -312.197242) (xy 398.733824 -312.220483) (xy 398.703333 -312.263136)
			(xy 398.666497 -312.300447) (xy 398.624238 -312.331482) (xy 398.577614 -312.355465) (xy 398.52779 -312.371794)
			(xy 398.476015 -312.380063) (xy 398.423585 -312.380063) (xy 398.37181 -312.371794) (xy 398.321986 -312.355465)
			(xy 398.275362 -312.331482) (xy 398.233103 -312.300447) (xy 398.196267 -312.263136) (xy 398.165776 -312.220483)
			(xy 398.153636 -312.197242) (xy 398.147286 -312.184288) (xy 398.122648 -312.169048) (xy 397.812768 -312.169048)
			(xy 397.803631 -312.169434) (xy 397.78652 -312.175852) (xy 397.772745 -312.187861) (xy 397.768064 -312.195718)
			(xy 397.755569 -312.21762) (xy 397.724538 -312.257361) (xy 397.687399 -312.291463) (xy 397.645161 -312.318999)
			(xy 397.598972 -312.33922) (xy 397.550089 -312.351577) (xy 397.49984 -312.355733) (xy 397.449591 -312.351577)
			(xy 397.400708 -312.33922) (xy 397.354519 -312.318999) (xy 397.312281 -312.291463) (xy 397.275142 -312.257361)
			(xy 397.244111 -312.21762) (xy 397.231616 -312.195718) (xy 397.226944 -312.18785) (xy 397.213173 -312.175822)
			(xy 397.196054 -312.169396) (xy 397.186912 -312.169048) (xy 396.877032 -312.169048) (xy 396.852394 -312.184288)
			(xy 396.846044 -312.197242) (xy 396.833904 -312.220483) (xy 396.803413 -312.263136) (xy 396.766577 -312.300447)
			(xy 396.724318 -312.331482) (xy 396.677694 -312.355465) (xy 396.62787 -312.371794) (xy 396.576095 -312.380063)
			(xy 396.523665 -312.380063) (xy 396.47189 -312.371794) (xy 396.422066 -312.355465) (xy 396.375442 -312.331482)
			(xy 396.333183 -312.300447) (xy 396.296347 -312.263136) (xy 396.265856 -312.220483) (xy 396.253716 -312.197242)
			(xy 396.247366 -312.184288) (xy 396.222728 -312.169048) (xy 395.912848 -312.169048) (xy 395.903703 -312.169421)
			(xy 395.886571 -312.175821) (xy 395.872773 -312.187826) (xy 395.868144 -312.195718) (xy 395.855649 -312.21762)
			(xy 395.824618 -312.257361) (xy 395.787479 -312.291463) (xy 395.745241 -312.318999) (xy 395.699052 -312.33922)
			(xy 395.650169 -312.351577) (xy 395.59992 -312.355733) (xy 395.549671 -312.351577) (xy 395.500788 -312.33922)
			(xy 395.454599 -312.318999) (xy 395.412361 -312.291463) (xy 395.375222 -312.257361) (xy 395.344191 -312.21762)
			(xy 395.331696 -312.195718) (xy 395.327023 -312.187852) (xy 395.313251 -312.17583) (xy 395.296133 -312.169411)
			(xy 395.286992 -312.169048) (xy 394.977112 -312.169048) (xy 394.952474 -312.184288) (xy 394.946124 -312.197242)
			(xy 394.933984 -312.220483) (xy 394.903493 -312.263136) (xy 394.866657 -312.300447) (xy 394.824398 -312.331482)
			(xy 394.777774 -312.355465) (xy 394.72795 -312.371794) (xy 394.676175 -312.380063) (xy 394.623745 -312.380063)
			(xy 394.57197 -312.371794) (xy 394.522146 -312.355465) (xy 394.475522 -312.331482) (xy 394.433263 -312.300447)
			(xy 394.396427 -312.263136) (xy 394.365936 -312.220483) (xy 394.353796 -312.197242) (xy 394.347446 -312.184288)
			(xy 394.322808 -312.169048) (xy 394.012928 -312.169048) (xy 394.003785 -312.169424) (xy 393.986658 -312.175829)
			(xy 393.972866 -312.187834) (xy 393.968224 -312.195718) (xy 393.955729 -312.21762) (xy 393.924698 -312.257361)
			(xy 393.887559 -312.291463) (xy 393.845321 -312.318999) (xy 393.799132 -312.33922) (xy 393.750249 -312.351577)
			(xy 393.7 -312.355733) (xy 393.649751 -312.351577) (xy 393.600868 -312.33922) (xy 393.554679 -312.318999)
			(xy 393.512441 -312.291463) (xy 393.475302 -312.257361) (xy 393.444271 -312.21762) (xy 393.431776 -312.195718)
			(xy 393.427102 -312.187855) (xy 393.413329 -312.175837) (xy 393.396212 -312.169425) (xy 393.387072 -312.169048)
			(xy 393.076938 -312.169048) (xy 393.0523 -312.184288) (xy 393.04595 -312.197242) (xy 393.03381 -312.220483)
			(xy 393.003319 -312.263136) (xy 392.966483 -312.300447) (xy 392.924224 -312.331482) (xy 392.8776 -312.355465)
			(xy 392.827776 -312.371794) (xy 392.776001 -312.380063) (xy 392.723571 -312.380063) (xy 392.671796 -312.371794)
			(xy 392.621972 -312.355465) (xy 392.575348 -312.331482) (xy 392.533089 -312.300447) (xy 392.496253 -312.263136)
			(xy 392.465762 -312.220483) (xy 392.453622 -312.197242) (xy 392.447272 -312.184288) (xy 392.422634 -312.169048)
			(xy 392.112754 -312.169048) (xy 392.103618 -312.169436) (xy 392.086511 -312.175857) (xy 392.07274 -312.187867)
			(xy 392.06805 -312.195718) (xy 392.055555 -312.21762) (xy 392.024524 -312.257361) (xy 391.987385 -312.291463)
			(xy 391.945147 -312.318999) (xy 391.898958 -312.33922) (xy 391.850075 -312.351577) (xy 391.799826 -312.355733)
			(xy 391.749577 -312.351577) (xy 391.700694 -312.33922) (xy 391.654505 -312.318999) (xy 391.612267 -312.291463)
			(xy 391.575128 -312.257361) (xy 391.544097 -312.21762) (xy 391.531602 -312.195718) (xy 391.52693 -312.187852)
			(xy 391.513158 -312.175827) (xy 391.496039 -312.169406) (xy 391.486898 -312.169048) (xy 391.177018 -312.169048)
			(xy 391.15238 -312.184288) (xy 391.14603 -312.197242) (xy 391.13389 -312.220483) (xy 391.103399 -312.263136)
			(xy 391.066563 -312.300447) (xy 391.024304 -312.331482) (xy 390.97768 -312.355465) (xy 390.927856 -312.371794)
			(xy 390.876081 -312.380063) (xy 390.823651 -312.380063) (xy 390.771876 -312.371794) (xy 390.722052 -312.355465)
			(xy 390.675428 -312.331482) (xy 390.633169 -312.300447) (xy 390.596333 -312.263136) (xy 390.565842 -312.220483)
			(xy 390.553702 -312.197242) (xy 390.547352 -312.184288) (xy 390.522714 -312.169048) (xy 390.212834 -312.169048)
			(xy 390.20369 -312.169423) (xy 390.186562 -312.175826) (xy 390.172768 -312.187832) (xy 390.16813 -312.195718)
			(xy 390.155635 -312.21762) (xy 390.124604 -312.257361) (xy 390.087465 -312.291463) (xy 390.045227 -312.318999)
			(xy 389.999038 -312.33922) (xy 389.950155 -312.351577) (xy 389.899906 -312.355733) (xy 389.849657 -312.351577)
			(xy 389.800774 -312.33922) (xy 389.754585 -312.318999) (xy 389.712347 -312.291463) (xy 389.675208 -312.257361)
			(xy 389.644177 -312.21762) (xy 389.631682 -312.195718) (xy 389.627009 -312.187854) (xy 389.613236 -312.175835)
			(xy 389.596118 -312.16942) (xy 389.586978 -312.169048) (xy 389.277098 -312.169048) (xy 389.25246 -312.184288)
			(xy 389.24611 -312.197242) (xy 389.23397 -312.220483) (xy 389.203479 -312.263136) (xy 389.166643 -312.300447)
			(xy 389.124384 -312.331482) (xy 389.07776 -312.355465) (xy 389.027936 -312.371794) (xy 388.976161 -312.380063)
			(xy 388.923731 -312.380063) (xy 388.871956 -312.371794) (xy 388.822132 -312.355465) (xy 388.775508 -312.331482)
			(xy 388.733249 -312.300447) (xy 388.696413 -312.263136) (xy 388.665922 -312.220483) (xy 388.653782 -312.197242)
			(xy 388.647432 -312.184288) (xy 388.622794 -312.169048) (xy 388.312914 -312.169048) (xy 388.303772 -312.169426)
			(xy 388.286649 -312.175834) (xy 388.272861 -312.187841) (xy 388.26821 -312.195718) (xy 388.255715 -312.21762)
			(xy 388.224684 -312.257361) (xy 388.187545 -312.291463) (xy 388.145307 -312.318999) (xy 388.099118 -312.33922)
			(xy 388.050235 -312.351577) (xy 387.999986 -312.355733) (xy 387.949737 -312.351577) (xy 387.900854 -312.33922)
			(xy 387.854665 -312.318999) (xy 387.812427 -312.291463) (xy 387.775288 -312.257361) (xy 387.744257 -312.21762)
			(xy 387.731762 -312.195718) (xy 387.727088 -312.187856) (xy 387.713314 -312.175842) (xy 387.696197 -312.169435)
			(xy 387.687058 -312.169048) (xy 387.377178 -312.169048) (xy 387.35254 -312.184288) (xy 387.34619 -312.197242)
			(xy 387.33405 -312.220483) (xy 387.303559 -312.263136) (xy 387.266723 -312.300447) (xy 387.224464 -312.331482)
			(xy 387.17784 -312.355465) (xy 387.128016 -312.371794) (xy 387.076241 -312.380063) (xy 387.023811 -312.380063)
			(xy 386.972036 -312.371794) (xy 386.922212 -312.355465) (xy 386.875588 -312.331482) (xy 386.833329 -312.300447)
			(xy 386.796493 -312.263136) (xy 386.766002 -312.220483) (xy 386.753862 -312.197242) (xy 386.747512 -312.184288)
			(xy 386.722874 -312.169048) (xy 386.41274 -312.169048) (xy 386.403596 -312.169422) (xy 386.386466 -312.175824)
			(xy 386.37267 -312.187829) (xy 386.368036 -312.195718) (xy 386.356482 -312.216082) (xy 386.328104 -312.253319)
			(xy 386.294373 -312.285788) (xy 386.256082 -312.312727) (xy 386.214126 -312.333504) (xy 386.169491 -312.347633)
			(xy 386.123221 -312.354782) (xy 386.099812 -312.35523) (xy 386.074577 -312.354706) (xy 386.024794 -312.346405)
			(xy 386.000752 -312.33872) (xy 385.993132 -312.336688) (xy 385.980178 -312.334402) (xy 385.970173 -312.334894)
			(xy 385.95169 -312.342557) (xy 385.937544 -312.35671) (xy 385.929889 -312.375197) (xy 385.929378 -312.385202)
			(xy 385.932172 -312.399426) (xy 385.934458 -312.408062) (xy 385.93776 -312.417206) (xy 385.946013 -312.443038)
			(xy 385.954952 -312.496521) (xy 385.95554 -312.523632) (xy 385.95554 -312.523886) (xy 385.95554 -312.524394)
			(xy 385.955794 -312.53176) (xy 385.954787 -312.557402) (xy 385.94583 -312.60793) (xy 385.92918 -312.656468)
			(xy 385.905235 -312.701854) (xy 385.87457 -312.742999) (xy 385.837921 -312.778917) (xy 385.796166 -312.808745)
			(xy 385.750306 -312.83177) (xy 385.701441 -312.847437) (xy 385.650743 -312.855373) (xy 385.625086 -312.855864)
			(xy 384.768344 -312.855864) (xy 384.758314 -312.856275) (xy 384.739776 -312.863936) (xy 384.725581 -312.878109)
			(xy 384.717891 -312.896635) (xy 384.717544 -312.906664) (xy 384.717544 -312.999882) (xy 386.744222 -312.999882)
			(xy 386.748182 -312.950828) (xy 386.759959 -312.903044) (xy 386.77925 -312.857768) (xy 386.805553 -312.816172)
			(xy 386.838188 -312.779335) (xy 386.876309 -312.74821) (xy 386.91893 -312.723603) (xy 386.964946 -312.706151)
			(xy 387.013165 -312.696307) (xy 387.06234 -312.694326) (xy 387.111195 -312.700258) (xy 387.158466 -312.71395)
			(xy 387.202928 -312.735048) (xy 387.243431 -312.763004) (xy 387.278924 -312.797096) (xy 387.308489 -312.83644)
			(xy 387.33136 -312.880017) (xy 387.346944 -312.926698) (xy 387.354839 -312.975275) (xy 387.355334 -312.999882)
			(xy 388.644142 -312.999882) (xy 388.648102 -312.950828) (xy 388.659879 -312.903044) (xy 388.67917 -312.857768)
			(xy 388.705473 -312.816172) (xy 388.738108 -312.779335) (xy 388.776229 -312.74821) (xy 388.81885 -312.723603)
			(xy 388.864866 -312.706151) (xy 388.913085 -312.696307) (xy 388.96226 -312.694326) (xy 389.011115 -312.700258)
			(xy 389.058386 -312.71395) (xy 389.102848 -312.735048) (xy 389.143351 -312.763004) (xy 389.178844 -312.797096)
			(xy 389.208409 -312.83644) (xy 389.23128 -312.880017) (xy 389.246864 -312.926698) (xy 389.254759 -312.975275)
			(xy 389.255254 -312.999882) (xy 390.544062 -312.999882) (xy 390.548022 -312.950828) (xy 390.559799 -312.903044)
			(xy 390.57909 -312.857768) (xy 390.605393 -312.816172) (xy 390.638028 -312.779335) (xy 390.676149 -312.74821)
			(xy 390.71877 -312.723603) (xy 390.764786 -312.706151) (xy 390.813005 -312.696307) (xy 390.86218 -312.694326)
			(xy 390.911035 -312.700258) (xy 390.958306 -312.71395) (xy 391.002768 -312.735048) (xy 391.043271 -312.763004)
			(xy 391.078764 -312.797096) (xy 391.108329 -312.83644) (xy 391.1312 -312.880017) (xy 391.146784 -312.926698)
			(xy 391.154679 -312.975275) (xy 391.155174 -312.999882) (xy 392.443982 -312.999882) (xy 392.447942 -312.950828)
			(xy 392.459719 -312.903044) (xy 392.47901 -312.857768) (xy 392.505313 -312.816172) (xy 392.537948 -312.779335)
			(xy 392.576069 -312.74821) (xy 392.61869 -312.723603) (xy 392.664706 -312.706151) (xy 392.712925 -312.696307)
			(xy 392.7621 -312.694326) (xy 392.810955 -312.700258) (xy 392.858226 -312.71395) (xy 392.902688 -312.735048)
			(xy 392.943191 -312.763004) (xy 392.978684 -312.797096) (xy 393.008249 -312.83644) (xy 393.03112 -312.880017)
			(xy 393.046704 -312.926698) (xy 393.054599 -312.975275) (xy 393.055094 -312.999882) (xy 394.344156 -312.999882)
			(xy 394.348116 -312.950828) (xy 394.359893 -312.903044) (xy 394.379184 -312.857768) (xy 394.405487 -312.816172)
			(xy 394.438122 -312.779335) (xy 394.476243 -312.74821) (xy 394.518864 -312.723603) (xy 394.56488 -312.706151)
			(xy 394.613099 -312.696307) (xy 394.662274 -312.694326) (xy 394.711129 -312.700258) (xy 394.7584 -312.71395)
			(xy 394.802862 -312.735048) (xy 394.843365 -312.763004) (xy 394.878858 -312.797096) (xy 394.908423 -312.83644)
			(xy 394.931294 -312.880017) (xy 394.946878 -312.926698) (xy 394.954773 -312.975275) (xy 394.955268 -312.999882)
			(xy 396.244076 -312.999882) (xy 396.248036 -312.950828) (xy 396.259813 -312.903044) (xy 396.279104 -312.857768)
			(xy 396.305407 -312.816172) (xy 396.338042 -312.779335) (xy 396.376163 -312.74821) (xy 396.418784 -312.723603)
			(xy 396.4648 -312.706151) (xy 396.513019 -312.696307) (xy 396.562194 -312.694326) (xy 396.611049 -312.700258)
			(xy 396.65832 -312.71395) (xy 396.702782 -312.735048) (xy 396.743285 -312.763004) (xy 396.778778 -312.797096)
			(xy 396.808343 -312.83644) (xy 396.831214 -312.880017) (xy 396.846798 -312.926698) (xy 396.854693 -312.975275)
			(xy 396.855188 -312.999882) (xy 398.143996 -312.999882) (xy 398.147956 -312.950828) (xy 398.159733 -312.903044)
			(xy 398.179024 -312.857768) (xy 398.205327 -312.816172) (xy 398.237962 -312.779335) (xy 398.276083 -312.74821)
			(xy 398.318704 -312.723603) (xy 398.36472 -312.706151) (xy 398.412939 -312.696307) (xy 398.462114 -312.694326)
			(xy 398.510969 -312.700258) (xy 398.55824 -312.71395) (xy 398.602702 -312.735048) (xy 398.643205 -312.763004)
			(xy 398.678698 -312.797096) (xy 398.708263 -312.83644) (xy 398.731134 -312.880017) (xy 398.746718 -312.926698)
			(xy 398.754613 -312.975275) (xy 398.755108 -312.999882) (xy 398.754613 -313.024489) (xy 398.754434 -313.02559)
			(xy 400.023326 -313.02559) (xy 400.023326 -312.974174) (xy 400.031369 -312.923392) (xy 400.047257 -312.874493)
			(xy 400.0706 -312.828681) (xy 400.100821 -312.787085) (xy 400.137177 -312.750729) (xy 400.178773 -312.720508)
			(xy 400.224585 -312.697165) (xy 400.273484 -312.681277) (xy 400.324266 -312.673234) (xy 400.375682 -312.673234)
			(xy 400.426464 -312.681277) (xy 400.475363 -312.697165) (xy 400.521175 -312.720508) (xy 400.562771 -312.750729)
			(xy 400.599127 -312.787085) (xy 400.629348 -312.828681) (xy 400.652691 -312.874493) (xy 400.668579 -312.923392)
			(xy 400.676622 -312.974174) (xy 400.677126 -312.999882) (xy 400.676622 -313.02559) (xy 401.923246 -313.02559)
			(xy 401.923246 -312.974174) (xy 401.931289 -312.923392) (xy 401.947177 -312.874493) (xy 401.97052 -312.828681)
			(xy 402.000741 -312.787085) (xy 402.037097 -312.750729) (xy 402.078693 -312.720508) (xy 402.124505 -312.697165)
			(xy 402.173404 -312.681277) (xy 402.224186 -312.673234) (xy 402.275602 -312.673234) (xy 402.326384 -312.681277)
			(xy 402.375283 -312.697165) (xy 402.421095 -312.720508) (xy 402.462691 -312.750729) (xy 402.499047 -312.787085)
			(xy 402.529268 -312.828681) (xy 402.552611 -312.874493) (xy 402.568499 -312.923392) (xy 402.576542 -312.974174)
			(xy 402.577046 -312.999882) (xy 402.576542 -313.02559) (xy 403.823166 -313.02559) (xy 403.823166 -312.974174)
			(xy 403.831209 -312.923392) (xy 403.847097 -312.874493) (xy 403.87044 -312.828681) (xy 403.900661 -312.787085)
			(xy 403.937017 -312.750729) (xy 403.978613 -312.720508) (xy 404.024425 -312.697165) (xy 404.073324 -312.681277)
			(xy 404.124106 -312.673234) (xy 404.175522 -312.673234) (xy 404.226304 -312.681277) (xy 404.275203 -312.697165)
			(xy 404.321015 -312.720508) (xy 404.362611 -312.750729) (xy 404.398967 -312.787085) (xy 404.429188 -312.828681)
			(xy 404.452531 -312.874493) (xy 404.468419 -312.923392) (xy 404.476462 -312.974174) (xy 404.476966 -312.999882)
			(xy 404.476462 -313.02559) (xy 405.72334 -313.02559) (xy 405.72334 -312.974174) (xy 405.731383 -312.923392)
			(xy 405.747271 -312.874493) (xy 405.770614 -312.828681) (xy 405.800835 -312.787085) (xy 405.837191 -312.750729)
			(xy 405.878787 -312.720508) (xy 405.924599 -312.697165) (xy 405.973498 -312.681277) (xy 406.02428 -312.673234)
			(xy 406.075696 -312.673234) (xy 406.126478 -312.681277) (xy 406.175377 -312.697165) (xy 406.221189 -312.720508)
			(xy 406.262785 -312.750729) (xy 406.299141 -312.787085) (xy 406.329362 -312.828681) (xy 406.352705 -312.874493)
			(xy 406.368593 -312.923392) (xy 406.376636 -312.974174) (xy 406.37714 -312.999882) (xy 406.376636 -313.02559)
			(xy 407.62326 -313.02559) (xy 407.62326 -312.974174) (xy 407.631303 -312.923392) (xy 407.647191 -312.874493)
			(xy 407.670534 -312.828681) (xy 407.700755 -312.787085) (xy 407.737111 -312.750729) (xy 407.778707 -312.720508)
			(xy 407.824519 -312.697165) (xy 407.873418 -312.681277) (xy 407.9242 -312.673234) (xy 407.975616 -312.673234)
			(xy 408.026398 -312.681277) (xy 408.075297 -312.697165) (xy 408.121109 -312.720508) (xy 408.162705 -312.750729)
			(xy 408.199061 -312.787085) (xy 408.229282 -312.828681) (xy 408.252625 -312.874493) (xy 408.268513 -312.923392)
			(xy 408.276556 -312.974174) (xy 408.27706 -312.999882) (xy 408.276556 -313.02559) (xy 409.52318 -313.02559)
			(xy 409.52318 -312.974174) (xy 409.531223 -312.923392) (xy 409.547111 -312.874493) (xy 409.570454 -312.828681)
			(xy 409.600675 -312.787085) (xy 409.637031 -312.750729) (xy 409.678627 -312.720508) (xy 409.724439 -312.697165)
			(xy 409.773338 -312.681277) (xy 409.82412 -312.673234) (xy 409.875536 -312.673234) (xy 409.926318 -312.681277)
			(xy 409.975217 -312.697165) (xy 410.021029 -312.720508) (xy 410.062625 -312.750729) (xy 410.098981 -312.787085)
			(xy 410.129202 -312.828681) (xy 410.152545 -312.874493) (xy 410.168433 -312.923392) (xy 410.176476 -312.974174)
			(xy 410.17698 -312.999882) (xy 410.176476 -313.02559) (xy 411.423354 -313.02559) (xy 411.423354 -312.974174)
			(xy 411.431397 -312.923392) (xy 411.447285 -312.874493) (xy 411.470628 -312.828681) (xy 411.500849 -312.787085)
			(xy 411.537205 -312.750729) (xy 411.578801 -312.720508) (xy 411.624613 -312.697165) (xy 411.673512 -312.681277)
			(xy 411.724294 -312.673234) (xy 411.77571 -312.673234) (xy 411.826492 -312.681277) (xy 411.875391 -312.697165)
			(xy 411.921203 -312.720508) (xy 411.962799 -312.750729) (xy 411.999155 -312.787085) (xy 412.029376 -312.828681)
			(xy 412.052719 -312.874493) (xy 412.068607 -312.923392) (xy 412.07665 -312.974174) (xy 412.077154 -312.999882)
			(xy 412.07665 -313.02559) (xy 413.323274 -313.02559) (xy 413.323274 -312.974174) (xy 413.331317 -312.923392)
			(xy 413.347205 -312.874493) (xy 413.370548 -312.828681) (xy 413.400769 -312.787085) (xy 413.437125 -312.750729)
			(xy 413.478721 -312.720508) (xy 413.524533 -312.697165) (xy 413.573432 -312.681277) (xy 413.624214 -312.673234)
			(xy 413.67563 -312.673234) (xy 413.726412 -312.681277) (xy 413.775311 -312.697165) (xy 413.821123 -312.720508)
			(xy 413.862719 -312.750729) (xy 413.899075 -312.787085) (xy 413.929296 -312.828681) (xy 413.952639 -312.874493)
			(xy 413.968527 -312.923392) (xy 413.97657 -312.974174) (xy 413.977074 -312.999882) (xy 415.244038 -312.999882)
			(xy 415.247998 -312.950828) (xy 415.259775 -312.903044) (xy 415.279066 -312.857768) (xy 415.305369 -312.816172)
			(xy 415.338004 -312.779335) (xy 415.376125 -312.74821) (xy 415.418746 -312.723603) (xy 415.464762 -312.706151)
			(xy 415.512981 -312.696307) (xy 415.562156 -312.694326) (xy 415.611011 -312.700258) (xy 415.658282 -312.71395)
			(xy 415.702744 -312.735048) (xy 415.743247 -312.763004) (xy 415.77874 -312.797096) (xy 415.808305 -312.83644)
			(xy 415.831176 -312.880017) (xy 415.84676 -312.926698) (xy 415.854655 -312.975275) (xy 415.85515 -312.999882)
			(xy 417.144212 -312.999882) (xy 417.148172 -312.950828) (xy 417.159949 -312.903044) (xy 417.17924 -312.857768)
			(xy 417.205543 -312.816172) (xy 417.238178 -312.779335) (xy 417.276299 -312.74821) (xy 417.31892 -312.723603)
			(xy 417.364936 -312.706151) (xy 417.413155 -312.696307) (xy 417.46233 -312.694326) (xy 417.511185 -312.700258)
			(xy 417.558456 -312.71395) (xy 417.602918 -312.735048) (xy 417.643421 -312.763004) (xy 417.678914 -312.797096)
			(xy 417.708479 -312.83644) (xy 417.73135 -312.880017) (xy 417.746934 -312.926698) (xy 417.754829 -312.975275)
			(xy 417.755324 -312.999882) (xy 419.044132 -312.999882) (xy 419.048092 -312.950828) (xy 419.059869 -312.903044)
			(xy 419.07916 -312.857768) (xy 419.105463 -312.816172) (xy 419.138098 -312.779335) (xy 419.176219 -312.74821)
			(xy 419.21884 -312.723603) (xy 419.264856 -312.706151) (xy 419.313075 -312.696307) (xy 419.36225 -312.694326)
			(xy 419.411105 -312.700258) (xy 419.458376 -312.71395) (xy 419.502838 -312.735048) (xy 419.543341 -312.763004)
			(xy 419.578834 -312.797096) (xy 419.608399 -312.83644) (xy 419.63127 -312.880017) (xy 419.646854 -312.926698)
			(xy 419.654749 -312.975275) (xy 419.655244 -312.999882) (xy 420.944052 -312.999882) (xy 420.948012 -312.950828)
			(xy 420.959789 -312.903044) (xy 420.97908 -312.857768) (xy 421.005383 -312.816172) (xy 421.038018 -312.779335)
			(xy 421.076139 -312.74821) (xy 421.11876 -312.723603) (xy 421.164776 -312.706151) (xy 421.212995 -312.696307)
			(xy 421.26217 -312.694326) (xy 421.311025 -312.700258) (xy 421.358296 -312.71395) (xy 421.402758 -312.735048)
			(xy 421.443261 -312.763004) (xy 421.478754 -312.797096) (xy 421.508319 -312.83644) (xy 421.53119 -312.880017)
			(xy 421.546774 -312.926698) (xy 421.554669 -312.975275) (xy 421.555164 -312.999882) (xy 421.554669 -313.024489)
			(xy 421.55449 -313.02559) (xy 422.823382 -313.02559) (xy 422.823382 -312.974174) (xy 422.831425 -312.923392)
			(xy 422.847313 -312.874493) (xy 422.870656 -312.828681) (xy 422.900877 -312.787085) (xy 422.937233 -312.750729)
			(xy 422.978829 -312.720508) (xy 423.024641 -312.697165) (xy 423.07354 -312.681277) (xy 423.124322 -312.673234)
			(xy 423.175738 -312.673234) (xy 423.22652 -312.681277) (xy 423.275419 -312.697165) (xy 423.321231 -312.720508)
			(xy 423.362827 -312.750729) (xy 423.399183 -312.787085) (xy 423.429404 -312.828681) (xy 423.452747 -312.874493)
			(xy 423.468635 -312.923392) (xy 423.476678 -312.974174) (xy 423.477182 -312.999882) (xy 423.476678 -313.02559)
			(xy 424.723302 -313.02559) (xy 424.723302 -312.974174) (xy 424.731345 -312.923392) (xy 424.747233 -312.874493)
			(xy 424.770576 -312.828681) (xy 424.800797 -312.787085) (xy 424.837153 -312.750729) (xy 424.878749 -312.720508)
			(xy 424.924561 -312.697165) (xy 424.97346 -312.681277) (xy 425.024242 -312.673234) (xy 425.075658 -312.673234)
			(xy 425.12644 -312.681277) (xy 425.175339 -312.697165) (xy 425.221151 -312.720508) (xy 425.262747 -312.750729)
			(xy 425.299103 -312.787085) (xy 425.329324 -312.828681) (xy 425.352667 -312.874493) (xy 425.368555 -312.923392)
			(xy 425.376598 -312.974174) (xy 425.377102 -312.999882) (xy 425.376598 -313.02559) (xy 426.623222 -313.02559)
			(xy 426.623222 -312.974174) (xy 426.631265 -312.923392) (xy 426.647153 -312.874493) (xy 426.670496 -312.828681)
			(xy 426.700717 -312.787085) (xy 426.737073 -312.750729) (xy 426.778669 -312.720508) (xy 426.824481 -312.697165)
			(xy 426.87338 -312.681277) (xy 426.924162 -312.673234) (xy 426.975578 -312.673234) (xy 427.02636 -312.681277)
			(xy 427.075259 -312.697165) (xy 427.121071 -312.720508) (xy 427.162667 -312.750729) (xy 427.199023 -312.787085)
			(xy 427.229244 -312.828681) (xy 427.252587 -312.874493) (xy 427.268475 -312.923392) (xy 427.276518 -312.974174)
			(xy 427.277022 -312.999882) (xy 427.276518 -313.02559) (xy 428.523142 -313.02559) (xy 428.523142 -312.974174)
			(xy 428.531185 -312.923392) (xy 428.547073 -312.874493) (xy 428.570416 -312.828681) (xy 428.600637 -312.787085)
			(xy 428.636993 -312.750729) (xy 428.678589 -312.720508) (xy 428.724401 -312.697165) (xy 428.7733 -312.681277)
			(xy 428.824082 -312.673234) (xy 428.875498 -312.673234) (xy 428.92628 -312.681277) (xy 428.975179 -312.697165)
			(xy 429.020991 -312.720508) (xy 429.062587 -312.750729) (xy 429.098943 -312.787085) (xy 429.129164 -312.828681)
			(xy 429.152507 -312.874493) (xy 429.168395 -312.923392) (xy 429.176438 -312.974174) (xy 429.176942 -312.999882)
			(xy 429.176438 -313.02559) (xy 429.168395 -313.076372) (xy 429.152507 -313.125271) (xy 429.129164 -313.171083)
			(xy 429.098943 -313.212679) (xy 429.062587 -313.249035) (xy 429.020991 -313.279256) (xy 428.975179 -313.302599)
			(xy 428.92628 -313.318487) (xy 428.875498 -313.32653) (xy 428.824082 -313.32653) (xy 428.7733 -313.318487)
			(xy 428.724401 -313.302599) (xy 428.678589 -313.279256) (xy 428.636993 -313.249035) (xy 428.600637 -313.212679)
			(xy 428.570416 -313.171083) (xy 428.547073 -313.125271) (xy 428.531185 -313.076372) (xy 428.523142 -313.02559)
			(xy 427.276518 -313.02559) (xy 427.268475 -313.076372) (xy 427.252587 -313.125271) (xy 427.229244 -313.171083)
			(xy 427.199023 -313.212679) (xy 427.162667 -313.249035) (xy 427.121071 -313.279256) (xy 427.075259 -313.302599)
			(xy 427.02636 -313.318487) (xy 426.975578 -313.32653) (xy 426.924162 -313.32653) (xy 426.87338 -313.318487)
			(xy 426.824481 -313.302599) (xy 426.778669 -313.279256) (xy 426.737073 -313.249035) (xy 426.700717 -313.212679)
			(xy 426.670496 -313.171083) (xy 426.647153 -313.125271) (xy 426.631265 -313.076372) (xy 426.623222 -313.02559)
			(xy 425.376598 -313.02559) (xy 425.368555 -313.076372) (xy 425.352667 -313.125271) (xy 425.329324 -313.171083)
			(xy 425.299103 -313.212679) (xy 425.262747 -313.249035) (xy 425.221151 -313.279256) (xy 425.175339 -313.302599)
			(xy 425.12644 -313.318487) (xy 425.075658 -313.32653) (xy 425.024242 -313.32653) (xy 424.97346 -313.318487)
			(xy 424.924561 -313.302599) (xy 424.878749 -313.279256) (xy 424.837153 -313.249035) (xy 424.800797 -313.212679)
			(xy 424.770576 -313.171083) (xy 424.747233 -313.125271) (xy 424.731345 -313.076372) (xy 424.723302 -313.02559)
			(xy 423.476678 -313.02559) (xy 423.468635 -313.076372) (xy 423.452747 -313.125271) (xy 423.429404 -313.171083)
			(xy 423.399183 -313.212679) (xy 423.362827 -313.249035) (xy 423.321231 -313.279256) (xy 423.275419 -313.302599)
			(xy 423.22652 -313.318487) (xy 423.175738 -313.32653) (xy 423.124322 -313.32653) (xy 423.07354 -313.318487)
			(xy 423.024641 -313.302599) (xy 422.978829 -313.279256) (xy 422.937233 -313.249035) (xy 422.900877 -313.212679)
			(xy 422.870656 -313.171083) (xy 422.847313 -313.125271) (xy 422.831425 -313.076372) (xy 422.823382 -313.02559)
			(xy 421.55449 -313.02559) (xy 421.546774 -313.073066) (xy 421.53119 -313.119747) (xy 421.508319 -313.163324)
			(xy 421.478754 -313.202668) (xy 421.443261 -313.23676) (xy 421.402758 -313.264716) (xy 421.358296 -313.285814)
			(xy 421.311025 -313.299506) (xy 421.26217 -313.305438) (xy 421.212995 -313.303457) (xy 421.164776 -313.293613)
			(xy 421.11876 -313.276161) (xy 421.076139 -313.251554) (xy 421.038018 -313.220429) (xy 421.005383 -313.183592)
			(xy 420.97908 -313.141996) (xy 420.959789 -313.09672) (xy 420.948012 -313.048936) (xy 420.944052 -312.999882)
			(xy 419.655244 -312.999882) (xy 419.654749 -313.024489) (xy 419.646854 -313.073066) (xy 419.63127 -313.119747)
			(xy 419.608399 -313.163324) (xy 419.578834 -313.202668) (xy 419.543341 -313.23676) (xy 419.502838 -313.264716)
			(xy 419.458376 -313.285814) (xy 419.411105 -313.299506) (xy 419.36225 -313.305438) (xy 419.313075 -313.303457)
			(xy 419.264856 -313.293613) (xy 419.21884 -313.276161) (xy 419.176219 -313.251554) (xy 419.138098 -313.220429)
			(xy 419.105463 -313.183592) (xy 419.07916 -313.141996) (xy 419.059869 -313.09672) (xy 419.048092 -313.048936)
			(xy 419.044132 -312.999882) (xy 417.755324 -312.999882) (xy 417.754829 -313.024489) (xy 417.746934 -313.073066)
			(xy 417.73135 -313.119747) (xy 417.708479 -313.163324) (xy 417.678914 -313.202668) (xy 417.643421 -313.23676)
			(xy 417.602918 -313.264716) (xy 417.558456 -313.285814) (xy 417.511185 -313.299506) (xy 417.46233 -313.305438)
			(xy 417.413155 -313.303457) (xy 417.364936 -313.293613) (xy 417.31892 -313.276161) (xy 417.276299 -313.251554)
			(xy 417.238178 -313.220429) (xy 417.205543 -313.183592) (xy 417.17924 -313.141996) (xy 417.159949 -313.09672)
			(xy 417.148172 -313.048936) (xy 417.144212 -312.999882) (xy 415.85515 -312.999882) (xy 415.854655 -313.024489)
			(xy 415.84676 -313.073066) (xy 415.831176 -313.119747) (xy 415.808305 -313.163324) (xy 415.77874 -313.202668)
			(xy 415.743247 -313.23676) (xy 415.702744 -313.264716) (xy 415.658282 -313.285814) (xy 415.611011 -313.299506)
			(xy 415.562156 -313.305438) (xy 415.512981 -313.303457) (xy 415.464762 -313.293613) (xy 415.418746 -313.276161)
			(xy 415.376125 -313.251554) (xy 415.338004 -313.220429) (xy 415.305369 -313.183592) (xy 415.279066 -313.141996)
			(xy 415.259775 -313.09672) (xy 415.247998 -313.048936) (xy 415.244038 -312.999882) (xy 413.977074 -312.999882)
			(xy 413.97657 -313.02559) (xy 413.968527 -313.076372) (xy 413.952639 -313.125271) (xy 413.929296 -313.171083)
			(xy 413.899075 -313.212679) (xy 413.862719 -313.249035) (xy 413.821123 -313.279256) (xy 413.775311 -313.302599)
			(xy 413.726412 -313.318487) (xy 413.67563 -313.32653) (xy 413.624214 -313.32653) (xy 413.573432 -313.318487)
			(xy 413.524533 -313.302599) (xy 413.478721 -313.279256) (xy 413.437125 -313.249035) (xy 413.400769 -313.212679)
			(xy 413.370548 -313.171083) (xy 413.347205 -313.125271) (xy 413.331317 -313.076372) (xy 413.323274 -313.02559)
			(xy 412.07665 -313.02559) (xy 412.068607 -313.076372) (xy 412.052719 -313.125271) (xy 412.029376 -313.171083)
			(xy 411.999155 -313.212679) (xy 411.962799 -313.249035) (xy 411.921203 -313.279256) (xy 411.875391 -313.302599)
			(xy 411.826492 -313.318487) (xy 411.77571 -313.32653) (xy 411.724294 -313.32653) (xy 411.673512 -313.318487)
			(xy 411.624613 -313.302599) (xy 411.578801 -313.279256) (xy 411.537205 -313.249035) (xy 411.500849 -313.212679)
			(xy 411.470628 -313.171083) (xy 411.447285 -313.125271) (xy 411.431397 -313.076372) (xy 411.423354 -313.02559)
			(xy 410.176476 -313.02559) (xy 410.168433 -313.076372) (xy 410.152545 -313.125271) (xy 410.129202 -313.171083)
			(xy 410.098981 -313.212679) (xy 410.062625 -313.249035) (xy 410.021029 -313.279256) (xy 409.975217 -313.302599)
			(xy 409.926318 -313.318487) (xy 409.875536 -313.32653) (xy 409.82412 -313.32653) (xy 409.773338 -313.318487)
			(xy 409.724439 -313.302599) (xy 409.678627 -313.279256) (xy 409.637031 -313.249035) (xy 409.600675 -313.212679)
			(xy 409.570454 -313.171083) (xy 409.547111 -313.125271) (xy 409.531223 -313.076372) (xy 409.52318 -313.02559)
			(xy 408.276556 -313.02559) (xy 408.268513 -313.076372) (xy 408.252625 -313.125271) (xy 408.229282 -313.171083)
			(xy 408.199061 -313.212679) (xy 408.162705 -313.249035) (xy 408.121109 -313.279256) (xy 408.075297 -313.302599)
			(xy 408.026398 -313.318487) (xy 407.975616 -313.32653) (xy 407.9242 -313.32653) (xy 407.873418 -313.318487)
			(xy 407.824519 -313.302599) (xy 407.778707 -313.279256) (xy 407.737111 -313.249035) (xy 407.700755 -313.212679)
			(xy 407.670534 -313.171083) (xy 407.647191 -313.125271) (xy 407.631303 -313.076372) (xy 407.62326 -313.02559)
			(xy 406.376636 -313.02559) (xy 406.368593 -313.076372) (xy 406.352705 -313.125271) (xy 406.329362 -313.171083)
			(xy 406.299141 -313.212679) (xy 406.262785 -313.249035) (xy 406.221189 -313.279256) (xy 406.175377 -313.302599)
			(xy 406.126478 -313.318487) (xy 406.075696 -313.32653) (xy 406.02428 -313.32653) (xy 405.973498 -313.318487)
			(xy 405.924599 -313.302599) (xy 405.878787 -313.279256) (xy 405.837191 -313.249035) (xy 405.800835 -313.212679)
			(xy 405.770614 -313.171083) (xy 405.747271 -313.125271) (xy 405.731383 -313.076372) (xy 405.72334 -313.02559)
			(xy 404.476462 -313.02559) (xy 404.468419 -313.076372) (xy 404.452531 -313.125271) (xy 404.429188 -313.171083)
			(xy 404.398967 -313.212679) (xy 404.362611 -313.249035) (xy 404.321015 -313.279256) (xy 404.275203 -313.302599)
			(xy 404.226304 -313.318487) (xy 404.175522 -313.32653) (xy 404.124106 -313.32653) (xy 404.073324 -313.318487)
			(xy 404.024425 -313.302599) (xy 403.978613 -313.279256) (xy 403.937017 -313.249035) (xy 403.900661 -313.212679)
			(xy 403.87044 -313.171083) (xy 403.847097 -313.125271) (xy 403.831209 -313.076372) (xy 403.823166 -313.02559)
			(xy 402.576542 -313.02559) (xy 402.568499 -313.076372) (xy 402.552611 -313.125271) (xy 402.529268 -313.171083)
			(xy 402.499047 -313.212679) (xy 402.462691 -313.249035) (xy 402.421095 -313.279256) (xy 402.375283 -313.302599)
			(xy 402.326384 -313.318487) (xy 402.275602 -313.32653) (xy 402.224186 -313.32653) (xy 402.173404 -313.318487)
			(xy 402.124505 -313.302599) (xy 402.078693 -313.279256) (xy 402.037097 -313.249035) (xy 402.000741 -313.212679)
			(xy 401.97052 -313.171083) (xy 401.947177 -313.125271) (xy 401.931289 -313.076372) (xy 401.923246 -313.02559)
			(xy 400.676622 -313.02559) (xy 400.668579 -313.076372) (xy 400.652691 -313.125271) (xy 400.629348 -313.171083)
			(xy 400.599127 -313.212679) (xy 400.562771 -313.249035) (xy 400.521175 -313.279256) (xy 400.475363 -313.302599)
			(xy 400.426464 -313.318487) (xy 400.375682 -313.32653) (xy 400.324266 -313.32653) (xy 400.273484 -313.318487)
			(xy 400.224585 -313.302599) (xy 400.178773 -313.279256) (xy 400.137177 -313.249035) (xy 400.100821 -313.212679)
			(xy 400.0706 -313.171083) (xy 400.047257 -313.125271) (xy 400.031369 -313.076372) (xy 400.023326 -313.02559)
			(xy 398.754434 -313.02559) (xy 398.746718 -313.073066) (xy 398.731134 -313.119747) (xy 398.708263 -313.163324)
			(xy 398.678698 -313.202668) (xy 398.643205 -313.23676) (xy 398.602702 -313.264716) (xy 398.55824 -313.285814)
			(xy 398.510969 -313.299506) (xy 398.462114 -313.305438) (xy 398.412939 -313.303457) (xy 398.36472 -313.293613)
			(xy 398.318704 -313.276161) (xy 398.276083 -313.251554) (xy 398.237962 -313.220429) (xy 398.205327 -313.183592)
			(xy 398.179024 -313.141996) (xy 398.159733 -313.09672) (xy 398.147956 -313.048936) (xy 398.143996 -312.999882)
			(xy 396.855188 -312.999882) (xy 396.854693 -313.024489) (xy 396.846798 -313.073066) (xy 396.831214 -313.119747)
			(xy 396.808343 -313.163324) (xy 396.778778 -313.202668) (xy 396.743285 -313.23676) (xy 396.702782 -313.264716)
			(xy 396.65832 -313.285814) (xy 396.611049 -313.299506) (xy 396.562194 -313.305438) (xy 396.513019 -313.303457)
			(xy 396.4648 -313.293613) (xy 396.418784 -313.276161) (xy 396.376163 -313.251554) (xy 396.338042 -313.220429)
			(xy 396.305407 -313.183592) (xy 396.279104 -313.141996) (xy 396.259813 -313.09672) (xy 396.248036 -313.048936)
			(xy 396.244076 -312.999882) (xy 394.955268 -312.999882) (xy 394.954773 -313.024489) (xy 394.946878 -313.073066)
			(xy 394.931294 -313.119747) (xy 394.908423 -313.163324) (xy 394.878858 -313.202668) (xy 394.843365 -313.23676)
			(xy 394.802862 -313.264716) (xy 394.7584 -313.285814) (xy 394.711129 -313.299506) (xy 394.662274 -313.305438)
			(xy 394.613099 -313.303457) (xy 394.56488 -313.293613) (xy 394.518864 -313.276161) (xy 394.476243 -313.251554)
			(xy 394.438122 -313.220429) (xy 394.405487 -313.183592) (xy 394.379184 -313.141996) (xy 394.359893 -313.09672)
			(xy 394.348116 -313.048936) (xy 394.344156 -312.999882) (xy 393.055094 -312.999882) (xy 393.054599 -313.024489)
			(xy 393.046704 -313.073066) (xy 393.03112 -313.119747) (xy 393.008249 -313.163324) (xy 392.978684 -313.202668)
			(xy 392.943191 -313.23676) (xy 392.902688 -313.264716) (xy 392.858226 -313.285814) (xy 392.810955 -313.299506)
			(xy 392.7621 -313.305438) (xy 392.712925 -313.303457) (xy 392.664706 -313.293613) (xy 392.61869 -313.276161)
			(xy 392.576069 -313.251554) (xy 392.537948 -313.220429) (xy 392.505313 -313.183592) (xy 392.47901 -313.141996)
			(xy 392.459719 -313.09672) (xy 392.447942 -313.048936) (xy 392.443982 -312.999882) (xy 391.155174 -312.999882)
			(xy 391.154679 -313.024489) (xy 391.146784 -313.073066) (xy 391.1312 -313.119747) (xy 391.108329 -313.163324)
			(xy 391.078764 -313.202668) (xy 391.043271 -313.23676) (xy 391.002768 -313.264716) (xy 390.958306 -313.285814)
			(xy 390.911035 -313.299506) (xy 390.86218 -313.305438) (xy 390.813005 -313.303457) (xy 390.764786 -313.293613)
			(xy 390.71877 -313.276161) (xy 390.676149 -313.251554) (xy 390.638028 -313.220429) (xy 390.605393 -313.183592)
			(xy 390.57909 -313.141996) (xy 390.559799 -313.09672) (xy 390.548022 -313.048936) (xy 390.544062 -312.999882)
			(xy 389.255254 -312.999882) (xy 389.254759 -313.024489) (xy 389.246864 -313.073066) (xy 389.23128 -313.119747)
			(xy 389.208409 -313.163324) (xy 389.178844 -313.202668) (xy 389.143351 -313.23676) (xy 389.102848 -313.264716)
			(xy 389.058386 -313.285814) (xy 389.011115 -313.299506) (xy 388.96226 -313.305438) (xy 388.913085 -313.303457)
			(xy 388.864866 -313.293613) (xy 388.81885 -313.276161) (xy 388.776229 -313.251554) (xy 388.738108 -313.220429)
			(xy 388.705473 -313.183592) (xy 388.67917 -313.141996) (xy 388.659879 -313.09672) (xy 388.648102 -313.048936)
			(xy 388.644142 -312.999882) (xy 387.355334 -312.999882) (xy 387.354839 -313.024489) (xy 387.346944 -313.073066)
			(xy 387.33136 -313.119747) (xy 387.308489 -313.163324) (xy 387.278924 -313.202668) (xy 387.243431 -313.23676)
			(xy 387.202928 -313.264716) (xy 387.158466 -313.285814) (xy 387.111195 -313.299506) (xy 387.06234 -313.305438)
			(xy 387.013165 -313.303457) (xy 386.964946 -313.293613) (xy 386.91893 -313.276161) (xy 386.876309 -313.251554)
			(xy 386.838188 -313.220429) (xy 386.805553 -313.183592) (xy 386.77925 -313.141996) (xy 386.759959 -313.09672)
			(xy 386.748182 -313.048936) (xy 386.744222 -312.999882) (xy 384.717544 -312.999882) (xy 384.717544 -313.949842)
			(xy 386.744222 -313.949842) (xy 386.748182 -313.900788) (xy 386.759959 -313.853004) (xy 386.77925 -313.807728)
			(xy 386.805553 -313.766132) (xy 386.838188 -313.729295) (xy 386.876309 -313.69817) (xy 386.91893 -313.673563)
			(xy 386.964946 -313.656111) (xy 387.013165 -313.646267) (xy 387.06234 -313.644286) (xy 387.111195 -313.650218)
			(xy 387.158466 -313.66391) (xy 387.202928 -313.685008) (xy 387.243431 -313.712964) (xy 387.278924 -313.747056)
			(xy 387.308489 -313.7864) (xy 387.33136 -313.829977) (xy 387.346944 -313.876658) (xy 387.354839 -313.925235)
			(xy 387.355334 -313.949842) (xy 388.644142 -313.949842) (xy 388.648102 -313.900788) (xy 388.659879 -313.853004)
			(xy 388.67917 -313.807728) (xy 388.705473 -313.766132) (xy 388.738108 -313.729295) (xy 388.776229 -313.69817)
			(xy 388.81885 -313.673563) (xy 388.864866 -313.656111) (xy 388.913085 -313.646267) (xy 388.96226 -313.644286)
			(xy 389.011115 -313.650218) (xy 389.058386 -313.66391) (xy 389.102848 -313.685008) (xy 389.143351 -313.712964)
			(xy 389.178844 -313.747056) (xy 389.208409 -313.7864) (xy 389.23128 -313.829977) (xy 389.246864 -313.876658)
			(xy 389.254759 -313.925235) (xy 389.255254 -313.949842) (xy 390.544062 -313.949842) (xy 390.548022 -313.900788)
			(xy 390.559799 -313.853004) (xy 390.57909 -313.807728) (xy 390.605393 -313.766132) (xy 390.638028 -313.729295)
			(xy 390.676149 -313.69817) (xy 390.71877 -313.673563) (xy 390.764786 -313.656111) (xy 390.813005 -313.646267)
			(xy 390.86218 -313.644286) (xy 390.911035 -313.650218) (xy 390.958306 -313.66391) (xy 391.002768 -313.685008)
			(xy 391.043271 -313.712964) (xy 391.078764 -313.747056) (xy 391.108329 -313.7864) (xy 391.1312 -313.829977)
			(xy 391.146784 -313.876658) (xy 391.154679 -313.925235) (xy 391.155174 -313.949842) (xy 392.443982 -313.949842)
			(xy 392.447942 -313.900788) (xy 392.459719 -313.853004) (xy 392.47901 -313.807728) (xy 392.505313 -313.766132)
			(xy 392.537948 -313.729295) (xy 392.576069 -313.69817) (xy 392.61869 -313.673563) (xy 392.664706 -313.656111)
			(xy 392.712925 -313.646267) (xy 392.7621 -313.644286) (xy 392.810955 -313.650218) (xy 392.858226 -313.66391)
			(xy 392.902688 -313.685008) (xy 392.943191 -313.712964) (xy 392.978684 -313.747056) (xy 393.008249 -313.7864)
			(xy 393.03112 -313.829977) (xy 393.046704 -313.876658) (xy 393.054599 -313.925235) (xy 393.055094 -313.949842)
			(xy 394.344156 -313.949842) (xy 394.348116 -313.900788) (xy 394.359893 -313.853004) (xy 394.379184 -313.807728)
			(xy 394.405487 -313.766132) (xy 394.438122 -313.729295) (xy 394.476243 -313.69817) (xy 394.518864 -313.673563)
			(xy 394.56488 -313.656111) (xy 394.613099 -313.646267) (xy 394.662274 -313.644286) (xy 394.711129 -313.650218)
			(xy 394.7584 -313.66391) (xy 394.802862 -313.685008) (xy 394.843365 -313.712964) (xy 394.878858 -313.747056)
			(xy 394.908423 -313.7864) (xy 394.931294 -313.829977) (xy 394.946878 -313.876658) (xy 394.954773 -313.925235)
			(xy 394.955268 -313.949842) (xy 396.244076 -313.949842) (xy 396.248036 -313.900788) (xy 396.259813 -313.853004)
			(xy 396.279104 -313.807728) (xy 396.305407 -313.766132) (xy 396.338042 -313.729295) (xy 396.376163 -313.69817)
			(xy 396.418784 -313.673563) (xy 396.4648 -313.656111) (xy 396.513019 -313.646267) (xy 396.562194 -313.644286)
			(xy 396.611049 -313.650218) (xy 396.65832 -313.66391) (xy 396.702782 -313.685008) (xy 396.743285 -313.712964)
			(xy 396.778778 -313.747056) (xy 396.808343 -313.7864) (xy 396.831214 -313.829977) (xy 396.846798 -313.876658)
			(xy 396.854693 -313.925235) (xy 396.855188 -313.949842) (xy 398.143996 -313.949842) (xy 398.147956 -313.900788)
			(xy 398.159733 -313.853004) (xy 398.179024 -313.807728) (xy 398.205327 -313.766132) (xy 398.237962 -313.729295)
			(xy 398.276083 -313.69817) (xy 398.318704 -313.673563) (xy 398.36472 -313.656111) (xy 398.412939 -313.646267)
			(xy 398.462114 -313.644286) (xy 398.510969 -313.650218) (xy 398.55824 -313.66391) (xy 398.602702 -313.685008)
			(xy 398.643205 -313.712964) (xy 398.678698 -313.747056) (xy 398.708263 -313.7864) (xy 398.731134 -313.829977)
			(xy 398.746718 -313.876658) (xy 398.754613 -313.925235) (xy 398.755108 -313.949842) (xy 398.754613 -313.974449)
			(xy 398.754434 -313.97555) (xy 400.023326 -313.97555) (xy 400.023326 -313.924134) (xy 400.031369 -313.873352)
			(xy 400.047257 -313.824453) (xy 400.0706 -313.778641) (xy 400.100821 -313.737045) (xy 400.137177 -313.700689)
			(xy 400.178773 -313.670468) (xy 400.224585 -313.647125) (xy 400.273484 -313.631237) (xy 400.324266 -313.623194)
			(xy 400.375682 -313.623194) (xy 400.426464 -313.631237) (xy 400.475363 -313.647125) (xy 400.521175 -313.670468)
			(xy 400.562771 -313.700689) (xy 400.599127 -313.737045) (xy 400.629348 -313.778641) (xy 400.652691 -313.824453)
			(xy 400.668579 -313.873352) (xy 400.676622 -313.924134) (xy 400.677126 -313.949842) (xy 400.676622 -313.97555)
			(xy 401.923246 -313.97555) (xy 401.923246 -313.924134) (xy 401.931289 -313.873352) (xy 401.947177 -313.824453)
			(xy 401.97052 -313.778641) (xy 402.000741 -313.737045) (xy 402.037097 -313.700689) (xy 402.078693 -313.670468)
			(xy 402.124505 -313.647125) (xy 402.173404 -313.631237) (xy 402.224186 -313.623194) (xy 402.275602 -313.623194)
			(xy 402.326384 -313.631237) (xy 402.375283 -313.647125) (xy 402.421095 -313.670468) (xy 402.462691 -313.700689)
			(xy 402.499047 -313.737045) (xy 402.529268 -313.778641) (xy 402.552611 -313.824453) (xy 402.568499 -313.873352)
			(xy 402.576542 -313.924134) (xy 402.577046 -313.949842) (xy 402.576542 -313.97555) (xy 403.823166 -313.97555)
			(xy 403.823166 -313.924134) (xy 403.831209 -313.873352) (xy 403.847097 -313.824453) (xy 403.87044 -313.778641)
			(xy 403.900661 -313.737045) (xy 403.937017 -313.700689) (xy 403.978613 -313.670468) (xy 404.024425 -313.647125)
			(xy 404.073324 -313.631237) (xy 404.124106 -313.623194) (xy 404.175522 -313.623194) (xy 404.226304 -313.631237)
			(xy 404.275203 -313.647125) (xy 404.321015 -313.670468) (xy 404.362611 -313.700689) (xy 404.398967 -313.737045)
			(xy 404.429188 -313.778641) (xy 404.452531 -313.824453) (xy 404.468419 -313.873352) (xy 404.476462 -313.924134)
			(xy 404.476966 -313.949842) (xy 404.476462 -313.97555) (xy 405.72334 -313.97555) (xy 405.72334 -313.924134)
			(xy 405.731383 -313.873352) (xy 405.747271 -313.824453) (xy 405.770614 -313.778641) (xy 405.800835 -313.737045)
			(xy 405.837191 -313.700689) (xy 405.878787 -313.670468) (xy 405.924599 -313.647125) (xy 405.973498 -313.631237)
			(xy 406.02428 -313.623194) (xy 406.075696 -313.623194) (xy 406.126478 -313.631237) (xy 406.175377 -313.647125)
			(xy 406.221189 -313.670468) (xy 406.262785 -313.700689) (xy 406.299141 -313.737045) (xy 406.329362 -313.778641)
			(xy 406.352705 -313.824453) (xy 406.368593 -313.873352) (xy 406.376636 -313.924134) (xy 406.37714 -313.949842)
			(xy 406.376636 -313.97555) (xy 407.62326 -313.97555) (xy 407.62326 -313.924134) (xy 407.631303 -313.873352)
			(xy 407.647191 -313.824453) (xy 407.670534 -313.778641) (xy 407.700755 -313.737045) (xy 407.737111 -313.700689)
			(xy 407.778707 -313.670468) (xy 407.824519 -313.647125) (xy 407.873418 -313.631237) (xy 407.9242 -313.623194)
			(xy 407.975616 -313.623194) (xy 408.026398 -313.631237) (xy 408.075297 -313.647125) (xy 408.121109 -313.670468)
			(xy 408.162705 -313.700689) (xy 408.199061 -313.737045) (xy 408.229282 -313.778641) (xy 408.252625 -313.824453)
			(xy 408.268513 -313.873352) (xy 408.276556 -313.924134) (xy 408.27706 -313.949842) (xy 408.276556 -313.97555)
			(xy 409.52318 -313.97555) (xy 409.52318 -313.924134) (xy 409.531223 -313.873352) (xy 409.547111 -313.824453)
			(xy 409.570454 -313.778641) (xy 409.600675 -313.737045) (xy 409.637031 -313.700689) (xy 409.678627 -313.670468)
			(xy 409.724439 -313.647125) (xy 409.773338 -313.631237) (xy 409.82412 -313.623194) (xy 409.875536 -313.623194)
			(xy 409.926318 -313.631237) (xy 409.975217 -313.647125) (xy 410.021029 -313.670468) (xy 410.062625 -313.700689)
			(xy 410.098981 -313.737045) (xy 410.129202 -313.778641) (xy 410.152545 -313.824453) (xy 410.168433 -313.873352)
			(xy 410.176476 -313.924134) (xy 410.17698 -313.949842) (xy 410.176476 -313.97555) (xy 411.423354 -313.97555)
			(xy 411.423354 -313.924134) (xy 411.431397 -313.873352) (xy 411.447285 -313.824453) (xy 411.470628 -313.778641)
			(xy 411.500849 -313.737045) (xy 411.537205 -313.700689) (xy 411.578801 -313.670468) (xy 411.624613 -313.647125)
			(xy 411.673512 -313.631237) (xy 411.724294 -313.623194) (xy 411.77571 -313.623194) (xy 411.826492 -313.631237)
			(xy 411.875391 -313.647125) (xy 411.921203 -313.670468) (xy 411.962799 -313.700689) (xy 411.999155 -313.737045)
			(xy 412.029376 -313.778641) (xy 412.052719 -313.824453) (xy 412.068607 -313.873352) (xy 412.07665 -313.924134)
			(xy 412.077154 -313.949842) (xy 412.07665 -313.97555) (xy 413.323274 -313.97555) (xy 413.323274 -313.924134)
			(xy 413.331317 -313.873352) (xy 413.347205 -313.824453) (xy 413.370548 -313.778641) (xy 413.400769 -313.737045)
			(xy 413.437125 -313.700689) (xy 413.478721 -313.670468) (xy 413.524533 -313.647125) (xy 413.573432 -313.631237)
			(xy 413.624214 -313.623194) (xy 413.67563 -313.623194) (xy 413.726412 -313.631237) (xy 413.775311 -313.647125)
			(xy 413.821123 -313.670468) (xy 413.862719 -313.700689) (xy 413.899075 -313.737045) (xy 413.929296 -313.778641)
			(xy 413.952639 -313.824453) (xy 413.968527 -313.873352) (xy 413.97657 -313.924134) (xy 413.977074 -313.949842)
			(xy 415.244038 -313.949842) (xy 415.247998 -313.900788) (xy 415.259775 -313.853004) (xy 415.279066 -313.807728)
			(xy 415.305369 -313.766132) (xy 415.338004 -313.729295) (xy 415.376125 -313.69817) (xy 415.418746 -313.673563)
			(xy 415.464762 -313.656111) (xy 415.512981 -313.646267) (xy 415.562156 -313.644286) (xy 415.611011 -313.650218)
			(xy 415.658282 -313.66391) (xy 415.702744 -313.685008) (xy 415.743247 -313.712964) (xy 415.77874 -313.747056)
			(xy 415.808305 -313.7864) (xy 415.831176 -313.829977) (xy 415.84676 -313.876658) (xy 415.854655 -313.925235)
			(xy 415.85515 -313.949842) (xy 417.144212 -313.949842) (xy 417.148172 -313.900788) (xy 417.159949 -313.853004)
			(xy 417.17924 -313.807728) (xy 417.205543 -313.766132) (xy 417.238178 -313.729295) (xy 417.276299 -313.69817)
			(xy 417.31892 -313.673563) (xy 417.364936 -313.656111) (xy 417.413155 -313.646267) (xy 417.46233 -313.644286)
			(xy 417.511185 -313.650218) (xy 417.558456 -313.66391) (xy 417.602918 -313.685008) (xy 417.643421 -313.712964)
			(xy 417.678914 -313.747056) (xy 417.708479 -313.7864) (xy 417.73135 -313.829977) (xy 417.746934 -313.876658)
			(xy 417.754829 -313.925235) (xy 417.755324 -313.949842) (xy 419.044132 -313.949842) (xy 419.048092 -313.900788)
			(xy 419.059869 -313.853004) (xy 419.07916 -313.807728) (xy 419.105463 -313.766132) (xy 419.138098 -313.729295)
			(xy 419.176219 -313.69817) (xy 419.21884 -313.673563) (xy 419.264856 -313.656111) (xy 419.313075 -313.646267)
			(xy 419.36225 -313.644286) (xy 419.411105 -313.650218) (xy 419.458376 -313.66391) (xy 419.502838 -313.685008)
			(xy 419.543341 -313.712964) (xy 419.578834 -313.747056) (xy 419.608399 -313.7864) (xy 419.63127 -313.829977)
			(xy 419.646854 -313.876658) (xy 419.654749 -313.925235) (xy 419.655244 -313.949842) (xy 420.944052 -313.949842)
			(xy 420.948012 -313.900788) (xy 420.959789 -313.853004) (xy 420.97908 -313.807728) (xy 421.005383 -313.766132)
			(xy 421.038018 -313.729295) (xy 421.076139 -313.69817) (xy 421.11876 -313.673563) (xy 421.164776 -313.656111)
			(xy 421.212995 -313.646267) (xy 421.26217 -313.644286) (xy 421.311025 -313.650218) (xy 421.358296 -313.66391)
			(xy 421.402758 -313.685008) (xy 421.443261 -313.712964) (xy 421.478754 -313.747056) (xy 421.508319 -313.7864)
			(xy 421.53119 -313.829977) (xy 421.546774 -313.876658) (xy 421.554669 -313.925235) (xy 421.555164 -313.949842)
			(xy 421.554669 -313.974449) (xy 421.55449 -313.97555) (xy 422.823382 -313.97555) (xy 422.823382 -313.924134)
			(xy 422.831425 -313.873352) (xy 422.847313 -313.824453) (xy 422.870656 -313.778641) (xy 422.900877 -313.737045)
			(xy 422.937233 -313.700689) (xy 422.978829 -313.670468) (xy 423.024641 -313.647125) (xy 423.07354 -313.631237)
			(xy 423.124322 -313.623194) (xy 423.175738 -313.623194) (xy 423.22652 -313.631237) (xy 423.275419 -313.647125)
			(xy 423.321231 -313.670468) (xy 423.362827 -313.700689) (xy 423.399183 -313.737045) (xy 423.429404 -313.778641)
			(xy 423.452747 -313.824453) (xy 423.468635 -313.873352) (xy 423.476678 -313.924134) (xy 423.477182 -313.949842)
			(xy 423.476678 -313.97555) (xy 424.723302 -313.97555) (xy 424.723302 -313.924134) (xy 424.731345 -313.873352)
			(xy 424.747233 -313.824453) (xy 424.770576 -313.778641) (xy 424.800797 -313.737045) (xy 424.837153 -313.700689)
			(xy 424.878749 -313.670468) (xy 424.924561 -313.647125) (xy 424.97346 -313.631237) (xy 425.024242 -313.623194)
			(xy 425.075658 -313.623194) (xy 425.12644 -313.631237) (xy 425.175339 -313.647125) (xy 425.221151 -313.670468)
			(xy 425.262747 -313.700689) (xy 425.299103 -313.737045) (xy 425.329324 -313.778641) (xy 425.352667 -313.824453)
			(xy 425.368555 -313.873352) (xy 425.376598 -313.924134) (xy 425.377102 -313.949842) (xy 425.376598 -313.97555)
			(xy 426.623222 -313.97555) (xy 426.623222 -313.924134) (xy 426.631265 -313.873352) (xy 426.647153 -313.824453)
			(xy 426.670496 -313.778641) (xy 426.700717 -313.737045) (xy 426.737073 -313.700689) (xy 426.778669 -313.670468)
			(xy 426.824481 -313.647125) (xy 426.87338 -313.631237) (xy 426.924162 -313.623194) (xy 426.975578 -313.623194)
			(xy 427.02636 -313.631237) (xy 427.075259 -313.647125) (xy 427.121071 -313.670468) (xy 427.162667 -313.700689)
			(xy 427.199023 -313.737045) (xy 427.229244 -313.778641) (xy 427.252587 -313.824453) (xy 427.268475 -313.873352)
			(xy 427.276518 -313.924134) (xy 427.277022 -313.949842) (xy 427.276518 -313.97555) (xy 428.523142 -313.97555)
			(xy 428.523142 -313.924134) (xy 428.531185 -313.873352) (xy 428.547073 -313.824453) (xy 428.570416 -313.778641)
			(xy 428.600637 -313.737045) (xy 428.636993 -313.700689) (xy 428.678589 -313.670468) (xy 428.724401 -313.647125)
			(xy 428.7733 -313.631237) (xy 428.824082 -313.623194) (xy 428.875498 -313.623194) (xy 428.92628 -313.631237)
			(xy 428.975179 -313.647125) (xy 429.020991 -313.670468) (xy 429.062587 -313.700689) (xy 429.098943 -313.737045)
			(xy 429.129164 -313.778641) (xy 429.152507 -313.824453) (xy 429.168395 -313.873352) (xy 429.176438 -313.924134)
			(xy 429.176942 -313.949842) (xy 429.176438 -313.97555) (xy 429.168395 -314.026332) (xy 429.152507 -314.075231)
			(xy 429.129164 -314.121043) (xy 429.098943 -314.162639) (xy 429.062587 -314.198995) (xy 429.020991 -314.229216)
			(xy 428.975179 -314.252559) (xy 428.92628 -314.268447) (xy 428.875498 -314.27649) (xy 428.824082 -314.27649)
			(xy 428.7733 -314.268447) (xy 428.724401 -314.252559) (xy 428.678589 -314.229216) (xy 428.636993 -314.198995)
			(xy 428.600637 -314.162639) (xy 428.570416 -314.121043) (xy 428.547073 -314.075231) (xy 428.531185 -314.026332)
			(xy 428.523142 -313.97555) (xy 427.276518 -313.97555) (xy 427.268475 -314.026332) (xy 427.252587 -314.075231)
			(xy 427.229244 -314.121043) (xy 427.199023 -314.162639) (xy 427.162667 -314.198995) (xy 427.121071 -314.229216)
			(xy 427.075259 -314.252559) (xy 427.02636 -314.268447) (xy 426.975578 -314.27649) (xy 426.924162 -314.27649)
			(xy 426.87338 -314.268447) (xy 426.824481 -314.252559) (xy 426.778669 -314.229216) (xy 426.737073 -314.198995)
			(xy 426.700717 -314.162639) (xy 426.670496 -314.121043) (xy 426.647153 -314.075231) (xy 426.631265 -314.026332)
			(xy 426.623222 -313.97555) (xy 425.376598 -313.97555) (xy 425.368555 -314.026332) (xy 425.352667 -314.075231)
			(xy 425.329324 -314.121043) (xy 425.299103 -314.162639) (xy 425.262747 -314.198995) (xy 425.221151 -314.229216)
			(xy 425.175339 -314.252559) (xy 425.12644 -314.268447) (xy 425.075658 -314.27649) (xy 425.024242 -314.27649)
			(xy 424.97346 -314.268447) (xy 424.924561 -314.252559) (xy 424.878749 -314.229216) (xy 424.837153 -314.198995)
			(xy 424.800797 -314.162639) (xy 424.770576 -314.121043) (xy 424.747233 -314.075231) (xy 424.731345 -314.026332)
			(xy 424.723302 -313.97555) (xy 423.476678 -313.97555) (xy 423.468635 -314.026332) (xy 423.452747 -314.075231)
			(xy 423.429404 -314.121043) (xy 423.399183 -314.162639) (xy 423.362827 -314.198995) (xy 423.321231 -314.229216)
			(xy 423.275419 -314.252559) (xy 423.22652 -314.268447) (xy 423.175738 -314.27649) (xy 423.124322 -314.27649)
			(xy 423.07354 -314.268447) (xy 423.024641 -314.252559) (xy 422.978829 -314.229216) (xy 422.937233 -314.198995)
			(xy 422.900877 -314.162639) (xy 422.870656 -314.121043) (xy 422.847313 -314.075231) (xy 422.831425 -314.026332)
			(xy 422.823382 -313.97555) (xy 421.55449 -313.97555) (xy 421.546774 -314.023026) (xy 421.53119 -314.069707)
			(xy 421.508319 -314.113284) (xy 421.478754 -314.152628) (xy 421.443261 -314.18672) (xy 421.402758 -314.214676)
			(xy 421.358296 -314.235774) (xy 421.311025 -314.249466) (xy 421.26217 -314.255398) (xy 421.212995 -314.253417)
			(xy 421.164776 -314.243573) (xy 421.11876 -314.226121) (xy 421.076139 -314.201514) (xy 421.038018 -314.170389)
			(xy 421.005383 -314.133552) (xy 420.97908 -314.091956) (xy 420.959789 -314.04668) (xy 420.948012 -313.998896)
			(xy 420.944052 -313.949842) (xy 419.655244 -313.949842) (xy 419.654749 -313.974449) (xy 419.646854 -314.023026)
			(xy 419.63127 -314.069707) (xy 419.608399 -314.113284) (xy 419.578834 -314.152628) (xy 419.543341 -314.18672)
			(xy 419.502838 -314.214676) (xy 419.458376 -314.235774) (xy 419.411105 -314.249466) (xy 419.36225 -314.255398)
			(xy 419.313075 -314.253417) (xy 419.264856 -314.243573) (xy 419.21884 -314.226121) (xy 419.176219 -314.201514)
			(xy 419.138098 -314.170389) (xy 419.105463 -314.133552) (xy 419.07916 -314.091956) (xy 419.059869 -314.04668)
			(xy 419.048092 -313.998896) (xy 419.044132 -313.949842) (xy 417.755324 -313.949842) (xy 417.754829 -313.974449)
			(xy 417.746934 -314.023026) (xy 417.73135 -314.069707) (xy 417.708479 -314.113284) (xy 417.678914 -314.152628)
			(xy 417.643421 -314.18672) (xy 417.602918 -314.214676) (xy 417.558456 -314.235774) (xy 417.511185 -314.249466)
			(xy 417.46233 -314.255398) (xy 417.413155 -314.253417) (xy 417.364936 -314.243573) (xy 417.31892 -314.226121)
			(xy 417.276299 -314.201514) (xy 417.238178 -314.170389) (xy 417.205543 -314.133552) (xy 417.17924 -314.091956)
			(xy 417.159949 -314.04668) (xy 417.148172 -313.998896) (xy 417.144212 -313.949842) (xy 415.85515 -313.949842)
			(xy 415.854655 -313.974449) (xy 415.84676 -314.023026) (xy 415.831176 -314.069707) (xy 415.808305 -314.113284)
			(xy 415.77874 -314.152628) (xy 415.743247 -314.18672) (xy 415.702744 -314.214676) (xy 415.658282 -314.235774)
			(xy 415.611011 -314.249466) (xy 415.562156 -314.255398) (xy 415.512981 -314.253417) (xy 415.464762 -314.243573)
			(xy 415.418746 -314.226121) (xy 415.376125 -314.201514) (xy 415.338004 -314.170389) (xy 415.305369 -314.133552)
			(xy 415.279066 -314.091956) (xy 415.259775 -314.04668) (xy 415.247998 -313.998896) (xy 415.244038 -313.949842)
			(xy 413.977074 -313.949842) (xy 413.97657 -313.97555) (xy 413.968527 -314.026332) (xy 413.952639 -314.075231)
			(xy 413.929296 -314.121043) (xy 413.899075 -314.162639) (xy 413.862719 -314.198995) (xy 413.821123 -314.229216)
			(xy 413.775311 -314.252559) (xy 413.726412 -314.268447) (xy 413.67563 -314.27649) (xy 413.624214 -314.27649)
			(xy 413.573432 -314.268447) (xy 413.524533 -314.252559) (xy 413.478721 -314.229216) (xy 413.437125 -314.198995)
			(xy 413.400769 -314.162639) (xy 413.370548 -314.121043) (xy 413.347205 -314.075231) (xy 413.331317 -314.026332)
			(xy 413.323274 -313.97555) (xy 412.07665 -313.97555) (xy 412.068607 -314.026332) (xy 412.052719 -314.075231)
			(xy 412.029376 -314.121043) (xy 411.999155 -314.162639) (xy 411.962799 -314.198995) (xy 411.921203 -314.229216)
			(xy 411.875391 -314.252559) (xy 411.826492 -314.268447) (xy 411.77571 -314.27649) (xy 411.724294 -314.27649)
			(xy 411.673512 -314.268447) (xy 411.624613 -314.252559) (xy 411.578801 -314.229216) (xy 411.537205 -314.198995)
			(xy 411.500849 -314.162639) (xy 411.470628 -314.121043) (xy 411.447285 -314.075231) (xy 411.431397 -314.026332)
			(xy 411.423354 -313.97555) (xy 410.176476 -313.97555) (xy 410.168433 -314.026332) (xy 410.152545 -314.075231)
			(xy 410.129202 -314.121043) (xy 410.098981 -314.162639) (xy 410.062625 -314.198995) (xy 410.021029 -314.229216)
			(xy 409.975217 -314.252559) (xy 409.926318 -314.268447) (xy 409.875536 -314.27649) (xy 409.82412 -314.27649)
			(xy 409.773338 -314.268447) (xy 409.724439 -314.252559) (xy 409.678627 -314.229216) (xy 409.637031 -314.198995)
			(xy 409.600675 -314.162639) (xy 409.570454 -314.121043) (xy 409.547111 -314.075231) (xy 409.531223 -314.026332)
			(xy 409.52318 -313.97555) (xy 408.276556 -313.97555) (xy 408.268513 -314.026332) (xy 408.252625 -314.075231)
			(xy 408.229282 -314.121043) (xy 408.199061 -314.162639) (xy 408.162705 -314.198995) (xy 408.121109 -314.229216)
			(xy 408.075297 -314.252559) (xy 408.026398 -314.268447) (xy 407.975616 -314.27649) (xy 407.9242 -314.27649)
			(xy 407.873418 -314.268447) (xy 407.824519 -314.252559) (xy 407.778707 -314.229216) (xy 407.737111 -314.198995)
			(xy 407.700755 -314.162639) (xy 407.670534 -314.121043) (xy 407.647191 -314.075231) (xy 407.631303 -314.026332)
			(xy 407.62326 -313.97555) (xy 406.376636 -313.97555) (xy 406.368593 -314.026332) (xy 406.352705 -314.075231)
			(xy 406.329362 -314.121043) (xy 406.299141 -314.162639) (xy 406.262785 -314.198995) (xy 406.221189 -314.229216)
			(xy 406.175377 -314.252559) (xy 406.126478 -314.268447) (xy 406.075696 -314.27649) (xy 406.02428 -314.27649)
			(xy 405.973498 -314.268447) (xy 405.924599 -314.252559) (xy 405.878787 -314.229216) (xy 405.837191 -314.198995)
			(xy 405.800835 -314.162639) (xy 405.770614 -314.121043) (xy 405.747271 -314.075231) (xy 405.731383 -314.026332)
			(xy 405.72334 -313.97555) (xy 404.476462 -313.97555) (xy 404.468419 -314.026332) (xy 404.452531 -314.075231)
			(xy 404.429188 -314.121043) (xy 404.398967 -314.162639) (xy 404.362611 -314.198995) (xy 404.321015 -314.229216)
			(xy 404.275203 -314.252559) (xy 404.226304 -314.268447) (xy 404.175522 -314.27649) (xy 404.124106 -314.27649)
			(xy 404.073324 -314.268447) (xy 404.024425 -314.252559) (xy 403.978613 -314.229216) (xy 403.937017 -314.198995)
			(xy 403.900661 -314.162639) (xy 403.87044 -314.121043) (xy 403.847097 -314.075231) (xy 403.831209 -314.026332)
			(xy 403.823166 -313.97555) (xy 402.576542 -313.97555) (xy 402.568499 -314.026332) (xy 402.552611 -314.075231)
			(xy 402.529268 -314.121043) (xy 402.499047 -314.162639) (xy 402.462691 -314.198995) (xy 402.421095 -314.229216)
			(xy 402.375283 -314.252559) (xy 402.326384 -314.268447) (xy 402.275602 -314.27649) (xy 402.224186 -314.27649)
			(xy 402.173404 -314.268447) (xy 402.124505 -314.252559) (xy 402.078693 -314.229216) (xy 402.037097 -314.198995)
			(xy 402.000741 -314.162639) (xy 401.97052 -314.121043) (xy 401.947177 -314.075231) (xy 401.931289 -314.026332)
			(xy 401.923246 -313.97555) (xy 400.676622 -313.97555) (xy 400.668579 -314.026332) (xy 400.652691 -314.075231)
			(xy 400.629348 -314.121043) (xy 400.599127 -314.162639) (xy 400.562771 -314.198995) (xy 400.521175 -314.229216)
			(xy 400.475363 -314.252559) (xy 400.426464 -314.268447) (xy 400.375682 -314.27649) (xy 400.324266 -314.27649)
			(xy 400.273484 -314.268447) (xy 400.224585 -314.252559) (xy 400.178773 -314.229216) (xy 400.137177 -314.198995)
			(xy 400.100821 -314.162639) (xy 400.0706 -314.121043) (xy 400.047257 -314.075231) (xy 400.031369 -314.026332)
			(xy 400.023326 -313.97555) (xy 398.754434 -313.97555) (xy 398.746718 -314.023026) (xy 398.731134 -314.069707)
			(xy 398.708263 -314.113284) (xy 398.678698 -314.152628) (xy 398.643205 -314.18672) (xy 398.602702 -314.214676)
			(xy 398.55824 -314.235774) (xy 398.510969 -314.249466) (xy 398.462114 -314.255398) (xy 398.412939 -314.253417)
			(xy 398.36472 -314.243573) (xy 398.318704 -314.226121) (xy 398.276083 -314.201514) (xy 398.237962 -314.170389)
			(xy 398.205327 -314.133552) (xy 398.179024 -314.091956) (xy 398.159733 -314.04668) (xy 398.147956 -313.998896)
			(xy 398.143996 -313.949842) (xy 396.855188 -313.949842) (xy 396.854693 -313.974449) (xy 396.846798 -314.023026)
			(xy 396.831214 -314.069707) (xy 396.808343 -314.113284) (xy 396.778778 -314.152628) (xy 396.743285 -314.18672)
			(xy 396.702782 -314.214676) (xy 396.65832 -314.235774) (xy 396.611049 -314.249466) (xy 396.562194 -314.255398)
			(xy 396.513019 -314.253417) (xy 396.4648 -314.243573) (xy 396.418784 -314.226121) (xy 396.376163 -314.201514)
			(xy 396.338042 -314.170389) (xy 396.305407 -314.133552) (xy 396.279104 -314.091956) (xy 396.259813 -314.04668)
			(xy 396.248036 -313.998896) (xy 396.244076 -313.949842) (xy 394.955268 -313.949842) (xy 394.954773 -313.974449)
			(xy 394.946878 -314.023026) (xy 394.931294 -314.069707) (xy 394.908423 -314.113284) (xy 394.878858 -314.152628)
			(xy 394.843365 -314.18672) (xy 394.802862 -314.214676) (xy 394.7584 -314.235774) (xy 394.711129 -314.249466)
			(xy 394.662274 -314.255398) (xy 394.613099 -314.253417) (xy 394.56488 -314.243573) (xy 394.518864 -314.226121)
			(xy 394.476243 -314.201514) (xy 394.438122 -314.170389) (xy 394.405487 -314.133552) (xy 394.379184 -314.091956)
			(xy 394.359893 -314.04668) (xy 394.348116 -313.998896) (xy 394.344156 -313.949842) (xy 393.055094 -313.949842)
			(xy 393.054599 -313.974449) (xy 393.046704 -314.023026) (xy 393.03112 -314.069707) (xy 393.008249 -314.113284)
			(xy 392.978684 -314.152628) (xy 392.943191 -314.18672) (xy 392.902688 -314.214676) (xy 392.858226 -314.235774)
			(xy 392.810955 -314.249466) (xy 392.7621 -314.255398) (xy 392.712925 -314.253417) (xy 392.664706 -314.243573)
			(xy 392.61869 -314.226121) (xy 392.576069 -314.201514) (xy 392.537948 -314.170389) (xy 392.505313 -314.133552)
			(xy 392.47901 -314.091956) (xy 392.459719 -314.04668) (xy 392.447942 -313.998896) (xy 392.443982 -313.949842)
			(xy 391.155174 -313.949842) (xy 391.154679 -313.974449) (xy 391.146784 -314.023026) (xy 391.1312 -314.069707)
			(xy 391.108329 -314.113284) (xy 391.078764 -314.152628) (xy 391.043271 -314.18672) (xy 391.002768 -314.214676)
			(xy 390.958306 -314.235774) (xy 390.911035 -314.249466) (xy 390.86218 -314.255398) (xy 390.813005 -314.253417)
			(xy 390.764786 -314.243573) (xy 390.71877 -314.226121) (xy 390.676149 -314.201514) (xy 390.638028 -314.170389)
			(xy 390.605393 -314.133552) (xy 390.57909 -314.091956) (xy 390.559799 -314.04668) (xy 390.548022 -313.998896)
			(xy 390.544062 -313.949842) (xy 389.255254 -313.949842) (xy 389.254759 -313.974449) (xy 389.246864 -314.023026)
			(xy 389.23128 -314.069707) (xy 389.208409 -314.113284) (xy 389.178844 -314.152628) (xy 389.143351 -314.18672)
			(xy 389.102848 -314.214676) (xy 389.058386 -314.235774) (xy 389.011115 -314.249466) (xy 388.96226 -314.255398)
			(xy 388.913085 -314.253417) (xy 388.864866 -314.243573) (xy 388.81885 -314.226121) (xy 388.776229 -314.201514)
			(xy 388.738108 -314.170389) (xy 388.705473 -314.133552) (xy 388.67917 -314.091956) (xy 388.659879 -314.04668)
			(xy 388.648102 -313.998896) (xy 388.644142 -313.949842) (xy 387.355334 -313.949842) (xy 387.354839 -313.974449)
			(xy 387.346944 -314.023026) (xy 387.33136 -314.069707) (xy 387.308489 -314.113284) (xy 387.278924 -314.152628)
			(xy 387.243431 -314.18672) (xy 387.202928 -314.214676) (xy 387.158466 -314.235774) (xy 387.111195 -314.249466)
			(xy 387.06234 -314.255398) (xy 387.013165 -314.253417) (xy 386.964946 -314.243573) (xy 386.91893 -314.226121)
			(xy 386.876309 -314.201514) (xy 386.838188 -314.170389) (xy 386.805553 -314.133552) (xy 386.77925 -314.091956)
			(xy 386.759959 -314.04668) (xy 386.748182 -313.998896) (xy 386.744222 -313.949842) (xy 384.717544 -313.949842)
			(xy 384.717544 -314.120784) (xy 384.717544 -314.121292) (xy 384.71729 -314.151264) (xy 384.69189 -314.99175)
			(xy 384.692028 -315.001944) (xy 384.699351 -315.020953) (xy 384.706114 -315.02858) (xy 384.712972 -315.035692)
			(xy 384.732022 -315.04382) (xy 384.74523 -315.04382) (xy 384.755922 -315.043256) (xy 384.775477 -315.034598)
			(xy 384.783076 -315.027056) (xy 384.833622 -314.970922) (xy 384.840406 -314.962701) (xy 384.846976 -314.942445)
			(xy 384.846322 -314.931806) (xy 384.846322 -314.931552) (xy 384.844544 -314.899802) (xy 384.845066 -314.874547)
			(xy 384.853379 -314.824725) (xy 384.86978 -314.776951) (xy 384.893821 -314.732528) (xy 384.924845 -314.692668)
			(xy 384.962007 -314.658458) (xy 385.004293 -314.630832) (xy 385.050549 -314.610542) (xy 385.099514 -314.598142)
			(xy 385.149852 -314.593971) (xy 385.20019 -314.598142) (xy 385.249155 -314.610542) (xy 385.295411 -314.630832)
			(xy 385.337697 -314.658458) (xy 385.374859 -314.692668) (xy 385.405883 -314.732528) (xy 385.429924 -314.776951)
			(xy 385.446325 -314.824725) (xy 385.454638 -314.874547) (xy 385.45516 -314.899802) (xy 385.453382 -314.931298)
			(xy 385.453382 -314.931806) (xy 385.452871 -314.942425) (xy 385.459439 -314.962621) (xy 385.466082 -314.970922)
			(xy 385.516628 -315.027056) (xy 385.524146 -315.034712) (xy 385.543751 -315.043386) (xy 385.554474 -315.04382)
			(xy 385.62534 -315.04382) (xy 385.639704 -315.043992) (xy 385.66832 -315.04654) (xy 385.68249 -315.0489)
			(xy 385.682998 -315.0489) (xy 385.691126 -315.05017) (xy 385.713732 -315.043312) (xy 385.781296 -314.978542)
			(xy 385.789363 -314.970048) (xy 385.797417 -314.948078) (xy 385.79679 -314.936378) (xy 385.79679 -314.936124)
			(xy 385.795741 -314.92708) (xy 385.794598 -314.908906) (xy 385.794504 -314.899802) (xy 385.79499 -314.874982)
			(xy 385.80302 -314.825997) (xy 385.81887 -314.778956) (xy 385.842121 -314.735098) (xy 385.872161 -314.69558)
			(xy 385.908198 -314.661443) (xy 385.949284 -314.633585) (xy 385.994335 -314.612742) (xy 386.042165 -314.599461)
			(xy 386.091513 -314.594093) (xy 386.14108 -314.59678) (xy 386.189559 -314.60745) (xy 386.235673 -314.625822)
			(xy 386.278208 -314.651413) (xy 386.316042 -314.683548) (xy 386.348178 -314.721381) (xy 386.373771 -314.763914)
			(xy 386.392146 -314.810028) (xy 386.402818 -314.858506) (xy 386.405507 -314.908073) (xy 386.400142 -314.957421)
			(xy 386.386863 -315.005252) (xy 386.366021 -315.050304) (xy 386.338166 -315.091391) (xy 386.30403 -315.12743)
			(xy 386.264513 -315.157472) (xy 386.220657 -315.180725) (xy 386.173617 -315.196577) (xy 386.124632 -315.204609)
			(xy 386.099812 -315.20511) (xy 386.090708 -315.205011) (xy 386.072535 -315.203865) (xy 386.06349 -315.202824)
			(xy 386.063236 -315.202824) (xy 386.051433 -315.202008) (xy 386.02918 -315.209956) (xy 386.020564 -315.218064)
			(xy 385.956048 -315.285628) (xy 385.948936 -315.308234) (xy 385.949952 -315.314838) (xy 385.952535 -315.32969)
			(xy 385.955331 -315.359708) (xy 385.95554 -315.374782) (xy 385.955058 -315.400792) (xy 385.946923 -315.45217)
			(xy 385.930849 -315.501644) (xy 385.907234 -315.547994) (xy 385.876658 -315.590078) (xy 385.839875 -315.626861)
			(xy 385.79779 -315.657436) (xy 385.75144 -315.681051) (xy 385.701967 -315.697123) (xy 385.650588 -315.705258)
			(xy 385.624578 -315.705744) (xy 385.519676 -315.705744) (xy 385.518914 -315.705744) (xy 385.50771 -315.706499)
			(xy 385.487558 -315.716341) (xy 385.473497 -315.733814) (xy 385.468194 -315.755606) (xy 385.469892 -315.766704)
			(xy 385.4704 -315.76899) (xy 385.474972 -315.789564) (xy 385.477505 -315.800397) (xy 385.490345 -315.818534)
			(xy 385.509661 -315.82952) (xy 385.520692 -315.830966) (xy 385.544568 -315.833106) (xy 385.592089 -315.839456)
			(xy 385.615688 -315.843666) (xy 385.620231 -315.844396) (xy 385.629433 -315.844396) (xy 385.633976 -315.843666)
			(xy 385.657578 -315.839474) (xy 385.705098 -315.833123) (xy 385.728972 -315.830966) (xy 385.739972 -315.82945)
			(xy 385.759223 -315.81843) (xy 385.772086 -315.800359) (xy 385.774692 -315.789564) (xy 385.779801 -315.76457)
			(xy 385.796684 -315.716432) (xy 385.820757 -315.671456) (xy 385.851451 -315.63071) (xy 385.888037 -315.59516)
			(xy 385.929648 -315.56565) (xy 385.975296 -315.542878) (xy 386.0239 -315.527385) (xy 386.074306 -315.519539)
			(xy 386.099812 -315.519054) (xy 386.1258 -315.519564) (xy 386.177135 -315.527696) (xy 386.226566 -315.543758)
			(xy 386.272877 -315.567354) (xy 386.314927 -315.597903) (xy 386.35168 -315.634654) (xy 386.382233 -315.676701)
			(xy 386.405832 -315.72301) (xy 386.421898 -315.77244) (xy 386.430034 -315.823774) (xy 386.43052 -315.849762)
			(xy 386.43052 -315.850778) (xy 386.430937 -315.860862) (xy 386.438702 -315.879472) (xy 386.453068 -315.893624)
			(xy 386.46227 -315.897768) (xy 386.490463 -315.909331) (xy 386.545494 -315.935512) (xy 386.572252 -315.950092)
			(xy 386.580907 -315.954413) (xy 386.600075 -315.956895) (xy 386.618812 -315.952149) (xy 386.626862 -315.94679)
			(xy 386.634736 -315.941202) (xy 386.64007 -315.937392) (xy 386.656072 -315.918342) (xy 386.658866 -315.9125)
			(xy 386.672115 -315.88516) (xy 386.701601 -315.832034) (xy 386.717794 -315.806328) (xy 386.720408 -315.802174)
			(xy 386.724121 -315.793091) (xy 386.72516 -315.788294) (xy 386.730217 -315.764071) (xy 386.746565 -315.717369)
			(xy 386.769692 -315.673624) (xy 386.799079 -315.633815) (xy 386.834072 -315.59883) (xy 386.873888 -315.569452)
			(xy 386.917637 -315.546335) (xy 386.964344 -315.529997) (xy 386.988558 -315.524896) (xy 386.993343 -315.52382)
			(xy 387.002424 -315.520116) (xy 387.006592 -315.51753) (xy 387.027733 -315.504163) (xy 387.07119 -315.479387)
			(xy 387.09346 -315.468) (xy 387.100986 -315.463855) (xy 387.112945 -315.451533) (xy 387.116828 -315.44387)
			(xy 387.134892 -315.405627) (xy 387.176735 -315.332117) (xy 387.200394 -315.297058) (xy 387.202692 -315.293649)
			(xy 387.206272 -315.286248) (xy 387.207506 -315.282326) (xy 387.215759 -315.255871) (xy 387.239844 -315.205966)
			(xy 387.271915 -315.160777) (xy 387.311075 -315.121571) (xy 387.356225 -315.089445) (xy 387.406102 -315.065301)
			(xy 387.43255 -315.057028) (xy 387.436459 -315.055847) (xy 387.44386 -315.052398) (xy 387.447282 -315.05017)
			(xy 387.492229 -315.019987) (xy 387.587574 -314.968685) (xy 387.637528 -314.947808) (xy 387.646694 -314.943617)
			(xy 387.66101 -314.929454) (xy 387.668806 -314.910885) (xy 387.669278 -314.900818) (xy 387.669278 -314.899802)
			(xy 387.669788 -314.873815) (xy 387.677918 -314.82248) (xy 387.693979 -314.77305) (xy 387.717575 -314.72674)
			(xy 387.748125 -314.684692) (xy 387.784876 -314.647941) (xy 387.826924 -314.617391) (xy 387.873234 -314.593795)
			(xy 387.922664 -314.577734) (xy 387.973999 -314.569604) (xy 388.025973 -314.569604) (xy 388.077308 -314.577734)
			(xy 388.126738 -314.593795) (xy 388.173048 -314.617391) (xy 388.215096 -314.647941) (xy 388.251847 -314.684692)
			(xy 388.282397 -314.72674) (xy 388.305993 -314.77305) (xy 388.322054 -314.82248) (xy 388.330184 -314.873815)
			(xy 388.330694 -314.899802) (xy 388.330694 -314.900818) (xy 388.331118 -314.910898) (xy 388.338889 -314.9295)
			(xy 388.353253 -314.943645) (xy 388.362444 -314.947808) (xy 388.40769 -314.966658) (xy 388.494498 -315.012191)
			(xy 388.576284 -315.066226) (xy 388.652217 -315.128217) (xy 388.68731 -315.162438) (xy 388.687564 -315.162692)
			(xy 388.717387 -315.193202) (xy 388.772164 -315.258621) (xy 388.821002 -315.328586) (xy 388.863525 -315.402559)
			(xy 388.881874 -315.441076) (xy 388.886656 -315.450211) (xy 388.902002 -315.463952) (xy 388.911592 -315.467746)
			(xy 388.941056 -315.477652) (xy 388.950983 -315.480499) (xy 388.971557 -315.478929) (xy 388.980934 -315.474604)
			(xy 388.992618 -315.468508) (xy 388.993634 -315.468) (xy 389.000965 -315.463815) (xy 389.012628 -315.451628)
			(xy 389.016494 -315.444124) (xy 389.034611 -315.40581) (xy 389.076582 -315.332172) (xy 389.100314 -315.297058)
			(xy 389.102612 -315.293649) (xy 389.10619 -315.286247) (xy 389.107426 -315.282326) (xy 389.11568 -315.255872)
			(xy 389.139765 -315.205968) (xy 389.171837 -315.160781) (xy 389.210997 -315.121577) (xy 389.256149 -315.089454)
			(xy 389.306025 -315.065312) (xy 389.33247 -315.057028) (xy 389.336381 -315.055852) (xy 389.343789 -315.052413)
			(xy 389.347202 -315.05017) (xy 389.392149 -315.019988) (xy 389.487495 -314.968688) (xy 389.537448 -314.947808)
			(xy 389.546611 -314.943615) (xy 389.560922 -314.92945) (xy 389.568715 -314.910884) (xy 389.569198 -314.900818)
			(xy 389.569198 -314.899802) (xy 389.569708 -314.873815) (xy 389.577838 -314.82248) (xy 389.593899 -314.77305)
			(xy 389.617495 -314.72674) (xy 389.648045 -314.684692) (xy 389.684796 -314.647941) (xy 389.726844 -314.617391)
			(xy 389.773154 -314.593795) (xy 389.822584 -314.577734) (xy 389.873919 -314.569604) (xy 389.925893 -314.569604)
			(xy 389.977228 -314.577734) (xy 390.026658 -314.593795) (xy 390.072968 -314.617391) (xy 390.115016 -314.647941)
			(xy 390.151767 -314.684692) (xy 390.182317 -314.72674) (xy 390.205913 -314.77305) (xy 390.221974 -314.82248)
			(xy 390.230104 -314.873815) (xy 390.230614 -314.899802) (xy 390.230614 -314.900818) (xy 390.231038 -314.910898)
			(xy 390.237145 -314.92551) (xy 429.473356 -314.92551) (xy 429.473356 -314.874094) (xy 429.481399 -314.823312)
			(xy 429.497287 -314.774413) (xy 429.52063 -314.728601) (xy 429.550851 -314.687005) (xy 429.587207 -314.650649)
			(xy 429.628803 -314.620428) (xy 429.674615 -314.597085) (xy 429.723514 -314.581197) (xy 429.774296 -314.573154)
			(xy 429.825712 -314.573154) (xy 429.876494 -314.581197) (xy 429.925393 -314.597085) (xy 429.971205 -314.620428)
			(xy 430.012801 -314.650649) (xy 430.049157 -314.687005) (xy 430.079378 -314.728601) (xy 430.102721 -314.774413)
			(xy 430.118609 -314.823312) (xy 430.126652 -314.874094) (xy 430.127156 -314.899802) (xy 430.126652 -314.92551)
			(xy 430.423316 -314.92551) (xy 430.423316 -314.874094) (xy 430.431359 -314.823312) (xy 430.447247 -314.774413)
			(xy 430.47059 -314.728601) (xy 430.500811 -314.687005) (xy 430.537167 -314.650649) (xy 430.578763 -314.620428)
			(xy 430.624575 -314.597085) (xy 430.673474 -314.581197) (xy 430.724256 -314.573154) (xy 430.775672 -314.573154)
			(xy 430.826454 -314.581197) (xy 430.875353 -314.597085) (xy 430.921165 -314.620428) (xy 430.962761 -314.650649)
			(xy 430.999117 -314.687005) (xy 431.029338 -314.728601) (xy 431.052681 -314.774413) (xy 431.068569 -314.823312)
			(xy 431.076612 -314.874094) (xy 431.077116 -314.899802) (xy 431.076612 -314.92551) (xy 431.068569 -314.976292)
			(xy 431.052681 -315.025191) (xy 431.029338 -315.071003) (xy 430.999117 -315.112599) (xy 430.962761 -315.148955)
			(xy 430.921165 -315.179176) (xy 430.875353 -315.202519) (xy 430.826454 -315.218407) (xy 430.775672 -315.22645)
			(xy 430.724256 -315.22645) (xy 430.673474 -315.218407) (xy 430.624575 -315.202519) (xy 430.578763 -315.179176)
			(xy 430.537167 -315.148955) (xy 430.500811 -315.112599) (xy 430.47059 -315.071003) (xy 430.447247 -315.025191)
			(xy 430.431359 -314.976292) (xy 430.423316 -314.92551) (xy 430.126652 -314.92551) (xy 430.118609 -314.976292)
			(xy 430.102721 -315.025191) (xy 430.079378 -315.071003) (xy 430.049157 -315.112599) (xy 430.012801 -315.148955)
			(xy 429.971205 -315.179176) (xy 429.925393 -315.202519) (xy 429.876494 -315.218407) (xy 429.825712 -315.22645)
			(xy 429.774296 -315.22645) (xy 429.723514 -315.218407) (xy 429.674615 -315.202519) (xy 429.628803 -315.179176)
			(xy 429.587207 -315.148955) (xy 429.550851 -315.112599) (xy 429.52063 -315.071003) (xy 429.497287 -315.025191)
			(xy 429.481399 -314.976292) (xy 429.473356 -314.92551) (xy 390.237145 -314.92551) (xy 390.238811 -314.929496)
			(xy 390.253177 -314.943637) (xy 390.262364 -314.947808) (xy 390.307613 -314.966655) (xy 390.394424 -315.012182)
			(xy 390.476215 -315.066213) (xy 390.552154 -315.1282) (xy 390.58723 -315.162438) (xy 390.587484 -315.162692)
			(xy 390.621674 -315.197754) (xy 390.683594 -315.273631) (xy 390.737564 -315.355354) (xy 390.783035 -315.442095)
			(xy 390.80186 -315.487304) (xy 390.806047 -315.496476) (xy 390.820207 -315.510808) (xy 390.838778 -315.51862)
			(xy 390.84885 -315.519054) (xy 390.849866 -315.519054) (xy 390.875856 -315.519561) (xy 390.927197 -315.527687)
			(xy 390.976634 -315.543745) (xy 391.022951 -315.567338) (xy 391.065007 -315.597887) (xy 391.101767 -315.634638)
			(xy 391.132324 -315.676687) (xy 391.155928 -315.722999) (xy 391.171996 -315.772433) (xy 391.180133 -315.823772)
			(xy 391.180574 -315.849762) (xy 391.180104 -315.875271) (xy 391.172272 -315.925684) (xy 391.156787 -315.974295)
			(xy 391.134018 -316.01995) (xy 391.104505 -316.061565) (xy 391.06895 -316.098151) (xy 391.028195 -316.128841)
			(xy 390.983209 -316.152905) (xy 390.93506 -316.169772) (xy 390.910064 -316.174882) (xy 390.899227 -316.177411)
			(xy 390.881083 -316.190248) (xy 390.870094 -316.209568) (xy 390.868662 -316.220602) (xy 390.866584 -316.244475)
			(xy 390.860357 -316.291995) (xy 390.856216 -316.315598) (xy 390.855488 -316.320141) (xy 390.855495 -316.329341)
			(xy 390.856216 -316.333886) (xy 390.860347 -316.357491) (xy 390.866574 -316.40501) (xy 390.868662 -316.428882)
			(xy 390.870181 -316.439879) (xy 390.881205 -316.45912) (xy 390.899277 -316.471971) (xy 390.910064 -316.474602)
			(xy 390.93013 -316.47892) (xy 390.939216 -316.480803) (xy 390.957631 -316.47866) (xy 390.974077 -316.4701)
			(xy 390.986398 -316.456247) (xy 390.992979 -316.438914) (xy 390.993376 -316.429644) (xy 390.993376 -316.324742)
			(xy 390.993856 -316.298732) (xy 391.001989 -316.247351) (xy 391.01806 -316.197875) (xy 391.041674 -316.151523)
			(xy 391.07225 -316.109437) (xy 391.109034 -316.072653) (xy 391.15112 -316.042077) (xy 391.197471 -316.018462)
			(xy 391.246947 -316.00239) (xy 391.298328 -315.994257) (xy 391.324338 -315.99378) (xy 391.324592 -315.99378)
			(xy 391.33902 -315.993944) (xy 391.367763 -315.996492) (xy 391.381996 -315.99886) (xy 391.382504 -315.99886)
			(xy 391.39114 -316.000384) (xy 391.413746 -315.993272) (xy 391.48131 -315.928502) (xy 391.489386 -315.92001)
			(xy 391.497463 -315.898038) (xy 391.496804 -315.886338) (xy 391.496804 -315.886084) (xy 391.495757 -315.87704)
			(xy 391.494615 -315.858866) (xy 391.494518 -315.849762) (xy 391.495007 -315.824944) (xy 391.503043 -315.775964)
			(xy 391.518896 -315.728929) (xy 391.542151 -315.685078) (xy 391.572192 -315.645566) (xy 391.60823 -315.611435)
			(xy 391.649315 -315.583584) (xy 391.694364 -315.562746) (xy 391.742191 -315.54947) (xy 391.791536 -315.544107)
			(xy 391.841098 -315.546796) (xy 391.889573 -315.557469) (xy 391.935682 -315.575842) (xy 391.978212 -315.601433)
			(xy 392.016041 -315.633567) (xy 392.048174 -315.671398) (xy 392.073763 -315.713929) (xy 392.092135 -315.760039)
			(xy 392.102805 -315.808514) (xy 392.105042 -315.849762) (xy 393.394196 -315.849762) (xy 393.398156 -315.800708)
			(xy 393.409933 -315.752924) (xy 393.429224 -315.707648) (xy 393.455527 -315.666052) (xy 393.488162 -315.629215)
			(xy 393.526283 -315.59809) (xy 393.568904 -315.573483) (xy 393.61492 -315.556031) (xy 393.663139 -315.546187)
			(xy 393.712314 -315.544206) (xy 393.761169 -315.550138) (xy 393.80844 -315.56383) (xy 393.852902 -315.584928)
			(xy 393.893405 -315.612884) (xy 393.928898 -315.646976) (xy 393.958463 -315.68632) (xy 393.981334 -315.729897)
			(xy 393.996918 -315.776578) (xy 394.004813 -315.825155) (xy 394.005308 -315.849762) (xy 395.294116 -315.849762)
			(xy 395.298076 -315.800708) (xy 395.309853 -315.752924) (xy 395.329144 -315.707648) (xy 395.355447 -315.666052)
			(xy 395.388082 -315.629215) (xy 395.426203 -315.59809) (xy 395.468824 -315.573483) (xy 395.51484 -315.556031)
			(xy 395.563059 -315.546187) (xy 395.612234 -315.544206) (xy 395.661089 -315.550138) (xy 395.70836 -315.56383)
			(xy 395.752822 -315.584928) (xy 395.793325 -315.612884) (xy 395.828818 -315.646976) (xy 395.858383 -315.68632)
			(xy 395.881254 -315.729897) (xy 395.896838 -315.776578) (xy 395.904733 -315.825155) (xy 395.905228 -315.849762)
			(xy 397.194036 -315.849762) (xy 397.197996 -315.800708) (xy 397.209773 -315.752924) (xy 397.229064 -315.707648)
			(xy 397.255367 -315.666052) (xy 397.288002 -315.629215) (xy 397.326123 -315.59809) (xy 397.368744 -315.573483)
			(xy 397.41476 -315.556031) (xy 397.462979 -315.546187) (xy 397.512154 -315.544206) (xy 397.561009 -315.550138)
			(xy 397.60828 -315.56383) (xy 397.652742 -315.584928) (xy 397.693245 -315.612884) (xy 397.728738 -315.646976)
			(xy 397.758303 -315.68632) (xy 397.781174 -315.729897) (xy 397.796758 -315.776578) (xy 397.804653 -315.825155)
			(xy 397.805148 -315.849762) (xy 397.804653 -315.874369) (xy 397.804474 -315.87547) (xy 399.073366 -315.87547)
			(xy 399.073366 -315.824054) (xy 399.081409 -315.773272) (xy 399.097297 -315.724373) (xy 399.12064 -315.678561)
			(xy 399.150861 -315.636965) (xy 399.187217 -315.600609) (xy 399.228813 -315.570388) (xy 399.274625 -315.547045)
			(xy 399.323524 -315.531157) (xy 399.374306 -315.523114) (xy 399.425722 -315.523114) (xy 399.476504 -315.531157)
			(xy 399.525403 -315.547045) (xy 399.571215 -315.570388) (xy 399.612811 -315.600609) (xy 399.649167 -315.636965)
			(xy 399.679388 -315.678561) (xy 399.702731 -315.724373) (xy 399.718619 -315.773272) (xy 399.726662 -315.824054)
			(xy 399.727166 -315.849762) (xy 399.726662 -315.87547) (xy 400.973286 -315.87547) (xy 400.973286 -315.824054)
			(xy 400.981329 -315.773272) (xy 400.997217 -315.724373) (xy 401.02056 -315.678561) (xy 401.050781 -315.636965)
			(xy 401.087137 -315.600609) (xy 401.128733 -315.570388) (xy 401.174545 -315.547045) (xy 401.223444 -315.531157)
			(xy 401.274226 -315.523114) (xy 401.325642 -315.523114) (xy 401.376424 -315.531157) (xy 401.425323 -315.547045)
			(xy 401.471135 -315.570388) (xy 401.512731 -315.600609) (xy 401.549087 -315.636965) (xy 401.579308 -315.678561)
			(xy 401.602651 -315.724373) (xy 401.618539 -315.773272) (xy 401.626582 -315.824054) (xy 401.627086 -315.849762)
			(xy 401.626582 -315.87547) (xy 402.873206 -315.87547) (xy 402.873206 -315.824054) (xy 402.881249 -315.773272)
			(xy 402.897137 -315.724373) (xy 402.92048 -315.678561) (xy 402.950701 -315.636965) (xy 402.987057 -315.600609)
			(xy 403.028653 -315.570388) (xy 403.074465 -315.547045) (xy 403.123364 -315.531157) (xy 403.174146 -315.523114)
			(xy 403.225562 -315.523114) (xy 403.276344 -315.531157) (xy 403.325243 -315.547045) (xy 403.371055 -315.570388)
			(xy 403.412651 -315.600609) (xy 403.449007 -315.636965) (xy 403.479228 -315.678561) (xy 403.502571 -315.724373)
			(xy 403.518459 -315.773272) (xy 403.526502 -315.824054) (xy 403.527006 -315.849762) (xy 403.526502 -315.87547)
			(xy 404.77338 -315.87547) (xy 404.77338 -315.824054) (xy 404.781423 -315.773272) (xy 404.797311 -315.724373)
			(xy 404.820654 -315.678561) (xy 404.850875 -315.636965) (xy 404.887231 -315.600609) (xy 404.928827 -315.570388)
			(xy 404.974639 -315.547045) (xy 405.023538 -315.531157) (xy 405.07432 -315.523114) (xy 405.125736 -315.523114)
			(xy 405.176518 -315.531157) (xy 405.225417 -315.547045) (xy 405.271229 -315.570388) (xy 405.312825 -315.600609)
			(xy 405.349181 -315.636965) (xy 405.379402 -315.678561) (xy 405.402745 -315.724373) (xy 405.418633 -315.773272)
			(xy 405.426676 -315.824054) (xy 405.42718 -315.849762) (xy 405.426676 -315.87547) (xy 406.6733 -315.87547)
			(xy 406.6733 -315.824054) (xy 406.681343 -315.773272) (xy 406.697231 -315.724373) (xy 406.720574 -315.678561)
			(xy 406.750795 -315.636965) (xy 406.787151 -315.600609) (xy 406.828747 -315.570388) (xy 406.874559 -315.547045)
			(xy 406.923458 -315.531157) (xy 406.97424 -315.523114) (xy 407.025656 -315.523114) (xy 407.076438 -315.531157)
			(xy 407.125337 -315.547045) (xy 407.171149 -315.570388) (xy 407.212745 -315.600609) (xy 407.249101 -315.636965)
			(xy 407.279322 -315.678561) (xy 407.302665 -315.724373) (xy 407.318553 -315.773272) (xy 407.326596 -315.824054)
			(xy 407.3271 -315.849762) (xy 407.326596 -315.87547) (xy 408.57322 -315.87547) (xy 408.57322 -315.824054)
			(xy 408.581263 -315.773272) (xy 408.597151 -315.724373) (xy 408.620494 -315.678561) (xy 408.650715 -315.636965)
			(xy 408.687071 -315.600609) (xy 408.728667 -315.570388) (xy 408.774479 -315.547045) (xy 408.823378 -315.531157)
			(xy 408.87416 -315.523114) (xy 408.925576 -315.523114) (xy 408.976358 -315.531157) (xy 409.025257 -315.547045)
			(xy 409.071069 -315.570388) (xy 409.112665 -315.600609) (xy 409.149021 -315.636965) (xy 409.179242 -315.678561)
			(xy 409.202585 -315.724373) (xy 409.218473 -315.773272) (xy 409.226516 -315.824054) (xy 409.22702 -315.849762)
			(xy 409.226516 -315.87547) (xy 410.47314 -315.87547) (xy 410.47314 -315.824054) (xy 410.481183 -315.773272)
			(xy 410.497071 -315.724373) (xy 410.520414 -315.678561) (xy 410.550635 -315.636965) (xy 410.586991 -315.600609)
			(xy 410.628587 -315.570388) (xy 410.674399 -315.547045) (xy 410.723298 -315.531157) (xy 410.77408 -315.523114)
			(xy 410.825496 -315.523114) (xy 410.876278 -315.531157) (xy 410.925177 -315.547045) (xy 410.970989 -315.570388)
			(xy 411.012585 -315.600609) (xy 411.048941 -315.636965) (xy 411.079162 -315.678561) (xy 411.102505 -315.724373)
			(xy 411.118393 -315.773272) (xy 411.126436 -315.824054) (xy 411.12694 -315.849762) (xy 411.126436 -315.87547)
			(xy 412.373314 -315.87547) (xy 412.373314 -315.824054) (xy 412.381357 -315.773272) (xy 412.397245 -315.724373)
			(xy 412.420588 -315.678561) (xy 412.450809 -315.636965) (xy 412.487165 -315.600609) (xy 412.528761 -315.570388)
			(xy 412.574573 -315.547045) (xy 412.623472 -315.531157) (xy 412.674254 -315.523114) (xy 412.72567 -315.523114)
			(xy 412.776452 -315.531157) (xy 412.825351 -315.547045) (xy 412.871163 -315.570388) (xy 412.912759 -315.600609)
			(xy 412.949115 -315.636965) (xy 412.979336 -315.678561) (xy 413.002679 -315.724373) (xy 413.018567 -315.773272)
			(xy 413.02661 -315.824054) (xy 413.027114 -315.849762) (xy 414.294078 -315.849762) (xy 414.298038 -315.800708)
			(xy 414.309815 -315.752924) (xy 414.329106 -315.707648) (xy 414.355409 -315.666052) (xy 414.388044 -315.629215)
			(xy 414.426165 -315.59809) (xy 414.468786 -315.573483) (xy 414.514802 -315.556031) (xy 414.563021 -315.546187)
			(xy 414.612196 -315.544206) (xy 414.661051 -315.550138) (xy 414.708322 -315.56383) (xy 414.752784 -315.584928)
			(xy 414.793287 -315.612884) (xy 414.82878 -315.646976) (xy 414.858345 -315.68632) (xy 414.881216 -315.729897)
			(xy 414.8968 -315.776578) (xy 414.904695 -315.825155) (xy 414.90519 -315.849762) (xy 416.193998 -315.849762)
			(xy 416.197958 -315.800708) (xy 416.209735 -315.752924) (xy 416.229026 -315.707648) (xy 416.255329 -315.666052)
			(xy 416.287964 -315.629215) (xy 416.326085 -315.59809) (xy 416.368706 -315.573483) (xy 416.414722 -315.556031)
			(xy 416.462941 -315.546187) (xy 416.512116 -315.544206) (xy 416.560971 -315.550138) (xy 416.608242 -315.56383)
			(xy 416.652704 -315.584928) (xy 416.693207 -315.612884) (xy 416.7287 -315.646976) (xy 416.758265 -315.68632)
			(xy 416.781136 -315.729897) (xy 416.79672 -315.776578) (xy 416.804615 -315.825155) (xy 416.80511 -315.849762)
			(xy 418.094172 -315.849762) (xy 418.098132 -315.800708) (xy 418.109909 -315.752924) (xy 418.1292 -315.707648)
			(xy 418.155503 -315.666052) (xy 418.188138 -315.629215) (xy 418.226259 -315.59809) (xy 418.26888 -315.573483)
			(xy 418.314896 -315.556031) (xy 418.363115 -315.546187) (xy 418.41229 -315.544206) (xy 418.461145 -315.550138)
			(xy 418.508416 -315.56383) (xy 418.552878 -315.584928) (xy 418.593381 -315.612884) (xy 418.628874 -315.646976)
			(xy 418.658439 -315.68632) (xy 418.68131 -315.729897) (xy 418.696894 -315.776578) (xy 418.704789 -315.825155)
			(xy 418.705284 -315.849762) (xy 419.994092 -315.849762) (xy 419.998052 -315.800708) (xy 420.009829 -315.752924)
			(xy 420.02912 -315.707648) (xy 420.055423 -315.666052) (xy 420.088058 -315.629215) (xy 420.126179 -315.59809)
			(xy 420.1688 -315.573483) (xy 420.214816 -315.556031) (xy 420.263035 -315.546187) (xy 420.31221 -315.544206)
			(xy 420.361065 -315.550138) (xy 420.408336 -315.56383) (xy 420.452798 -315.584928) (xy 420.493301 -315.612884)
			(xy 420.528794 -315.646976) (xy 420.558359 -315.68632) (xy 420.58123 -315.729897) (xy 420.596814 -315.776578)
			(xy 420.604709 -315.825155) (xy 420.605204 -315.849762) (xy 420.604709 -315.874369) (xy 420.60453 -315.87547)
			(xy 421.873168 -315.87547) (xy 421.873168 -315.824054) (xy 421.881211 -315.773272) (xy 421.897099 -315.724373)
			(xy 421.920442 -315.678561) (xy 421.950663 -315.636965) (xy 421.987019 -315.600609) (xy 422.028615 -315.570388)
			(xy 422.074427 -315.547045) (xy 422.123326 -315.531157) (xy 422.174108 -315.523114) (xy 422.225524 -315.523114)
			(xy 422.276306 -315.531157) (xy 422.325205 -315.547045) (xy 422.371017 -315.570388) (xy 422.412613 -315.600609)
			(xy 422.448969 -315.636965) (xy 422.47919 -315.678561) (xy 422.502533 -315.724373) (xy 422.518421 -315.773272)
			(xy 422.526464 -315.824054) (xy 422.526968 -315.849762) (xy 422.526464 -315.87547) (xy 423.773342 -315.87547)
			(xy 423.773342 -315.824054) (xy 423.781385 -315.773272) (xy 423.797273 -315.724373) (xy 423.820616 -315.678561)
			(xy 423.850837 -315.636965) (xy 423.887193 -315.600609) (xy 423.928789 -315.570388) (xy 423.974601 -315.547045)
			(xy 424.0235 -315.531157) (xy 424.074282 -315.523114) (xy 424.125698 -315.523114) (xy 424.17648 -315.531157)
			(xy 424.225379 -315.547045) (xy 424.271191 -315.570388) (xy 424.312787 -315.600609) (xy 424.349143 -315.636965)
			(xy 424.379364 -315.678561) (xy 424.402707 -315.724373) (xy 424.418595 -315.773272) (xy 424.426638 -315.824054)
			(xy 424.427142 -315.849762) (xy 424.426638 -315.87547) (xy 425.673262 -315.87547) (xy 425.673262 -315.824054)
			(xy 425.681305 -315.773272) (xy 425.697193 -315.724373) (xy 425.720536 -315.678561) (xy 425.750757 -315.636965)
			(xy 425.787113 -315.600609) (xy 425.828709 -315.570388) (xy 425.874521 -315.547045) (xy 425.92342 -315.531157)
			(xy 425.974202 -315.523114) (xy 426.025618 -315.523114) (xy 426.0764 -315.531157) (xy 426.125299 -315.547045)
			(xy 426.171111 -315.570388) (xy 426.212707 -315.600609) (xy 426.249063 -315.636965) (xy 426.279284 -315.678561)
			(xy 426.302627 -315.724373) (xy 426.318515 -315.773272) (xy 426.326558 -315.824054) (xy 426.327062 -315.849762)
			(xy 426.326558 -315.87547) (xy 427.573182 -315.87547) (xy 427.573182 -315.824054) (xy 427.581225 -315.773272)
			(xy 427.597113 -315.724373) (xy 427.620456 -315.678561) (xy 427.650677 -315.636965) (xy 427.687033 -315.600609)
			(xy 427.728629 -315.570388) (xy 427.774441 -315.547045) (xy 427.82334 -315.531157) (xy 427.874122 -315.523114)
			(xy 427.925538 -315.523114) (xy 427.97632 -315.531157) (xy 428.025219 -315.547045) (xy 428.071031 -315.570388)
			(xy 428.112627 -315.600609) (xy 428.148983 -315.636965) (xy 428.179204 -315.678561) (xy 428.202547 -315.724373)
			(xy 428.218435 -315.773272) (xy 428.226478 -315.824054) (xy 428.226982 -315.849762) (xy 428.226478 -315.87547)
			(xy 428.218435 -315.926252) (xy 428.202547 -315.975151) (xy 428.179204 -316.020963) (xy 428.148983 -316.062559)
			(xy 428.112627 -316.098915) (xy 428.071031 -316.129136) (xy 428.025219 -316.152479) (xy 427.97632 -316.168367)
			(xy 427.925538 -316.17641) (xy 427.874122 -316.17641) (xy 427.82334 -316.168367) (xy 427.774441 -316.152479)
			(xy 427.728629 -316.129136) (xy 427.687033 -316.098915) (xy 427.650677 -316.062559) (xy 427.620456 -316.020963)
			(xy 427.597113 -315.975151) (xy 427.581225 -315.926252) (xy 427.573182 -315.87547) (xy 426.326558 -315.87547)
			(xy 426.318515 -315.926252) (xy 426.302627 -315.975151) (xy 426.279284 -316.020963) (xy 426.249063 -316.062559)
			(xy 426.212707 -316.098915) (xy 426.171111 -316.129136) (xy 426.125299 -316.152479) (xy 426.0764 -316.168367)
			(xy 426.025618 -316.17641) (xy 425.974202 -316.17641) (xy 425.92342 -316.168367) (xy 425.874521 -316.152479)
			(xy 425.828709 -316.129136) (xy 425.787113 -316.098915) (xy 425.750757 -316.062559) (xy 425.720536 -316.020963)
			(xy 425.697193 -315.975151) (xy 425.681305 -315.926252) (xy 425.673262 -315.87547) (xy 424.426638 -315.87547)
			(xy 424.418595 -315.926252) (xy 424.402707 -315.975151) (xy 424.379364 -316.020963) (xy 424.349143 -316.062559)
			(xy 424.312787 -316.098915) (xy 424.271191 -316.129136) (xy 424.225379 -316.152479) (xy 424.17648 -316.168367)
			(xy 424.125698 -316.17641) (xy 424.074282 -316.17641) (xy 424.0235 -316.168367) (xy 423.974601 -316.152479)
			(xy 423.928789 -316.129136) (xy 423.887193 -316.098915) (xy 423.850837 -316.062559) (xy 423.820616 -316.020963)
			(xy 423.797273 -315.975151) (xy 423.781385 -315.926252) (xy 423.773342 -315.87547) (xy 422.526464 -315.87547)
			(xy 422.518421 -315.926252) (xy 422.502533 -315.975151) (xy 422.47919 -316.020963) (xy 422.448969 -316.062559)
			(xy 422.412613 -316.098915) (xy 422.371017 -316.129136) (xy 422.325205 -316.152479) (xy 422.276306 -316.168367)
			(xy 422.225524 -316.17641) (xy 422.174108 -316.17641) (xy 422.123326 -316.168367) (xy 422.074427 -316.152479)
			(xy 422.028615 -316.129136) (xy 421.987019 -316.098915) (xy 421.950663 -316.062559) (xy 421.920442 -316.020963)
			(xy 421.897099 -315.975151) (xy 421.881211 -315.926252) (xy 421.873168 -315.87547) (xy 420.60453 -315.87547)
			(xy 420.596814 -315.922946) (xy 420.58123 -315.969627) (xy 420.558359 -316.013204) (xy 420.528794 -316.052548)
			(xy 420.493301 -316.08664) (xy 420.452798 -316.114596) (xy 420.408336 -316.135694) (xy 420.361065 -316.149386)
			(xy 420.31221 -316.155318) (xy 420.263035 -316.153337) (xy 420.214816 -316.143493) (xy 420.1688 -316.126041)
			(xy 420.126179 -316.101434) (xy 420.088058 -316.070309) (xy 420.055423 -316.033472) (xy 420.02912 -315.991876)
			(xy 420.009829 -315.9466) (xy 419.998052 -315.898816) (xy 419.994092 -315.849762) (xy 418.705284 -315.849762)
			(xy 418.704789 -315.874369) (xy 418.696894 -315.922946) (xy 418.68131 -315.969627) (xy 418.658439 -316.013204)
			(xy 418.628874 -316.052548) (xy 418.593381 -316.08664) (xy 418.552878 -316.114596) (xy 418.508416 -316.135694)
			(xy 418.461145 -316.149386) (xy 418.41229 -316.155318) (xy 418.363115 -316.153337) (xy 418.314896 -316.143493)
			(xy 418.26888 -316.126041) (xy 418.226259 -316.101434) (xy 418.188138 -316.070309) (xy 418.155503 -316.033472)
			(xy 418.1292 -315.991876) (xy 418.109909 -315.9466) (xy 418.098132 -315.898816) (xy 418.094172 -315.849762)
			(xy 416.80511 -315.849762) (xy 416.804615 -315.874369) (xy 416.79672 -315.922946) (xy 416.781136 -315.969627)
			(xy 416.758265 -316.013204) (xy 416.7287 -316.052548) (xy 416.693207 -316.08664) (xy 416.652704 -316.114596)
			(xy 416.608242 -316.135694) (xy 416.560971 -316.149386) (xy 416.512116 -316.155318) (xy 416.462941 -316.153337)
			(xy 416.414722 -316.143493) (xy 416.368706 -316.126041) (xy 416.326085 -316.101434) (xy 416.287964 -316.070309)
			(xy 416.255329 -316.033472) (xy 416.229026 -315.991876) (xy 416.209735 -315.9466) (xy 416.197958 -315.898816)
			(xy 416.193998 -315.849762) (xy 414.90519 -315.849762) (xy 414.904695 -315.874369) (xy 414.8968 -315.922946)
			(xy 414.881216 -315.969627) (xy 414.858345 -316.013204) (xy 414.82878 -316.052548) (xy 414.793287 -316.08664)
			(xy 414.752784 -316.114596) (xy 414.708322 -316.135694) (xy 414.661051 -316.149386) (xy 414.612196 -316.155318)
			(xy 414.563021 -316.153337) (xy 414.514802 -316.143493) (xy 414.468786 -316.126041) (xy 414.426165 -316.101434)
			(xy 414.388044 -316.070309) (xy 414.355409 -316.033472) (xy 414.329106 -315.991876) (xy 414.309815 -315.9466)
			(xy 414.298038 -315.898816) (xy 414.294078 -315.849762) (xy 413.027114 -315.849762) (xy 413.02661 -315.87547)
			(xy 413.018567 -315.926252) (xy 413.002679 -315.975151) (xy 412.979336 -316.020963) (xy 412.949115 -316.062559)
			(xy 412.912759 -316.098915) (xy 412.871163 -316.129136) (xy 412.825351 -316.152479) (xy 412.776452 -316.168367)
			(xy 412.72567 -316.17641) (xy 412.674254 -316.17641) (xy 412.623472 -316.168367) (xy 412.574573 -316.152479)
			(xy 412.528761 -316.129136) (xy 412.487165 -316.098915) (xy 412.450809 -316.062559) (xy 412.420588 -316.020963)
			(xy 412.397245 -315.975151) (xy 412.381357 -315.926252) (xy 412.373314 -315.87547) (xy 411.126436 -315.87547)
			(xy 411.118393 -315.926252) (xy 411.102505 -315.975151) (xy 411.079162 -316.020963) (xy 411.048941 -316.062559)
			(xy 411.012585 -316.098915) (xy 410.970989 -316.129136) (xy 410.925177 -316.152479) (xy 410.876278 -316.168367)
			(xy 410.825496 -316.17641) (xy 410.77408 -316.17641) (xy 410.723298 -316.168367) (xy 410.674399 -316.152479)
			(xy 410.628587 -316.129136) (xy 410.586991 -316.098915) (xy 410.550635 -316.062559) (xy 410.520414 -316.020963)
			(xy 410.497071 -315.975151) (xy 410.481183 -315.926252) (xy 410.47314 -315.87547) (xy 409.226516 -315.87547)
			(xy 409.218473 -315.926252) (xy 409.202585 -315.975151) (xy 409.179242 -316.020963) (xy 409.149021 -316.062559)
			(xy 409.112665 -316.098915) (xy 409.071069 -316.129136) (xy 409.025257 -316.152479) (xy 408.976358 -316.168367)
			(xy 408.925576 -316.17641) (xy 408.87416 -316.17641) (xy 408.823378 -316.168367) (xy 408.774479 -316.152479)
			(xy 408.728667 -316.129136) (xy 408.687071 -316.098915) (xy 408.650715 -316.062559) (xy 408.620494 -316.020963)
			(xy 408.597151 -315.975151) (xy 408.581263 -315.926252) (xy 408.57322 -315.87547) (xy 407.326596 -315.87547)
			(xy 407.318553 -315.926252) (xy 407.302665 -315.975151) (xy 407.279322 -316.020963) (xy 407.249101 -316.062559)
			(xy 407.212745 -316.098915) (xy 407.171149 -316.129136) (xy 407.125337 -316.152479) (xy 407.076438 -316.168367)
			(xy 407.025656 -316.17641) (xy 406.97424 -316.17641) (xy 406.923458 -316.168367) (xy 406.874559 -316.152479)
			(xy 406.828747 -316.129136) (xy 406.787151 -316.098915) (xy 406.750795 -316.062559) (xy 406.720574 -316.020963)
			(xy 406.697231 -315.975151) (xy 406.681343 -315.926252) (xy 406.6733 -315.87547) (xy 405.426676 -315.87547)
			(xy 405.418633 -315.926252) (xy 405.402745 -315.975151) (xy 405.379402 -316.020963) (xy 405.349181 -316.062559)
			(xy 405.312825 -316.098915) (xy 405.271229 -316.129136) (xy 405.225417 -316.152479) (xy 405.176518 -316.168367)
			(xy 405.125736 -316.17641) (xy 405.07432 -316.17641) (xy 405.023538 -316.168367) (xy 404.974639 -316.152479)
			(xy 404.928827 -316.129136) (xy 404.887231 -316.098915) (xy 404.850875 -316.062559) (xy 404.820654 -316.020963)
			(xy 404.797311 -315.975151) (xy 404.781423 -315.926252) (xy 404.77338 -315.87547) (xy 403.526502 -315.87547)
			(xy 403.518459 -315.926252) (xy 403.502571 -315.975151) (xy 403.479228 -316.020963) (xy 403.449007 -316.062559)
			(xy 403.412651 -316.098915) (xy 403.371055 -316.129136) (xy 403.325243 -316.152479) (xy 403.276344 -316.168367)
			(xy 403.225562 -316.17641) (xy 403.174146 -316.17641) (xy 403.123364 -316.168367) (xy 403.074465 -316.152479)
			(xy 403.028653 -316.129136) (xy 402.987057 -316.098915) (xy 402.950701 -316.062559) (xy 402.92048 -316.020963)
			(xy 402.897137 -315.975151) (xy 402.881249 -315.926252) (xy 402.873206 -315.87547) (xy 401.626582 -315.87547)
			(xy 401.618539 -315.926252) (xy 401.602651 -315.975151) (xy 401.579308 -316.020963) (xy 401.549087 -316.062559)
			(xy 401.512731 -316.098915) (xy 401.471135 -316.129136) (xy 401.425323 -316.152479) (xy 401.376424 -316.168367)
			(xy 401.325642 -316.17641) (xy 401.274226 -316.17641) (xy 401.223444 -316.168367) (xy 401.174545 -316.152479)
			(xy 401.128733 -316.129136) (xy 401.087137 -316.098915) (xy 401.050781 -316.062559) (xy 401.02056 -316.020963)
			(xy 400.997217 -315.975151) (xy 400.981329 -315.926252) (xy 400.973286 -315.87547) (xy 399.726662 -315.87547)
			(xy 399.718619 -315.926252) (xy 399.702731 -315.975151) (xy 399.679388 -316.020963) (xy 399.649167 -316.062559)
			(xy 399.612811 -316.098915) (xy 399.571215 -316.129136) (xy 399.525403 -316.152479) (xy 399.476504 -316.168367)
			(xy 399.425722 -316.17641) (xy 399.374306 -316.17641) (xy 399.323524 -316.168367) (xy 399.274625 -316.152479)
			(xy 399.228813 -316.129136) (xy 399.187217 -316.098915) (xy 399.150861 -316.062559) (xy 399.12064 -316.020963)
			(xy 399.097297 -315.975151) (xy 399.081409 -315.926252) (xy 399.073366 -315.87547) (xy 397.804474 -315.87547)
			(xy 397.796758 -315.922946) (xy 397.781174 -315.969627) (xy 397.758303 -316.013204) (xy 397.728738 -316.052548)
			(xy 397.693245 -316.08664) (xy 397.652742 -316.114596) (xy 397.60828 -316.135694) (xy 397.561009 -316.149386)
			(xy 397.512154 -316.155318) (xy 397.462979 -316.153337) (xy 397.41476 -316.143493) (xy 397.368744 -316.126041)
			(xy 397.326123 -316.101434) (xy 397.288002 -316.070309) (xy 397.255367 -316.033472) (xy 397.229064 -315.991876)
			(xy 397.209773 -315.9466) (xy 397.197996 -315.898816) (xy 397.194036 -315.849762) (xy 395.905228 -315.849762)
			(xy 395.904733 -315.874369) (xy 395.896838 -315.922946) (xy 395.881254 -315.969627) (xy 395.858383 -316.013204)
			(xy 395.828818 -316.052548) (xy 395.793325 -316.08664) (xy 395.752822 -316.114596) (xy 395.70836 -316.135694)
			(xy 395.661089 -316.149386) (xy 395.612234 -316.155318) (xy 395.563059 -316.153337) (xy 395.51484 -316.143493)
			(xy 395.468824 -316.126041) (xy 395.426203 -316.101434) (xy 395.388082 -316.070309) (xy 395.355447 -316.033472)
			(xy 395.329144 -315.991876) (xy 395.309853 -315.9466) (xy 395.298076 -315.898816) (xy 395.294116 -315.849762)
			(xy 394.005308 -315.849762) (xy 394.004813 -315.874369) (xy 393.996918 -315.922946) (xy 393.981334 -315.969627)
			(xy 393.958463 -316.013204) (xy 393.928898 -316.052548) (xy 393.893405 -316.08664) (xy 393.852902 -316.114596)
			(xy 393.80844 -316.135694) (xy 393.761169 -316.149386) (xy 393.712314 -316.155318) (xy 393.663139 -316.153337)
			(xy 393.61492 -316.143493) (xy 393.568904 -316.126041) (xy 393.526283 -316.101434) (xy 393.488162 -316.070309)
			(xy 393.455527 -316.033472) (xy 393.429224 -315.991876) (xy 393.409933 -315.9466) (xy 393.398156 -315.898816)
			(xy 393.394196 -315.849762) (xy 392.105042 -315.849762) (xy 392.105493 -315.858076) (xy 392.100127 -315.90742)
			(xy 392.08685 -315.955247) (xy 392.06601 -316.000295) (xy 392.038157 -316.041379) (xy 392.004025 -316.077416)
			(xy 391.964512 -316.107456) (xy 391.92066 -316.130708) (xy 391.873624 -316.14656) (xy 391.824644 -316.154594)
			(xy 391.799826 -316.15507) (xy 391.790658 -316.154978) (xy 391.772358 -316.153836) (xy 391.76325 -316.152784)
			(xy 391.762996 -316.152784) (xy 391.751196 -316.151976) (xy 391.728952 -316.159932) (xy 391.720324 -316.168024)
			(xy 391.655808 -316.235588) (xy 391.648696 -316.258194) (xy 391.649712 -316.264798) (xy 391.652297 -316.27965)
			(xy 391.655097 -316.309668) (xy 391.6553 -316.324742) (xy 391.6553 -316.3951) (xy 391.655859 -316.405794)
			(xy 391.664512 -316.425356) (xy 391.672064 -316.432946) (xy 391.73658 -316.490604) (xy 391.7569 -316.497208)
			(xy 391.767568 -316.496192) (xy 391.799826 -316.494414) (xy 391.825078 -316.494938) (xy 391.874893 -316.503254)
			(xy 391.92266 -316.519656) (xy 391.967075 -316.543696) (xy 392.006929 -316.574718) (xy 392.041133 -316.611877)
			(xy 392.068755 -316.654158) (xy 392.089041 -316.700409) (xy 392.101439 -316.749368) (xy 392.105609 -316.7997)
			(xy 392.105607 -316.799722) (xy 393.394196 -316.799722) (xy 393.398156 -316.750668) (xy 393.409933 -316.702884)
			(xy 393.429224 -316.657608) (xy 393.455527 -316.616012) (xy 393.488162 -316.579175) (xy 393.526283 -316.54805)
			(xy 393.568904 -316.523443) (xy 393.61492 -316.505991) (xy 393.663139 -316.496147) (xy 393.712314 -316.494166)
			(xy 393.761169 -316.500098) (xy 393.80844 -316.51379) (xy 393.852902 -316.534888) (xy 393.893405 -316.562844)
			(xy 393.928898 -316.596936) (xy 393.958463 -316.63628) (xy 393.981334 -316.679857) (xy 393.996918 -316.726538)
			(xy 394.004813 -316.775115) (xy 394.005308 -316.799722) (xy 395.294116 -316.799722) (xy 395.298076 -316.750668)
			(xy 395.309853 -316.702884) (xy 395.329144 -316.657608) (xy 395.355447 -316.616012) (xy 395.388082 -316.579175)
			(xy 395.426203 -316.54805) (xy 395.468824 -316.523443) (xy 395.51484 -316.505991) (xy 395.563059 -316.496147)
			(xy 395.612234 -316.494166) (xy 395.661089 -316.500098) (xy 395.70836 -316.51379) (xy 395.752822 -316.534888)
			(xy 395.793325 -316.562844) (xy 395.828818 -316.596936) (xy 395.858383 -316.63628) (xy 395.881254 -316.679857)
			(xy 395.896838 -316.726538) (xy 395.904733 -316.775115) (xy 395.905228 -316.799722) (xy 397.194036 -316.799722)
			(xy 397.197996 -316.750668) (xy 397.209773 -316.702884) (xy 397.229064 -316.657608) (xy 397.255367 -316.616012)
			(xy 397.288002 -316.579175) (xy 397.326123 -316.54805) (xy 397.368744 -316.523443) (xy 397.41476 -316.505991)
			(xy 397.462979 -316.496147) (xy 397.512154 -316.494166) (xy 397.561009 -316.500098) (xy 397.60828 -316.51379)
			(xy 397.652742 -316.534888) (xy 397.693245 -316.562844) (xy 397.728738 -316.596936) (xy 397.758303 -316.63628)
			(xy 397.781174 -316.679857) (xy 397.796758 -316.726538) (xy 397.804653 -316.775115) (xy 397.805148 -316.799722)
			(xy 397.804653 -316.824329) (xy 397.804474 -316.82543) (xy 399.073366 -316.82543) (xy 399.073366 -316.774014)
			(xy 399.081409 -316.723232) (xy 399.097297 -316.674333) (xy 399.12064 -316.628521) (xy 399.150861 -316.586925)
			(xy 399.187217 -316.550569) (xy 399.228813 -316.520348) (xy 399.274625 -316.497005) (xy 399.323524 -316.481117)
			(xy 399.374306 -316.473074) (xy 399.425722 -316.473074) (xy 399.476504 -316.481117) (xy 399.525403 -316.497005)
			(xy 399.571215 -316.520348) (xy 399.612811 -316.550569) (xy 399.649167 -316.586925) (xy 399.679388 -316.628521)
			(xy 399.702731 -316.674333) (xy 399.718619 -316.723232) (xy 399.726662 -316.774014) (xy 399.727166 -316.799722)
			(xy 399.726662 -316.82543) (xy 400.973286 -316.82543) (xy 400.973286 -316.774014) (xy 400.981329 -316.723232)
			(xy 400.997217 -316.674333) (xy 401.02056 -316.628521) (xy 401.050781 -316.586925) (xy 401.087137 -316.550569)
			(xy 401.128733 -316.520348) (xy 401.174545 -316.497005) (xy 401.223444 -316.481117) (xy 401.274226 -316.473074)
			(xy 401.325642 -316.473074) (xy 401.376424 -316.481117) (xy 401.425323 -316.497005) (xy 401.471135 -316.520348)
			(xy 401.512731 -316.550569) (xy 401.549087 -316.586925) (xy 401.579308 -316.628521) (xy 401.602651 -316.674333)
			(xy 401.618539 -316.723232) (xy 401.626582 -316.774014) (xy 401.627086 -316.799722) (xy 401.626582 -316.82543)
			(xy 402.873206 -316.82543) (xy 402.873206 -316.774014) (xy 402.881249 -316.723232) (xy 402.897137 -316.674333)
			(xy 402.92048 -316.628521) (xy 402.950701 -316.586925) (xy 402.987057 -316.550569) (xy 403.028653 -316.520348)
			(xy 403.074465 -316.497005) (xy 403.123364 -316.481117) (xy 403.174146 -316.473074) (xy 403.225562 -316.473074)
			(xy 403.276344 -316.481117) (xy 403.325243 -316.497005) (xy 403.371055 -316.520348) (xy 403.412651 -316.550569)
			(xy 403.449007 -316.586925) (xy 403.479228 -316.628521) (xy 403.502571 -316.674333) (xy 403.518459 -316.723232)
			(xy 403.526502 -316.774014) (xy 403.527006 -316.799722) (xy 403.526502 -316.82543) (xy 404.77338 -316.82543)
			(xy 404.77338 -316.774014) (xy 404.781423 -316.723232) (xy 404.797311 -316.674333) (xy 404.820654 -316.628521)
			(xy 404.850875 -316.586925) (xy 404.887231 -316.550569) (xy 404.928827 -316.520348) (xy 404.974639 -316.497005)
			(xy 405.023538 -316.481117) (xy 405.07432 -316.473074) (xy 405.125736 -316.473074) (xy 405.176518 -316.481117)
			(xy 405.225417 -316.497005) (xy 405.271229 -316.520348) (xy 405.312825 -316.550569) (xy 405.349181 -316.586925)
			(xy 405.379402 -316.628521) (xy 405.402745 -316.674333) (xy 405.418633 -316.723232) (xy 405.426676 -316.774014)
			(xy 405.42718 -316.799722) (xy 405.426676 -316.82543) (xy 406.6733 -316.82543) (xy 406.6733 -316.774014)
			(xy 406.681343 -316.723232) (xy 406.697231 -316.674333) (xy 406.720574 -316.628521) (xy 406.750795 -316.586925)
			(xy 406.787151 -316.550569) (xy 406.828747 -316.520348) (xy 406.874559 -316.497005) (xy 406.923458 -316.481117)
			(xy 406.97424 -316.473074) (xy 407.025656 -316.473074) (xy 407.076438 -316.481117) (xy 407.125337 -316.497005)
			(xy 407.171149 -316.520348) (xy 407.212745 -316.550569) (xy 407.249101 -316.586925) (xy 407.279322 -316.628521)
			(xy 407.302665 -316.674333) (xy 407.318553 -316.723232) (xy 407.326596 -316.774014) (xy 407.3271 -316.799722)
			(xy 407.326596 -316.82543) (xy 408.57322 -316.82543) (xy 408.57322 -316.774014) (xy 408.581263 -316.723232)
			(xy 408.597151 -316.674333) (xy 408.620494 -316.628521) (xy 408.650715 -316.586925) (xy 408.687071 -316.550569)
			(xy 408.728667 -316.520348) (xy 408.774479 -316.497005) (xy 408.823378 -316.481117) (xy 408.87416 -316.473074)
			(xy 408.925576 -316.473074) (xy 408.976358 -316.481117) (xy 409.025257 -316.497005) (xy 409.071069 -316.520348)
			(xy 409.112665 -316.550569) (xy 409.149021 -316.586925) (xy 409.179242 -316.628521) (xy 409.202585 -316.674333)
			(xy 409.218473 -316.723232) (xy 409.226516 -316.774014) (xy 409.22702 -316.799722) (xy 409.226516 -316.82543)
			(xy 410.47314 -316.82543) (xy 410.47314 -316.774014) (xy 410.481183 -316.723232) (xy 410.497071 -316.674333)
			(xy 410.520414 -316.628521) (xy 410.550635 -316.586925) (xy 410.586991 -316.550569) (xy 410.628587 -316.520348)
			(xy 410.674399 -316.497005) (xy 410.723298 -316.481117) (xy 410.77408 -316.473074) (xy 410.825496 -316.473074)
			(xy 410.876278 -316.481117) (xy 410.925177 -316.497005) (xy 410.970989 -316.520348) (xy 411.012585 -316.550569)
			(xy 411.048941 -316.586925) (xy 411.079162 -316.628521) (xy 411.102505 -316.674333) (xy 411.118393 -316.723232)
			(xy 411.126436 -316.774014) (xy 411.12694 -316.799722) (xy 411.126436 -316.82543) (xy 412.373314 -316.82543)
			(xy 412.373314 -316.774014) (xy 412.381357 -316.723232) (xy 412.397245 -316.674333) (xy 412.420588 -316.628521)
			(xy 412.450809 -316.586925) (xy 412.487165 -316.550569) (xy 412.528761 -316.520348) (xy 412.574573 -316.497005)
			(xy 412.623472 -316.481117) (xy 412.674254 -316.473074) (xy 412.72567 -316.473074) (xy 412.776452 -316.481117)
			(xy 412.825351 -316.497005) (xy 412.871163 -316.520348) (xy 412.912759 -316.550569) (xy 412.949115 -316.586925)
			(xy 412.979336 -316.628521) (xy 413.002679 -316.674333) (xy 413.018567 -316.723232) (xy 413.02661 -316.774014)
			(xy 413.027114 -316.799722) (xy 414.294078 -316.799722) (xy 414.298038 -316.750668) (xy 414.309815 -316.702884)
			(xy 414.329106 -316.657608) (xy 414.355409 -316.616012) (xy 414.388044 -316.579175) (xy 414.426165 -316.54805)
			(xy 414.468786 -316.523443) (xy 414.514802 -316.505991) (xy 414.563021 -316.496147) (xy 414.612196 -316.494166)
			(xy 414.661051 -316.500098) (xy 414.708322 -316.51379) (xy 414.752784 -316.534888) (xy 414.793287 -316.562844)
			(xy 414.82878 -316.596936) (xy 414.858345 -316.63628) (xy 414.881216 -316.679857) (xy 414.8968 -316.726538)
			(xy 414.904695 -316.775115) (xy 414.90519 -316.799722) (xy 416.193998 -316.799722) (xy 416.197958 -316.750668)
			(xy 416.209735 -316.702884) (xy 416.229026 -316.657608) (xy 416.255329 -316.616012) (xy 416.287964 -316.579175)
			(xy 416.326085 -316.54805) (xy 416.368706 -316.523443) (xy 416.414722 -316.505991) (xy 416.462941 -316.496147)
			(xy 416.512116 -316.494166) (xy 416.560971 -316.500098) (xy 416.608242 -316.51379) (xy 416.652704 -316.534888)
			(xy 416.693207 -316.562844) (xy 416.7287 -316.596936) (xy 416.758265 -316.63628) (xy 416.781136 -316.679857)
			(xy 416.79672 -316.726538) (xy 416.804615 -316.775115) (xy 416.80511 -316.799722) (xy 418.094172 -316.799722)
			(xy 418.098132 -316.750668) (xy 418.109909 -316.702884) (xy 418.1292 -316.657608) (xy 418.155503 -316.616012)
			(xy 418.188138 -316.579175) (xy 418.226259 -316.54805) (xy 418.26888 -316.523443) (xy 418.314896 -316.505991)
			(xy 418.363115 -316.496147) (xy 418.41229 -316.494166) (xy 418.461145 -316.500098) (xy 418.508416 -316.51379)
			(xy 418.552878 -316.534888) (xy 418.593381 -316.562844) (xy 418.628874 -316.596936) (xy 418.658439 -316.63628)
			(xy 418.68131 -316.679857) (xy 418.696894 -316.726538) (xy 418.704789 -316.775115) (xy 418.705284 -316.799722)
			(xy 419.994092 -316.799722) (xy 419.998052 -316.750668) (xy 420.009829 -316.702884) (xy 420.02912 -316.657608)
			(xy 420.055423 -316.616012) (xy 420.088058 -316.579175) (xy 420.126179 -316.54805) (xy 420.1688 -316.523443)
			(xy 420.214816 -316.505991) (xy 420.263035 -316.496147) (xy 420.31221 -316.494166) (xy 420.361065 -316.500098)
			(xy 420.408336 -316.51379) (xy 420.452798 -316.534888) (xy 420.493301 -316.562844) (xy 420.528794 -316.596936)
			(xy 420.558359 -316.63628) (xy 420.58123 -316.679857) (xy 420.596814 -316.726538) (xy 420.604709 -316.775115)
			(xy 420.605204 -316.799722) (xy 420.604709 -316.824329) (xy 420.60453 -316.82543) (xy 421.873168 -316.82543)
			(xy 421.873168 -316.774014) (xy 421.881211 -316.723232) (xy 421.897099 -316.674333) (xy 421.920442 -316.628521)
			(xy 421.950663 -316.586925) (xy 421.987019 -316.550569) (xy 422.028615 -316.520348) (xy 422.074427 -316.497005)
			(xy 422.123326 -316.481117) (xy 422.174108 -316.473074) (xy 422.225524 -316.473074) (xy 422.276306 -316.481117)
			(xy 422.325205 -316.497005) (xy 422.371017 -316.520348) (xy 422.412613 -316.550569) (xy 422.448969 -316.586925)
			(xy 422.47919 -316.628521) (xy 422.502533 -316.674333) (xy 422.518421 -316.723232) (xy 422.526464 -316.774014)
			(xy 422.526968 -316.799722) (xy 422.526464 -316.82543) (xy 423.773342 -316.82543) (xy 423.773342 -316.774014)
			(xy 423.781385 -316.723232) (xy 423.797273 -316.674333) (xy 423.820616 -316.628521) (xy 423.850837 -316.586925)
			(xy 423.887193 -316.550569) (xy 423.928789 -316.520348) (xy 423.974601 -316.497005) (xy 424.0235 -316.481117)
			(xy 424.074282 -316.473074) (xy 424.125698 -316.473074) (xy 424.17648 -316.481117) (xy 424.225379 -316.497005)
			(xy 424.271191 -316.520348) (xy 424.312787 -316.550569) (xy 424.349143 -316.586925) (xy 424.379364 -316.628521)
			(xy 424.402707 -316.674333) (xy 424.418595 -316.723232) (xy 424.426638 -316.774014) (xy 424.427142 -316.799722)
			(xy 424.426638 -316.82543) (xy 425.673262 -316.82543) (xy 425.673262 -316.774014) (xy 425.681305 -316.723232)
			(xy 425.697193 -316.674333) (xy 425.720536 -316.628521) (xy 425.750757 -316.586925) (xy 425.787113 -316.550569)
			(xy 425.828709 -316.520348) (xy 425.874521 -316.497005) (xy 425.92342 -316.481117) (xy 425.974202 -316.473074)
			(xy 426.025618 -316.473074) (xy 426.0764 -316.481117) (xy 426.125299 -316.497005) (xy 426.171111 -316.520348)
			(xy 426.212707 -316.550569) (xy 426.249063 -316.586925) (xy 426.279284 -316.628521) (xy 426.302627 -316.674333)
			(xy 426.318515 -316.723232) (xy 426.326558 -316.774014) (xy 426.327062 -316.799722) (xy 426.326558 -316.82543)
			(xy 427.573182 -316.82543) (xy 427.573182 -316.774014) (xy 427.581225 -316.723232) (xy 427.597113 -316.674333)
			(xy 427.620456 -316.628521) (xy 427.650677 -316.586925) (xy 427.687033 -316.550569) (xy 427.728629 -316.520348)
			(xy 427.774441 -316.497005) (xy 427.82334 -316.481117) (xy 427.874122 -316.473074) (xy 427.925538 -316.473074)
			(xy 427.97632 -316.481117) (xy 428.025219 -316.497005) (xy 428.071031 -316.520348) (xy 428.112627 -316.550569)
			(xy 428.148983 -316.586925) (xy 428.179204 -316.628521) (xy 428.202547 -316.674333) (xy 428.218435 -316.723232)
			(xy 428.226478 -316.774014) (xy 428.226982 -316.799722) (xy 428.226478 -316.82543) (xy 429.473356 -316.82543)
			(xy 429.473356 -316.774014) (xy 429.481399 -316.723232) (xy 429.497287 -316.674333) (xy 429.52063 -316.628521)
			(xy 429.550851 -316.586925) (xy 429.587207 -316.550569) (xy 429.628803 -316.520348) (xy 429.674615 -316.497005)
			(xy 429.723514 -316.481117) (xy 429.774296 -316.473074) (xy 429.825712 -316.473074) (xy 429.876494 -316.481117)
			(xy 429.925393 -316.497005) (xy 429.971205 -316.520348) (xy 430.012801 -316.550569) (xy 430.049157 -316.586925)
			(xy 430.079378 -316.628521) (xy 430.102721 -316.674333) (xy 430.118609 -316.723232) (xy 430.126652 -316.774014)
			(xy 430.127156 -316.799722) (xy 430.126652 -316.82543) (xy 430.423316 -316.82543) (xy 430.423316 -316.774014)
			(xy 430.431359 -316.723232) (xy 430.447247 -316.674333) (xy 430.47059 -316.628521) (xy 430.500811 -316.586925)
			(xy 430.537167 -316.550569) (xy 430.578763 -316.520348) (xy 430.624575 -316.497005) (xy 430.673474 -316.481117)
			(xy 430.724256 -316.473074) (xy 430.775672 -316.473074) (xy 430.826454 -316.481117) (xy 430.875353 -316.497005)
			(xy 430.921165 -316.520348) (xy 430.962761 -316.550569) (xy 430.999117 -316.586925) (xy 431.029338 -316.628521)
			(xy 431.052681 -316.674333) (xy 431.068569 -316.723232) (xy 431.076612 -316.774014) (xy 431.077116 -316.799722)
			(xy 431.076612 -316.82543) (xy 431.068569 -316.876212) (xy 431.052681 -316.925111) (xy 431.029338 -316.970923)
			(xy 430.999117 -317.012519) (xy 430.962761 -317.048875) (xy 430.921165 -317.079096) (xy 430.875353 -317.102439)
			(xy 430.826454 -317.118327) (xy 430.775672 -317.12637) (xy 430.724256 -317.12637) (xy 430.673474 -317.118327)
			(xy 430.624575 -317.102439) (xy 430.578763 -317.079096) (xy 430.537167 -317.048875) (xy 430.500811 -317.012519)
			(xy 430.47059 -316.970923) (xy 430.447247 -316.925111) (xy 430.431359 -316.876212) (xy 430.423316 -316.82543)
			(xy 430.126652 -316.82543) (xy 430.118609 -316.876212) (xy 430.102721 -316.925111) (xy 430.079378 -316.970923)
			(xy 430.049157 -317.012519) (xy 430.012801 -317.048875) (xy 429.971205 -317.079096) (xy 429.925393 -317.102439)
			(xy 429.876494 -317.118327) (xy 429.825712 -317.12637) (xy 429.774296 -317.12637) (xy 429.723514 -317.118327)
			(xy 429.674615 -317.102439) (xy 429.628803 -317.079096) (xy 429.587207 -317.048875) (xy 429.550851 -317.012519)
			(xy 429.52063 -316.970923) (xy 429.497287 -316.925111) (xy 429.481399 -316.876212) (xy 429.473356 -316.82543)
			(xy 428.226478 -316.82543) (xy 428.218435 -316.876212) (xy 428.202547 -316.925111) (xy 428.179204 -316.970923)
			(xy 428.148983 -317.012519) (xy 428.112627 -317.048875) (xy 428.071031 -317.079096) (xy 428.025219 -317.102439)
			(xy 427.97632 -317.118327) (xy 427.925538 -317.12637) (xy 427.874122 -317.12637) (xy 427.82334 -317.118327)
			(xy 427.774441 -317.102439) (xy 427.728629 -317.079096) (xy 427.687033 -317.048875) (xy 427.650677 -317.012519)
			(xy 427.620456 -316.970923) (xy 427.597113 -316.925111) (xy 427.581225 -316.876212) (xy 427.573182 -316.82543)
			(xy 426.326558 -316.82543) (xy 426.318515 -316.876212) (xy 426.302627 -316.925111) (xy 426.279284 -316.970923)
			(xy 426.249063 -317.012519) (xy 426.212707 -317.048875) (xy 426.171111 -317.079096) (xy 426.125299 -317.102439)
			(xy 426.0764 -317.118327) (xy 426.025618 -317.12637) (xy 425.974202 -317.12637) (xy 425.92342 -317.118327)
			(xy 425.874521 -317.102439) (xy 425.828709 -317.079096) (xy 425.787113 -317.048875) (xy 425.750757 -317.012519)
			(xy 425.720536 -316.970923) (xy 425.697193 -316.925111) (xy 425.681305 -316.876212) (xy 425.673262 -316.82543)
			(xy 424.426638 -316.82543) (xy 424.418595 -316.876212) (xy 424.402707 -316.925111) (xy 424.379364 -316.970923)
			(xy 424.349143 -317.012519) (xy 424.312787 -317.048875) (xy 424.271191 -317.079096) (xy 424.225379 -317.102439)
			(xy 424.17648 -317.118327) (xy 424.125698 -317.12637) (xy 424.074282 -317.12637) (xy 424.0235 -317.118327)
			(xy 423.974601 -317.102439) (xy 423.928789 -317.079096) (xy 423.887193 -317.048875) (xy 423.850837 -317.012519)
			(xy 423.820616 -316.970923) (xy 423.797273 -316.925111) (xy 423.781385 -316.876212) (xy 423.773342 -316.82543)
			(xy 422.526464 -316.82543) (xy 422.518421 -316.876212) (xy 422.502533 -316.925111) (xy 422.47919 -316.970923)
			(xy 422.448969 -317.012519) (xy 422.412613 -317.048875) (xy 422.371017 -317.079096) (xy 422.325205 -317.102439)
			(xy 422.276306 -317.118327) (xy 422.225524 -317.12637) (xy 422.174108 -317.12637) (xy 422.123326 -317.118327)
			(xy 422.074427 -317.102439) (xy 422.028615 -317.079096) (xy 421.987019 -317.048875) (xy 421.950663 -317.012519)
			(xy 421.920442 -316.970923) (xy 421.897099 -316.925111) (xy 421.881211 -316.876212) (xy 421.873168 -316.82543)
			(xy 420.60453 -316.82543) (xy 420.596814 -316.872906) (xy 420.58123 -316.919587) (xy 420.558359 -316.963164)
			(xy 420.528794 -317.002508) (xy 420.493301 -317.0366) (xy 420.452798 -317.064556) (xy 420.408336 -317.085654)
			(xy 420.361065 -317.099346) (xy 420.31221 -317.105278) (xy 420.263035 -317.103297) (xy 420.214816 -317.093453)
			(xy 420.1688 -317.076001) (xy 420.126179 -317.051394) (xy 420.088058 -317.020269) (xy 420.055423 -316.983432)
			(xy 420.02912 -316.941836) (xy 420.009829 -316.89656) (xy 419.998052 -316.848776) (xy 419.994092 -316.799722)
			(xy 418.705284 -316.799722) (xy 418.704789 -316.824329) (xy 418.696894 -316.872906) (xy 418.68131 -316.919587)
			(xy 418.658439 -316.963164) (xy 418.628874 -317.002508) (xy 418.593381 -317.0366) (xy 418.552878 -317.064556)
			(xy 418.508416 -317.085654) (xy 418.461145 -317.099346) (xy 418.41229 -317.105278) (xy 418.363115 -317.103297)
			(xy 418.314896 -317.093453) (xy 418.26888 -317.076001) (xy 418.226259 -317.051394) (xy 418.188138 -317.020269)
			(xy 418.155503 -316.983432) (xy 418.1292 -316.941836) (xy 418.109909 -316.89656) (xy 418.098132 -316.848776)
			(xy 418.094172 -316.799722) (xy 416.80511 -316.799722) (xy 416.804615 -316.824329) (xy 416.79672 -316.872906)
			(xy 416.781136 -316.919587) (xy 416.758265 -316.963164) (xy 416.7287 -317.002508) (xy 416.693207 -317.0366)
			(xy 416.652704 -317.064556) (xy 416.608242 -317.085654) (xy 416.560971 -317.099346) (xy 416.512116 -317.105278)
			(xy 416.462941 -317.103297) (xy 416.414722 -317.093453) (xy 416.368706 -317.076001) (xy 416.326085 -317.051394)
			(xy 416.287964 -317.020269) (xy 416.255329 -316.983432) (xy 416.229026 -316.941836) (xy 416.209735 -316.89656)
			(xy 416.197958 -316.848776) (xy 416.193998 -316.799722) (xy 414.90519 -316.799722) (xy 414.904695 -316.824329)
			(xy 414.8968 -316.872906) (xy 414.881216 -316.919587) (xy 414.858345 -316.963164) (xy 414.82878 -317.002508)
			(xy 414.793287 -317.0366) (xy 414.752784 -317.064556) (xy 414.708322 -317.085654) (xy 414.661051 -317.099346)
			(xy 414.612196 -317.105278) (xy 414.563021 -317.103297) (xy 414.514802 -317.093453) (xy 414.468786 -317.076001)
			(xy 414.426165 -317.051394) (xy 414.388044 -317.020269) (xy 414.355409 -316.983432) (xy 414.329106 -316.941836)
			(xy 414.309815 -316.89656) (xy 414.298038 -316.848776) (xy 414.294078 -316.799722) (xy 413.027114 -316.799722)
			(xy 413.02661 -316.82543) (xy 413.018567 -316.876212) (xy 413.002679 -316.925111) (xy 412.979336 -316.970923)
			(xy 412.949115 -317.012519) (xy 412.912759 -317.048875) (xy 412.871163 -317.079096) (xy 412.825351 -317.102439)
			(xy 412.776452 -317.118327) (xy 412.72567 -317.12637) (xy 412.674254 -317.12637) (xy 412.623472 -317.118327)
			(xy 412.574573 -317.102439) (xy 412.528761 -317.079096) (xy 412.487165 -317.048875) (xy 412.450809 -317.012519)
			(xy 412.420588 -316.970923) (xy 412.397245 -316.925111) (xy 412.381357 -316.876212) (xy 412.373314 -316.82543)
			(xy 411.126436 -316.82543) (xy 411.118393 -316.876212) (xy 411.102505 -316.925111) (xy 411.079162 -316.970923)
			(xy 411.048941 -317.012519) (xy 411.012585 -317.048875) (xy 410.970989 -317.079096) (xy 410.925177 -317.102439)
			(xy 410.876278 -317.118327) (xy 410.825496 -317.12637) (xy 410.77408 -317.12637) (xy 410.723298 -317.118327)
			(xy 410.674399 -317.102439) (xy 410.628587 -317.079096) (xy 410.586991 -317.048875) (xy 410.550635 -317.012519)
			(xy 410.520414 -316.970923) (xy 410.497071 -316.925111) (xy 410.481183 -316.876212) (xy 410.47314 -316.82543)
			(xy 409.226516 -316.82543) (xy 409.218473 -316.876212) (xy 409.202585 -316.925111) (xy 409.179242 -316.970923)
			(xy 409.149021 -317.012519) (xy 409.112665 -317.048875) (xy 409.071069 -317.079096) (xy 409.025257 -317.102439)
			(xy 408.976358 -317.118327) (xy 408.925576 -317.12637) (xy 408.87416 -317.12637) (xy 408.823378 -317.118327)
			(xy 408.774479 -317.102439) (xy 408.728667 -317.079096) (xy 408.687071 -317.048875) (xy 408.650715 -317.012519)
			(xy 408.620494 -316.970923) (xy 408.597151 -316.925111) (xy 408.581263 -316.876212) (xy 408.57322 -316.82543)
			(xy 407.326596 -316.82543) (xy 407.318553 -316.876212) (xy 407.302665 -316.925111) (xy 407.279322 -316.970923)
			(xy 407.249101 -317.012519) (xy 407.212745 -317.048875) (xy 407.171149 -317.079096) (xy 407.125337 -317.102439)
			(xy 407.076438 -317.118327) (xy 407.025656 -317.12637) (xy 406.97424 -317.12637) (xy 406.923458 -317.118327)
			(xy 406.874559 -317.102439) (xy 406.828747 -317.079096) (xy 406.787151 -317.048875) (xy 406.750795 -317.012519)
			(xy 406.720574 -316.970923) (xy 406.697231 -316.925111) (xy 406.681343 -316.876212) (xy 406.6733 -316.82543)
			(xy 405.426676 -316.82543) (xy 405.418633 -316.876212) (xy 405.402745 -316.925111) (xy 405.379402 -316.970923)
			(xy 405.349181 -317.012519) (xy 405.312825 -317.048875) (xy 405.271229 -317.079096) (xy 405.225417 -317.102439)
			(xy 405.176518 -317.118327) (xy 405.125736 -317.12637) (xy 405.07432 -317.12637) (xy 405.023538 -317.118327)
			(xy 404.974639 -317.102439) (xy 404.928827 -317.079096) (xy 404.887231 -317.048875) (xy 404.850875 -317.012519)
			(xy 404.820654 -316.970923) (xy 404.797311 -316.925111) (xy 404.781423 -316.876212) (xy 404.77338 -316.82543)
			(xy 403.526502 -316.82543) (xy 403.518459 -316.876212) (xy 403.502571 -316.925111) (xy 403.479228 -316.970923)
			(xy 403.449007 -317.012519) (xy 403.412651 -317.048875) (xy 403.371055 -317.079096) (xy 403.325243 -317.102439)
			(xy 403.276344 -317.118327) (xy 403.225562 -317.12637) (xy 403.174146 -317.12637) (xy 403.123364 -317.118327)
			(xy 403.074465 -317.102439) (xy 403.028653 -317.079096) (xy 402.987057 -317.048875) (xy 402.950701 -317.012519)
			(xy 402.92048 -316.970923) (xy 402.897137 -316.925111) (xy 402.881249 -316.876212) (xy 402.873206 -316.82543)
			(xy 401.626582 -316.82543) (xy 401.618539 -316.876212) (xy 401.602651 -316.925111) (xy 401.579308 -316.970923)
			(xy 401.549087 -317.012519) (xy 401.512731 -317.048875) (xy 401.471135 -317.079096) (xy 401.425323 -317.102439)
			(xy 401.376424 -317.118327) (xy 401.325642 -317.12637) (xy 401.274226 -317.12637) (xy 401.223444 -317.118327)
			(xy 401.174545 -317.102439) (xy 401.128733 -317.079096) (xy 401.087137 -317.048875) (xy 401.050781 -317.012519)
			(xy 401.02056 -316.970923) (xy 400.997217 -316.925111) (xy 400.981329 -316.876212) (xy 400.973286 -316.82543)
			(xy 399.726662 -316.82543) (xy 399.718619 -316.876212) (xy 399.702731 -316.925111) (xy 399.679388 -316.970923)
			(xy 399.649167 -317.012519) (xy 399.612811 -317.048875) (xy 399.571215 -317.079096) (xy 399.525403 -317.102439)
			(xy 399.476504 -317.118327) (xy 399.425722 -317.12637) (xy 399.374306 -317.12637) (xy 399.323524 -317.118327)
			(xy 399.274625 -317.102439) (xy 399.228813 -317.079096) (xy 399.187217 -317.048875) (xy 399.150861 -317.012519)
			(xy 399.12064 -316.970923) (xy 399.097297 -316.925111) (xy 399.081409 -316.876212) (xy 399.073366 -316.82543)
			(xy 397.804474 -316.82543) (xy 397.796758 -316.872906) (xy 397.781174 -316.919587) (xy 397.758303 -316.963164)
			(xy 397.728738 -317.002508) (xy 397.693245 -317.0366) (xy 397.652742 -317.064556) (xy 397.60828 -317.085654)
			(xy 397.561009 -317.099346) (xy 397.512154 -317.105278) (xy 397.462979 -317.103297) (xy 397.41476 -317.093453)
			(xy 397.368744 -317.076001) (xy 397.326123 -317.051394) (xy 397.288002 -317.020269) (xy 397.255367 -316.983432)
			(xy 397.229064 -316.941836) (xy 397.209773 -316.89656) (xy 397.197996 -316.848776) (xy 397.194036 -316.799722)
			(xy 395.905228 -316.799722) (xy 395.904733 -316.824329) (xy 395.896838 -316.872906) (xy 395.881254 -316.919587)
			(xy 395.858383 -316.963164) (xy 395.828818 -317.002508) (xy 395.793325 -317.0366) (xy 395.752822 -317.064556)
			(xy 395.70836 -317.085654) (xy 395.661089 -317.099346) (xy 395.612234 -317.105278) (xy 395.563059 -317.103297)
			(xy 395.51484 -317.093453) (xy 395.468824 -317.076001) (xy 395.426203 -317.051394) (xy 395.388082 -317.020269)
			(xy 395.355447 -316.983432) (xy 395.329144 -316.941836) (xy 395.309853 -316.89656) (xy 395.298076 -316.848776)
			(xy 395.294116 -316.799722) (xy 394.005308 -316.799722) (xy 394.004813 -316.824329) (xy 393.996918 -316.872906)
			(xy 393.981334 -316.919587) (xy 393.958463 -316.963164) (xy 393.928898 -317.002508) (xy 393.893405 -317.0366)
			(xy 393.852902 -317.064556) (xy 393.80844 -317.085654) (xy 393.761169 -317.099346) (xy 393.712314 -317.105278)
			(xy 393.663139 -317.103297) (xy 393.61492 -317.093453) (xy 393.568904 -317.076001) (xy 393.526283 -317.051394)
			(xy 393.488162 -317.020269) (xy 393.455527 -316.983432) (xy 393.429224 -316.941836) (xy 393.409933 -316.89656)
			(xy 393.398156 -316.848776) (xy 393.394196 -316.799722) (xy 392.105607 -316.799722) (xy 392.101439 -316.850032)
			(xy 392.089041 -316.898991) (xy 392.068755 -316.945242) (xy 392.041133 -316.987523) (xy 392.006929 -317.024682)
			(xy 391.967075 -317.055704) (xy 391.92266 -317.079744) (xy 391.874893 -317.096146) (xy 391.825078 -317.104462)
			(xy 391.799826 -317.10503) (xy 391.799318 -317.10503) (xy 391.779135 -317.104687) (xy 391.739126 -317.099332)
			(xy 391.719562 -317.094362) (xy 391.712958 -317.092584) (xy 391.7061 -317.092584) (xy 391.696091 -317.093072)
			(xy 391.677597 -317.100731) (xy 391.66344 -317.114883) (xy 391.655775 -317.133375) (xy 391.6553 -317.143384)
			(xy 391.6553 -317.197994) (xy 391.659618 -317.211964) (xy 391.663682 -317.218314) (xy 391.689332 -317.258623)
			(xy 391.733479 -317.343361) (xy 391.75182 -317.387478) (xy 391.756018 -317.396634) (xy 391.770186 -317.410928)
			(xy 391.788749 -317.418706) (xy 391.79881 -317.419228) (xy 391.799826 -317.419228) (xy 391.825813 -317.419713)
			(xy 391.877146 -317.427848) (xy 391.926575 -317.443913) (xy 391.972882 -317.467512) (xy 392.014927 -317.498066)
			(xy 392.051675 -317.53482) (xy 392.08222 -317.576871) (xy 392.105811 -317.623182) (xy 392.121867 -317.672614)
			(xy 392.129992 -317.723949) (xy 392.130534 -317.749936) (xy 392.443982 -317.749936) (xy 392.447942 -317.700882)
			(xy 392.459719 -317.653098) (xy 392.47901 -317.607822) (xy 392.505313 -317.566226) (xy 392.537948 -317.529389)
			(xy 392.576069 -317.498264) (xy 392.61869 -317.473657) (xy 392.664706 -317.456205) (xy 392.712925 -317.446361)
			(xy 392.7621 -317.44438) (xy 392.810955 -317.450312) (xy 392.858226 -317.464004) (xy 392.902688 -317.485102)
			(xy 392.943191 -317.513058) (xy 392.978684 -317.54715) (xy 393.008249 -317.586494) (xy 393.03112 -317.630071)
			(xy 393.046704 -317.676752) (xy 393.054599 -317.725329) (xy 393.055094 -317.749936) (xy 394.344156 -317.749936)
			(xy 394.348116 -317.700882) (xy 394.359893 -317.653098) (xy 394.379184 -317.607822) (xy 394.405487 -317.566226)
			(xy 394.438122 -317.529389) (xy 394.476243 -317.498264) (xy 394.518864 -317.473657) (xy 394.56488 -317.456205)
			(xy 394.613099 -317.446361) (xy 394.662274 -317.44438) (xy 394.711129 -317.450312) (xy 394.7584 -317.464004)
			(xy 394.802862 -317.485102) (xy 394.843365 -317.513058) (xy 394.878858 -317.54715) (xy 394.908423 -317.586494)
			(xy 394.931294 -317.630071) (xy 394.946878 -317.676752) (xy 394.954773 -317.725329) (xy 394.955268 -317.749936)
			(xy 396.244076 -317.749936) (xy 396.248036 -317.700882) (xy 396.259813 -317.653098) (xy 396.279104 -317.607822)
			(xy 396.305407 -317.566226) (xy 396.338042 -317.529389) (xy 396.376163 -317.498264) (xy 396.418784 -317.473657)
			(xy 396.4648 -317.456205) (xy 396.513019 -317.446361) (xy 396.562194 -317.44438) (xy 396.611049 -317.450312)
			(xy 396.65832 -317.464004) (xy 396.702782 -317.485102) (xy 396.743285 -317.513058) (xy 396.778778 -317.54715)
			(xy 396.808343 -317.586494) (xy 396.831214 -317.630071) (xy 396.846798 -317.676752) (xy 396.854693 -317.725329)
			(xy 396.855188 -317.749936) (xy 398.143996 -317.749936) (xy 398.147956 -317.700882) (xy 398.159733 -317.653098)
			(xy 398.179024 -317.607822) (xy 398.205327 -317.566226) (xy 398.237962 -317.529389) (xy 398.276083 -317.498264)
			(xy 398.318704 -317.473657) (xy 398.36472 -317.456205) (xy 398.412939 -317.446361) (xy 398.462114 -317.44438)
			(xy 398.510969 -317.450312) (xy 398.55824 -317.464004) (xy 398.602702 -317.485102) (xy 398.643205 -317.513058)
			(xy 398.678698 -317.54715) (xy 398.708263 -317.586494) (xy 398.731134 -317.630071) (xy 398.746718 -317.676752)
			(xy 398.754613 -317.725329) (xy 398.755108 -317.749936) (xy 398.754613 -317.774543) (xy 398.754434 -317.775644)
			(xy 400.023326 -317.775644) (xy 400.023326 -317.724228) (xy 400.031369 -317.673446) (xy 400.047257 -317.624547)
			(xy 400.0706 -317.578735) (xy 400.100821 -317.537139) (xy 400.137177 -317.500783) (xy 400.178773 -317.470562)
			(xy 400.224585 -317.447219) (xy 400.273484 -317.431331) (xy 400.324266 -317.423288) (xy 400.375682 -317.423288)
			(xy 400.426464 -317.431331) (xy 400.475363 -317.447219) (xy 400.521175 -317.470562) (xy 400.562771 -317.500783)
			(xy 400.599127 -317.537139) (xy 400.629348 -317.578735) (xy 400.652691 -317.624547) (xy 400.668579 -317.673446)
			(xy 400.676622 -317.724228) (xy 400.677126 -317.749936) (xy 400.676622 -317.775644) (xy 401.923246 -317.775644)
			(xy 401.923246 -317.724228) (xy 401.931289 -317.673446) (xy 401.947177 -317.624547) (xy 401.97052 -317.578735)
			(xy 402.000741 -317.537139) (xy 402.037097 -317.500783) (xy 402.078693 -317.470562) (xy 402.124505 -317.447219)
			(xy 402.173404 -317.431331) (xy 402.224186 -317.423288) (xy 402.275602 -317.423288) (xy 402.326384 -317.431331)
			(xy 402.375283 -317.447219) (xy 402.421095 -317.470562) (xy 402.462691 -317.500783) (xy 402.499047 -317.537139)
			(xy 402.529268 -317.578735) (xy 402.552611 -317.624547) (xy 402.568499 -317.673446) (xy 402.576542 -317.724228)
			(xy 402.577046 -317.749936) (xy 402.576542 -317.775644) (xy 403.823166 -317.775644) (xy 403.823166 -317.724228)
			(xy 403.831209 -317.673446) (xy 403.847097 -317.624547) (xy 403.87044 -317.578735) (xy 403.900661 -317.537139)
			(xy 403.937017 -317.500783) (xy 403.978613 -317.470562) (xy 404.024425 -317.447219) (xy 404.073324 -317.431331)
			(xy 404.124106 -317.423288) (xy 404.175522 -317.423288) (xy 404.226304 -317.431331) (xy 404.275203 -317.447219)
			(xy 404.321015 -317.470562) (xy 404.362611 -317.500783) (xy 404.398967 -317.537139) (xy 404.429188 -317.578735)
			(xy 404.452531 -317.624547) (xy 404.468419 -317.673446) (xy 404.476462 -317.724228) (xy 404.476966 -317.749936)
			(xy 404.476462 -317.775644) (xy 405.72334 -317.775644) (xy 405.72334 -317.724228) (xy 405.731383 -317.673446)
			(xy 405.747271 -317.624547) (xy 405.770614 -317.578735) (xy 405.800835 -317.537139) (xy 405.837191 -317.500783)
			(xy 405.878787 -317.470562) (xy 405.924599 -317.447219) (xy 405.973498 -317.431331) (xy 406.02428 -317.423288)
			(xy 406.075696 -317.423288) (xy 406.126478 -317.431331) (xy 406.175377 -317.447219) (xy 406.221189 -317.470562)
			(xy 406.262785 -317.500783) (xy 406.299141 -317.537139) (xy 406.329362 -317.578735) (xy 406.352705 -317.624547)
			(xy 406.368593 -317.673446) (xy 406.376636 -317.724228) (xy 406.37714 -317.749936) (xy 406.376636 -317.775644)
			(xy 407.62326 -317.775644) (xy 407.62326 -317.724228) (xy 407.631303 -317.673446) (xy 407.647191 -317.624547)
			(xy 407.670534 -317.578735) (xy 407.700755 -317.537139) (xy 407.737111 -317.500783) (xy 407.778707 -317.470562)
			(xy 407.824519 -317.447219) (xy 407.873418 -317.431331) (xy 407.9242 -317.423288) (xy 407.975616 -317.423288)
			(xy 408.026398 -317.431331) (xy 408.075297 -317.447219) (xy 408.121109 -317.470562) (xy 408.162705 -317.500783)
			(xy 408.199061 -317.537139) (xy 408.229282 -317.578735) (xy 408.252625 -317.624547) (xy 408.268513 -317.673446)
			(xy 408.276556 -317.724228) (xy 408.27706 -317.749936) (xy 408.276556 -317.775644) (xy 409.52318 -317.775644)
			(xy 409.52318 -317.724228) (xy 409.531223 -317.673446) (xy 409.547111 -317.624547) (xy 409.570454 -317.578735)
			(xy 409.600675 -317.537139) (xy 409.637031 -317.500783) (xy 409.678627 -317.470562) (xy 409.724439 -317.447219)
			(xy 409.773338 -317.431331) (xy 409.82412 -317.423288) (xy 409.875536 -317.423288) (xy 409.926318 -317.431331)
			(xy 409.975217 -317.447219) (xy 410.021029 -317.470562) (xy 410.062625 -317.500783) (xy 410.098981 -317.537139)
			(xy 410.129202 -317.578735) (xy 410.152545 -317.624547) (xy 410.168433 -317.673446) (xy 410.176476 -317.724228)
			(xy 410.17698 -317.749936) (xy 410.176476 -317.775644) (xy 411.423354 -317.775644) (xy 411.423354 -317.724228)
			(xy 411.431397 -317.673446) (xy 411.447285 -317.624547) (xy 411.470628 -317.578735) (xy 411.500849 -317.537139)
			(xy 411.537205 -317.500783) (xy 411.578801 -317.470562) (xy 411.624613 -317.447219) (xy 411.673512 -317.431331)
			(xy 411.724294 -317.423288) (xy 411.77571 -317.423288) (xy 411.826492 -317.431331) (xy 411.875391 -317.447219)
			(xy 411.921203 -317.470562) (xy 411.962799 -317.500783) (xy 411.999155 -317.537139) (xy 412.029376 -317.578735)
			(xy 412.052719 -317.624547) (xy 412.068607 -317.673446) (xy 412.07665 -317.724228) (xy 412.077154 -317.749936)
			(xy 412.07665 -317.775644) (xy 413.323274 -317.775644) (xy 413.323274 -317.724228) (xy 413.331317 -317.673446)
			(xy 413.347205 -317.624547) (xy 413.370548 -317.578735) (xy 413.400769 -317.537139) (xy 413.437125 -317.500783)
			(xy 413.478721 -317.470562) (xy 413.524533 -317.447219) (xy 413.573432 -317.431331) (xy 413.624214 -317.423288)
			(xy 413.67563 -317.423288) (xy 413.726412 -317.431331) (xy 413.775311 -317.447219) (xy 413.821123 -317.470562)
			(xy 413.862719 -317.500783) (xy 413.899075 -317.537139) (xy 413.929296 -317.578735) (xy 413.952639 -317.624547)
			(xy 413.968527 -317.673446) (xy 413.97657 -317.724228) (xy 413.977074 -317.749936) (xy 415.244038 -317.749936)
			(xy 415.247998 -317.700882) (xy 415.259775 -317.653098) (xy 415.279066 -317.607822) (xy 415.305369 -317.566226)
			(xy 415.338004 -317.529389) (xy 415.376125 -317.498264) (xy 415.418746 -317.473657) (xy 415.464762 -317.456205)
			(xy 415.512981 -317.446361) (xy 415.562156 -317.44438) (xy 415.611011 -317.450312) (xy 415.658282 -317.464004)
			(xy 415.702744 -317.485102) (xy 415.743247 -317.513058) (xy 415.77874 -317.54715) (xy 415.808305 -317.586494)
			(xy 415.831176 -317.630071) (xy 415.84676 -317.676752) (xy 415.854655 -317.725329) (xy 415.85515 -317.749936)
			(xy 417.144212 -317.749936) (xy 417.148172 -317.700882) (xy 417.159949 -317.653098) (xy 417.17924 -317.607822)
			(xy 417.205543 -317.566226) (xy 417.238178 -317.529389) (xy 417.276299 -317.498264) (xy 417.31892 -317.473657)
			(xy 417.364936 -317.456205) (xy 417.413155 -317.446361) (xy 417.46233 -317.44438) (xy 417.511185 -317.450312)
			(xy 417.558456 -317.464004) (xy 417.602918 -317.485102) (xy 417.643421 -317.513058) (xy 417.678914 -317.54715)
			(xy 417.708479 -317.586494) (xy 417.73135 -317.630071) (xy 417.746934 -317.676752) (xy 417.754829 -317.725329)
			(xy 417.755324 -317.749936) (xy 419.044132 -317.749936) (xy 419.048092 -317.700882) (xy 419.059869 -317.653098)
			(xy 419.07916 -317.607822) (xy 419.105463 -317.566226) (xy 419.138098 -317.529389) (xy 419.176219 -317.498264)
			(xy 419.21884 -317.473657) (xy 419.264856 -317.456205) (xy 419.313075 -317.446361) (xy 419.36225 -317.44438)
			(xy 419.411105 -317.450312) (xy 419.458376 -317.464004) (xy 419.502838 -317.485102) (xy 419.543341 -317.513058)
			(xy 419.578834 -317.54715) (xy 419.608399 -317.586494) (xy 419.63127 -317.630071) (xy 419.646854 -317.676752)
			(xy 419.654749 -317.725329) (xy 419.655244 -317.749936) (xy 420.944052 -317.749936) (xy 420.948012 -317.700882)
			(xy 420.959789 -317.653098) (xy 420.97908 -317.607822) (xy 421.005383 -317.566226) (xy 421.038018 -317.529389)
			(xy 421.076139 -317.498264) (xy 421.11876 -317.473657) (xy 421.164776 -317.456205) (xy 421.212995 -317.446361)
			(xy 421.26217 -317.44438) (xy 421.311025 -317.450312) (xy 421.358296 -317.464004) (xy 421.402758 -317.485102)
			(xy 421.443261 -317.513058) (xy 421.478754 -317.54715) (xy 421.508319 -317.586494) (xy 421.53119 -317.630071)
			(xy 421.546774 -317.676752) (xy 421.554669 -317.725329) (xy 421.555164 -317.749936) (xy 421.554669 -317.774543)
			(xy 421.55449 -317.775644) (xy 422.823382 -317.775644) (xy 422.823382 -317.724228) (xy 422.831425 -317.673446)
			(xy 422.847313 -317.624547) (xy 422.870656 -317.578735) (xy 422.900877 -317.537139) (xy 422.937233 -317.500783)
			(xy 422.978829 -317.470562) (xy 423.024641 -317.447219) (xy 423.07354 -317.431331) (xy 423.124322 -317.423288)
			(xy 423.175738 -317.423288) (xy 423.22652 -317.431331) (xy 423.275419 -317.447219) (xy 423.321231 -317.470562)
			(xy 423.362827 -317.500783) (xy 423.399183 -317.537139) (xy 423.429404 -317.578735) (xy 423.452747 -317.624547)
			(xy 423.468635 -317.673446) (xy 423.476678 -317.724228) (xy 423.477182 -317.749936) (xy 423.476678 -317.775644)
			(xy 424.723302 -317.775644) (xy 424.723302 -317.724228) (xy 424.731345 -317.673446) (xy 424.747233 -317.624547)
			(xy 424.770576 -317.578735) (xy 424.800797 -317.537139) (xy 424.837153 -317.500783) (xy 424.878749 -317.470562)
			(xy 424.924561 -317.447219) (xy 424.97346 -317.431331) (xy 425.024242 -317.423288) (xy 425.075658 -317.423288)
			(xy 425.12644 -317.431331) (xy 425.175339 -317.447219) (xy 425.221151 -317.470562) (xy 425.262747 -317.500783)
			(xy 425.299103 -317.537139) (xy 425.329324 -317.578735) (xy 425.352667 -317.624547) (xy 425.368555 -317.673446)
			(xy 425.376598 -317.724228) (xy 425.377102 -317.749936) (xy 425.376598 -317.775644) (xy 426.623222 -317.775644)
			(xy 426.623222 -317.724228) (xy 426.631265 -317.673446) (xy 426.647153 -317.624547) (xy 426.670496 -317.578735)
			(xy 426.700717 -317.537139) (xy 426.737073 -317.500783) (xy 426.778669 -317.470562) (xy 426.824481 -317.447219)
			(xy 426.87338 -317.431331) (xy 426.924162 -317.423288) (xy 426.975578 -317.423288) (xy 427.02636 -317.431331)
			(xy 427.075259 -317.447219) (xy 427.121071 -317.470562) (xy 427.162667 -317.500783) (xy 427.199023 -317.537139)
			(xy 427.229244 -317.578735) (xy 427.252587 -317.624547) (xy 427.268475 -317.673446) (xy 427.276518 -317.724228)
			(xy 427.277022 -317.749936) (xy 427.276518 -317.775644) (xy 428.523142 -317.775644) (xy 428.523142 -317.724228)
			(xy 428.531185 -317.673446) (xy 428.547073 -317.624547) (xy 428.570416 -317.578735) (xy 428.600637 -317.537139)
			(xy 428.636993 -317.500783) (xy 428.678589 -317.470562) (xy 428.724401 -317.447219) (xy 428.7733 -317.431331)
			(xy 428.824082 -317.423288) (xy 428.875498 -317.423288) (xy 428.92628 -317.431331) (xy 428.975179 -317.447219)
			(xy 429.020991 -317.470562) (xy 429.062587 -317.500783) (xy 429.098943 -317.537139) (xy 429.129164 -317.578735)
			(xy 429.152507 -317.624547) (xy 429.168395 -317.673446) (xy 429.176438 -317.724228) (xy 429.176942 -317.749936)
			(xy 429.176438 -317.775644) (xy 429.168395 -317.826426) (xy 429.152507 -317.875325) (xy 429.129164 -317.921137)
			(xy 429.098943 -317.962733) (xy 429.062587 -317.999089) (xy 429.020991 -318.02931) (xy 428.975179 -318.052653)
			(xy 428.92628 -318.068541) (xy 428.875498 -318.076584) (xy 428.824082 -318.076584) (xy 428.7733 -318.068541)
			(xy 428.724401 -318.052653) (xy 428.678589 -318.02931) (xy 428.636993 -317.999089) (xy 428.600637 -317.962733)
			(xy 428.570416 -317.921137) (xy 428.547073 -317.875325) (xy 428.531185 -317.826426) (xy 428.523142 -317.775644)
			(xy 427.276518 -317.775644) (xy 427.268475 -317.826426) (xy 427.252587 -317.875325) (xy 427.229244 -317.921137)
			(xy 427.199023 -317.962733) (xy 427.162667 -317.999089) (xy 427.121071 -318.02931) (xy 427.075259 -318.052653)
			(xy 427.02636 -318.068541) (xy 426.975578 -318.076584) (xy 426.924162 -318.076584) (xy 426.87338 -318.068541)
			(xy 426.824481 -318.052653) (xy 426.778669 -318.02931) (xy 426.737073 -317.999089) (xy 426.700717 -317.962733)
			(xy 426.670496 -317.921137) (xy 426.647153 -317.875325) (xy 426.631265 -317.826426) (xy 426.623222 -317.775644)
			(xy 425.376598 -317.775644) (xy 425.368555 -317.826426) (xy 425.352667 -317.875325) (xy 425.329324 -317.921137)
			(xy 425.299103 -317.962733) (xy 425.262747 -317.999089) (xy 425.221151 -318.02931) (xy 425.175339 -318.052653)
			(xy 425.12644 -318.068541) (xy 425.075658 -318.076584) (xy 425.024242 -318.076584) (xy 424.97346 -318.068541)
			(xy 424.924561 -318.052653) (xy 424.878749 -318.02931) (xy 424.837153 -317.999089) (xy 424.800797 -317.962733)
			(xy 424.770576 -317.921137) (xy 424.747233 -317.875325) (xy 424.731345 -317.826426) (xy 424.723302 -317.775644)
			(xy 423.476678 -317.775644) (xy 423.468635 -317.826426) (xy 423.452747 -317.875325) (xy 423.429404 -317.921137)
			(xy 423.399183 -317.962733) (xy 423.362827 -317.999089) (xy 423.321231 -318.02931) (xy 423.275419 -318.052653)
			(xy 423.22652 -318.068541) (xy 423.175738 -318.076584) (xy 423.124322 -318.076584) (xy 423.07354 -318.068541)
			(xy 423.024641 -318.052653) (xy 422.978829 -318.02931) (xy 422.937233 -317.999089) (xy 422.900877 -317.962733)
			(xy 422.870656 -317.921137) (xy 422.847313 -317.875325) (xy 422.831425 -317.826426) (xy 422.823382 -317.775644)
			(xy 421.55449 -317.775644) (xy 421.546774 -317.82312) (xy 421.53119 -317.869801) (xy 421.508319 -317.913378)
			(xy 421.478754 -317.952722) (xy 421.443261 -317.986814) (xy 421.402758 -318.01477) (xy 421.358296 -318.035868)
			(xy 421.311025 -318.04956) (xy 421.26217 -318.055492) (xy 421.212995 -318.053511) (xy 421.164776 -318.043667)
			(xy 421.11876 -318.026215) (xy 421.076139 -318.001608) (xy 421.038018 -317.970483) (xy 421.005383 -317.933646)
			(xy 420.97908 -317.89205) (xy 420.959789 -317.846774) (xy 420.948012 -317.79899) (xy 420.944052 -317.749936)
			(xy 419.655244 -317.749936) (xy 419.654749 -317.774543) (xy 419.646854 -317.82312) (xy 419.63127 -317.869801)
			(xy 419.608399 -317.913378) (xy 419.578834 -317.952722) (xy 419.543341 -317.986814) (xy 419.502838 -318.01477)
			(xy 419.458376 -318.035868) (xy 419.411105 -318.04956) (xy 419.36225 -318.055492) (xy 419.313075 -318.053511)
			(xy 419.264856 -318.043667) (xy 419.21884 -318.026215) (xy 419.176219 -318.001608) (xy 419.138098 -317.970483)
			(xy 419.105463 -317.933646) (xy 419.07916 -317.89205) (xy 419.059869 -317.846774) (xy 419.048092 -317.79899)
			(xy 419.044132 -317.749936) (xy 417.755324 -317.749936) (xy 417.754829 -317.774543) (xy 417.746934 -317.82312)
			(xy 417.73135 -317.869801) (xy 417.708479 -317.913378) (xy 417.678914 -317.952722) (xy 417.643421 -317.986814)
			(xy 417.602918 -318.01477) (xy 417.558456 -318.035868) (xy 417.511185 -318.04956) (xy 417.46233 -318.055492)
			(xy 417.413155 -318.053511) (xy 417.364936 -318.043667) (xy 417.31892 -318.026215) (xy 417.276299 -318.001608)
			(xy 417.238178 -317.970483) (xy 417.205543 -317.933646) (xy 417.17924 -317.89205) (xy 417.159949 -317.846774)
			(xy 417.148172 -317.79899) (xy 417.144212 -317.749936) (xy 415.85515 -317.749936) (xy 415.854655 -317.774543)
			(xy 415.84676 -317.82312) (xy 415.831176 -317.869801) (xy 415.808305 -317.913378) (xy 415.77874 -317.952722)
			(xy 415.743247 -317.986814) (xy 415.702744 -318.01477) (xy 415.658282 -318.035868) (xy 415.611011 -318.04956)
			(xy 415.562156 -318.055492) (xy 415.512981 -318.053511) (xy 415.464762 -318.043667) (xy 415.418746 -318.026215)
			(xy 415.376125 -318.001608) (xy 415.338004 -317.970483) (xy 415.305369 -317.933646) (xy 415.279066 -317.89205)
			(xy 415.259775 -317.846774) (xy 415.247998 -317.79899) (xy 415.244038 -317.749936) (xy 413.977074 -317.749936)
			(xy 413.97657 -317.775644) (xy 413.968527 -317.826426) (xy 413.952639 -317.875325) (xy 413.929296 -317.921137)
			(xy 413.899075 -317.962733) (xy 413.862719 -317.999089) (xy 413.821123 -318.02931) (xy 413.775311 -318.052653)
			(xy 413.726412 -318.068541) (xy 413.67563 -318.076584) (xy 413.624214 -318.076584) (xy 413.573432 -318.068541)
			(xy 413.524533 -318.052653) (xy 413.478721 -318.02931) (xy 413.437125 -317.999089) (xy 413.400769 -317.962733)
			(xy 413.370548 -317.921137) (xy 413.347205 -317.875325) (xy 413.331317 -317.826426) (xy 413.323274 -317.775644)
			(xy 412.07665 -317.775644) (xy 412.068607 -317.826426) (xy 412.052719 -317.875325) (xy 412.029376 -317.921137)
			(xy 411.999155 -317.962733) (xy 411.962799 -317.999089) (xy 411.921203 -318.02931) (xy 411.875391 -318.052653)
			(xy 411.826492 -318.068541) (xy 411.77571 -318.076584) (xy 411.724294 -318.076584) (xy 411.673512 -318.068541)
			(xy 411.624613 -318.052653) (xy 411.578801 -318.02931) (xy 411.537205 -317.999089) (xy 411.500849 -317.962733)
			(xy 411.470628 -317.921137) (xy 411.447285 -317.875325) (xy 411.431397 -317.826426) (xy 411.423354 -317.775644)
			(xy 410.176476 -317.775644) (xy 410.168433 -317.826426) (xy 410.152545 -317.875325) (xy 410.129202 -317.921137)
			(xy 410.098981 -317.962733) (xy 410.062625 -317.999089) (xy 410.021029 -318.02931) (xy 409.975217 -318.052653)
			(xy 409.926318 -318.068541) (xy 409.875536 -318.076584) (xy 409.82412 -318.076584) (xy 409.773338 -318.068541)
			(xy 409.724439 -318.052653) (xy 409.678627 -318.02931) (xy 409.637031 -317.999089) (xy 409.600675 -317.962733)
			(xy 409.570454 -317.921137) (xy 409.547111 -317.875325) (xy 409.531223 -317.826426) (xy 409.52318 -317.775644)
			(xy 408.276556 -317.775644) (xy 408.268513 -317.826426) (xy 408.252625 -317.875325) (xy 408.229282 -317.921137)
			(xy 408.199061 -317.962733) (xy 408.162705 -317.999089) (xy 408.121109 -318.02931) (xy 408.075297 -318.052653)
			(xy 408.026398 -318.068541) (xy 407.975616 -318.076584) (xy 407.9242 -318.076584) (xy 407.873418 -318.068541)
			(xy 407.824519 -318.052653) (xy 407.778707 -318.02931) (xy 407.737111 -317.999089) (xy 407.700755 -317.962733)
			(xy 407.670534 -317.921137) (xy 407.647191 -317.875325) (xy 407.631303 -317.826426) (xy 407.62326 -317.775644)
			(xy 406.376636 -317.775644) (xy 406.368593 -317.826426) (xy 406.352705 -317.875325) (xy 406.329362 -317.921137)
			(xy 406.299141 -317.962733) (xy 406.262785 -317.999089) (xy 406.221189 -318.02931) (xy 406.175377 -318.052653)
			(xy 406.126478 -318.068541) (xy 406.075696 -318.076584) (xy 406.02428 -318.076584) (xy 405.973498 -318.068541)
			(xy 405.924599 -318.052653) (xy 405.878787 -318.02931) (xy 405.837191 -317.999089) (xy 405.800835 -317.962733)
			(xy 405.770614 -317.921137) (xy 405.747271 -317.875325) (xy 405.731383 -317.826426) (xy 405.72334 -317.775644)
			(xy 404.476462 -317.775644) (xy 404.468419 -317.826426) (xy 404.452531 -317.875325) (xy 404.429188 -317.921137)
			(xy 404.398967 -317.962733) (xy 404.362611 -317.999089) (xy 404.321015 -318.02931) (xy 404.275203 -318.052653)
			(xy 404.226304 -318.068541) (xy 404.175522 -318.076584) (xy 404.124106 -318.076584) (xy 404.073324 -318.068541)
			(xy 404.024425 -318.052653) (xy 403.978613 -318.02931) (xy 403.937017 -317.999089) (xy 403.900661 -317.962733)
			(xy 403.87044 -317.921137) (xy 403.847097 -317.875325) (xy 403.831209 -317.826426) (xy 403.823166 -317.775644)
			(xy 402.576542 -317.775644) (xy 402.568499 -317.826426) (xy 402.552611 -317.875325) (xy 402.529268 -317.921137)
			(xy 402.499047 -317.962733) (xy 402.462691 -317.999089) (xy 402.421095 -318.02931) (xy 402.375283 -318.052653)
			(xy 402.326384 -318.068541) (xy 402.275602 -318.076584) (xy 402.224186 -318.076584) (xy 402.173404 -318.068541)
			(xy 402.124505 -318.052653) (xy 402.078693 -318.02931) (xy 402.037097 -317.999089) (xy 402.000741 -317.962733)
			(xy 401.97052 -317.921137) (xy 401.947177 -317.875325) (xy 401.931289 -317.826426) (xy 401.923246 -317.775644)
			(xy 400.676622 -317.775644) (xy 400.668579 -317.826426) (xy 400.652691 -317.875325) (xy 400.629348 -317.921137)
			(xy 400.599127 -317.962733) (xy 400.562771 -317.999089) (xy 400.521175 -318.02931) (xy 400.475363 -318.052653)
			(xy 400.426464 -318.068541) (xy 400.375682 -318.076584) (xy 400.324266 -318.076584) (xy 400.273484 -318.068541)
			(xy 400.224585 -318.052653) (xy 400.178773 -318.02931) (xy 400.137177 -317.999089) (xy 400.100821 -317.962733)
			(xy 400.0706 -317.921137) (xy 400.047257 -317.875325) (xy 400.031369 -317.826426) (xy 400.023326 -317.775644)
			(xy 398.754434 -317.775644) (xy 398.746718 -317.82312) (xy 398.731134 -317.869801) (xy 398.708263 -317.913378)
			(xy 398.678698 -317.952722) (xy 398.643205 -317.986814) (xy 398.602702 -318.01477) (xy 398.55824 -318.035868)
			(xy 398.510969 -318.04956) (xy 398.462114 -318.055492) (xy 398.412939 -318.053511) (xy 398.36472 -318.043667)
			(xy 398.318704 -318.026215) (xy 398.276083 -318.001608) (xy 398.237962 -317.970483) (xy 398.205327 -317.933646)
			(xy 398.179024 -317.89205) (xy 398.159733 -317.846774) (xy 398.147956 -317.79899) (xy 398.143996 -317.749936)
			(xy 396.855188 -317.749936) (xy 396.854693 -317.774543) (xy 396.846798 -317.82312) (xy 396.831214 -317.869801)
			(xy 396.808343 -317.913378) (xy 396.778778 -317.952722) (xy 396.743285 -317.986814) (xy 396.702782 -318.01477)
			(xy 396.65832 -318.035868) (xy 396.611049 -318.04956) (xy 396.562194 -318.055492) (xy 396.513019 -318.053511)
			(xy 396.4648 -318.043667) (xy 396.418784 -318.026215) (xy 396.376163 -318.001608) (xy 396.338042 -317.970483)
			(xy 396.305407 -317.933646) (xy 396.279104 -317.89205) (xy 396.259813 -317.846774) (xy 396.248036 -317.79899)
			(xy 396.244076 -317.749936) (xy 394.955268 -317.749936) (xy 394.954773 -317.774543) (xy 394.946878 -317.82312)
			(xy 394.931294 -317.869801) (xy 394.908423 -317.913378) (xy 394.878858 -317.952722) (xy 394.843365 -317.986814)
			(xy 394.802862 -318.01477) (xy 394.7584 -318.035868) (xy 394.711129 -318.04956) (xy 394.662274 -318.055492)
			(xy 394.613099 -318.053511) (xy 394.56488 -318.043667) (xy 394.518864 -318.026215) (xy 394.476243 -318.001608)
			(xy 394.438122 -317.970483) (xy 394.405487 -317.933646) (xy 394.379184 -317.89205) (xy 394.359893 -317.846774)
			(xy 394.348116 -317.79899) (xy 394.344156 -317.749936) (xy 393.055094 -317.749936) (xy 393.054599 -317.774543)
			(xy 393.046704 -317.82312) (xy 393.03112 -317.869801) (xy 393.008249 -317.913378) (xy 392.978684 -317.952722)
			(xy 392.943191 -317.986814) (xy 392.902688 -318.01477) (xy 392.858226 -318.035868) (xy 392.810955 -318.04956)
			(xy 392.7621 -318.055492) (xy 392.712925 -318.053511) (xy 392.664706 -318.043667) (xy 392.61869 -318.026215)
			(xy 392.576069 -318.001608) (xy 392.537948 -317.970483) (xy 392.505313 -317.933646) (xy 392.47901 -317.89205)
			(xy 392.459719 -317.846774) (xy 392.447942 -317.79899) (xy 392.443982 -317.749936) (xy 392.130534 -317.749936)
			(xy 392.130066 -317.775445) (xy 392.122236 -317.825859) (xy 392.106754 -317.874471) (xy 392.083985 -317.920127)
			(xy 392.054472 -317.961742) (xy 392.018915 -317.998329) (xy 391.978158 -318.029017) (xy 391.933171 -318.053078)
			(xy 391.88502 -318.069941) (xy 391.860024 -318.075056) (xy 391.849191 -318.07759) (xy 391.831054 -318.09043)
			(xy 391.820066 -318.109745) (xy 391.818622 -318.120776) (xy 391.81648 -318.144652) (xy 391.810125 -318.192172)
			(xy 391.805922 -318.215772) (xy 391.805193 -318.220315) (xy 391.805196 -318.229516) (xy 391.805922 -318.23406)
			(xy 391.810114 -318.257662) (xy 391.816466 -318.305182) (xy 391.818622 -318.329056) (xy 391.820135 -318.340059)
			(xy 391.831152 -318.359318) (xy 391.849223 -318.372189) (xy 391.860024 -318.374776) (xy 391.885019 -318.379885)
			(xy 391.93316 -318.396765) (xy 391.978139 -318.420838) (xy 392.018887 -318.451531) (xy 392.05444 -318.488117)
			(xy 392.083954 -318.529727) (xy 392.106729 -318.575376) (xy 392.122224 -318.623981) (xy 392.130073 -318.674389)
			(xy 392.130534 -318.699896) (xy 392.443982 -318.699896) (xy 392.447942 -318.650842) (xy 392.459719 -318.603058)
			(xy 392.47901 -318.557782) (xy 392.505313 -318.516186) (xy 392.537948 -318.479349) (xy 392.576069 -318.448224)
			(xy 392.61869 -318.423617) (xy 392.664706 -318.406165) (xy 392.712925 -318.396321) (xy 392.7621 -318.39434)
			(xy 392.810955 -318.400272) (xy 392.858226 -318.413964) (xy 392.902688 -318.435062) (xy 392.943191 -318.463018)
			(xy 392.978684 -318.49711) (xy 393.008249 -318.536454) (xy 393.03112 -318.580031) (xy 393.046704 -318.626712)
			(xy 393.054599 -318.675289) (xy 393.055094 -318.699896) (xy 394.344156 -318.699896) (xy 394.348116 -318.650842)
			(xy 394.359893 -318.603058) (xy 394.379184 -318.557782) (xy 394.405487 -318.516186) (xy 394.438122 -318.479349)
			(xy 394.476243 -318.448224) (xy 394.518864 -318.423617) (xy 394.56488 -318.406165) (xy 394.613099 -318.396321)
			(xy 394.662274 -318.39434) (xy 394.711129 -318.400272) (xy 394.7584 -318.413964) (xy 394.802862 -318.435062)
			(xy 394.843365 -318.463018) (xy 394.878858 -318.49711) (xy 394.908423 -318.536454) (xy 394.931294 -318.580031)
			(xy 394.946878 -318.626712) (xy 394.954773 -318.675289) (xy 394.955268 -318.699896) (xy 396.244076 -318.699896)
			(xy 396.248036 -318.650842) (xy 396.259813 -318.603058) (xy 396.279104 -318.557782) (xy 396.305407 -318.516186)
			(xy 396.338042 -318.479349) (xy 396.376163 -318.448224) (xy 396.418784 -318.423617) (xy 396.4648 -318.406165)
			(xy 396.513019 -318.396321) (xy 396.562194 -318.39434) (xy 396.611049 -318.400272) (xy 396.65832 -318.413964)
			(xy 396.702782 -318.435062) (xy 396.743285 -318.463018) (xy 396.778778 -318.49711) (xy 396.808343 -318.536454)
			(xy 396.831214 -318.580031) (xy 396.846798 -318.626712) (xy 396.854693 -318.675289) (xy 396.855188 -318.699896)
			(xy 398.143996 -318.699896) (xy 398.147956 -318.650842) (xy 398.159733 -318.603058) (xy 398.179024 -318.557782)
			(xy 398.205327 -318.516186) (xy 398.237962 -318.479349) (xy 398.276083 -318.448224) (xy 398.318704 -318.423617)
			(xy 398.36472 -318.406165) (xy 398.412939 -318.396321) (xy 398.462114 -318.39434) (xy 398.510969 -318.400272)
			(xy 398.55824 -318.413964) (xy 398.602702 -318.435062) (xy 398.643205 -318.463018) (xy 398.678698 -318.49711)
			(xy 398.708263 -318.536454) (xy 398.731134 -318.580031) (xy 398.746718 -318.626712) (xy 398.754613 -318.675289)
			(xy 398.755108 -318.699896) (xy 398.754613 -318.724503) (xy 398.754434 -318.725604) (xy 400.023326 -318.725604)
			(xy 400.023326 -318.674188) (xy 400.031369 -318.623406) (xy 400.047257 -318.574507) (xy 400.0706 -318.528695)
			(xy 400.100821 -318.487099) (xy 400.137177 -318.450743) (xy 400.178773 -318.420522) (xy 400.224585 -318.397179)
			(xy 400.273484 -318.381291) (xy 400.324266 -318.373248) (xy 400.375682 -318.373248) (xy 400.426464 -318.381291)
			(xy 400.475363 -318.397179) (xy 400.521175 -318.420522) (xy 400.562771 -318.450743) (xy 400.599127 -318.487099)
			(xy 400.629348 -318.528695) (xy 400.652691 -318.574507) (xy 400.668579 -318.623406) (xy 400.676622 -318.674188)
			(xy 400.677126 -318.699896) (xy 400.676622 -318.725604) (xy 401.923246 -318.725604) (xy 401.923246 -318.674188)
			(xy 401.931289 -318.623406) (xy 401.947177 -318.574507) (xy 401.97052 -318.528695) (xy 402.000741 -318.487099)
			(xy 402.037097 -318.450743) (xy 402.078693 -318.420522) (xy 402.124505 -318.397179) (xy 402.173404 -318.381291)
			(xy 402.224186 -318.373248) (xy 402.275602 -318.373248) (xy 402.326384 -318.381291) (xy 402.375283 -318.397179)
			(xy 402.421095 -318.420522) (xy 402.462691 -318.450743) (xy 402.499047 -318.487099) (xy 402.529268 -318.528695)
			(xy 402.552611 -318.574507) (xy 402.568499 -318.623406) (xy 402.576542 -318.674188) (xy 402.577046 -318.699896)
			(xy 402.576542 -318.725604) (xy 403.823166 -318.725604) (xy 403.823166 -318.674188) (xy 403.831209 -318.623406)
			(xy 403.847097 -318.574507) (xy 403.87044 -318.528695) (xy 403.900661 -318.487099) (xy 403.937017 -318.450743)
			(xy 403.978613 -318.420522) (xy 404.024425 -318.397179) (xy 404.073324 -318.381291) (xy 404.124106 -318.373248)
			(xy 404.175522 -318.373248) (xy 404.226304 -318.381291) (xy 404.275203 -318.397179) (xy 404.321015 -318.420522)
			(xy 404.362611 -318.450743) (xy 404.398967 -318.487099) (xy 404.429188 -318.528695) (xy 404.452531 -318.574507)
			(xy 404.468419 -318.623406) (xy 404.476462 -318.674188) (xy 404.476966 -318.699896) (xy 404.476462 -318.725604)
			(xy 405.72334 -318.725604) (xy 405.72334 -318.674188) (xy 405.731383 -318.623406) (xy 405.747271 -318.574507)
			(xy 405.770614 -318.528695) (xy 405.800835 -318.487099) (xy 405.837191 -318.450743) (xy 405.878787 -318.420522)
			(xy 405.924599 -318.397179) (xy 405.973498 -318.381291) (xy 406.02428 -318.373248) (xy 406.075696 -318.373248)
			(xy 406.126478 -318.381291) (xy 406.175377 -318.397179) (xy 406.221189 -318.420522) (xy 406.262785 -318.450743)
			(xy 406.299141 -318.487099) (xy 406.329362 -318.528695) (xy 406.352705 -318.574507) (xy 406.368593 -318.623406)
			(xy 406.376636 -318.674188) (xy 406.37714 -318.699896) (xy 406.376636 -318.725604) (xy 407.62326 -318.725604)
			(xy 407.62326 -318.674188) (xy 407.631303 -318.623406) (xy 407.647191 -318.574507) (xy 407.670534 -318.528695)
			(xy 407.700755 -318.487099) (xy 407.737111 -318.450743) (xy 407.778707 -318.420522) (xy 407.824519 -318.397179)
			(xy 407.873418 -318.381291) (xy 407.9242 -318.373248) (xy 407.975616 -318.373248) (xy 408.026398 -318.381291)
			(xy 408.075297 -318.397179) (xy 408.121109 -318.420522) (xy 408.162705 -318.450743) (xy 408.199061 -318.487099)
			(xy 408.229282 -318.528695) (xy 408.252625 -318.574507) (xy 408.268513 -318.623406) (xy 408.276556 -318.674188)
			(xy 408.27706 -318.699896) (xy 408.276556 -318.725604) (xy 409.52318 -318.725604) (xy 409.52318 -318.674188)
			(xy 409.531223 -318.623406) (xy 409.547111 -318.574507) (xy 409.570454 -318.528695) (xy 409.600675 -318.487099)
			(xy 409.637031 -318.450743) (xy 409.678627 -318.420522) (xy 409.724439 -318.397179) (xy 409.773338 -318.381291)
			(xy 409.82412 -318.373248) (xy 409.875536 -318.373248) (xy 409.926318 -318.381291) (xy 409.975217 -318.397179)
			(xy 410.021029 -318.420522) (xy 410.062625 -318.450743) (xy 410.098981 -318.487099) (xy 410.129202 -318.528695)
			(xy 410.152545 -318.574507) (xy 410.168433 -318.623406) (xy 410.176476 -318.674188) (xy 410.17698 -318.699896)
			(xy 410.176476 -318.725604) (xy 411.423354 -318.725604) (xy 411.423354 -318.674188) (xy 411.431397 -318.623406)
			(xy 411.447285 -318.574507) (xy 411.470628 -318.528695) (xy 411.500849 -318.487099) (xy 411.537205 -318.450743)
			(xy 411.578801 -318.420522) (xy 411.624613 -318.397179) (xy 411.673512 -318.381291) (xy 411.724294 -318.373248)
			(xy 411.77571 -318.373248) (xy 411.826492 -318.381291) (xy 411.875391 -318.397179) (xy 411.921203 -318.420522)
			(xy 411.962799 -318.450743) (xy 411.999155 -318.487099) (xy 412.029376 -318.528695) (xy 412.052719 -318.574507)
			(xy 412.068607 -318.623406) (xy 412.07665 -318.674188) (xy 412.077154 -318.699896) (xy 412.07665 -318.725604)
			(xy 413.323274 -318.725604) (xy 413.323274 -318.674188) (xy 413.331317 -318.623406) (xy 413.347205 -318.574507)
			(xy 413.370548 -318.528695) (xy 413.400769 -318.487099) (xy 413.437125 -318.450743) (xy 413.478721 -318.420522)
			(xy 413.524533 -318.397179) (xy 413.573432 -318.381291) (xy 413.624214 -318.373248) (xy 413.67563 -318.373248)
			(xy 413.726412 -318.381291) (xy 413.775311 -318.397179) (xy 413.821123 -318.420522) (xy 413.862719 -318.450743)
			(xy 413.899075 -318.487099) (xy 413.929296 -318.528695) (xy 413.952639 -318.574507) (xy 413.968527 -318.623406)
			(xy 413.97657 -318.674188) (xy 413.977074 -318.699896) (xy 415.244038 -318.699896) (xy 415.247998 -318.650842)
			(xy 415.259775 -318.603058) (xy 415.279066 -318.557782) (xy 415.305369 -318.516186) (xy 415.338004 -318.479349)
			(xy 415.376125 -318.448224) (xy 415.418746 -318.423617) (xy 415.464762 -318.406165) (xy 415.512981 -318.396321)
			(xy 415.562156 -318.39434) (xy 415.611011 -318.400272) (xy 415.658282 -318.413964) (xy 415.702744 -318.435062)
			(xy 415.743247 -318.463018) (xy 415.77874 -318.49711) (xy 415.808305 -318.536454) (xy 415.831176 -318.580031)
			(xy 415.84676 -318.626712) (xy 415.854655 -318.675289) (xy 415.85515 -318.699896) (xy 417.144212 -318.699896)
			(xy 417.148172 -318.650842) (xy 417.159949 -318.603058) (xy 417.17924 -318.557782) (xy 417.205543 -318.516186)
			(xy 417.238178 -318.479349) (xy 417.276299 -318.448224) (xy 417.31892 -318.423617) (xy 417.364936 -318.406165)
			(xy 417.413155 -318.396321) (xy 417.46233 -318.39434) (xy 417.511185 -318.400272) (xy 417.558456 -318.413964)
			(xy 417.602918 -318.435062) (xy 417.643421 -318.463018) (xy 417.678914 -318.49711) (xy 417.708479 -318.536454)
			(xy 417.73135 -318.580031) (xy 417.746934 -318.626712) (xy 417.754829 -318.675289) (xy 417.755324 -318.699896)
			(xy 419.044132 -318.699896) (xy 419.048092 -318.650842) (xy 419.059869 -318.603058) (xy 419.07916 -318.557782)
			(xy 419.105463 -318.516186) (xy 419.138098 -318.479349) (xy 419.176219 -318.448224) (xy 419.21884 -318.423617)
			(xy 419.264856 -318.406165) (xy 419.313075 -318.396321) (xy 419.36225 -318.39434) (xy 419.411105 -318.400272)
			(xy 419.458376 -318.413964) (xy 419.502838 -318.435062) (xy 419.543341 -318.463018) (xy 419.578834 -318.49711)
			(xy 419.608399 -318.536454) (xy 419.63127 -318.580031) (xy 419.646854 -318.626712) (xy 419.654749 -318.675289)
			(xy 419.655244 -318.699896) (xy 420.944052 -318.699896) (xy 420.948012 -318.650842) (xy 420.959789 -318.603058)
			(xy 420.97908 -318.557782) (xy 421.005383 -318.516186) (xy 421.038018 -318.479349) (xy 421.076139 -318.448224)
			(xy 421.11876 -318.423617) (xy 421.164776 -318.406165) (xy 421.212995 -318.396321) (xy 421.26217 -318.39434)
			(xy 421.311025 -318.400272) (xy 421.358296 -318.413964) (xy 421.402758 -318.435062) (xy 421.443261 -318.463018)
			(xy 421.478754 -318.49711) (xy 421.508319 -318.536454) (xy 421.53119 -318.580031) (xy 421.546774 -318.626712)
			(xy 421.554669 -318.675289) (xy 421.555164 -318.699896) (xy 421.554669 -318.724503) (xy 421.55449 -318.725604)
			(xy 422.823382 -318.725604) (xy 422.823382 -318.674188) (xy 422.831425 -318.623406) (xy 422.847313 -318.574507)
			(xy 422.870656 -318.528695) (xy 422.900877 -318.487099) (xy 422.937233 -318.450743) (xy 422.978829 -318.420522)
			(xy 423.024641 -318.397179) (xy 423.07354 -318.381291) (xy 423.124322 -318.373248) (xy 423.175738 -318.373248)
			(xy 423.22652 -318.381291) (xy 423.275419 -318.397179) (xy 423.321231 -318.420522) (xy 423.362827 -318.450743)
			(xy 423.399183 -318.487099) (xy 423.429404 -318.528695) (xy 423.452747 -318.574507) (xy 423.468635 -318.623406)
			(xy 423.476678 -318.674188) (xy 423.477182 -318.699896) (xy 423.476678 -318.725604) (xy 424.723302 -318.725604)
			(xy 424.723302 -318.674188) (xy 424.731345 -318.623406) (xy 424.747233 -318.574507) (xy 424.770576 -318.528695)
			(xy 424.800797 -318.487099) (xy 424.837153 -318.450743) (xy 424.878749 -318.420522) (xy 424.924561 -318.397179)
			(xy 424.97346 -318.381291) (xy 425.024242 -318.373248) (xy 425.075658 -318.373248) (xy 425.12644 -318.381291)
			(xy 425.175339 -318.397179) (xy 425.221151 -318.420522) (xy 425.262747 -318.450743) (xy 425.299103 -318.487099)
			(xy 425.329324 -318.528695) (xy 425.352667 -318.574507) (xy 425.368555 -318.623406) (xy 425.376598 -318.674188)
			(xy 425.377102 -318.699896) (xy 425.376598 -318.725604) (xy 426.623222 -318.725604) (xy 426.623222 -318.674188)
			(xy 426.631265 -318.623406) (xy 426.647153 -318.574507) (xy 426.670496 -318.528695) (xy 426.700717 -318.487099)
			(xy 426.737073 -318.450743) (xy 426.778669 -318.420522) (xy 426.824481 -318.397179) (xy 426.87338 -318.381291)
			(xy 426.924162 -318.373248) (xy 426.975578 -318.373248) (xy 427.02636 -318.381291) (xy 427.075259 -318.397179)
			(xy 427.121071 -318.420522) (xy 427.162667 -318.450743) (xy 427.199023 -318.487099) (xy 427.229244 -318.528695)
			(xy 427.252587 -318.574507) (xy 427.268475 -318.623406) (xy 427.276518 -318.674188) (xy 427.277022 -318.699896)
			(xy 427.276518 -318.725604) (xy 428.523142 -318.725604) (xy 428.523142 -318.674188) (xy 428.531185 -318.623406)
			(xy 428.547073 -318.574507) (xy 428.570416 -318.528695) (xy 428.600637 -318.487099) (xy 428.636993 -318.450743)
			(xy 428.678589 -318.420522) (xy 428.724401 -318.397179) (xy 428.7733 -318.381291) (xy 428.824082 -318.373248)
			(xy 428.875498 -318.373248) (xy 428.92628 -318.381291) (xy 428.975179 -318.397179) (xy 429.020991 -318.420522)
			(xy 429.062587 -318.450743) (xy 429.098943 -318.487099) (xy 429.129164 -318.528695) (xy 429.152507 -318.574507)
			(xy 429.168395 -318.623406) (xy 429.176438 -318.674188) (xy 429.176942 -318.699896) (xy 429.176438 -318.725604)
			(xy 429.168395 -318.776386) (xy 429.152507 -318.825285) (xy 429.129164 -318.871097) (xy 429.098943 -318.912693)
			(xy 429.062587 -318.949049) (xy 429.020991 -318.97927) (xy 428.975179 -319.002613) (xy 428.92628 -319.018501)
			(xy 428.875498 -319.026544) (xy 428.824082 -319.026544) (xy 428.7733 -319.018501) (xy 428.724401 -319.002613)
			(xy 428.678589 -318.97927) (xy 428.636993 -318.949049) (xy 428.600637 -318.912693) (xy 428.570416 -318.871097)
			(xy 428.547073 -318.825285) (xy 428.531185 -318.776386) (xy 428.523142 -318.725604) (xy 427.276518 -318.725604)
			(xy 427.268475 -318.776386) (xy 427.252587 -318.825285) (xy 427.229244 -318.871097) (xy 427.199023 -318.912693)
			(xy 427.162667 -318.949049) (xy 427.121071 -318.97927) (xy 427.075259 -319.002613) (xy 427.02636 -319.018501)
			(xy 426.975578 -319.026544) (xy 426.924162 -319.026544) (xy 426.87338 -319.018501) (xy 426.824481 -319.002613)
			(xy 426.778669 -318.97927) (xy 426.737073 -318.949049) (xy 426.700717 -318.912693) (xy 426.670496 -318.871097)
			(xy 426.647153 -318.825285) (xy 426.631265 -318.776386) (xy 426.623222 -318.725604) (xy 425.376598 -318.725604)
			(xy 425.368555 -318.776386) (xy 425.352667 -318.825285) (xy 425.329324 -318.871097) (xy 425.299103 -318.912693)
			(xy 425.262747 -318.949049) (xy 425.221151 -318.97927) (xy 425.175339 -319.002613) (xy 425.12644 -319.018501)
			(xy 425.075658 -319.026544) (xy 425.024242 -319.026544) (xy 424.97346 -319.018501) (xy 424.924561 -319.002613)
			(xy 424.878749 -318.97927) (xy 424.837153 -318.949049) (xy 424.800797 -318.912693) (xy 424.770576 -318.871097)
			(xy 424.747233 -318.825285) (xy 424.731345 -318.776386) (xy 424.723302 -318.725604) (xy 423.476678 -318.725604)
			(xy 423.468635 -318.776386) (xy 423.452747 -318.825285) (xy 423.429404 -318.871097) (xy 423.399183 -318.912693)
			(xy 423.362827 -318.949049) (xy 423.321231 -318.97927) (xy 423.275419 -319.002613) (xy 423.22652 -319.018501)
			(xy 423.175738 -319.026544) (xy 423.124322 -319.026544) (xy 423.07354 -319.018501) (xy 423.024641 -319.002613)
			(xy 422.978829 -318.97927) (xy 422.937233 -318.949049) (xy 422.900877 -318.912693) (xy 422.870656 -318.871097)
			(xy 422.847313 -318.825285) (xy 422.831425 -318.776386) (xy 422.823382 -318.725604) (xy 421.55449 -318.725604)
			(xy 421.546774 -318.77308) (xy 421.53119 -318.819761) (xy 421.508319 -318.863338) (xy 421.478754 -318.902682)
			(xy 421.443261 -318.936774) (xy 421.402758 -318.96473) (xy 421.358296 -318.985828) (xy 421.311025 -318.99952)
			(xy 421.26217 -319.005452) (xy 421.212995 -319.003471) (xy 421.164776 -318.993627) (xy 421.11876 -318.976175)
			(xy 421.076139 -318.951568) (xy 421.038018 -318.920443) (xy 421.005383 -318.883606) (xy 420.97908 -318.84201)
			(xy 420.959789 -318.796734) (xy 420.948012 -318.74895) (xy 420.944052 -318.699896) (xy 419.655244 -318.699896)
			(xy 419.654749 -318.724503) (xy 419.646854 -318.77308) (xy 419.63127 -318.819761) (xy 419.608399 -318.863338)
			(xy 419.578834 -318.902682) (xy 419.543341 -318.936774) (xy 419.502838 -318.96473) (xy 419.458376 -318.985828)
			(xy 419.411105 -318.99952) (xy 419.36225 -319.005452) (xy 419.313075 -319.003471) (xy 419.264856 -318.993627)
			(xy 419.21884 -318.976175) (xy 419.176219 -318.951568) (xy 419.138098 -318.920443) (xy 419.105463 -318.883606)
			(xy 419.07916 -318.84201) (xy 419.059869 -318.796734) (xy 419.048092 -318.74895) (xy 419.044132 -318.699896)
			(xy 417.755324 -318.699896) (xy 417.754829 -318.724503) (xy 417.746934 -318.77308) (xy 417.73135 -318.819761)
			(xy 417.708479 -318.863338) (xy 417.678914 -318.902682) (xy 417.643421 -318.936774) (xy 417.602918 -318.96473)
			(xy 417.558456 -318.985828) (xy 417.511185 -318.99952) (xy 417.46233 -319.005452) (xy 417.413155 -319.003471)
			(xy 417.364936 -318.993627) (xy 417.31892 -318.976175) (xy 417.276299 -318.951568) (xy 417.238178 -318.920443)
			(xy 417.205543 -318.883606) (xy 417.17924 -318.84201) (xy 417.159949 -318.796734) (xy 417.148172 -318.74895)
			(xy 417.144212 -318.699896) (xy 415.85515 -318.699896) (xy 415.854655 -318.724503) (xy 415.84676 -318.77308)
			(xy 415.831176 -318.819761) (xy 415.808305 -318.863338) (xy 415.77874 -318.902682) (xy 415.743247 -318.936774)
			(xy 415.702744 -318.96473) (xy 415.658282 -318.985828) (xy 415.611011 -318.99952) (xy 415.562156 -319.005452)
			(xy 415.512981 -319.003471) (xy 415.464762 -318.993627) (xy 415.418746 -318.976175) (xy 415.376125 -318.951568)
			(xy 415.338004 -318.920443) (xy 415.305369 -318.883606) (xy 415.279066 -318.84201) (xy 415.259775 -318.796734)
			(xy 415.247998 -318.74895) (xy 415.244038 -318.699896) (xy 413.977074 -318.699896) (xy 413.97657 -318.725604)
			(xy 413.968527 -318.776386) (xy 413.952639 -318.825285) (xy 413.929296 -318.871097) (xy 413.899075 -318.912693)
			(xy 413.862719 -318.949049) (xy 413.821123 -318.97927) (xy 413.775311 -319.002613) (xy 413.726412 -319.018501)
			(xy 413.67563 -319.026544) (xy 413.624214 -319.026544) (xy 413.573432 -319.018501) (xy 413.524533 -319.002613)
			(xy 413.478721 -318.97927) (xy 413.437125 -318.949049) (xy 413.400769 -318.912693) (xy 413.370548 -318.871097)
			(xy 413.347205 -318.825285) (xy 413.331317 -318.776386) (xy 413.323274 -318.725604) (xy 412.07665 -318.725604)
			(xy 412.068607 -318.776386) (xy 412.052719 -318.825285) (xy 412.029376 -318.871097) (xy 411.999155 -318.912693)
			(xy 411.962799 -318.949049) (xy 411.921203 -318.97927) (xy 411.875391 -319.002613) (xy 411.826492 -319.018501)
			(xy 411.77571 -319.026544) (xy 411.724294 -319.026544) (xy 411.673512 -319.018501) (xy 411.624613 -319.002613)
			(xy 411.578801 -318.97927) (xy 411.537205 -318.949049) (xy 411.500849 -318.912693) (xy 411.470628 -318.871097)
			(xy 411.447285 -318.825285) (xy 411.431397 -318.776386) (xy 411.423354 -318.725604) (xy 410.176476 -318.725604)
			(xy 410.168433 -318.776386) (xy 410.152545 -318.825285) (xy 410.129202 -318.871097) (xy 410.098981 -318.912693)
			(xy 410.062625 -318.949049) (xy 410.021029 -318.97927) (xy 409.975217 -319.002613) (xy 409.926318 -319.018501)
			(xy 409.875536 -319.026544) (xy 409.82412 -319.026544) (xy 409.773338 -319.018501) (xy 409.724439 -319.002613)
			(xy 409.678627 -318.97927) (xy 409.637031 -318.949049) (xy 409.600675 -318.912693) (xy 409.570454 -318.871097)
			(xy 409.547111 -318.825285) (xy 409.531223 -318.776386) (xy 409.52318 -318.725604) (xy 408.276556 -318.725604)
			(xy 408.268513 -318.776386) (xy 408.252625 -318.825285) (xy 408.229282 -318.871097) (xy 408.199061 -318.912693)
			(xy 408.162705 -318.949049) (xy 408.121109 -318.97927) (xy 408.075297 -319.002613) (xy 408.026398 -319.018501)
			(xy 407.975616 -319.026544) (xy 407.9242 -319.026544) (xy 407.873418 -319.018501) (xy 407.824519 -319.002613)
			(xy 407.778707 -318.97927) (xy 407.737111 -318.949049) (xy 407.700755 -318.912693) (xy 407.670534 -318.871097)
			(xy 407.647191 -318.825285) (xy 407.631303 -318.776386) (xy 407.62326 -318.725604) (xy 406.376636 -318.725604)
			(xy 406.368593 -318.776386) (xy 406.352705 -318.825285) (xy 406.329362 -318.871097) (xy 406.299141 -318.912693)
			(xy 406.262785 -318.949049) (xy 406.221189 -318.97927) (xy 406.175377 -319.002613) (xy 406.126478 -319.018501)
			(xy 406.075696 -319.026544) (xy 406.02428 -319.026544) (xy 405.973498 -319.018501) (xy 405.924599 -319.002613)
			(xy 405.878787 -318.97927) (xy 405.837191 -318.949049) (xy 405.800835 -318.912693) (xy 405.770614 -318.871097)
			(xy 405.747271 -318.825285) (xy 405.731383 -318.776386) (xy 405.72334 -318.725604) (xy 404.476462 -318.725604)
			(xy 404.468419 -318.776386) (xy 404.452531 -318.825285) (xy 404.429188 -318.871097) (xy 404.398967 -318.912693)
			(xy 404.362611 -318.949049) (xy 404.321015 -318.97927) (xy 404.275203 -319.002613) (xy 404.226304 -319.018501)
			(xy 404.175522 -319.026544) (xy 404.124106 -319.026544) (xy 404.073324 -319.018501) (xy 404.024425 -319.002613)
			(xy 403.978613 -318.97927) (xy 403.937017 -318.949049) (xy 403.900661 -318.912693) (xy 403.87044 -318.871097)
			(xy 403.847097 -318.825285) (xy 403.831209 -318.776386) (xy 403.823166 -318.725604) (xy 402.576542 -318.725604)
			(xy 402.568499 -318.776386) (xy 402.552611 -318.825285) (xy 402.529268 -318.871097) (xy 402.499047 -318.912693)
			(xy 402.462691 -318.949049) (xy 402.421095 -318.97927) (xy 402.375283 -319.002613) (xy 402.326384 -319.018501)
			(xy 402.275602 -319.026544) (xy 402.224186 -319.026544) (xy 402.173404 -319.018501) (xy 402.124505 -319.002613)
			(xy 402.078693 -318.97927) (xy 402.037097 -318.949049) (xy 402.000741 -318.912693) (xy 401.97052 -318.871097)
			(xy 401.947177 -318.825285) (xy 401.931289 -318.776386) (xy 401.923246 -318.725604) (xy 400.676622 -318.725604)
			(xy 400.668579 -318.776386) (xy 400.652691 -318.825285) (xy 400.629348 -318.871097) (xy 400.599127 -318.912693)
			(xy 400.562771 -318.949049) (xy 400.521175 -318.97927) (xy 400.475363 -319.002613) (xy 400.426464 -319.018501)
			(xy 400.375682 -319.026544) (xy 400.324266 -319.026544) (xy 400.273484 -319.018501) (xy 400.224585 -319.002613)
			(xy 400.178773 -318.97927) (xy 400.137177 -318.949049) (xy 400.100821 -318.912693) (xy 400.0706 -318.871097)
			(xy 400.047257 -318.825285) (xy 400.031369 -318.776386) (xy 400.023326 -318.725604) (xy 398.754434 -318.725604)
			(xy 398.746718 -318.77308) (xy 398.731134 -318.819761) (xy 398.708263 -318.863338) (xy 398.678698 -318.902682)
			(xy 398.643205 -318.936774) (xy 398.602702 -318.96473) (xy 398.55824 -318.985828) (xy 398.510969 -318.99952)
			(xy 398.462114 -319.005452) (xy 398.412939 -319.003471) (xy 398.36472 -318.993627) (xy 398.318704 -318.976175)
			(xy 398.276083 -318.951568) (xy 398.237962 -318.920443) (xy 398.205327 -318.883606) (xy 398.179024 -318.84201)
			(xy 398.159733 -318.796734) (xy 398.147956 -318.74895) (xy 398.143996 -318.699896) (xy 396.855188 -318.699896)
			(xy 396.854693 -318.724503) (xy 396.846798 -318.77308) (xy 396.831214 -318.819761) (xy 396.808343 -318.863338)
			(xy 396.778778 -318.902682) (xy 396.743285 -318.936774) (xy 396.702782 -318.96473) (xy 396.65832 -318.985828)
			(xy 396.611049 -318.99952) (xy 396.562194 -319.005452) (xy 396.513019 -319.003471) (xy 396.4648 -318.993627)
			(xy 396.418784 -318.976175) (xy 396.376163 -318.951568) (xy 396.338042 -318.920443) (xy 396.305407 -318.883606)
			(xy 396.279104 -318.84201) (xy 396.259813 -318.796734) (xy 396.248036 -318.74895) (xy 396.244076 -318.699896)
			(xy 394.955268 -318.699896) (xy 394.954773 -318.724503) (xy 394.946878 -318.77308) (xy 394.931294 -318.819761)
			(xy 394.908423 -318.863338) (xy 394.878858 -318.902682) (xy 394.843365 -318.936774) (xy 394.802862 -318.96473)
			(xy 394.7584 -318.985828) (xy 394.711129 -318.99952) (xy 394.662274 -319.005452) (xy 394.613099 -319.003471)
			(xy 394.56488 -318.993627) (xy 394.518864 -318.976175) (xy 394.476243 -318.951568) (xy 394.438122 -318.920443)
			(xy 394.405487 -318.883606) (xy 394.379184 -318.84201) (xy 394.359893 -318.796734) (xy 394.348116 -318.74895)
			(xy 394.344156 -318.699896) (xy 393.055094 -318.699896) (xy 393.054599 -318.724503) (xy 393.046704 -318.77308)
			(xy 393.03112 -318.819761) (xy 393.008249 -318.863338) (xy 392.978684 -318.902682) (xy 392.943191 -318.936774)
			(xy 392.902688 -318.96473) (xy 392.858226 -318.985828) (xy 392.810955 -318.99952) (xy 392.7621 -319.005452)
			(xy 392.712925 -319.003471) (xy 392.664706 -318.993627) (xy 392.61869 -318.976175) (xy 392.576069 -318.951568)
			(xy 392.537948 -318.920443) (xy 392.505313 -318.883606) (xy 392.47901 -318.84201) (xy 392.459719 -318.796734)
			(xy 392.447942 -318.74895) (xy 392.443982 -318.699896) (xy 392.130534 -318.699896) (xy 392.130025 -318.725884)
			(xy 392.121895 -318.777221) (xy 392.105835 -318.826653) (xy 392.082239 -318.872965) (xy 392.05169 -318.915016)
			(xy 392.014939 -318.951771) (xy 391.972891 -318.982324) (xy 391.926581 -319.005923) (xy 391.87715 -319.021988)
			(xy 391.825814 -319.030122) (xy 391.799826 -319.030604) (xy 391.79881 -319.030604) (xy 391.788727 -319.031023)
			(xy 391.770118 -319.038789) (xy 391.755967 -319.053154) (xy 391.75182 -319.062354) (xy 391.730932 -319.112302)
			(xy 391.679627 -319.207645) (xy 391.649458 -319.2526) (xy 391.647232 -319.256023) (xy 391.643784 -319.263424)
			(xy 391.6426 -319.267332) (xy 391.633636 -319.295773) (xy 391.606936 -319.349088) (xy 391.571104 -319.396749)
			(xy 391.549636 -319.417446) (xy 391.535175 -319.430468) (xy 391.503727 -319.453395) (xy 391.486898 -319.463166)
			(xy 391.479496 -319.467746) (xy 391.46807 -319.480861) (xy 391.464546 -319.48882) (xy 391.453624 -319.517014)
			(xy 391.450636 -319.525702) (xy 391.450375 -319.544059) (xy 391.453116 -319.552828) (xy 391.466646 -319.591239)
			(xy 391.488125 -319.669801) (xy 391.503118 -319.749855) (xy 391.507726 -319.790318) (xy 391.50925 -319.805304)
			(xy 391.528554 -319.828672) (xy 393.452096 -320.437764) (xy 393.462764 -320.436494) (xy 393.491179 -320.433484)
			(xy 393.548237 -320.43031) (xy 393.57681 -320.430144) (xy 393.62778 -320.430788) (xy 393.729188 -320.441189)
			(xy 393.829008 -320.461871) (xy 393.8778 -320.476626) (xy 394.35024 -320.626232) (xy 394.390126 -320.639303)
			(xy 394.46775 -320.671251) (xy 394.542416 -320.709606) (xy 394.613597 -320.754097) (xy 394.68079 -320.804408)
			(xy 394.712444 -320.831972) (xy 394.716508 -320.835528) (xy 394.725906 -320.841116) (xy 407.32329 -324.828916)
			(xy 407.355096 -324.839266) (xy 407.41738 -324.863668) (xy 407.44775 -324.877684) (xy 410.489146 -326.311768)
			(xy 410.492194 -326.313292) (xy 410.703014 -326.395334) (xy 410.710126 -326.398128) (xy 410.71038 -326.398128)
			(xy 410.716222 -326.400668) (xy 410.717746 -326.401176) (xy 410.722318 -326.402954) (xy 410.723334 -326.403462)
			(xy 410.732224 -326.407018) (xy 410.732732 -326.407526) (xy 410.74848 -326.414384) (xy 410.748988 -326.414892)
			(xy 425.237402 -332.915514) (xy 425.240704 -332.916784) (xy 437.690514 -337.483196) (xy 437.694754 -337.484626)
			(xy 437.703567 -337.486166) (xy 437.70804 -337.486244) (xy 442.765434 -337.486244) (xy 442.7755 -337.486675)
			(xy 442.794092 -337.494403) (xy 442.801502 -337.50123) (xy 447.421 -342.120728) (xy 447.427842 -342.128128)
			(xy 447.435566 -342.146726) (xy 447.435986 -342.156796) (xy 447.435986 -357.311452) (xy 447.435553 -357.321518)
			(xy 447.427824 -357.340107) (xy 447.421 -357.34752) (xy 441.962794 -362.805726) (xy 449.753734 -362.805726)
			(xy 449.757805 -362.750104) (xy 449.769931 -362.695667) (xy 449.789854 -362.643576) (xy 449.81715 -362.594941)
			(xy 449.851236 -362.550798) (xy 449.891385 -362.512089) (xy 449.936743 -362.479638) (xy 449.986343 -362.454137)
			(xy 450.039127 -362.43613) (xy 450.09397 -362.426) (xy 450.149704 -362.423963) (xy 450.205141 -362.430063)
			(xy 450.259098 -362.444169) (xy 450.310427 -362.465981) (xy 450.358033 -362.495035) (xy 450.400901 -362.53071)
			(xy 450.438118 -362.572247) (xy 450.468891 -362.61876) (xy 450.492563 -362.669257) (xy 450.508631 -362.722664)
			(xy 450.516751 -362.77784) (xy 450.51726 -362.805726) (xy 450.516751 -362.833612) (xy 450.508631 -362.888788)
			(xy 450.492563 -362.942195) (xy 450.468891 -362.992692) (xy 450.438118 -363.039205) (xy 450.400901 -363.080742)
			(xy 450.358033 -363.116417) (xy 450.310427 -363.145471) (xy 450.259098 -363.167283) (xy 450.205141 -363.181389)
			(xy 450.149704 -363.187489) (xy 450.09397 -363.185452) (xy 450.039127 -363.175322) (xy 449.986343 -363.157315)
			(xy 449.936743 -363.131814) (xy 449.891385 -363.099363) (xy 449.851236 -363.060654) (xy 449.81715 -363.016511)
			(xy 449.789854 -362.967876) (xy 449.769931 -362.915785) (xy 449.757805 -362.861348) (xy 449.753734 -362.805726)
			(xy 441.962794 -362.805726) (xy 440.958986 -363.809534) (xy 440.95289 -363.816646) (xy 440.905209 -363.886496)
			(xy 459.91729 -363.886496) (xy 459.921361 -363.830874) (xy 459.933487 -363.776437) (xy 459.95341 -363.724346)
			(xy 459.980706 -363.675711) (xy 460.014792 -363.631568) (xy 460.054941 -363.592859) (xy 460.100299 -363.560408)
			(xy 460.149899 -363.534907) (xy 460.202683 -363.5169) (xy 460.257526 -363.50677) (xy 460.31326 -363.504733)
			(xy 460.368697 -363.510833) (xy 460.422654 -363.524939) (xy 460.473983 -363.546751) (xy 460.521589 -363.575805)
			(xy 460.564457 -363.61148) (xy 460.601674 -363.653017) (xy 460.632447 -363.69953) (xy 460.656119 -363.750027)
			(xy 460.672187 -363.803434) (xy 460.680307 -363.85861) (xy 460.680816 -363.886496) (xy 460.680307 -363.914382)
			(xy 460.672187 -363.969558) (xy 460.656119 -364.022965) (xy 460.632447 -364.073462) (xy 460.601674 -364.119975)
			(xy 460.564457 -364.161512) (xy 460.521589 -364.197187) (xy 460.473983 -364.226241) (xy 460.422654 -364.248053)
			(xy 460.368697 -364.262159) (xy 460.31326 -364.268259) (xy 460.257526 -364.266222) (xy 460.202683 -364.256092)
			(xy 460.149899 -364.238085) (xy 460.100299 -364.212584) (xy 460.054941 -364.180133) (xy 460.014792 -364.141424)
			(xy 459.980706 -364.097281) (xy 459.95341 -364.048646) (xy 459.933487 -363.996555) (xy 459.921361 -363.942118)
			(xy 459.91729 -363.886496) (xy 440.905209 -363.886496) (xy 440.485273 -364.501684) (xy 457.804772 -364.501684)
			(xy 457.808843 -364.446062) (xy 457.820969 -364.391625) (xy 457.840892 -364.339534) (xy 457.868188 -364.290899)
			(xy 457.902274 -364.246756) (xy 457.942423 -364.208047) (xy 457.987781 -364.175596) (xy 458.037381 -364.150095)
			(xy 458.090165 -364.132088) (xy 458.145008 -364.121958) (xy 458.200742 -364.119921) (xy 458.256179 -364.126021)
			(xy 458.310136 -364.140127) (xy 458.361465 -364.161939) (xy 458.409071 -364.190993) (xy 458.451939 -364.226668)
			(xy 458.489156 -364.268205) (xy 458.519929 -364.314718) (xy 458.543601 -364.365215) (xy 458.559669 -364.418622)
			(xy 458.567789 -364.473798) (xy 458.568298 -364.501684) (xy 458.567789 -364.52957) (xy 458.559669 -364.584746)
			(xy 458.543601 -364.638153) (xy 458.519929 -364.68865) (xy 458.489156 -364.735163) (xy 458.451939 -364.7767)
			(xy 458.409071 -364.812375) (xy 458.361465 -364.841429) (xy 458.310136 -364.863241) (xy 458.256179 -364.877347)
			(xy 458.200742 -364.883447) (xy 458.145008 -364.88141) (xy 458.090165 -364.87128) (xy 458.037381 -364.853273)
			(xy 457.987781 -364.827772) (xy 457.942423 -364.795321) (xy 457.902274 -364.756612) (xy 457.868188 -364.712469)
			(xy 457.840892 -364.663834) (xy 457.820969 -364.611743) (xy 457.808843 -364.557306) (xy 457.804772 -364.501684)
			(xy 440.485273 -364.501684) (xy 439.955932 -365.277146) (xy 451.28764 -365.277146) (xy 451.291711 -365.221524)
			(xy 451.303837 -365.167087) (xy 451.32376 -365.114996) (xy 451.351056 -365.066361) (xy 451.385142 -365.022218)
			(xy 451.425291 -364.983509) (xy 451.470649 -364.951058) (xy 451.520249 -364.925557) (xy 451.573033 -364.90755)
			(xy 451.627876 -364.89742) (xy 451.68361 -364.895383) (xy 451.739047 -364.901483) (xy 451.793004 -364.915589)
			(xy 451.844333 -364.937401) (xy 451.891939 -364.966455) (xy 451.934807 -365.00213) (xy 451.972024 -365.043667)
			(xy 452.002797 -365.09018) (xy 452.025073 -365.1377) (xy 452.545194 -365.1377) (xy 452.549265 -365.082078)
			(xy 452.561391 -365.027641) (xy 452.581314 -364.97555) (xy 452.60861 -364.926915) (xy 452.642696 -364.882772)
			(xy 452.682845 -364.844063) (xy 452.728203 -364.811612) (xy 452.777803 -364.786111) (xy 452.830587 -364.768104)
			(xy 452.88543 -364.757974) (xy 452.941164 -364.755937) (xy 452.996601 -364.762037) (xy 453.050558 -364.776143)
			(xy 453.101887 -364.797955) (xy 453.149493 -364.827009) (xy 453.192361 -364.862684) (xy 453.229578 -364.904221)
			(xy 453.260351 -364.950734) (xy 453.284023 -365.001231) (xy 453.300091 -365.054638) (xy 453.308211 -365.109814)
			(xy 453.30872 -365.1377) (xy 453.308211 -365.165586) (xy 453.304278 -365.19231) (xy 453.705212 -365.19231)
			(xy 453.709283 -365.136688) (xy 453.721409 -365.082251) (xy 453.741332 -365.03016) (xy 453.768628 -364.981525)
			(xy 453.802714 -364.937382) (xy 453.842863 -364.898673) (xy 453.888221 -364.866222) (xy 453.937821 -364.840721)
			(xy 453.990605 -364.822714) (xy 454.045448 -364.812584) (xy 454.101182 -364.810547) (xy 454.156619 -364.816647)
			(xy 454.210576 -364.830753) (xy 454.261905 -364.852565) (xy 454.309511 -364.881619) (xy 454.352379 -364.917294)
			(xy 454.389596 -364.958831) (xy 454.420369 -365.005344) (xy 454.444041 -365.055841) (xy 454.460109 -365.109248)
			(xy 454.468229 -365.164424) (xy 454.468738 -365.19231) (xy 454.468229 -365.220196) (xy 454.460109 -365.275372)
			(xy 454.444041 -365.328779) (xy 454.420369 -365.379276) (xy 454.389596 -365.425789) (xy 454.352379 -365.467326)
			(xy 454.309511 -365.503001) (xy 454.261905 -365.532055) (xy 454.210576 -365.553867) (xy 454.156619 -365.567973)
			(xy 454.101182 -365.574073) (xy 454.045448 -365.572036) (xy 453.990605 -365.561906) (xy 453.937821 -365.543899)
			(xy 453.888221 -365.518398) (xy 453.842863 -365.485947) (xy 453.802714 -365.447238) (xy 453.768628 -365.403095)
			(xy 453.741332 -365.35446) (xy 453.721409 -365.302369) (xy 453.709283 -365.247932) (xy 453.705212 -365.19231)
			(xy 453.304278 -365.19231) (xy 453.300091 -365.220762) (xy 453.284023 -365.274169) (xy 453.260351 -365.324666)
			(xy 453.229578 -365.371179) (xy 453.192361 -365.412716) (xy 453.149493 -365.448391) (xy 453.101887 -365.477445)
			(xy 453.050558 -365.499257) (xy 452.996601 -365.513363) (xy 452.941164 -365.519463) (xy 452.88543 -365.517426)
			(xy 452.830587 -365.507296) (xy 452.777803 -365.489289) (xy 452.728203 -365.463788) (xy 452.682845 -365.431337)
			(xy 452.642696 -365.392628) (xy 452.60861 -365.348485) (xy 452.581314 -365.29985) (xy 452.561391 -365.247759)
			(xy 452.549265 -365.193322) (xy 452.545194 -365.1377) (xy 452.025073 -365.1377) (xy 452.026469 -365.140677)
			(xy 452.042537 -365.194084) (xy 452.050657 -365.24926) (xy 452.051166 -365.277146) (xy 452.050657 -365.305032)
			(xy 452.042537 -365.360208) (xy 452.026469 -365.413615) (xy 452.002797 -365.464112) (xy 451.972024 -365.510625)
			(xy 451.934807 -365.552162) (xy 451.891939 -365.587837) (xy 451.844333 -365.616891) (xy 451.793004 -365.638703)
			(xy 451.739047 -365.652809) (xy 451.68361 -365.658909) (xy 451.627876 -365.656872) (xy 451.573033 -365.646742)
			(xy 451.520249 -365.628735) (xy 451.470649 -365.603234) (xy 451.425291 -365.570783) (xy 451.385142 -365.532074)
			(xy 451.351056 -365.487931) (xy 451.32376 -365.439296) (xy 451.303837 -365.387205) (xy 451.291711 -365.332768)
			(xy 451.28764 -365.277146) (xy 439.955932 -365.277146) (xy 438.982207 -366.70361) (xy 453.285096 -366.70361)
			(xy 453.289167 -366.647988) (xy 453.301293 -366.593551) (xy 453.321216 -366.54146) (xy 453.348512 -366.492825)
			(xy 453.382598 -366.448682) (xy 453.422747 -366.409973) (xy 453.468105 -366.377522) (xy 453.517705 -366.352021)
			(xy 453.570489 -366.334014) (xy 453.625332 -366.323884) (xy 453.681066 -366.321847) (xy 453.736503 -366.327947)
			(xy 453.79046 -366.342053) (xy 453.841789 -366.363865) (xy 453.889395 -366.392919) (xy 453.932263 -366.428594)
			(xy 453.96948 -366.470131) (xy 454.000253 -366.516644) (xy 454.023925 -366.567141) (xy 454.039993 -366.620548)
			(xy 454.048113 -366.675724) (xy 454.048622 -366.70361) (xy 454.048113 -366.731496) (xy 454.039993 -366.786672)
			(xy 454.023925 -366.840079) (xy 454.000253 -366.890576) (xy 453.984807 -366.913922) (xy 455.642978 -366.913922)
			(xy 455.647049 -366.8583) (xy 455.659175 -366.803863) (xy 455.679098 -366.751772) (xy 455.706394 -366.703137)
			(xy 455.74048 -366.658994) (xy 455.780629 -366.620285) (xy 455.825987 -366.587834) (xy 455.875587 -366.562333)
			(xy 455.928371 -366.544326) (xy 455.983214 -366.534196) (xy 456.038948 -366.532159) (xy 456.094385 -366.538259)
			(xy 456.148342 -366.552365) (xy 456.199671 -366.574177) (xy 456.247277 -366.603231) (xy 456.290145 -366.638906)
			(xy 456.327362 -366.680443) (xy 456.358135 -366.726956) (xy 456.381807 -366.777453) (xy 456.397875 -366.83086)
			(xy 456.405995 -366.886036) (xy 456.406504 -366.913922) (xy 458.450694 -366.913922) (xy 458.454765 -366.8583)
			(xy 458.466891 -366.803863) (xy 458.486814 -366.751772) (xy 458.51411 -366.703137) (xy 458.548196 -366.658994)
			(xy 458.588345 -366.620285) (xy 458.633703 -366.587834) (xy 458.683303 -366.562333) (xy 458.736087 -366.544326)
			(xy 458.79093 -366.534196) (xy 458.846664 -366.532159) (xy 458.902101 -366.538259) (xy 458.956058 -366.552365)
			(xy 459.007387 -366.574177) (xy 459.054993 -366.603231) (xy 459.097861 -366.638906) (xy 459.135078 -366.680443)
			(xy 459.165851 -366.726956) (xy 459.189523 -366.777453) (xy 459.205591 -366.83086) (xy 459.213711 -366.886036)
			(xy 459.21422 -366.913922) (xy 459.213711 -366.941808) (xy 459.205591 -366.996984) (xy 459.189523 -367.050391)
			(xy 459.165851 -367.100888) (xy 459.135078 -367.147401) (xy 459.097861 -367.188938) (xy 459.054993 -367.224613)
			(xy 459.007387 -367.253667) (xy 458.956058 -367.275479) (xy 458.902101 -367.289585) (xy 458.846664 -367.295685)
			(xy 458.79093 -367.293648) (xy 458.736087 -367.283518) (xy 458.683303 -367.265511) (xy 458.633703 -367.24001)
			(xy 458.588345 -367.207559) (xy 458.548196 -367.16885) (xy 458.51411 -367.124707) (xy 458.486814 -367.076072)
			(xy 458.466891 -367.023981) (xy 458.454765 -366.969544) (xy 458.450694 -366.913922) (xy 456.406504 -366.913922)
			(xy 456.405995 -366.941808) (xy 456.397875 -366.996984) (xy 456.381807 -367.050391) (xy 456.358135 -367.100888)
			(xy 456.327362 -367.147401) (xy 456.290145 -367.188938) (xy 456.247277 -367.224613) (xy 456.199671 -367.253667)
			(xy 456.148342 -367.275479) (xy 456.094385 -367.289585) (xy 456.038948 -367.295685) (xy 455.983214 -367.293648)
			(xy 455.928371 -367.283518) (xy 455.875587 -367.265511) (xy 455.825987 -367.24001) (xy 455.780629 -367.207559)
			(xy 455.74048 -367.16885) (xy 455.706394 -367.124707) (xy 455.679098 -367.076072) (xy 455.659175 -367.023981)
			(xy 455.647049 -366.969544) (xy 455.642978 -366.913922) (xy 453.984807 -366.913922) (xy 453.96948 -366.937089)
			(xy 453.932263 -366.978626) (xy 453.889395 -367.014301) (xy 453.841789 -367.043355) (xy 453.79046 -367.065167)
			(xy 453.736503 -367.079273) (xy 453.681066 -367.085373) (xy 453.625332 -367.083336) (xy 453.570489 -367.073206)
			(xy 453.517705 -367.055199) (xy 453.468105 -367.029698) (xy 453.422747 -366.997247) (xy 453.382598 -366.958538)
			(xy 453.348512 -366.914395) (xy 453.321216 -366.86576) (xy 453.301293 -366.813669) (xy 453.289167 -366.759232)
			(xy 453.285096 -366.70361) (xy 438.982207 -366.70361) (xy 438.111646 -367.978944) (xy 438.107536 -367.985396)
			(xy 438.103002 -368) (xy 438.102756 -368.007646) (xy 438.102756 -368.990118) (xy 438.803804 -368.990118)
			(xy 438.807795 -368.927951) (xy 438.819704 -368.866804) (xy 438.839333 -368.807683) (xy 438.866362 -368.751557)
			(xy 438.900346 -368.699348) (xy 438.940728 -368.651913) (xy 438.986844 -368.610032) (xy 439.037936 -368.574392)
			(xy 439.093167 -368.545578) (xy 439.151629 -368.524064) (xy 439.212363 -368.510202) (xy 439.27437 -368.50422)
			(xy 439.336633 -368.506216) (xy 439.39813 -368.516159) (xy 439.457851 -368.533883) (xy 439.514814 -368.5591)
			(xy 439.568085 -368.591393) (xy 439.61679 -368.630233) (xy 439.660127 -368.674983) (xy 439.697387 -368.724907)
			(xy 439.727956 -368.779186) (xy 439.751334 -368.836929) (xy 439.767135 -368.897187) (xy 439.775101 -368.95897)
			(xy 439.7756 -368.990118) (xy 439.775101 -369.021266) (xy 439.767135 -369.083049) (xy 439.751334 -369.143307)
			(xy 439.727956 -369.20105) (xy 439.697387 -369.255329) (xy 439.660127 -369.305253) (xy 439.61679 -369.350003)
			(xy 439.568085 -369.388843) (xy 439.514814 -369.421136) (xy 439.457851 -369.446353) (xy 439.39813 -369.464077)
			(xy 439.336633 -369.47402) (xy 439.27437 -369.476016) (xy 439.212363 -369.470034) (xy 439.151629 -369.456172)
			(xy 439.093167 -369.434658) (xy 439.037936 -369.405844) (xy 438.986844 -369.370204) (xy 438.940728 -369.328323)
			(xy 438.900346 -369.280888) (xy 438.866362 -369.228679) (xy 438.839333 -369.172553) (xy 438.819704 -369.113432)
			(xy 438.807795 -369.052285) (xy 438.803804 -368.990118) (xy 438.102756 -368.990118) (xy 438.102756 -371.590062)
			(xy 438.803804 -371.590062) (xy 438.807795 -371.527895) (xy 438.819704 -371.466748) (xy 438.839333 -371.407627)
			(xy 438.866362 -371.351501) (xy 438.900346 -371.299292) (xy 438.940728 -371.251857) (xy 438.986844 -371.209976)
			(xy 439.037936 -371.174336) (xy 439.093167 -371.145522) (xy 439.151629 -371.124008) (xy 439.212363 -371.110146)
			(xy 439.27437 -371.104164) (xy 439.336633 -371.10616) (xy 439.39813 -371.116103) (xy 439.457851 -371.133827)
			(xy 439.514814 -371.159044) (xy 439.568085 -371.191337) (xy 439.61679 -371.230177) (xy 439.660127 -371.274927)
			(xy 439.697387 -371.324851) (xy 439.727956 -371.37913) (xy 439.751334 -371.436873) (xy 439.767135 -371.497131)
			(xy 439.775101 -371.558914) (xy 439.7756 -371.590062) (xy 439.775101 -371.62121) (xy 439.767135 -371.682993)
			(xy 439.751334 -371.743251) (xy 439.727956 -371.800994) (xy 439.697387 -371.855273) (xy 439.694001 -371.85981)
			(xy 457.532994 -371.85981) (xy 457.53348 -371.832559) (xy 457.541236 -371.778611) (xy 457.556591 -371.726316)
			(xy 457.579233 -371.676739) (xy 457.608699 -371.630889) (xy 457.64439 -371.589698) (xy 457.685581 -371.554007)
			(xy 457.731431 -371.524541) (xy 457.781008 -371.501899) (xy 457.833303 -371.486544) (xy 457.887251 -371.478788)
			(xy 457.941753 -371.478788) (xy 457.995701 -371.486544) (xy 458.047996 -371.501899) (xy 458.097573 -371.524541)
			(xy 458.143423 -371.554007) (xy 458.184614 -371.589698) (xy 458.220305 -371.630889) (xy 458.249771 -371.676739)
			(xy 458.272413 -371.726316) (xy 458.287768 -371.778611) (xy 458.295524 -371.832559) (xy 458.29601 -371.85981)
			(xy 458.29539 -371.890148) (xy 458.285787 -371.950059) (xy 458.266823 -372.007696) (xy 458.238976 -372.061604)
			(xy 458.202949 -372.110427) (xy 458.18171 -372.132098) (xy 458.17212 -372.141991) (xy 458.1583 -372.165823)
			(xy 458.151349 -372.192479) (xy 458.151771 -372.220024) (xy 458.159536 -372.246455) (xy 458.174079 -372.269852)
			(xy 458.194344 -372.288513) (xy 458.218858 -372.301083) (xy 458.232256 -372.30431) (xy 458.260571 -372.310664)
			(xy 458.314998 -372.330791) (xy 458.365747 -372.358932) (xy 458.411647 -372.394436) (xy 458.451638 -372.436485)
			(xy 458.484797 -372.484106) (xy 458.510358 -372.536202) (xy 458.527732 -372.591569) (xy 458.536517 -372.648929)
			(xy 458.537056 -372.677944) (xy 458.53657 -372.705195) (xy 458.528814 -372.759143) (xy 458.513459 -372.811438)
			(xy 458.490817 -372.861015) (xy 458.461351 -372.906865) (xy 458.42566 -372.948056) (xy 458.384469 -372.983747)
			(xy 458.338619 -373.013213) (xy 458.289042 -373.035855) (xy 458.236747 -373.05121) (xy 458.182799 -373.058966)
			(xy 458.128297 -373.058966) (xy 458.074349 -373.05121) (xy 458.022054 -373.035855) (xy 457.972477 -373.013213)
			(xy 457.926627 -372.983747) (xy 457.885436 -372.948056) (xy 457.849745 -372.906865) (xy 457.820279 -372.861015)
			(xy 457.797637 -372.811438) (xy 457.782282 -372.759143) (xy 457.774526 -372.705195) (xy 457.77404 -372.677944)
			(xy 457.774616 -372.647604) (xy 457.784228 -372.58769) (xy 457.803202 -372.530053) (xy 457.831058 -372.476145)
			(xy 457.867095 -372.427325) (xy 457.88834 -372.405656) (xy 457.897843 -372.395687) (xy 457.911655 -372.371873)
			(xy 457.918606 -372.345236) (xy 457.918191 -372.317709) (xy 457.910439 -372.291294) (xy 457.895914 -372.267908)
			(xy 457.875672 -372.24925) (xy 457.851181 -372.236677) (xy 457.837794 -372.233444) (xy 457.809476 -372.227098)
			(xy 457.755046 -372.206974) (xy 457.704294 -372.178835) (xy 457.658391 -372.143331) (xy 457.618399 -372.101281)
			(xy 457.58524 -372.053657) (xy 457.55968 -372.001559) (xy 457.54231 -371.946188) (xy 457.53353 -371.888826)
			(xy 457.532994 -371.85981) (xy 439.694001 -371.85981) (xy 439.660127 -371.905197) (xy 439.61679 -371.949947)
			(xy 439.568085 -371.988787) (xy 439.514814 -372.02108) (xy 439.457851 -372.046297) (xy 439.39813 -372.064021)
			(xy 439.336633 -372.073964) (xy 439.27437 -372.07596) (xy 439.212363 -372.069978) (xy 439.151629 -372.056116)
			(xy 439.093167 -372.034602) (xy 439.037936 -372.005788) (xy 438.986844 -371.970148) (xy 438.940728 -371.928267)
			(xy 438.900346 -371.880832) (xy 438.866362 -371.828623) (xy 438.839333 -371.772497) (xy 438.819704 -371.713376)
			(xy 438.807795 -371.652229) (xy 438.803804 -371.590062) (xy 438.102756 -371.590062) (xy 438.102756 -372.890034)
			(xy 438.803804 -372.890034) (xy 438.807795 -372.827867) (xy 438.819704 -372.76672) (xy 438.839333 -372.707599)
			(xy 438.866362 -372.651473) (xy 438.900346 -372.599264) (xy 438.940728 -372.551829) (xy 438.986844 -372.509948)
			(xy 439.037936 -372.474308) (xy 439.093167 -372.445494) (xy 439.151629 -372.42398) (xy 439.212363 -372.410118)
			(xy 439.27437 -372.404136) (xy 439.336633 -372.406132) (xy 439.39813 -372.416075) (xy 439.457851 -372.433799)
			(xy 439.514814 -372.459016) (xy 439.568085 -372.491309) (xy 439.61679 -372.530149) (xy 439.660127 -372.574899)
			(xy 439.697387 -372.624823) (xy 439.727956 -372.679102) (xy 439.751334 -372.736845) (xy 439.767135 -372.797103)
			(xy 439.775101 -372.858886) (xy 439.7756 -372.890034) (xy 439.775101 -372.921182) (xy 439.767135 -372.982965)
			(xy 439.751334 -373.043223) (xy 439.727956 -373.100966) (xy 439.697387 -373.155245) (xy 439.660127 -373.205169)
			(xy 439.61679 -373.249919) (xy 439.568085 -373.288759) (xy 439.514814 -373.321052) (xy 439.457851 -373.346269)
			(xy 439.39813 -373.363993) (xy 439.336633 -373.373936) (xy 439.27437 -373.375932) (xy 439.212363 -373.36995)
			(xy 439.151629 -373.356088) (xy 439.093167 -373.334574) (xy 439.037936 -373.30576) (xy 438.986844 -373.27012)
			(xy 438.940728 -373.228239) (xy 438.900346 -373.180804) (xy 438.866362 -373.128595) (xy 438.839333 -373.072469)
			(xy 438.819704 -373.013348) (xy 438.807795 -372.952201) (xy 438.803804 -372.890034) (xy 438.102756 -372.890034)
			(xy 438.102756 -373.453406) (xy 451.256398 -373.453406) (xy 451.260469 -373.397784) (xy 451.272595 -373.343347)
			(xy 451.292518 -373.291256) (xy 451.319814 -373.242621) (xy 451.3539 -373.198478) (xy 451.394049 -373.159769)
			(xy 451.439407 -373.127318) (xy 451.489007 -373.101817) (xy 451.541791 -373.08381) (xy 451.596634 -373.07368)
			(xy 451.652368 -373.071643) (xy 451.707805 -373.077743) (xy 451.761762 -373.091849) (xy 451.813091 -373.113661)
			(xy 451.860697 -373.142715) (xy 451.903565 -373.17839) (xy 451.940782 -373.219927) (xy 451.971555 -373.26644)
			(xy 451.995227 -373.316937) (xy 452.011295 -373.370344) (xy 452.019415 -373.42552) (xy 452.019924 -373.453406)
			(xy 452.019415 -373.481292) (xy 452.011295 -373.536468) (xy 451.995227 -373.589875) (xy 451.971555 -373.640372)
			(xy 451.940782 -373.686885) (xy 451.903565 -373.728422) (xy 451.860697 -373.764097) (xy 451.813091 -373.793151)
			(xy 451.761762 -373.814963) (xy 451.707805 -373.829069) (xy 451.652368 -373.835169) (xy 451.596634 -373.833132)
			(xy 451.541791 -373.823002) (xy 451.489007 -373.804995) (xy 451.439407 -373.779494) (xy 451.394049 -373.747043)
			(xy 451.3539 -373.708334) (xy 451.319814 -373.664191) (xy 451.292518 -373.615556) (xy 451.272595 -373.563465)
			(xy 451.260469 -373.509028) (xy 451.256398 -373.453406) (xy 438.102756 -373.453406) (xy 438.102756 -375.490232)
			(xy 438.803804 -375.490232) (xy 438.807795 -375.428065) (xy 438.819704 -375.366918) (xy 438.839333 -375.307797)
			(xy 438.866362 -375.251671) (xy 438.900346 -375.199462) (xy 438.940728 -375.152027) (xy 438.986844 -375.110146)
			(xy 439.037936 -375.074506) (xy 439.093167 -375.045692) (xy 439.151629 -375.024178) (xy 439.212363 -375.010316)
			(xy 439.27437 -375.004334) (xy 439.336633 -375.00633) (xy 439.39813 -375.016273) (xy 439.457851 -375.033997)
			(xy 439.514814 -375.059214) (xy 439.565899 -375.090182) (xy 459.19085 -375.090182) (xy 459.194921 -375.03456)
			(xy 459.207047 -374.980123) (xy 459.22697 -374.928032) (xy 459.254266 -374.879397) (xy 459.288352 -374.835254)
			(xy 459.328501 -374.796545) (xy 459.373859 -374.764094) (xy 459.423459 -374.738593) (xy 459.476243 -374.720586)
			(xy 459.531086 -374.710456) (xy 459.58682 -374.708419) (xy 459.642257 -374.714519) (xy 459.696214 -374.728625)
			(xy 459.747543 -374.750437) (xy 459.795149 -374.779491) (xy 459.838017 -374.815166) (xy 459.875234 -374.856703)
			(xy 459.906007 -374.903216) (xy 459.929679 -374.953713) (xy 459.945747 -375.00712) (xy 459.953867 -375.062296)
			(xy 459.954376 -375.090182) (xy 459.953867 -375.118068) (xy 459.945747 -375.173244) (xy 459.929679 -375.226651)
			(xy 459.906007 -375.277148) (xy 459.875234 -375.323661) (xy 459.838017 -375.365198) (xy 459.795149 -375.400873)
			(xy 459.747543 -375.429927) (xy 459.696214 -375.451739) (xy 459.642257 -375.465845) (xy 459.58682 -375.471945)
			(xy 459.531086 -375.469908) (xy 459.476243 -375.459778) (xy 459.423459 -375.441771) (xy 459.373859 -375.41627)
			(xy 459.328501 -375.383819) (xy 459.288352 -375.34511) (xy 459.254266 -375.300967) (xy 459.22697 -375.252332)
			(xy 459.207047 -375.200241) (xy 459.194921 -375.145804) (xy 459.19085 -375.090182) (xy 439.565899 -375.090182)
			(xy 439.568085 -375.091507) (xy 439.61679 -375.130347) (xy 439.660127 -375.175097) (xy 439.697387 -375.225021)
			(xy 439.727956 -375.2793) (xy 439.751334 -375.337043) (xy 439.767135 -375.397301) (xy 439.775101 -375.459084)
			(xy 439.7756 -375.490232) (xy 439.775101 -375.52138) (xy 439.767135 -375.583163) (xy 439.751334 -375.643421)
			(xy 439.727956 -375.701164) (xy 439.697387 -375.755443) (xy 439.660127 -375.805367) (xy 439.61679 -375.850117)
			(xy 439.568085 -375.888957) (xy 439.514814 -375.92125) (xy 439.457851 -375.946467) (xy 439.39813 -375.964191)
			(xy 439.336633 -375.974134) (xy 439.27437 -375.97613) (xy 439.212363 -375.970148) (xy 439.151629 -375.956286)
			(xy 439.093167 -375.934772) (xy 439.037936 -375.905958) (xy 438.986844 -375.870318) (xy 438.940728 -375.828437)
			(xy 438.900346 -375.781002) (xy 438.866362 -375.728793) (xy 438.839333 -375.672667) (xy 438.819704 -375.613546)
			(xy 438.807795 -375.552399) (xy 438.803804 -375.490232) (xy 438.102756 -375.490232) (xy 438.102756 -376.790204)
			(xy 438.803804 -376.790204) (xy 438.807795 -376.728037) (xy 438.819704 -376.66689) (xy 438.839333 -376.607769)
			(xy 438.866362 -376.551643) (xy 438.900346 -376.499434) (xy 438.940728 -376.451999) (xy 438.986844 -376.410118)
			(xy 439.037936 -376.374478) (xy 439.093167 -376.345664) (xy 439.151629 -376.32415) (xy 439.212363 -376.310288)
			(xy 439.27437 -376.304306) (xy 439.336633 -376.306302) (xy 439.39813 -376.316245) (xy 439.457851 -376.333969)
			(xy 439.514814 -376.359186) (xy 439.568085 -376.391479) (xy 439.61679 -376.430319) (xy 439.660127 -376.475069)
			(xy 439.697387 -376.524993) (xy 439.727956 -376.579272) (xy 439.751334 -376.637015) (xy 439.767135 -376.697273)
			(xy 439.775101 -376.759056) (xy 439.7756 -376.790204) (xy 439.775101 -376.821352) (xy 439.767135 -376.883135)
			(xy 439.751334 -376.943393) (xy 439.727956 -377.001136) (xy 439.697387 -377.055415) (xy 439.660127 -377.105339)
			(xy 439.61679 -377.150089) (xy 439.568085 -377.188929) (xy 439.514814 -377.221222) (xy 439.457851 -377.246439)
			(xy 439.39813 -377.264163) (xy 439.336633 -377.274106) (xy 439.27437 -377.276102) (xy 439.212363 -377.27012)
			(xy 439.151629 -377.256258) (xy 439.093167 -377.234744) (xy 439.037936 -377.20593) (xy 438.986844 -377.17029)
			(xy 438.940728 -377.128409) (xy 438.900346 -377.080974) (xy 438.866362 -377.028765) (xy 438.839333 -376.972639)
			(xy 438.819704 -376.913518) (xy 438.807795 -376.852371) (xy 438.803804 -376.790204) (xy 438.102756 -376.790204)
			(xy 438.102756 -379.390148) (xy 438.803804 -379.390148) (xy 438.807795 -379.327981) (xy 438.819704 -379.266834)
			(xy 438.839333 -379.207713) (xy 438.866362 -379.151587) (xy 438.900346 -379.099378) (xy 438.940728 -379.051943)
			(xy 438.986844 -379.010062) (xy 439.037936 -378.974422) (xy 439.093167 -378.945608) (xy 439.151629 -378.924094)
			(xy 439.212363 -378.910232) (xy 439.27437 -378.90425) (xy 439.336633 -378.906246) (xy 439.39813 -378.916189)
			(xy 439.457851 -378.933913) (xy 439.514814 -378.95913) (xy 439.568085 -378.991423) (xy 439.61679 -379.030263)
			(xy 439.660127 -379.075013) (xy 439.697387 -379.124937) (xy 439.727956 -379.179216) (xy 439.751334 -379.236959)
			(xy 439.767135 -379.297217) (xy 439.775101 -379.359) (xy 439.7756 -379.390148) (xy 439.775101 -379.421296)
			(xy 439.767135 -379.483079) (xy 439.751334 -379.543337) (xy 439.727956 -379.60108) (xy 439.697387 -379.655359)
			(xy 439.660127 -379.705283) (xy 439.61679 -379.750033) (xy 439.568085 -379.788873) (xy 439.514814 -379.821166)
			(xy 439.457851 -379.846383) (xy 439.39813 -379.864107) (xy 439.336633 -379.87405) (xy 439.27437 -379.876046)
			(xy 439.212363 -379.870064) (xy 439.151629 -379.856202) (xy 439.093167 -379.834688) (xy 439.037936 -379.805874)
			(xy 438.986844 -379.770234) (xy 438.940728 -379.728353) (xy 438.900346 -379.680918) (xy 438.866362 -379.628709)
			(xy 438.839333 -379.572583) (xy 438.819704 -379.513462) (xy 438.807795 -379.452315) (xy 438.803804 -379.390148)
			(xy 438.102756 -379.390148) (xy 438.102756 -380.69012) (xy 438.803804 -380.69012) (xy 438.807795 -380.627953)
			(xy 438.819704 -380.566806) (xy 438.839333 -380.507685) (xy 438.866362 -380.451559) (xy 438.900346 -380.39935)
			(xy 438.940728 -380.351915) (xy 438.986844 -380.310034) (xy 439.037936 -380.274394) (xy 439.093167 -380.24558)
			(xy 439.151629 -380.224066) (xy 439.212363 -380.210204) (xy 439.27437 -380.204222) (xy 439.336633 -380.206218)
			(xy 439.39813 -380.216161) (xy 439.457851 -380.233885) (xy 439.514814 -380.259102) (xy 439.568085 -380.291395)
			(xy 439.61679 -380.330235) (xy 439.660127 -380.374985) (xy 439.697387 -380.424909) (xy 439.727956 -380.479188)
			(xy 439.751334 -380.536931) (xy 439.767135 -380.597189) (xy 439.775101 -380.658972) (xy 439.7756 -380.69012)
			(xy 439.775101 -380.721268) (xy 439.767135 -380.783051) (xy 439.751334 -380.843309) (xy 439.727956 -380.901052)
			(xy 439.697387 -380.955331) (xy 439.660127 -381.005255) (xy 439.61679 -381.050005) (xy 439.568085 -381.088845)
			(xy 439.514814 -381.121138) (xy 439.457851 -381.146355) (xy 439.39813 -381.164079) (xy 439.336633 -381.174022)
			(xy 439.27437 -381.176018) (xy 439.212363 -381.170036) (xy 439.151629 -381.156174) (xy 439.093167 -381.13466)
			(xy 439.037936 -381.105846) (xy 438.986844 -381.070206) (xy 438.940728 -381.028325) (xy 438.900346 -380.98089)
			(xy 438.866362 -380.928681) (xy 438.839333 -380.872555) (xy 438.819704 -380.813434) (xy 438.807795 -380.752287)
			(xy 438.803804 -380.69012) (xy 438.102756 -380.69012) (xy 438.102756 -383.290064) (xy 438.803804 -383.290064)
			(xy 438.807795 -383.227897) (xy 438.819704 -383.16675) (xy 438.839333 -383.107629) (xy 438.866362 -383.051503)
			(xy 438.900346 -382.999294) (xy 438.940728 -382.951859) (xy 438.986844 -382.909978) (xy 439.037936 -382.874338)
			(xy 439.093167 -382.845524) (xy 439.151629 -382.82401) (xy 439.212363 -382.810148) (xy 439.27437 -382.804166)
			(xy 439.336633 -382.806162) (xy 439.39813 -382.816105) (xy 439.457851 -382.833829) (xy 439.514814 -382.859046)
			(xy 439.568085 -382.891339) (xy 439.61679 -382.930179) (xy 439.660127 -382.974929) (xy 439.697387 -383.024853)
			(xy 439.727956 -383.079132) (xy 439.751334 -383.136875) (xy 439.767135 -383.197133) (xy 439.775101 -383.258916)
			(xy 439.7756 -383.290064) (xy 439.775101 -383.321212) (xy 439.767135 -383.382995) (xy 439.751334 -383.443253)
			(xy 439.727956 -383.500996) (xy 439.697387 -383.555275) (xy 439.660127 -383.605199) (xy 439.61679 -383.649949)
			(xy 439.568085 -383.688789) (xy 439.514814 -383.721082) (xy 439.457851 -383.746299) (xy 439.39813 -383.764023)
			(xy 439.336633 -383.773966) (xy 439.27437 -383.775962) (xy 439.212363 -383.76998) (xy 439.151629 -383.756118)
			(xy 439.093167 -383.734604) (xy 439.037936 -383.70579) (xy 438.986844 -383.67015) (xy 438.940728 -383.628269)
			(xy 438.900346 -383.580834) (xy 438.866362 -383.528625) (xy 438.839333 -383.472499) (xy 438.819704 -383.413378)
			(xy 438.807795 -383.352231) (xy 438.803804 -383.290064) (xy 438.102756 -383.290064) (xy 438.102756 -384.590036)
			(xy 438.803804 -384.590036) (xy 438.807795 -384.527869) (xy 438.819704 -384.466722) (xy 438.839333 -384.407601)
			(xy 438.866362 -384.351475) (xy 438.900346 -384.299266) (xy 438.940728 -384.251831) (xy 438.986844 -384.20995)
			(xy 439.037936 -384.17431) (xy 439.093167 -384.145496) (xy 439.151629 -384.123982) (xy 439.212363 -384.11012)
			(xy 439.27437 -384.104138) (xy 439.336633 -384.106134) (xy 439.39813 -384.116077) (xy 439.457851 -384.133801)
			(xy 439.514814 -384.159018) (xy 439.568085 -384.191311) (xy 439.61679 -384.230151) (xy 439.660127 -384.274901)
			(xy 439.697387 -384.324825) (xy 439.727956 -384.379104) (xy 439.751334 -384.436847) (xy 439.767135 -384.497105)
			(xy 439.775101 -384.558888) (xy 439.7756 -384.590036) (xy 439.775101 -384.621184) (xy 439.767135 -384.682967)
			(xy 439.751334 -384.743225) (xy 439.727956 -384.800968) (xy 439.697387 -384.855247) (xy 439.660127 -384.905171)
			(xy 439.61679 -384.949921) (xy 439.568085 -384.988761) (xy 439.514814 -385.021054) (xy 439.457851 -385.046271)
			(xy 439.39813 -385.063995) (xy 439.336633 -385.073938) (xy 439.27437 -385.075934) (xy 439.212363 -385.069952)
			(xy 439.151629 -385.05609) (xy 439.093167 -385.034576) (xy 439.037936 -385.005762) (xy 438.986844 -384.970122)
			(xy 438.940728 -384.928241) (xy 438.900346 -384.880806) (xy 438.866362 -384.828597) (xy 438.839333 -384.772471)
			(xy 438.819704 -384.71335) (xy 438.807795 -384.652203) (xy 438.803804 -384.590036) (xy 438.102756 -384.590036)
			(xy 438.102756 -385.608376) (xy 454.303373 -385.608376) (xy 454.303373 -385.479236) (xy 454.311323 -385.350341)
			(xy 454.327193 -385.222181) (xy 454.350922 -385.09524) (xy 454.382421 -384.970001) (xy 454.42157 -384.846938)
			(xy 454.468221 -384.726519) (xy 454.522196 -384.6092) (xy 454.583291 -384.495426) (xy 454.651274 -384.385629)
			(xy 454.725888 -384.280226) (xy 454.806849 -384.179616) (xy 454.893849 -384.084181) (xy 454.98656 -383.994282)
			(xy 455.08463 -383.910261) (xy 455.187685 -383.832437) (xy 455.295336 -383.761105) (xy 455.407175 -383.696535)
			(xy 455.522776 -383.638973) (xy 455.641701 -383.588636) (xy 455.7635 -383.545716) (xy 455.88771 -383.510375)
			(xy 456.013859 -383.482748) (xy 456.141471 -383.462939) (xy 456.27006 -383.451023) (xy 456.399138 -383.447047)
			(xy 456.528216 -383.451023) (xy 456.656805 -383.462939) (xy 456.784417 -383.482748) (xy 456.910566 -383.510375)
			(xy 457.034776 -383.545716) (xy 457.156575 -383.588636) (xy 457.2755 -383.638973) (xy 457.391101 -383.696535)
			(xy 457.50294 -383.761105) (xy 457.610591 -383.832437) (xy 457.713646 -383.910261) (xy 457.811716 -383.994282)
			(xy 457.904427 -384.084181) (xy 457.991427 -384.179616) (xy 458.072388 -384.280226) (xy 458.147002 -384.385629)
			(xy 458.214985 -384.495426) (xy 458.27608 -384.6092) (xy 458.330055 -384.726519) (xy 458.376706 -384.846938)
			(xy 458.415855 -384.970001) (xy 458.447354 -385.09524) (xy 458.471083 -385.222181) (xy 458.486953 -385.350341)
			(xy 458.494903 -385.479236) (xy 458.4954 -385.543806) (xy 458.494903 -385.608376) (xy 458.486953 -385.737271)
			(xy 458.471083 -385.865431) (xy 458.447354 -385.992372) (xy 458.415855 -386.117611) (xy 458.376706 -386.240674)
			(xy 458.330055 -386.361093) (xy 458.27608 -386.478412) (xy 458.214985 -386.592186) (xy 458.147002 -386.701983)
			(xy 458.072388 -386.807386) (xy 457.991427 -386.907996) (xy 457.904427 -387.003431) (xy 457.811716 -387.09333)
			(xy 457.713646 -387.177351) (xy 457.610591 -387.255175) (xy 457.50294 -387.326507) (xy 457.391101 -387.391077)
			(xy 457.2755 -387.448639) (xy 457.156575 -387.498976) (xy 457.034776 -387.541896) (xy 456.910566 -387.577237)
			(xy 456.784417 -387.604864) (xy 456.656805 -387.624673) (xy 456.528216 -387.636589) (xy 456.399138 -387.640566)
			(xy 456.27006 -387.636589) (xy 456.141471 -387.624673) (xy 456.013859 -387.604864) (xy 455.88771 -387.577237)
			(xy 455.7635 -387.541896) (xy 455.641701 -387.498976) (xy 455.522776 -387.448639) (xy 455.407175 -387.391077)
			(xy 455.295336 -387.326507) (xy 455.187685 -387.255175) (xy 455.08463 -387.177351) (xy 454.98656 -387.09333)
			(xy 454.893849 -387.003431) (xy 454.806849 -386.907996) (xy 454.725888 -386.807386) (xy 454.651274 -386.701983)
			(xy 454.583291 -386.592186) (xy 454.522196 -386.478412) (xy 454.468221 -386.361093) (xy 454.42157 -386.240674)
			(xy 454.382421 -386.117611) (xy 454.350922 -385.992372) (xy 454.327193 -385.865431) (xy 454.311323 -385.737271)
			(xy 454.303373 -385.608376) (xy 438.102756 -385.608376) (xy 438.102756 -392.66876) (xy 438.103772 -392.678412)
			(xy 438.105396 -392.685658) (xy 438.112234 -392.69883) (xy 438.117234 -392.70432) (xy 440.87034 -395.457426)
			(xy 440.877189 -395.464823) (xy 440.884923 -395.483422) (xy 440.885326 -395.493494) (xy 440.885326 -398.100042)
			(xy 459.541382 -398.100042) (xy 459.545364 -397.972056) (xy 459.557296 -397.844565) (xy 459.57713 -397.718062)
			(xy 459.604791 -397.593037) (xy 459.640171 -397.469974) (xy 459.683133 -397.349348) (xy 459.733511 -397.231627)
			(xy 459.791111 -397.117265) (xy 459.855709 -397.006706) (xy 459.927056 -396.900376) (xy 460.004875 -396.798688)
			(xy 460.088865 -396.702034) (xy 460.178702 -396.610789) (xy 460.274038 -396.525306) (xy 460.374503 -396.445915)
			(xy 460.479711 -396.372923) (xy 460.589252 -396.306614) (xy 460.702704 -396.247243) (xy 460.819628 -396.195039)
			(xy 460.939571 -396.150206) (xy 461.062069 -396.112917) (xy 461.186649 -396.083315) (xy 461.312827 -396.061516)
			(xy 461.440117 -396.047603) (xy 461.568026 -396.041631) (xy 461.696059 -396.043622) (xy 461.82372 -396.05357)
			(xy 461.950516 -396.071434) (xy 462.075955 -396.097147) (xy 462.199554 -396.130609) (xy 462.320833 -396.17169)
			(xy 462.439324 -396.220232) (xy 462.554568 -396.276046) (xy 462.666118 -396.338917) (xy 462.773545 -396.408601)
			(xy 462.876431 -396.484829) (xy 462.974379 -396.567306) (xy 463.06701 -396.655713) (xy 463.153966 -396.749708)
			(xy 463.23491 -396.848927) (xy 463.309529 -396.952986) (xy 463.377534 -397.061483) (xy 463.438662 -397.173998)
			(xy 463.492677 -397.290096) (xy 463.53937 -397.409327) (xy 463.57856 -397.531231) (xy 463.610096 -397.655335)
			(xy 463.633855 -397.781159) (xy 463.649745 -397.908218) (xy 463.657706 -398.036018) (xy 463.658204 -398.100042)
			(xy 463.657706 -398.164066) (xy 463.649745 -398.291866) (xy 463.633855 -398.418925) (xy 463.610096 -398.544749)
			(xy 463.57856 -398.668853) (xy 463.53937 -398.790757) (xy 463.492677 -398.909988) (xy 463.438662 -399.026086)
			(xy 463.377534 -399.138601) (xy 463.309529 -399.247098) (xy 463.23491 -399.351157) (xy 463.153966 -399.450376)
			(xy 463.06701 -399.544371) (xy 462.974379 -399.632778) (xy 462.876431 -399.715255) (xy 462.773545 -399.791483)
			(xy 462.666118 -399.861167) (xy 462.554568 -399.924038) (xy 462.439324 -399.979852) (xy 462.320833 -400.028394)
			(xy 462.199554 -400.069475) (xy 462.075955 -400.102937) (xy 461.950516 -400.12865) (xy 461.82372 -400.146514)
			(xy 461.696059 -400.156462) (xy 461.568026 -400.158453) (xy 461.440117 -400.152481) (xy 461.312827 -400.138568)
			(xy 461.186649 -400.116769) (xy 461.062069 -400.087167) (xy 460.939571 -400.049878) (xy 460.819628 -400.005045)
			(xy 460.702704 -399.952841) (xy 460.589252 -399.89347) (xy 460.479711 -399.827161) (xy 460.374503 -399.754169)
			(xy 460.274038 -399.674778) (xy 460.178702 -399.589295) (xy 460.088865 -399.49805) (xy 460.004875 -399.401396)
			(xy 459.927056 -399.299708) (xy 459.855709 -399.193378) (xy 459.791111 -399.082819) (xy 459.733511 -398.968457)
			(xy 459.683133 -398.850736) (xy 459.640171 -398.73011) (xy 459.604791 -398.607047) (xy 459.57713 -398.482022)
			(xy 459.557296 -398.355519) (xy 459.545364 -398.228028) (xy 459.541382 -398.100042) (xy 440.885326 -398.100042)
			(xy 440.885326 -400.78787) (xy 446.249042 -400.78787) (xy 446.253113 -400.732248) (xy 446.265239 -400.677811)
			(xy 446.285162 -400.62572) (xy 446.312458 -400.577085) (xy 446.346544 -400.532942) (xy 446.386693 -400.494233)
			(xy 446.432051 -400.461782) (xy 446.481651 -400.436281) (xy 446.534435 -400.418274) (xy 446.589278 -400.408144)
			(xy 446.645012 -400.406107) (xy 446.700449 -400.412207) (xy 446.754406 -400.426313) (xy 446.805735 -400.448125)
			(xy 446.853341 -400.477179) (xy 446.896209 -400.512854) (xy 446.933426 -400.554391) (xy 446.964199 -400.600904)
			(xy 446.987871 -400.651401) (xy 447.003939 -400.704808) (xy 447.012059 -400.759984) (xy 447.012568 -400.78787)
			(xy 447.012059 -400.815756) (xy 447.003939 -400.870932) (xy 446.987871 -400.924339) (xy 446.964199 -400.974836)
			(xy 446.933426 -401.021349) (xy 446.896209 -401.062886) (xy 446.853341 -401.098561) (xy 446.805735 -401.127615)
			(xy 446.754406 -401.149427) (xy 446.700449 -401.163533) (xy 446.645012 -401.169633) (xy 446.589278 -401.167596)
			(xy 446.534435 -401.157466) (xy 446.481651 -401.139459) (xy 446.432051 -401.113958) (xy 446.386693 -401.081507)
			(xy 446.346544 -401.042798) (xy 446.312458 -400.998655) (xy 446.285162 -400.95002) (xy 446.265239 -400.897929)
			(xy 446.253113 -400.843492) (xy 446.249042 -400.78787) (xy 440.885326 -400.78787) (xy 440.885326 -401.370292)
			(xy 448.261484 -401.370292) (xy 448.265555 -401.31467) (xy 448.277681 -401.260233) (xy 448.297604 -401.208142)
			(xy 448.3249 -401.159507) (xy 448.358986 -401.115364) (xy 448.399135 -401.076655) (xy 448.444493 -401.044204)
			(xy 448.494093 -401.018703) (xy 448.546877 -401.000696) (xy 448.60172 -400.990566) (xy 448.657454 -400.988529)
			(xy 448.712891 -400.994629) (xy 448.766848 -401.008735) (xy 448.818177 -401.030547) (xy 448.865783 -401.059601)
			(xy 448.908651 -401.095276) (xy 448.945868 -401.136813) (xy 448.976641 -401.183326) (xy 449.000313 -401.233823)
			(xy 449.016381 -401.28723) (xy 449.024501 -401.342406) (xy 449.02501 -401.370292) (xy 449.024501 -401.398178)
			(xy 449.016381 -401.453354) (xy 449.000313 -401.506761) (xy 448.976641 -401.557258) (xy 448.945868 -401.603771)
			(xy 448.908651 -401.645308) (xy 448.865783 -401.680983) (xy 448.818177 -401.710037) (xy 448.766848 -401.731849)
			(xy 448.712891 -401.745955) (xy 448.657454 -401.752055) (xy 448.60172 -401.750018) (xy 448.546877 -401.739888)
			(xy 448.494093 -401.721881) (xy 448.444493 -401.69638) (xy 448.399135 -401.663929) (xy 448.358986 -401.62522)
			(xy 448.3249 -401.581077) (xy 448.297604 -401.532442) (xy 448.277681 -401.480351) (xy 448.265555 -401.425914)
			(xy 448.261484 -401.370292) (xy 440.885326 -401.370292) (xy 440.885326 -404.042626) (xy 446.93027 -404.042626)
			(xy 446.934341 -403.987004) (xy 446.946467 -403.932567) (xy 446.96639 -403.880476) (xy 446.993686 -403.831841)
			(xy 447.027772 -403.787698) (xy 447.067921 -403.748989) (xy 447.113279 -403.716538) (xy 447.162879 -403.691037)
			(xy 447.215663 -403.67303) (xy 447.270506 -403.6629) (xy 447.32624 -403.660863) (xy 447.381677 -403.666963)
			(xy 447.435634 -403.681069) (xy 447.486963 -403.702881) (xy 447.534569 -403.731935) (xy 447.577437 -403.76761)
			(xy 447.614654 -403.809147) (xy 447.645427 -403.85566) (xy 447.669099 -403.906157) (xy 447.685167 -403.959564)
			(xy 447.693287 -404.01474) (xy 447.693796 -404.042626) (xy 447.693287 -404.070512) (xy 447.685167 -404.125688)
			(xy 447.669099 -404.179095) (xy 447.645427 -404.229592) (xy 447.614654 -404.276105) (xy 447.577437 -404.317642)
			(xy 447.534569 -404.353317) (xy 447.486963 -404.382371) (xy 447.435634 -404.404183) (xy 447.381677 -404.418289)
			(xy 447.32624 -404.424389) (xy 447.270506 -404.422352) (xy 447.215663 -404.412222) (xy 447.162879 -404.394215)
			(xy 447.113279 -404.368714) (xy 447.067921 -404.336263) (xy 447.027772 -404.297554) (xy 446.993686 -404.253411)
			(xy 446.96639 -404.204776) (xy 446.946467 -404.152685) (xy 446.934341 -404.098248) (xy 446.93027 -404.042626)
			(xy 440.885326 -404.042626) (xy 440.885326 -406.153366) (xy 446.64452 -406.153366) (xy 446.648591 -406.097744)
			(xy 446.660717 -406.043307) (xy 446.68064 -405.991216) (xy 446.707936 -405.942581) (xy 446.742022 -405.898438)
			(xy 446.782171 -405.859729) (xy 446.827529 -405.827278) (xy 446.877129 -405.801777) (xy 446.929913 -405.78377)
			(xy 446.984756 -405.77364) (xy 447.04049 -405.771603) (xy 447.095927 -405.777703) (xy 447.149884 -405.791809)
			(xy 447.201213 -405.813621) (xy 447.248819 -405.842675) (xy 447.291687 -405.87835) (xy 447.328904 -405.919887)
			(xy 447.359677 -405.9664) (xy 447.383349 -406.016897) (xy 447.399417 -406.070304) (xy 447.407537 -406.12548)
			(xy 447.408046 -406.153366) (xy 447.407537 -406.181252) (xy 447.399417 -406.236428) (xy 447.387573 -406.275794)
			(xy 447.938142 -406.275794) (xy 447.942213 -406.220172) (xy 447.954339 -406.165735) (xy 447.974262 -406.113644)
			(xy 448.001558 -406.065009) (xy 448.035644 -406.020866) (xy 448.075793 -405.982157) (xy 448.121151 -405.949706)
			(xy 448.170751 -405.924205) (xy 448.223535 -405.906198) (xy 448.278378 -405.896068) (xy 448.334112 -405.894031)
			(xy 448.389549 -405.900131) (xy 448.443506 -405.914237) (xy 448.494835 -405.936049) (xy 448.542441 -405.965103)
			(xy 448.585309 -406.000778) (xy 448.622526 -406.042315) (xy 448.653299 -406.088828) (xy 448.676971 -406.139325)
			(xy 448.693039 -406.192732) (xy 448.701159 -406.247908) (xy 448.701668 -406.275794) (xy 448.701159 -406.30368)
			(xy 448.693039 -406.358856) (xy 448.676971 -406.412263) (xy 448.653299 -406.46276) (xy 448.622526 -406.509273)
			(xy 448.585309 -406.55081) (xy 448.542441 -406.586485) (xy 448.494835 -406.615539) (xy 448.443506 -406.637351)
			(xy 448.389549 -406.651457) (xy 448.334112 -406.657557) (xy 448.278378 -406.65552) (xy 448.223535 -406.64539)
			(xy 448.170751 -406.627383) (xy 448.121151 -406.601882) (xy 448.075793 -406.569431) (xy 448.035644 -406.530722)
			(xy 448.001558 -406.486579) (xy 447.974262 -406.437944) (xy 447.954339 -406.385853) (xy 447.942213 -406.331416)
			(xy 447.938142 -406.275794) (xy 447.387573 -406.275794) (xy 447.383349 -406.289835) (xy 447.359677 -406.340332)
			(xy 447.328904 -406.386845) (xy 447.291687 -406.428382) (xy 447.248819 -406.464057) (xy 447.201213 -406.493111)
			(xy 447.149884 -406.514923) (xy 447.095927 -406.529029) (xy 447.04049 -406.535129) (xy 446.984756 -406.533092)
			(xy 446.929913 -406.522962) (xy 446.877129 -406.504955) (xy 446.827529 -406.479454) (xy 446.782171 -406.447003)
			(xy 446.742022 -406.408294) (xy 446.707936 -406.364151) (xy 446.68064 -406.315516) (xy 446.660717 -406.263425)
			(xy 446.648591 -406.208988) (xy 446.64452 -406.153366) (xy 440.885326 -406.153366) (xy 440.885326 -411.900116)
			(xy 444.291972 -411.900116) (xy 444.296043 -411.844494) (xy 444.308169 -411.790057) (xy 444.328092 -411.737966)
			(xy 444.355388 -411.689331) (xy 444.389474 -411.645188) (xy 444.429623 -411.606479) (xy 444.474981 -411.574028)
			(xy 444.524581 -411.548527) (xy 444.577365 -411.53052) (xy 444.632208 -411.52039) (xy 444.687942 -411.518353)
			(xy 444.743379 -411.524453) (xy 444.797336 -411.538559) (xy 444.848665 -411.560371) (xy 444.896271 -411.589425)
			(xy 444.939139 -411.6251) (xy 444.976356 -411.666637) (xy 445.007129 -411.71315) (xy 445.030801 -411.763647)
			(xy 445.046869 -411.817054) (xy 445.054989 -411.87223) (xy 445.055498 -411.900116) (xy 445.054989 -411.928002)
			(xy 445.046869 -411.983178) (xy 445.030801 -412.036585) (xy 445.007129 -412.087082) (xy 444.976356 -412.133595)
			(xy 444.939139 -412.175132) (xy 444.896271 -412.210807) (xy 444.848665 -412.239861) (xy 444.797336 -412.261673)
			(xy 444.743379 -412.275779) (xy 444.687942 -412.281879) (xy 444.632208 -412.279842) (xy 444.577365 -412.269712)
			(xy 444.524581 -412.251705) (xy 444.474981 -412.226204) (xy 444.429623 -412.193753) (xy 444.389474 -412.155044)
			(xy 444.355388 -412.110901) (xy 444.328092 -412.062266) (xy 444.308169 -412.010175) (xy 444.296043 -411.955738)
			(xy 444.291972 -411.900116) (xy 440.885326 -411.900116) (xy 440.885326 -413.037782) (xy 440.88482 -413.047832)
			(xy 440.877098 -413.066392) (xy 440.87034 -413.07385) (xy 440.45505 -413.48914) (xy 440.447652 -413.495985)
			(xy 440.429053 -413.503711) (xy 440.418982 -413.504126) (xy 439.067702 -413.504126) (xy 439.061606 -413.50438)
			(xy 439.053526 -413.505653) (xy 439.038748 -413.512645) (xy 439.03265 -413.518096) (xy 438.960514 -413.590486)
			(xy 438.329578 -414.221422) (xy 438.311362 -414.238976) (xy 438.270438 -414.268711) (xy 438.225364 -414.291674)
			(xy 438.177252 -414.307298) (xy 438.127287 -414.3152) (xy 438.101994 -414.315656) (xy 437.163464 -414.315656)
			(xy 437.154019 -414.316145) (xy 437.13643 -414.323052) (xy 437.129174 -414.329118) (xy 437.110688 -414.345582)
			(xy 437.06975 -414.37341) (xy 437.025133 -414.394849) (xy 436.996098 -414.403794) (xy 447.176396 -414.403794)
			(xy 447.180467 -414.348172) (xy 447.192593 -414.293735) (xy 447.212516 -414.241644) (xy 447.239812 -414.193009)
			(xy 447.273898 -414.148866) (xy 447.314047 -414.110157) (xy 447.359405 -414.077706) (xy 447.409005 -414.052205)
			(xy 447.461789 -414.034198) (xy 447.516632 -414.024068) (xy 447.572366 -414.022031) (xy 447.627803 -414.028131)
			(xy 447.68176 -414.042237) (xy 447.733089 -414.064049) (xy 447.780695 -414.093103) (xy 447.823563 -414.128778)
			(xy 447.86078 -414.170315) (xy 447.891553 -414.216828) (xy 447.915225 -414.267325) (xy 447.931293 -414.320732)
			(xy 447.939413 -414.375908) (xy 447.939922 -414.403794) (xy 447.939413 -414.43168) (xy 447.931293 -414.486856)
			(xy 447.915225 -414.540263) (xy 447.891801 -414.59023) (xy 448.79717 -414.59023) (xy 448.801241 -414.534608)
			(xy 448.813367 -414.480171) (xy 448.83329 -414.42808) (xy 448.860586 -414.379445) (xy 448.894672 -414.335302)
			(xy 448.934821 -414.296593) (xy 448.980179 -414.264142) (xy 449.029779 -414.238641) (xy 449.082563 -414.220634)
			(xy 449.137406 -414.210504) (xy 449.19314 -414.208467) (xy 449.248577 -414.214567) (xy 449.302534 -414.228673)
			(xy 449.353863 -414.250485) (xy 449.401469 -414.279539) (xy 449.444337 -414.315214) (xy 449.461574 -414.334452)
			(xy 450.168262 -414.334452) (xy 450.172333 -414.27883) (xy 450.184459 -414.224393) (xy 450.204382 -414.172302)
			(xy 450.231678 -414.123667) (xy 450.265764 -414.079524) (xy 450.305913 -414.040815) (xy 450.351271 -414.008364)
			(xy 450.400871 -413.982863) (xy 450.453655 -413.964856) (xy 450.508498 -413.954726) (xy 450.564232 -413.952689)
			(xy 450.619669 -413.958789) (xy 450.673626 -413.972895) (xy 450.724955 -413.994707) (xy 450.772561 -414.023761)
			(xy 450.815429 -414.059436) (xy 450.852646 -414.100973) (xy 450.883419 -414.147486) (xy 450.907091 -414.197983)
			(xy 450.923159 -414.25139) (xy 450.931279 -414.306566) (xy 450.931788 -414.334452) (xy 450.931279 -414.362338)
			(xy 450.923159 -414.417514) (xy 450.907091 -414.470921) (xy 450.883419 -414.521418) (xy 450.852646 -414.567931)
			(xy 450.815429 -414.609468) (xy 450.772561 -414.645143) (xy 450.724955 -414.674197) (xy 450.673626 -414.696009)
			(xy 450.619669 -414.710115) (xy 450.564232 -414.716215) (xy 450.508498 -414.714178) (xy 450.453655 -414.704048)
			(xy 450.400871 -414.686041) (xy 450.351271 -414.66054) (xy 450.305913 -414.628089) (xy 450.265764 -414.58938)
			(xy 450.231678 -414.545237) (xy 450.204382 -414.496602) (xy 450.184459 -414.444511) (xy 450.172333 -414.390074)
			(xy 450.168262 -414.334452) (xy 449.461574 -414.334452) (xy 449.481554 -414.356751) (xy 449.512327 -414.403264)
			(xy 449.535999 -414.453761) (xy 449.552067 -414.507168) (xy 449.560187 -414.562344) (xy 449.560696 -414.59023)
			(xy 449.560187 -414.618116) (xy 449.552067 -414.673292) (xy 449.535999 -414.726699) (xy 449.512327 -414.777196)
			(xy 449.481554 -414.823709) (xy 449.444337 -414.865246) (xy 449.401469 -414.900921) (xy 449.353863 -414.929975)
			(xy 449.302534 -414.951787) (xy 449.248577 -414.965893) (xy 449.19314 -414.971993) (xy 449.137406 -414.969956)
			(xy 449.082563 -414.959826) (xy 449.029779 -414.941819) (xy 448.980179 -414.916318) (xy 448.934821 -414.883867)
			(xy 448.894672 -414.845158) (xy 448.860586 -414.801015) (xy 448.83329 -414.75238) (xy 448.813367 -414.700289)
			(xy 448.801241 -414.645852) (xy 448.79717 -414.59023) (xy 447.891801 -414.59023) (xy 447.891553 -414.59076)
			(xy 447.86078 -414.637273) (xy 447.823563 -414.67881) (xy 447.780695 -414.714485) (xy 447.733089 -414.743539)
			(xy 447.68176 -414.765351) (xy 447.627803 -414.779457) (xy 447.572366 -414.785557) (xy 447.516632 -414.78352)
			(xy 447.461789 -414.77339) (xy 447.409005 -414.755383) (xy 447.359405 -414.729882) (xy 447.314047 -414.697431)
			(xy 447.273898 -414.658722) (xy 447.239812 -414.614579) (xy 447.212516 -414.565944) (xy 447.192593 -414.513853)
			(xy 447.180467 -414.459416) (xy 447.176396 -414.403794) (xy 436.996098 -414.403794) (xy 436.977827 -414.409423)
			(xy 436.92888 -414.416809) (xy 436.90413 -414.417256) (xy 418.657532 -414.417256) (xy 418.631444 -414.416772)
			(xy 418.57991 -414.40861) (xy 418.530289 -414.392481) (xy 418.483804 -414.368784) (xy 418.441602 -414.338103)
			(xy 418.422836 -414.319974) (xy 417.621974 -413.519112) (xy 417.614575 -413.512268) (xy 417.595976 -413.504542)
			(xy 417.585906 -413.504126) (xy 414.881822 -413.504126) (xy 414.871759 -413.504564) (xy 414.853177 -413.512301)
			(xy 414.845754 -413.519112) (xy 414.62325 -413.741616) (xy 414.615853 -413.748464) (xy 414.597254 -413.756193)
			(xy 414.587182 -413.756602) (xy 414.57626 -413.756602) (xy 414.566258 -413.757097) (xy 414.54778 -413.764764)
			(xy 414.53364 -413.778915) (xy 414.525989 -413.797399) (xy 414.52546 -413.807402) (xy 414.52546 -416.903662)
			(xy 414.525941 -416.913678) (xy 414.533592 -416.932189) (xy 414.547745 -416.946364) (xy 414.566245 -416.954044)
			(xy 414.57626 -416.954462) (xy 446.715134 -416.954462)
		)
		(stroke
			(width 0)
			(type solid)
		)
		(fill yes)
		(layer "In9.Cu")
		(net "GND")
	)
	(gr_poly
		(pts
			(xy 402.522436 -369.349528) (xy 402.532504 -369.349099) (xy 402.551102 -369.341379) (xy 402.558504 -369.334542)
			(xy 402.871686 -369.02136) (xy 402.878528 -369.01396) (xy 402.88625 -368.995362) (xy 402.886672 -368.985292)
			(xy 402.886672 -358.190292) (xy 402.88625 -358.180274) (xy 402.878578 -358.161765) (xy 402.864405 -358.147602)
			(xy 402.84589 -358.139942) (xy 402.835872 -358.139492) (xy 402.27758 -358.139492) (xy 402.250309 -358.139004)
			(xy 402.196324 -358.13124) (xy 402.143993 -358.115871) (xy 402.094381 -358.093212) (xy 402.048499 -358.063723)
			(xy 402.00728 -358.028005) (xy 401.971565 -357.986785) (xy 401.942078 -357.940901) (xy 401.919422 -357.891289)
			(xy 401.904056 -357.838957) (xy 401.896294 -357.784971) (xy 401.896294 -357.730429) (xy 401.904056 -357.676443)
			(xy 401.919422 -357.624111) (xy 401.942078 -357.574499) (xy 401.971565 -357.528615) (xy 402.00728 -357.487395)
			(xy 402.048499 -357.451677) (xy 402.094381 -357.422188) (xy 402.143993 -357.399529) (xy 402.196324 -357.38416)
			(xy 402.250309 -357.376396) (xy 402.27758 -357.375968) (xy 402.835872 -357.375968) (xy 402.845895 -357.375553)
			(xy 402.864416 -357.367887) (xy 402.878589 -357.353712) (xy 402.886253 -357.335191) (xy 402.886672 -357.325168)
			(xy 402.886672 -356.083362) (xy 402.665946 -355.152706) (xy 402.662673 -355.141858) (xy 402.648401 -355.124296)
			(xy 402.627983 -355.114537) (xy 402.61667 -355.113844) (xy 402.27758 -355.113844) (xy 402.250313 -355.113356)
			(xy 402.196334 -355.105593) (xy 402.144009 -355.090226) (xy 402.094404 -355.06757) (xy 402.048528 -355.038085)
			(xy 402.007314 -355.002371) (xy 401.971603 -354.961156) (xy 401.94212 -354.915278) (xy 401.919467 -354.865672)
			(xy 401.904103 -354.813346) (xy 401.896342 -354.759367) (xy 401.896342 -354.704833) (xy 401.904103 -354.650854)
			(xy 401.919467 -354.598528) (xy 401.94212 -354.548922) (xy 401.971603 -354.503044) (xy 402.007314 -354.461829)
			(xy 402.048528 -354.426115) (xy 402.094404 -354.39663) (xy 402.144009 -354.373974) (xy 402.196334 -354.358607)
			(xy 402.250313 -354.350844) (xy 402.27758 -354.35032) (xy 402.411438 -354.35032) (xy 402.422946 -354.349836)
			(xy 402.443709 -354.339918) (xy 402.451316 -354.33127) (xy 402.458682 -354.321872) (xy 402.463762 -354.29952)
			(xy 402.06549 -352.620834) (xy 402.042884 -352.600006) (xy 402.027136 -352.59772) (xy 401.999383 -352.592995)
			(xy 401.94573 -352.575952) (xy 401.895423 -352.550685) (xy 401.849714 -352.517825) (xy 401.809739 -352.478187)
			(xy 401.776493 -352.432759) (xy 401.750801 -352.382668) (xy 401.733303 -352.329161) (xy 401.724434 -352.273569)
			(xy 401.72386 -352.245422) (xy 401.72447 -352.21531) (xy 401.734562 -352.155938) (xy 401.743926 -352.127312)
			(xy 401.748244 -352.115374) (xy 401.74418 -352.090228) (xy 401.677632 -352.00209) (xy 401.654264 -351.991676)
			(xy 401.641564 -351.992438) (xy 401.616926 -351.9932) (xy 400.753326 -351.9932) (xy 400.72879 -351.992819)
			(xy 400.680122 -351.986533) (xy 400.632658 -351.974075) (xy 400.587176 -351.955649) (xy 400.56562 -351.943924)
			(xy 400.561618 -351.941811) (xy 400.553057 -351.938878) (xy 400.548602 -351.938082) (xy 400.521881 -351.933196)
			(xy 400.470401 -351.91587) (xy 400.422439 -351.890374) (xy 400.40052 -351.874328) (xy 400.393055 -351.869075)
			(xy 400.375611 -351.863742) (xy 400.366484 -351.863914) (xy 400.335242 -351.865946) (xy 400.326045 -351.866936)
			(xy 400.309236 -351.874619) (xy 400.302476 -351.880932) (xy 400.280868 -351.901827) (xy 400.232298 -351.937235)
			(xy 400.178779 -351.964591) (xy 400.121633 -351.98322) (xy 400.062273 -351.99266) (xy 400.03222 -351.9932)
			(xy 399.16862 -351.9932) (xy 399.141345 -351.992738) (xy 399.087351 -351.984977) (xy 399.035011 -351.969611)
			(xy 398.98539 -351.946952) (xy 398.939499 -351.917462) (xy 398.898273 -351.881741) (xy 398.86255 -351.840517)
			(xy 398.833057 -351.794628) (xy 398.810396 -351.745008) (xy 398.795027 -351.692669) (xy 398.787264 -351.638675)
			(xy 398.787264 -351.584125) (xy 398.795027 -351.530131) (xy 398.810396 -351.477792) (xy 398.833057 -351.428172)
			(xy 398.86255 -351.382283) (xy 398.898273 -351.341059) (xy 398.939499 -351.305338) (xy 398.98539 -351.275848)
			(xy 399.035011 -351.253189) (xy 399.087351 -351.237823) (xy 399.141345 -351.230062) (xy 399.16862 -351.229676)
			(xy 400.03222 -351.229676) (xy 400.062274 -351.230233) (xy 400.12164 -351.239651) (xy 400.178793 -351.258266)
			(xy 400.232318 -351.285617) (xy 400.28089 -351.321026) (xy 400.302476 -351.341944) (xy 400.309268 -351.348209)
			(xy 400.326061 -351.355887) (xy 400.335242 -351.35693) (xy 400.366484 -351.358962) (xy 400.375608 -351.359129)
			(xy 400.393044 -351.353783) (xy 400.40052 -351.348548) (xy 400.422426 -351.332482) (xy 400.470388 -351.306983)
			(xy 400.521879 -351.28968) (xy 400.548602 -351.284794) (xy 400.553063 -351.284021) (xy 400.561626 -351.281084)
			(xy 400.56562 -351.278952) (xy 400.587172 -351.267216) (xy 400.632647 -351.248768) (xy 400.680114 -351.23631)
			(xy 400.728788 -351.230051) (xy 400.753326 -351.229676) (xy 401.616926 -351.229676) (xy 401.641564 -351.230438)
			(xy 401.654264 -351.2312) (xy 401.677632 -351.220786) (xy 401.74418 -351.132648) (xy 401.748244 -351.107502)
			(xy 401.743926 -351.095564) (xy 401.734552 -351.066941) (xy 401.724461 -351.007567) (xy 401.72386 -350.977454)
			(xy 401.724337 -350.95112) (xy 401.732096 -350.899026) (xy 401.747439 -350.848642) (xy 401.770031 -350.801065)
			(xy 401.79938 -350.757331) (xy 401.834846 -350.718394) (xy 401.875658 -350.685102) (xy 401.920925 -350.658179)
			(xy 401.969662 -350.638213) (xy 401.995132 -350.631506) (xy 402.012404 -350.627442) (xy 402.03374 -350.60001)
			(xy 402.03374 -349.597218) (xy 402.012404 -349.569786) (xy 401.995132 -349.565722) (xy 401.969663 -349.558995)
			(xy 401.920905 -349.539062) (xy 401.875618 -349.51216) (xy 401.834789 -349.478878) (xy 401.799312 -349.439941)
			(xy 401.76996 -349.396202) (xy 401.747375 -349.348614) (xy 401.73205 -349.298217) (xy 401.72432 -349.246112)
			(xy 401.72386 -349.219774) (xy 401.724466 -349.189661) (xy 401.73455 -349.130286) (xy 401.743926 -349.101664)
			(xy 401.748244 -349.089726) (xy 401.74418 -349.06458) (xy 401.677632 -348.976442) (xy 401.654264 -348.966028)
			(xy 401.641564 -348.96679) (xy 401.616926 -348.967552) (xy 400.753326 -348.967552) (xy 400.728791 -348.967154)
			(xy 400.680125 -348.96087) (xy 400.632662 -348.948414) (xy 400.587181 -348.929991) (xy 400.56562 -348.918276)
			(xy 400.561618 -348.916162) (xy 400.553058 -348.913225) (xy 400.548602 -348.912434) (xy 400.52188 -348.907549)
			(xy 400.470399 -348.890225) (xy 400.422435 -348.864732) (xy 400.40052 -348.84868) (xy 400.393054 -348.84343)
			(xy 400.37561 -348.838103) (xy 400.366484 -348.838266) (xy 400.335242 -348.840298) (xy 400.326046 -348.84129)
			(xy 400.309242 -348.848978) (xy 400.302476 -348.855284) (xy 400.280867 -348.876176) (xy 400.232296 -348.911579)
			(xy 400.178776 -348.938932) (xy 400.12163 -348.957558) (xy 400.062272 -348.966997) (xy 400.03222 -348.967552)
			(xy 399.16862 -348.967552) (xy 399.141349 -348.96709) (xy 399.087361 -348.95933) (xy 399.035027 -348.943966)
			(xy 398.985413 -348.92131) (xy 398.939528 -348.891824) (xy 398.898307 -348.856107) (xy 398.862588 -348.814888)
			(xy 398.833099 -348.769005) (xy 398.810441 -348.719391) (xy 398.795074 -348.667058) (xy 398.787312 -348.613071)
			(xy 398.787312 -348.558529) (xy 398.795074 -348.504542) (xy 398.810441 -348.452209) (xy 398.833099 -348.402595)
			(xy 398.862588 -348.356712) (xy 398.898307 -348.315493) (xy 398.939528 -348.279776) (xy 398.985413 -348.25029)
			(xy 399.035027 -348.227634) (xy 399.087361 -348.21227) (xy 399.141349 -348.20451) (xy 399.16862 -348.204028)
			(xy 400.03222 -348.204028) (xy 400.062275 -348.204585) (xy 400.121641 -348.214002) (xy 400.178796 -348.232615)
			(xy 400.232323 -348.259963) (xy 400.280897 -348.29537) (xy 400.302476 -348.316296) (xy 400.309265 -348.322566)
			(xy 400.326058 -348.330251) (xy 400.335242 -348.331282) (xy 400.366484 -348.333314) (xy 400.375609 -348.333481)
			(xy 400.393047 -348.32814) (xy 400.40052 -348.3229) (xy 400.422425 -348.306832) (xy 400.470386 -348.281329)
			(xy 400.521877 -348.264023) (xy 400.548602 -348.259146) (xy 400.553063 -348.258373) (xy 400.561624 -348.255433)
			(xy 400.56562 -348.253304) (xy 400.587173 -348.24157) (xy 400.632648 -348.223123) (xy 400.680115 -348.210668)
			(xy 400.728789 -348.204409) (xy 400.753326 -348.204028) (xy 401.43176 -348.204028) (xy 401.440652 -348.203694)
			(xy 401.457361 -348.197609) (xy 401.47097 -348.186164) (xy 401.475702 -348.178628) (xy 401.491196 -348.152212)
			(xy 401.496875 -348.141174) (xy 401.497814 -348.116398) (xy 401.492974 -348.104968) (xy 401.482056 -348.080928)
			(xy 401.466652 -348.030428) (xy 401.458885 -347.978205) (xy 401.45843 -347.951806) (xy 401.45843 -347.951298)
			(xy 401.458699 -347.932289) (xy 401.462771 -347.89449) (xy 401.466558 -347.87586) (xy 401.467995 -347.8674)
			(xy 401.4658 -347.850392) (xy 401.46224 -347.842586) (xy 401.449032 -347.815916) (xy 401.444754 -347.808017)
			(xy 401.431739 -347.795654) (xy 401.423632 -347.791786) (xy 401.380261 -347.772527) (xy 401.297028 -347.726933)
			(xy 401.218501 -347.673642) (xy 401.145389 -347.613134) (xy 401.111466 -347.57995) (xy 400.76247 -347.230446)
			(xy 400.755125 -347.223635) (xy 400.736662 -347.215907) (xy 400.726656 -347.21546) (xy 399.424144 -347.21546)
			(xy 399.414079 -347.215025) (xy 399.395493 -347.207292) (xy 399.388076 -347.200474) (xy 398.801082 -346.61348)
			(xy 398.79423 -346.606084) (xy 398.78649 -346.587485) (xy 398.786096 -346.577412) (xy 398.786096 -346.430854)
			(xy 398.785395 -346.418696) (xy 398.774251 -346.397084) (xy 398.76476 -346.389452) (xy 398.743727 -346.373949)
			(xy 398.706007 -346.337792) (xy 398.673975 -346.296512) (xy 398.648319 -346.250995) (xy 398.629588 -346.202218)
			(xy 398.618186 -346.151227) (xy 398.614356 -346.099117) (xy 398.61818 -346.047007) (xy 398.629578 -345.996016)
			(xy 398.648304 -345.947236) (xy 398.673956 -345.901717) (xy 398.705984 -345.860433) (xy 398.7437 -345.824273)
			(xy 398.76476 -345.808808) (xy 398.774267 -345.801192) (xy 398.785402 -345.779568) (xy 398.786096 -345.767406)
			(xy 398.786096 -345.162886) (xy 398.785402 -345.150725) (xy 398.774265 -345.129101) (xy 398.76476 -345.121484)
			(xy 398.743732 -345.105981) (xy 398.706022 -345.069826) (xy 398.674 -345.028549) (xy 398.648353 -344.983036)
			(xy 398.62963 -344.934264) (xy 398.618235 -344.88328) (xy 398.614411 -344.831178) (xy 398.618242 -344.779077)
			(xy 398.629643 -344.728094) (xy 398.648371 -344.679324) (xy 398.674025 -344.633815) (xy 398.706052 -344.592542)
			(xy 398.743766 -344.556391) (xy 398.76476 -344.54084) (xy 398.774272 -344.533226) (xy 398.78542 -344.511603)
			(xy 398.786096 -344.499438) (xy 398.786096 -343.405206) (xy 398.785406 -343.393042) (xy 398.774274 -343.371411)
			(xy 398.76476 -343.363804) (xy 398.74373 -343.348301) (xy 398.706018 -343.312146) (xy 398.673993 -343.270868)
			(xy 398.648342 -343.225353) (xy 398.629618 -343.17658) (xy 398.61822 -343.125594) (xy 398.614395 -343.07349)
			(xy 398.618223 -343.021386) (xy 398.629624 -342.9704) (xy 398.648351 -342.921628) (xy 398.674004 -342.876115)
			(xy 398.706032 -342.834839) (xy 398.743746 -342.798685) (xy 398.76476 -342.78316) (xy 398.774276 -342.775548)
			(xy 398.785432 -342.753924) (xy 398.786096 -342.741758) (xy 398.786096 -342.113362) (xy 398.785397 -342.101203)
			(xy 398.774254 -342.079588) (xy 398.76476 -342.07196) (xy 398.742006 -342.055123) (xy 398.701634 -342.015453)
			(xy 398.668046 -341.969896) (xy 398.642089 -341.919598) (xy 398.624415 -341.865828) (xy 398.615471 -341.809938)
			(xy 398.6149 -341.781638) (xy 398.615322 -341.756878) (xy 398.622172 -341.707836) (xy 398.635746 -341.660213)
			(xy 398.655782 -341.614929) (xy 398.668494 -341.593678) (xy 398.674336 -341.58428) (xy 398.67713 -341.56269)
			(xy 398.650968 -341.478616) (xy 398.647227 -341.468306) (xy 398.632604 -341.451989) (xy 398.622774 -341.44712)
			(xy 396.196058 -340.385654) (xy 396.187168 -340.382606) (xy 392.746992 -339.59419) (xy 392.735562 -339.59292)
			(xy 388.84733 -339.59292) (xy 388.837265 -339.592485) (xy 388.818677 -339.584755) (xy 388.811262 -339.577934)
			(xy 388.431278 -339.19795) (xy 388.424431 -339.190553) (xy 388.416702 -339.171953) (xy 388.416292 -339.161882)
			(xy 388.416292 -338.642706) (xy 388.41587 -338.632635) (xy 388.408156 -338.61403) (xy 388.401306 -338.606638)
			(xy 388.400798 -338.60613) (xy 388.395621 -338.601315) (xy 388.383246 -338.59449) (xy 388.376414 -338.592668)
			(xy 377.593352 -336.121502) (xy 377.573872 -336.116971) (xy 377.535253 -336.106553) (xy 377.516136 -336.100674)
			(xy 373.26062 -334.758284) (xy 373.215145 -334.743358) (xy 373.127033 -334.705965) (xy 373.042913 -334.660295)
			(xy 372.963561 -334.606768) (xy 372.889708 -334.545877) (xy 372.85549 -334.512412) (xy 366.810036 -328.467212)
			(xy 366.775787 -328.432146) (xy 366.713596 -328.356375) (xy 366.659135 -328.274871) (xy 366.612929 -328.188418)
			(xy 366.593628 -328.143362) (xy 364.863888 -323.96684) (xy 364.845747 -323.921382) (xy 364.817394 -323.827697)
			(xy 364.798348 -323.731687) (xy 364.788793 -323.634273) (xy 364.788196 -323.585332) (xy 364.788196 -317.803276)
			(xy 364.78875 -317.754333) (xy 364.798293 -317.656914) (xy 364.817344 -317.5609) (xy 364.845719 -317.467217)
			(xy 364.863888 -317.421768) (xy 367.103152 -312.015124) (xy 367.104954 -312.010438) (xy 367.106879 -312.000586)
			(xy 367.106962 -311.995566) (xy 367.106962 -310.69788) (xy 367.106534 -310.687812) (xy 367.098811 -310.669217)
			(xy 367.091976 -310.661812) (xy 366.214406 -309.784242) (xy 366.207294 -309.776876) (xy 366.188498 -309.769256)
			(xy 366.11941 -309.769256) (xy 366.108996 -309.770272) (xy 366.098582 -309.772558) (xy 366.089946 -309.775098)
			(xy 366.067181 -309.783866) (xy 366.01998 -309.796198) (xy 365.971591 -309.802402) (xy 365.947198 -309.802784)
			(xy 365.94669 -309.802784) (xy 365.921518 -309.802381) (xy 365.871611 -309.795767) (xy 365.823005 -309.782654)
			(xy 365.799624 -309.77332) (xy 365.790226 -309.769256) (xy 365.10341 -309.769256) (xy 365.092996 -309.770272)
			(xy 365.082582 -309.772558) (xy 365.073946 -309.775098) (xy 365.051181 -309.783866) (xy 365.00398 -309.796198)
			(xy 364.955591 -309.802402) (xy 364.931198 -309.802784) (xy 364.93069 -309.802784) (xy 364.905518 -309.802381)
			(xy 364.855611 -309.795767) (xy 364.807005 -309.782654) (xy 364.783624 -309.77332) (xy 364.774226 -309.769256)
			(xy 364.08741 -309.769256) (xy 364.076996 -309.770272) (xy 364.066582 -309.772558) (xy 364.057946 -309.775098)
			(xy 364.035181 -309.783866) (xy 363.98798 -309.796198) (xy 363.939591 -309.802402) (xy 363.915198 -309.802784)
			(xy 363.91469 -309.802784) (xy 363.889518 -309.802381) (xy 363.839611 -309.795767) (xy 363.791005 -309.782654)
			(xy 363.767624 -309.77332) (xy 363.758226 -309.769256) (xy 363.07141 -309.769256) (xy 363.060996 -309.770272)
			(xy 363.050582 -309.772558) (xy 363.041946 -309.775098) (xy 363.019181 -309.783866) (xy 362.97198 -309.796198)
			(xy 362.923591 -309.802402) (xy 362.899198 -309.802784) (xy 362.89869 -309.802784) (xy 362.873518 -309.802381)
			(xy 362.823611 -309.795767) (xy 362.775005 -309.782654) (xy 362.751624 -309.77332) (xy 362.742226 -309.769256)
			(xy 362.05541 -309.769256) (xy 362.044996 -309.770272) (xy 362.034582 -309.772558) (xy 362.025946 -309.775098)
			(xy 362.003181 -309.783866) (xy 361.95598 -309.796198) (xy 361.907591 -309.802402) (xy 361.883198 -309.802784)
			(xy 361.88269 -309.802784) (xy 361.857518 -309.802381) (xy 361.807611 -309.795767) (xy 361.759005 -309.782654)
			(xy 361.735624 -309.77332) (xy 361.726226 -309.769256) (xy 361.03941 -309.769256) (xy 361.028996 -309.770272)
			(xy 361.018582 -309.772558) (xy 361.009946 -309.775098) (xy 360.987181 -309.783866) (xy 360.93998 -309.796198)
			(xy 360.891591 -309.802402) (xy 360.867198 -309.802784) (xy 360.86669 -309.802784) (xy 360.841518 -309.802381)
			(xy 360.791611 -309.795767) (xy 360.743005 -309.782654) (xy 360.719624 -309.77332) (xy 360.710226 -309.769256)
			(xy 360.02341 -309.769256) (xy 360.012996 -309.770272) (xy 360.002582 -309.772558) (xy 359.993946 -309.775098)
			(xy 359.971181 -309.783866) (xy 359.92398 -309.796198) (xy 359.875591 -309.802402) (xy 359.851198 -309.802784)
			(xy 359.85069 -309.802784) (xy 359.825518 -309.802381) (xy 359.775611 -309.795767) (xy 359.727005 -309.782654)
			(xy 359.703624 -309.77332) (xy 359.694226 -309.769256) (xy 359.00741 -309.769256) (xy 358.996996 -309.770272)
			(xy 358.986582 -309.772558) (xy 358.977946 -309.775098) (xy 358.955181 -309.783866) (xy 358.90798 -309.796198)
			(xy 358.859591 -309.802402) (xy 358.835198 -309.802784) (xy 358.83469 -309.802784) (xy 358.809518 -309.802381)
			(xy 358.759611 -309.795767) (xy 358.711005 -309.782654) (xy 358.687624 -309.77332) (xy 358.678226 -309.769256)
			(xy 357.99141 -309.769256) (xy 357.980996 -309.770272) (xy 357.970582 -309.772558) (xy 357.961946 -309.775098)
			(xy 357.939181 -309.783866) (xy 357.89198 -309.796198) (xy 357.843591 -309.802402) (xy 357.819198 -309.802784)
			(xy 357.81869 -309.802784) (xy 357.793518 -309.802381) (xy 357.743611 -309.795767) (xy 357.695005 -309.782654)
			(xy 357.671624 -309.77332) (xy 357.662226 -309.769256) (xy 342.506554 -309.769256) (xy 342.504776 -309.769256)
			(xy 342.495663 -309.76995) (xy 342.478796 -309.776947) (xy 342.465464 -309.789428) (xy 342.461088 -309.79745)
			(xy 342.458802 -309.803038) (xy 342.42883 -309.886604) (xy 342.425951 -309.896129) (xy 342.426874 -309.915988)
			(xy 342.430608 -309.925212) (xy 342.44153 -309.948834) (xy 342.449658 -309.955692) (xy 342.469703 -309.973904)
			(xy 342.504961 -310.015013) (xy 342.534056 -310.060692) (xy 342.556404 -310.110024) (xy 342.571556 -310.162019)
			(xy 342.579208 -310.215633) (xy 342.579706 -310.242712) (xy 342.57922 -310.269963) (xy 342.571464 -310.323911)
			(xy 342.556109 -310.376206) (xy 342.533467 -310.425783) (xy 342.526081 -310.437276) (xy 357.436926 -310.437276)
			(xy 357.440997 -310.381654) (xy 357.453123 -310.327217) (xy 357.473046 -310.275126) (xy 357.500342 -310.226491)
			(xy 357.534428 -310.182348) (xy 357.574577 -310.143639) (xy 357.619935 -310.111188) (xy 357.669535 -310.085687)
			(xy 357.722319 -310.06768) (xy 357.777162 -310.05755) (xy 357.832896 -310.055513) (xy 357.888333 -310.061613)
			(xy 357.94229 -310.075719) (xy 357.993619 -310.097531) (xy 358.041225 -310.126585) (xy 358.084093 -310.16226)
			(xy 358.12131 -310.203797) (xy 358.152083 -310.25031) (xy 358.175755 -310.300807) (xy 358.191823 -310.354214)
			(xy 358.199943 -310.40939) (xy 358.200452 -310.437276) (xy 358.452926 -310.437276) (xy 358.456997 -310.381654)
			(xy 358.469123 -310.327217) (xy 358.489046 -310.275126) (xy 358.516342 -310.226491) (xy 358.550428 -310.182348)
			(xy 358.590577 -310.143639) (xy 358.635935 -310.111188) (xy 358.685535 -310.085687) (xy 358.738319 -310.06768)
			(xy 358.793162 -310.05755) (xy 358.848896 -310.055513) (xy 358.904333 -310.061613) (xy 358.95829 -310.075719)
			(xy 359.009619 -310.097531) (xy 359.057225 -310.126585) (xy 359.100093 -310.16226) (xy 359.13731 -310.203797)
			(xy 359.168083 -310.25031) (xy 359.191755 -310.300807) (xy 359.207823 -310.354214) (xy 359.215943 -310.40939)
			(xy 359.216452 -310.437276) (xy 359.468926 -310.437276) (xy 359.472997 -310.381654) (xy 359.485123 -310.327217)
			(xy 359.505046 -310.275126) (xy 359.532342 -310.226491) (xy 359.566428 -310.182348) (xy 359.606577 -310.143639)
			(xy 359.651935 -310.111188) (xy 359.701535 -310.085687) (xy 359.754319 -310.06768) (xy 359.809162 -310.05755)
			(xy 359.864896 -310.055513) (xy 359.920333 -310.061613) (xy 359.97429 -310.075719) (xy 360.025619 -310.097531)
			(xy 360.073225 -310.126585) (xy 360.116093 -310.16226) (xy 360.15331 -310.203797) (xy 360.184083 -310.25031)
			(xy 360.207755 -310.300807) (xy 360.223823 -310.354214) (xy 360.231943 -310.40939) (xy 360.232452 -310.437276)
			(xy 360.484926 -310.437276) (xy 360.488997 -310.381654) (xy 360.501123 -310.327217) (xy 360.521046 -310.275126)
			(xy 360.548342 -310.226491) (xy 360.582428 -310.182348) (xy 360.622577 -310.143639) (xy 360.667935 -310.111188)
			(xy 360.717535 -310.085687) (xy 360.770319 -310.06768) (xy 360.825162 -310.05755) (xy 360.880896 -310.055513)
			(xy 360.936333 -310.061613) (xy 360.99029 -310.075719) (xy 361.041619 -310.097531) (xy 361.089225 -310.126585)
			(xy 361.132093 -310.16226) (xy 361.16931 -310.203797) (xy 361.200083 -310.25031) (xy 361.223755 -310.300807)
			(xy 361.239823 -310.354214) (xy 361.247943 -310.40939) (xy 361.248452 -310.437276) (xy 361.500926 -310.437276)
			(xy 361.504997 -310.381654) (xy 361.517123 -310.327217) (xy 361.537046 -310.275126) (xy 361.564342 -310.226491)
			(xy 361.598428 -310.182348) (xy 361.638577 -310.143639) (xy 361.683935 -310.111188) (xy 361.733535 -310.085687)
			(xy 361.786319 -310.06768) (xy 361.841162 -310.05755) (xy 361.896896 -310.055513) (xy 361.952333 -310.061613)
			(xy 362.00629 -310.075719) (xy 362.057619 -310.097531) (xy 362.105225 -310.126585) (xy 362.148093 -310.16226)
			(xy 362.18531 -310.203797) (xy 362.216083 -310.25031) (xy 362.239755 -310.300807) (xy 362.255823 -310.354214)
			(xy 362.263943 -310.40939) (xy 362.264452 -310.437276) (xy 362.516926 -310.437276) (xy 362.520997 -310.381654)
			(xy 362.533123 -310.327217) (xy 362.553046 -310.275126) (xy 362.580342 -310.226491) (xy 362.614428 -310.182348)
			(xy 362.654577 -310.143639) (xy 362.699935 -310.111188) (xy 362.749535 -310.085687) (xy 362.802319 -310.06768)
			(xy 362.857162 -310.05755) (xy 362.912896 -310.055513) (xy 362.968333 -310.061613) (xy 363.02229 -310.075719)
			(xy 363.073619 -310.097531) (xy 363.121225 -310.126585) (xy 363.164093 -310.16226) (xy 363.20131 -310.203797)
			(xy 363.232083 -310.25031) (xy 363.255755 -310.300807) (xy 363.271823 -310.354214) (xy 363.279943 -310.40939)
			(xy 363.280452 -310.437276) (xy 363.532926 -310.437276) (xy 363.536997 -310.381654) (xy 363.549123 -310.327217)
			(xy 363.569046 -310.275126) (xy 363.596342 -310.226491) (xy 363.630428 -310.182348) (xy 363.670577 -310.143639)
			(xy 363.715935 -310.111188) (xy 363.765535 -310.085687) (xy 363.818319 -310.06768) (xy 363.873162 -310.05755)
			(xy 363.928896 -310.055513) (xy 363.984333 -310.061613) (xy 364.03829 -310.075719) (xy 364.089619 -310.097531)
			(xy 364.137225 -310.126585) (xy 364.180093 -310.16226) (xy 364.21731 -310.203797) (xy 364.248083 -310.25031)
			(xy 364.271755 -310.300807) (xy 364.287823 -310.354214) (xy 364.295943 -310.40939) (xy 364.296452 -310.437276)
			(xy 364.548926 -310.437276) (xy 364.552997 -310.381654) (xy 364.565123 -310.327217) (xy 364.585046 -310.275126)
			(xy 364.612342 -310.226491) (xy 364.646428 -310.182348) (xy 364.686577 -310.143639) (xy 364.731935 -310.111188)
			(xy 364.781535 -310.085687) (xy 364.834319 -310.06768) (xy 364.889162 -310.05755) (xy 364.944896 -310.055513)
			(xy 365.000333 -310.061613) (xy 365.05429 -310.075719) (xy 365.105619 -310.097531) (xy 365.153225 -310.126585)
			(xy 365.196093 -310.16226) (xy 365.23331 -310.203797) (xy 365.264083 -310.25031) (xy 365.287755 -310.300807)
			(xy 365.303823 -310.354214) (xy 365.311943 -310.40939) (xy 365.312452 -310.437276) (xy 365.311943 -310.465162)
			(xy 365.303823 -310.520338) (xy 365.287755 -310.573745) (xy 365.264083 -310.624242) (xy 365.23331 -310.670755)
			(xy 365.196093 -310.712292) (xy 365.153225 -310.747967) (xy 365.105619 -310.777021) (xy 365.05429 -310.798833)
			(xy 365.000333 -310.812939) (xy 364.944896 -310.819039) (xy 364.889162 -310.817002) (xy 364.834319 -310.806872)
			(xy 364.781535 -310.788865) (xy 364.731935 -310.763364) (xy 364.686577 -310.730913) (xy 364.646428 -310.692204)
			(xy 364.612342 -310.648061) (xy 364.585046 -310.599426) (xy 364.565123 -310.547335) (xy 364.552997 -310.492898)
			(xy 364.548926 -310.437276) (xy 364.296452 -310.437276) (xy 364.295943 -310.465162) (xy 364.287823 -310.520338)
			(xy 364.271755 -310.573745) (xy 364.248083 -310.624242) (xy 364.21731 -310.670755) (xy 364.180093 -310.712292)
			(xy 364.137225 -310.747967) (xy 364.089619 -310.777021) (xy 364.03829 -310.798833) (xy 363.984333 -310.812939)
			(xy 363.928896 -310.819039) (xy 363.873162 -310.817002) (xy 363.818319 -310.806872) (xy 363.765535 -310.788865)
			(xy 363.715935 -310.763364) (xy 363.670577 -310.730913) (xy 363.630428 -310.692204) (xy 363.596342 -310.648061)
			(xy 363.569046 -310.599426) (xy 363.549123 -310.547335) (xy 363.536997 -310.492898) (xy 363.532926 -310.437276)
			(xy 363.280452 -310.437276) (xy 363.279943 -310.465162) (xy 363.271823 -310.520338) (xy 363.255755 -310.573745)
			(xy 363.232083 -310.624242) (xy 363.20131 -310.670755) (xy 363.164093 -310.712292) (xy 363.121225 -310.747967)
			(xy 363.073619 -310.777021) (xy 363.02229 -310.798833) (xy 362.968333 -310.812939) (xy 362.912896 -310.819039)
			(xy 362.857162 -310.817002) (xy 362.802319 -310.806872) (xy 362.749535 -310.788865) (xy 362.699935 -310.763364)
			(xy 362.654577 -310.730913) (xy 362.614428 -310.692204) (xy 362.580342 -310.648061) (xy 362.553046 -310.599426)
			(xy 362.533123 -310.547335) (xy 362.520997 -310.492898) (xy 362.516926 -310.437276) (xy 362.264452 -310.437276)
			(xy 362.263943 -310.465162) (xy 362.255823 -310.520338) (xy 362.239755 -310.573745) (xy 362.216083 -310.624242)
			(xy 362.18531 -310.670755) (xy 362.148093 -310.712292) (xy 362.105225 -310.747967) (xy 362.057619 -310.777021)
			(xy 362.00629 -310.798833) (xy 361.952333 -310.812939) (xy 361.896896 -310.819039) (xy 361.841162 -310.817002)
			(xy 361.786319 -310.806872) (xy 361.733535 -310.788865) (xy 361.683935 -310.763364) (xy 361.638577 -310.730913)
			(xy 361.598428 -310.692204) (xy 361.564342 -310.648061) (xy 361.537046 -310.599426) (xy 361.517123 -310.547335)
			(xy 361.504997 -310.492898) (xy 361.500926 -310.437276) (xy 361.248452 -310.437276) (xy 361.247943 -310.465162)
			(xy 361.239823 -310.520338) (xy 361.223755 -310.573745) (xy 361.200083 -310.624242) (xy 361.16931 -310.670755)
			(xy 361.132093 -310.712292) (xy 361.089225 -310.747967) (xy 361.041619 -310.777021) (xy 360.99029 -310.798833)
			(xy 360.936333 -310.812939) (xy 360.880896 -310.819039) (xy 360.825162 -310.817002) (xy 360.770319 -310.806872)
			(xy 360.717535 -310.788865) (xy 360.667935 -310.763364) (xy 360.622577 -310.730913) (xy 360.582428 -310.692204)
			(xy 360.548342 -310.648061) (xy 360.521046 -310.599426) (xy 360.501123 -310.547335) (xy 360.488997 -310.492898)
			(xy 360.484926 -310.437276) (xy 360.232452 -310.437276) (xy 360.231943 -310.465162) (xy 360.223823 -310.520338)
			(xy 360.207755 -310.573745) (xy 360.184083 -310.624242) (xy 360.15331 -310.670755) (xy 360.116093 -310.712292)
			(xy 360.073225 -310.747967) (xy 360.025619 -310.777021) (xy 359.97429 -310.798833) (xy 359.920333 -310.812939)
			(xy 359.864896 -310.819039) (xy 359.809162 -310.817002) (xy 359.754319 -310.806872) (xy 359.701535 -310.788865)
			(xy 359.651935 -310.763364) (xy 359.606577 -310.730913) (xy 359.566428 -310.692204) (xy 359.532342 -310.648061)
			(xy 359.505046 -310.599426) (xy 359.485123 -310.547335) (xy 359.472997 -310.492898) (xy 359.468926 -310.437276)
			(xy 359.216452 -310.437276) (xy 359.215943 -310.465162) (xy 359.207823 -310.520338) (xy 359.191755 -310.573745)
			(xy 359.168083 -310.624242) (xy 359.13731 -310.670755) (xy 359.100093 -310.712292) (xy 359.057225 -310.747967)
			(xy 359.009619 -310.777021) (xy 358.95829 -310.798833) (xy 358.904333 -310.812939) (xy 358.848896 -310.819039)
			(xy 358.793162 -310.817002) (xy 358.738319 -310.806872) (xy 358.685535 -310.788865) (xy 358.635935 -310.763364)
			(xy 358.590577 -310.730913) (xy 358.550428 -310.692204) (xy 358.516342 -310.648061) (xy 358.489046 -310.599426)
			(xy 358.469123 -310.547335) (xy 358.456997 -310.492898) (xy 358.452926 -310.437276) (xy 358.200452 -310.437276)
			(xy 358.199943 -310.465162) (xy 358.191823 -310.520338) (xy 358.175755 -310.573745) (xy 358.152083 -310.624242)
			(xy 358.12131 -310.670755) (xy 358.084093 -310.712292) (xy 358.041225 -310.747967) (xy 357.993619 -310.777021)
			(xy 357.94229 -310.798833) (xy 357.888333 -310.812939) (xy 357.832896 -310.819039) (xy 357.777162 -310.817002)
			(xy 357.722319 -310.806872) (xy 357.669535 -310.788865) (xy 357.619935 -310.763364) (xy 357.574577 -310.730913)
			(xy 357.534428 -310.692204) (xy 357.500342 -310.648061) (xy 357.473046 -310.599426) (xy 357.453123 -310.547335)
			(xy 357.440997 -310.492898) (xy 357.436926 -310.437276) (xy 342.526081 -310.437276) (xy 342.504001 -310.471633)
			(xy 342.46831 -310.512824) (xy 342.427119 -310.548515) (xy 342.381269 -310.577981) (xy 342.331692 -310.600623)
			(xy 342.279397 -310.615978) (xy 342.225449 -310.623734) (xy 342.170947 -310.623734) (xy 342.116999 -310.615978)
			(xy 342.064704 -310.600623) (xy 342.015127 -310.577981) (xy 341.969277 -310.548515) (xy 341.928086 -310.512824)
			(xy 341.892395 -310.471633) (xy 341.862929 -310.425783) (xy 341.840287 -310.376206) (xy 341.824932 -310.323911)
			(xy 341.817176 -310.269963) (xy 341.81669 -310.242712) (xy 341.817162 -310.215632) (xy 341.824816 -310.162016)
			(xy 341.839972 -310.110019) (xy 341.862325 -310.060688) (xy 341.891427 -310.015011) (xy 341.926693 -309.973906)
			(xy 341.946738 -309.955692) (xy 341.954866 -309.948834) (xy 341.965788 -309.925212) (xy 341.969652 -309.91602)
			(xy 341.97056 -309.896116) (xy 341.967566 -309.886604) (xy 341.937594 -309.803038) (xy 341.935308 -309.79745)
			(xy 341.930901 -309.789453) (xy 341.917566 -309.776999) (xy 341.900722 -309.769987) (xy 341.89162 -309.769256)
			(xy 341.490554 -309.769256) (xy 341.488776 -309.769256) (xy 341.479663 -309.76995) (xy 341.462796 -309.776947)
			(xy 341.449464 -309.789428) (xy 341.445088 -309.79745) (xy 341.442802 -309.803038) (xy 341.41283 -309.886604)
			(xy 341.409951 -309.896129) (xy 341.410874 -309.915988) (xy 341.414608 -309.925212) (xy 341.42553 -309.948834)
			(xy 341.433658 -309.955692) (xy 341.453703 -309.973904) (xy 341.488961 -310.015013) (xy 341.518056 -310.060692)
			(xy 341.540404 -310.110024) (xy 341.555556 -310.162019) (xy 341.563208 -310.215633) (xy 341.563706 -310.242712)
			(xy 341.56322 -310.269963) (xy 341.555464 -310.323911) (xy 341.540109 -310.376206) (xy 341.517467 -310.425783)
			(xy 341.488001 -310.471633) (xy 341.45231 -310.512824) (xy 341.411119 -310.548515) (xy 341.365269 -310.577981)
			(xy 341.315692 -310.600623) (xy 341.263397 -310.615978) (xy 341.209449 -310.623734) (xy 341.154947 -310.623734)
			(xy 341.100999 -310.615978) (xy 341.048704 -310.600623) (xy 340.999127 -310.577981) (xy 340.953277 -310.548515)
			(xy 340.912086 -310.512824) (xy 340.876395 -310.471633) (xy 340.846929 -310.425783) (xy 340.824287 -310.376206)
			(xy 340.808932 -310.323911) (xy 340.801176 -310.269963) (xy 340.80069 -310.242712) (xy 340.801162 -310.215632)
			(xy 340.808816 -310.162016) (xy 340.823972 -310.110019) (xy 340.846325 -310.060688) (xy 340.875427 -310.015011)
			(xy 340.910693 -309.973906) (xy 340.930738 -309.955692) (xy 340.938866 -309.948834) (xy 340.949788 -309.925212)
			(xy 340.953652 -309.91602) (xy 340.95456 -309.896116) (xy 340.951566 -309.886604) (xy 340.921594 -309.803038)
			(xy 340.919308 -309.79745) (xy 340.914901 -309.789453) (xy 340.901566 -309.776999) (xy 340.884722 -309.769987)
			(xy 340.87562 -309.769256) (xy 340.474554 -309.769256) (xy 340.472776 -309.769256) (xy 340.463663 -309.76995)
			(xy 340.446796 -309.776947) (xy 340.433464 -309.789428) (xy 340.429088 -309.79745) (xy 340.426802 -309.803038)
			(xy 340.39683 -309.886604) (xy 340.393951 -309.896129) (xy 340.394874 -309.915988) (xy 340.398608 -309.925212)
			(xy 340.40953 -309.948834) (xy 340.417658 -309.955692) (xy 340.437703 -309.973904) (xy 340.472961 -310.015013)
			(xy 340.502056 -310.060692) (xy 340.524404 -310.110024) (xy 340.539556 -310.162019) (xy 340.547208 -310.215633)
			(xy 340.547706 -310.242712) (xy 340.54722 -310.269963) (xy 340.539464 -310.323911) (xy 340.524109 -310.376206)
			(xy 340.501467 -310.425783) (xy 340.472001 -310.471633) (xy 340.43631 -310.512824) (xy 340.395119 -310.548515)
			(xy 340.349269 -310.577981) (xy 340.299692 -310.600623) (xy 340.247397 -310.615978) (xy 340.193449 -310.623734)
			(xy 340.138947 -310.623734) (xy 340.084999 -310.615978) (xy 340.032704 -310.600623) (xy 339.983127 -310.577981)
			(xy 339.937277 -310.548515) (xy 339.896086 -310.512824) (xy 339.860395 -310.471633) (xy 339.830929 -310.425783)
			(xy 339.808287 -310.376206) (xy 339.792932 -310.323911) (xy 339.785176 -310.269963) (xy 339.78469 -310.242712)
			(xy 339.785162 -310.215632) (xy 339.792816 -310.162016) (xy 339.807972 -310.110019) (xy 339.830325 -310.060688)
			(xy 339.859427 -310.015011) (xy 339.894693 -309.973906) (xy 339.914738 -309.955692) (xy 339.922866 -309.948834)
			(xy 339.933788 -309.925212) (xy 339.937652 -309.91602) (xy 339.93856 -309.896116) (xy 339.935566 -309.886604)
			(xy 339.905594 -309.803038) (xy 339.903308 -309.79745) (xy 339.898901 -309.789453) (xy 339.885566 -309.776999)
			(xy 339.868722 -309.769987) (xy 339.85962 -309.769256) (xy 339.458554 -309.769256) (xy 339.456776 -309.769256)
			(xy 339.447663 -309.76995) (xy 339.430796 -309.776947) (xy 339.417464 -309.789428) (xy 339.413088 -309.79745)
			(xy 339.410802 -309.803038) (xy 339.38083 -309.886604) (xy 339.377951 -309.896129) (xy 339.378874 -309.915988)
			(xy 339.382608 -309.925212) (xy 339.39353 -309.948834) (xy 339.401658 -309.955692) (xy 339.421703 -309.973904)
			(xy 339.456961 -310.015013) (xy 339.486056 -310.060692) (xy 339.508404 -310.110024) (xy 339.523556 -310.162019)
			(xy 339.531208 -310.215633) (xy 339.531706 -310.242712) (xy 339.53122 -310.269963) (xy 339.523464 -310.323911)
			(xy 339.508109 -310.376206) (xy 339.485467 -310.425783) (xy 339.456001 -310.471633) (xy 339.42031 -310.512824)
			(xy 339.379119 -310.548515) (xy 339.333269 -310.577981) (xy 339.283692 -310.600623) (xy 339.231397 -310.615978)
			(xy 339.177449 -310.623734) (xy 339.122947 -310.623734) (xy 339.068999 -310.615978) (xy 339.016704 -310.600623)
			(xy 338.967127 -310.577981) (xy 338.921277 -310.548515) (xy 338.880086 -310.512824) (xy 338.844395 -310.471633)
			(xy 338.814929 -310.425783) (xy 338.792287 -310.376206) (xy 338.776932 -310.323911) (xy 338.769176 -310.269963)
			(xy 338.76869 -310.242712) (xy 338.769162 -310.215632) (xy 338.776816 -310.162016) (xy 338.791972 -310.110019)
			(xy 338.814325 -310.060688) (xy 338.843427 -310.015011) (xy 338.878693 -309.973906) (xy 338.898738 -309.955692)
			(xy 338.906866 -309.948834) (xy 338.917788 -309.925212) (xy 338.921652 -309.91602) (xy 338.92256 -309.896116)
			(xy 338.919566 -309.886604) (xy 338.889594 -309.803038) (xy 338.887308 -309.79745) (xy 338.882901 -309.789453)
			(xy 338.869566 -309.776999) (xy 338.852722 -309.769987) (xy 338.84362 -309.769256) (xy 338.442554 -309.769256)
			(xy 338.440776 -309.769256) (xy 338.431663 -309.76995) (xy 338.414796 -309.776947) (xy 338.401464 -309.789428)
			(xy 338.397088 -309.79745) (xy 338.394802 -309.803038) (xy 338.36483 -309.886604) (xy 338.361951 -309.896129)
			(xy 338.362874 -309.915988) (xy 338.366608 -309.925212) (xy 338.37753 -309.948834) (xy 338.385658 -309.955692)
			(xy 338.405703 -309.973904) (xy 338.440961 -310.015013) (xy 338.470056 -310.060692) (xy 338.492404 -310.110024)
			(xy 338.507556 -310.162019) (xy 338.515208 -310.215633) (xy 338.515706 -310.242712) (xy 338.51522 -310.269963)
			(xy 338.507464 -310.323911) (xy 338.492109 -310.376206) (xy 338.469467 -310.425783) (xy 338.440001 -310.471633)
			(xy 338.40431 -310.512824) (xy 338.363119 -310.548515) (xy 338.317269 -310.577981) (xy 338.267692 -310.600623)
			(xy 338.215397 -310.615978) (xy 338.161449 -310.623734) (xy 338.106947 -310.623734) (xy 338.052999 -310.615978)
			(xy 338.000704 -310.600623) (xy 337.951127 -310.577981) (xy 337.905277 -310.548515) (xy 337.864086 -310.512824)
			(xy 337.828395 -310.471633) (xy 337.798929 -310.425783) (xy 337.776287 -310.376206) (xy 337.760932 -310.323911)
			(xy 337.753176 -310.269963) (xy 337.75269 -310.242712) (xy 337.753162 -310.215632) (xy 337.760816 -310.162016)
			(xy 337.775972 -310.110019) (xy 337.798325 -310.060688) (xy 337.827427 -310.015011) (xy 337.862693 -309.973906)
			(xy 337.882738 -309.955692) (xy 337.890866 -309.948834) (xy 337.901788 -309.925212) (xy 337.905652 -309.91602)
			(xy 337.90656 -309.896116) (xy 337.903566 -309.886604) (xy 337.873594 -309.803038) (xy 337.871308 -309.79745)
			(xy 337.866901 -309.789453) (xy 337.853566 -309.776999) (xy 337.836722 -309.769987) (xy 337.82762 -309.769256)
			(xy 337.426554 -309.769256) (xy 337.424776 -309.769256) (xy 337.415663 -309.76995) (xy 337.398796 -309.776947)
			(xy 337.385464 -309.789428) (xy 337.381088 -309.79745) (xy 337.378802 -309.803038) (xy 337.34883 -309.886604)
			(xy 337.345951 -309.896129) (xy 337.346874 -309.915988) (xy 337.350608 -309.925212) (xy 337.36153 -309.948834)
			(xy 337.369658 -309.955692) (xy 337.389703 -309.973904) (xy 337.424961 -310.015013) (xy 337.454056 -310.060692)
			(xy 337.476404 -310.110024) (xy 337.491556 -310.162019) (xy 337.499208 -310.215633) (xy 337.499706 -310.242712)
			(xy 337.49922 -310.269963) (xy 337.491464 -310.323911) (xy 337.476109 -310.376206) (xy 337.453467 -310.425783)
			(xy 337.424001 -310.471633) (xy 337.38831 -310.512824) (xy 337.347119 -310.548515) (xy 337.301269 -310.577981)
			(xy 337.251692 -310.600623) (xy 337.199397 -310.615978) (xy 337.145449 -310.623734) (xy 337.090947 -310.623734)
			(xy 337.036999 -310.615978) (xy 336.984704 -310.600623) (xy 336.935127 -310.577981) (xy 336.889277 -310.548515)
			(xy 336.848086 -310.512824) (xy 336.812395 -310.471633) (xy 336.782929 -310.425783) (xy 336.760287 -310.376206)
			(xy 336.744932 -310.323911) (xy 336.737176 -310.269963) (xy 336.73669 -310.242712) (xy 336.737162 -310.215632)
			(xy 336.744816 -310.162016) (xy 336.759972 -310.110019) (xy 336.782325 -310.060688) (xy 336.811427 -310.015011)
			(xy 336.846693 -309.973906) (xy 336.866738 -309.955692) (xy 336.874866 -309.948834) (xy 336.885788 -309.925212)
			(xy 336.889652 -309.91602) (xy 336.89056 -309.896116) (xy 336.887566 -309.886604) (xy 336.857594 -309.803038)
			(xy 336.855308 -309.79745) (xy 336.850901 -309.789453) (xy 336.837566 -309.776999) (xy 336.820722 -309.769987)
			(xy 336.81162 -309.769256) (xy 336.410554 -309.769256) (xy 336.408776 -309.769256) (xy 336.399663 -309.76995)
			(xy 336.382796 -309.776947) (xy 336.369464 -309.789428) (xy 336.365088 -309.79745) (xy 336.362802 -309.803038)
			(xy 336.33283 -309.886604) (xy 336.329951 -309.896129) (xy 336.330874 -309.915988) (xy 336.334608 -309.925212)
			(xy 336.34553 -309.948834) (xy 336.353658 -309.955692) (xy 336.373703 -309.973904) (xy 336.408961 -310.015013)
			(xy 336.438056 -310.060692) (xy 336.460404 -310.110024) (xy 336.475556 -310.162019) (xy 336.483208 -310.215633)
			(xy 336.483706 -310.242712) (xy 336.48322 -310.269963) (xy 336.475464 -310.323911) (xy 336.460109 -310.376206)
			(xy 336.437467 -310.425783) (xy 336.408001 -310.471633) (xy 336.37231 -310.512824) (xy 336.331119 -310.548515)
			(xy 336.285269 -310.577981) (xy 336.235692 -310.600623) (xy 336.183397 -310.615978) (xy 336.129449 -310.623734)
			(xy 336.074947 -310.623734) (xy 336.020999 -310.615978) (xy 335.968704 -310.600623) (xy 335.919127 -310.577981)
			(xy 335.873277 -310.548515) (xy 335.832086 -310.512824) (xy 335.796395 -310.471633) (xy 335.766929 -310.425783)
			(xy 335.744287 -310.376206) (xy 335.728932 -310.323911) (xy 335.721176 -310.269963) (xy 335.72069 -310.242712)
			(xy 335.721162 -310.215632) (xy 335.728816 -310.162016) (xy 335.743972 -310.110019) (xy 335.766325 -310.060688)
			(xy 335.795427 -310.015011) (xy 335.830693 -309.973906) (xy 335.850738 -309.955692) (xy 335.858866 -309.948834)
			(xy 335.869788 -309.925212) (xy 335.873652 -309.91602) (xy 335.87456 -309.896116) (xy 335.871566 -309.886604)
			(xy 335.841594 -309.803038) (xy 335.839308 -309.79745) (xy 335.834901 -309.789453) (xy 335.821566 -309.776999)
			(xy 335.804722 -309.769987) (xy 335.79562 -309.769256) (xy 335.394554 -309.769256) (xy 335.392776 -309.769256)
			(xy 335.383663 -309.76995) (xy 335.366796 -309.776947) (xy 335.353464 -309.789428) (xy 335.349088 -309.79745)
			(xy 335.346802 -309.803038) (xy 335.31683 -309.886604) (xy 335.313951 -309.896129) (xy 335.314874 -309.915988)
			(xy 335.318608 -309.925212) (xy 335.32953 -309.948834) (xy 335.337658 -309.955692) (xy 335.357703 -309.973904)
			(xy 335.392961 -310.015013) (xy 335.422056 -310.060692) (xy 335.444404 -310.110024) (xy 335.459556 -310.162019)
			(xy 335.467208 -310.215633) (xy 335.467706 -310.242712) (xy 335.46722 -310.269963) (xy 335.459464 -310.323911)
			(xy 335.444109 -310.376206) (xy 335.421467 -310.425783) (xy 335.392001 -310.471633) (xy 335.35631 -310.512824)
			(xy 335.315119 -310.548515) (xy 335.269269 -310.577981) (xy 335.219692 -310.600623) (xy 335.167397 -310.615978)
			(xy 335.113449 -310.623734) (xy 335.058947 -310.623734) (xy 335.004999 -310.615978) (xy 334.952704 -310.600623)
			(xy 334.903127 -310.577981) (xy 334.857277 -310.548515) (xy 334.816086 -310.512824) (xy 334.780395 -310.471633)
			(xy 334.750929 -310.425783) (xy 334.728287 -310.376206) (xy 334.712932 -310.323911) (xy 334.705176 -310.269963)
			(xy 334.70469 -310.242712) (xy 334.705162 -310.215632) (xy 334.712816 -310.162016) (xy 334.727972 -310.110019)
			(xy 334.750325 -310.060688) (xy 334.779427 -310.015011) (xy 334.814693 -309.973906) (xy 334.834738 -309.955692)
			(xy 334.842866 -309.948834) (xy 334.853788 -309.925212) (xy 334.857652 -309.91602) (xy 334.85856 -309.896116)
			(xy 334.855566 -309.886604) (xy 334.825594 -309.803038) (xy 334.823308 -309.79745) (xy 334.818901 -309.789453)
			(xy 334.805566 -309.776999) (xy 334.788722 -309.769987) (xy 334.77962 -309.769256) (xy 334.378554 -309.769256)
			(xy 334.376776 -309.769256) (xy 334.367663 -309.76995) (xy 334.350796 -309.776947) (xy 334.337464 -309.789428)
			(xy 334.333088 -309.79745) (xy 334.330802 -309.803038) (xy 334.30083 -309.886604) (xy 334.297951 -309.896129)
			(xy 334.298874 -309.915988) (xy 334.302608 -309.925212) (xy 334.31353 -309.948834) (xy 334.321658 -309.955692)
			(xy 334.341703 -309.973904) (xy 334.376961 -310.015013) (xy 334.406056 -310.060692) (xy 334.428404 -310.110024)
			(xy 334.443556 -310.162019) (xy 334.451208 -310.215633) (xy 334.451706 -310.242712) (xy 334.45122 -310.269963)
			(xy 334.443464 -310.323911) (xy 334.428109 -310.376206) (xy 334.405467 -310.425783) (xy 334.376001 -310.471633)
			(xy 334.34031 -310.512824) (xy 334.299119 -310.548515) (xy 334.253269 -310.577981) (xy 334.203692 -310.600623)
			(xy 334.151397 -310.615978) (xy 334.097449 -310.623734) (xy 334.042947 -310.623734) (xy 333.988999 -310.615978)
			(xy 333.936704 -310.600623) (xy 333.887127 -310.577981) (xy 333.841277 -310.548515) (xy 333.800086 -310.512824)
			(xy 333.764395 -310.471633) (xy 333.734929 -310.425783) (xy 333.712287 -310.376206) (xy 333.696932 -310.323911)
			(xy 333.689176 -310.269963) (xy 333.68869 -310.242712) (xy 333.689162 -310.215632) (xy 333.696816 -310.162016)
			(xy 333.711972 -310.110019) (xy 333.734325 -310.060688) (xy 333.763427 -310.015011) (xy 333.798693 -309.973906)
			(xy 333.818738 -309.955692) (xy 333.826866 -309.948834) (xy 333.837788 -309.925212) (xy 333.841652 -309.91602)
			(xy 333.84256 -309.896116) (xy 333.839566 -309.886604) (xy 333.809594 -309.803038) (xy 333.807308 -309.79745)
			(xy 333.802901 -309.789453) (xy 333.789566 -309.776999) (xy 333.772722 -309.769987) (xy 333.76362 -309.769256)
			(xy 333.362554 -309.769256) (xy 333.360776 -309.769256) (xy 333.351663 -309.76995) (xy 333.334796 -309.776947)
			(xy 333.321464 -309.789428) (xy 333.317088 -309.79745) (xy 333.314802 -309.803038) (xy 333.28483 -309.886604)
			(xy 333.281951 -309.896129) (xy 333.282874 -309.915988) (xy 333.286608 -309.925212) (xy 333.29753 -309.948834)
			(xy 333.305658 -309.955692) (xy 333.325703 -309.973904) (xy 333.360961 -310.015013) (xy 333.390056 -310.060692)
			(xy 333.412404 -310.110024) (xy 333.427556 -310.162019) (xy 333.435208 -310.215633) (xy 333.435706 -310.242712)
			(xy 333.43522 -310.269963) (xy 333.427464 -310.323911) (xy 333.412109 -310.376206) (xy 333.389467 -310.425783)
			(xy 333.360001 -310.471633) (xy 333.32431 -310.512824) (xy 333.283119 -310.548515) (xy 333.237269 -310.577981)
			(xy 333.187692 -310.600623) (xy 333.135397 -310.615978) (xy 333.081449 -310.623734) (xy 333.026947 -310.623734)
			(xy 332.972999 -310.615978) (xy 332.920704 -310.600623) (xy 332.871127 -310.577981) (xy 332.825277 -310.548515)
			(xy 332.784086 -310.512824) (xy 332.748395 -310.471633) (xy 332.718929 -310.425783) (xy 332.696287 -310.376206)
			(xy 332.680932 -310.323911) (xy 332.673176 -310.269963) (xy 332.67269 -310.242712) (xy 332.673162 -310.215632)
			(xy 332.680816 -310.162016) (xy 332.695972 -310.110019) (xy 332.718325 -310.060688) (xy 332.747427 -310.015011)
			(xy 332.782693 -309.973906) (xy 332.802738 -309.955692) (xy 332.810866 -309.948834) (xy 332.821788 -309.925212)
			(xy 332.825652 -309.91602) (xy 332.82656 -309.896116) (xy 332.823566 -309.886604) (xy 332.793594 -309.803038)
			(xy 332.791308 -309.79745) (xy 332.786901 -309.789453) (xy 332.773566 -309.776999) (xy 332.756722 -309.769987)
			(xy 332.74762 -309.769256) (xy 332.208378 -309.769256) (xy 332.198311 -309.768828) (xy 332.179716 -309.761103)
			(xy 332.17231 -309.75427) (xy 330.866242 -308.448202) (xy 330.859391 -308.440806) (xy 330.851649 -308.422207)
			(xy 330.851256 -308.412134) (xy 330.851256 -298.002452) (xy 330.850823 -297.992387) (xy 330.843091 -297.973799)
			(xy 330.83627 -297.966384) (xy 325.513446 -292.64356) (xy 325.506601 -292.636161) (xy 325.498874 -292.617563)
			(xy 325.49846 -292.607492) (xy 325.49846 -292.359842) (xy 325.496428 -292.345872) (xy 325.490586 -292.325806)
			(xy 325.487284 -292.319964) (xy 325.474177 -292.297492) (xy 325.453502 -292.249754) (xy 325.439502 -292.19965)
			(xy 325.432437 -292.14811) (xy 325.432437 -292.096087) (xy 325.439503 -292.044546) (xy 325.453503 -291.994443)
			(xy 325.474179 -291.946705) (xy 325.487284 -291.924232) (xy 325.490586 -291.91839) (xy 325.496428 -291.898324)
			(xy 325.49846 -291.884354) (xy 325.49846 -291.559742) (xy 325.496428 -291.545772) (xy 325.490586 -291.525706)
			(xy 325.487284 -291.519864) (xy 325.474177 -291.497392) (xy 325.453502 -291.449654) (xy 325.439502 -291.39955)
			(xy 325.432437 -291.34801) (xy 325.432437 -291.295987) (xy 325.439503 -291.244446) (xy 325.453503 -291.194343)
			(xy 325.474179 -291.146605) (xy 325.487284 -291.124132) (xy 325.490586 -291.11829) (xy 325.496428 -291.098224)
			(xy 325.49846 -291.084254) (xy 325.49846 -289.164776) (xy 325.498292 -289.159402) (xy 325.495977 -289.148903)
			(xy 325.493888 -289.143948) (xy 325.481696 -289.116262) (xy 325.474076 -289.109404) (xy 325.453708 -289.0896)
			(xy 325.418473 -289.045042) (xy 325.390229 -288.995755) (xy 325.369598 -288.942827) (xy 325.357035 -288.887427)
			(xy 325.352819 -288.830777) (xy 325.357042 -288.774127) (xy 325.369611 -288.718729) (xy 325.390249 -288.665803)
			(xy 325.4185 -288.61652) (xy 325.45374 -288.571965) (xy 325.474076 -288.552128) (xy 325.481696 -288.54527)
			(xy 325.493888 -288.517584) (xy 325.495992 -288.512635) (xy 325.498288 -288.502131) (xy 325.49846 -288.496756)
			(xy 325.49846 -287.474152) (xy 325.498027 -287.464087) (xy 325.490296 -287.445499) (xy 325.483474 -287.438084)
			(xy 325.345298 -287.299908) (xy 325.338186 -287.292542) (xy 325.31939 -287.284922) (xy 322.390262 -287.284922)
			(xy 322.387976 -287.284922) (xy 322.380688 -287.285488) (xy 322.366881 -287.290267) (xy 322.360798 -287.29432)
			(xy 322.35521 -287.298892) (xy 322.014342 -287.624774) (xy 321.984309 -287.652913) (xy 321.920307 -287.704662)
			(xy 321.852228 -287.750917) (xy 321.780542 -287.791358) (xy 321.743324 -287.808924) (xy 321.441064 -287.947354)
			(xy 321.432427 -287.9518) (xy 321.419094 -287.965906) (xy 321.415156 -287.974786) (xy 321.385692 -288.049208)
			(xy 321.385692 -288.068512) (xy 321.389502 -288.077656) (xy 321.398208 -288.100136) (xy 321.410537 -288.14674)
			(xy 321.416908 -288.194525) (xy 321.417442 -288.218626) (xy 321.417442 -288.221166) (xy 321.669916 -288.221166)
			(xy 321.673987 -288.165544) (xy 321.686113 -288.111107) (xy 321.706036 -288.059016) (xy 321.733332 -288.010381)
			(xy 321.767418 -287.966238) (xy 321.807567 -287.927529) (xy 321.852925 -287.895078) (xy 321.902525 -287.869577)
			(xy 321.955309 -287.85157) (xy 322.010152 -287.84144) (xy 322.065886 -287.839403) (xy 322.121323 -287.845503)
			(xy 322.17528 -287.859609) (xy 322.226609 -287.881421) (xy 322.274215 -287.910475) (xy 322.317083 -287.94615)
			(xy 322.3543 -287.987687) (xy 322.385073 -288.0342) (xy 322.408745 -288.084697) (xy 322.424813 -288.138104)
			(xy 322.432933 -288.19328) (xy 322.433442 -288.221166) (xy 322.685916 -288.221166) (xy 322.689987 -288.165544)
			(xy 322.702113 -288.111107) (xy 322.722036 -288.059016) (xy 322.749332 -288.010381) (xy 322.783418 -287.966238)
			(xy 322.823567 -287.927529) (xy 322.868925 -287.895078) (xy 322.918525 -287.869577) (xy 322.971309 -287.85157)
			(xy 323.026152 -287.84144) (xy 323.081886 -287.839403) (xy 323.137323 -287.845503) (xy 323.19128 -287.859609)
			(xy 323.242609 -287.881421) (xy 323.290215 -287.910475) (xy 323.333083 -287.94615) (xy 323.3703 -287.987687)
			(xy 323.401073 -288.0342) (xy 323.424745 -288.084697) (xy 323.440813 -288.138104) (xy 323.448933 -288.19328)
			(xy 323.449442 -288.221166) (xy 323.669658 -288.221166) (xy 323.673729 -288.165544) (xy 323.685855 -288.111107)
			(xy 323.705778 -288.059016) (xy 323.733074 -288.010381) (xy 323.76716 -287.966238) (xy 323.807309 -287.927529)
			(xy 323.852667 -287.895078) (xy 323.902267 -287.869577) (xy 323.955051 -287.85157) (xy 324.009894 -287.84144)
			(xy 324.065628 -287.839403) (xy 324.121065 -287.845503) (xy 324.175022 -287.859609) (xy 324.226351 -287.881421)
			(xy 324.273957 -287.910475) (xy 324.316825 -287.94615) (xy 324.354042 -287.987687) (xy 324.384815 -288.0342)
			(xy 324.408487 -288.084697) (xy 324.424555 -288.138104) (xy 324.432675 -288.19328) (xy 324.433184 -288.221166)
			(xy 324.432675 -288.249052) (xy 324.424555 -288.304228) (xy 324.408487 -288.357635) (xy 324.384815 -288.408132)
			(xy 324.354042 -288.454645) (xy 324.316825 -288.496182) (xy 324.273957 -288.531857) (xy 324.226351 -288.560911)
			(xy 324.175022 -288.582723) (xy 324.121065 -288.596829) (xy 324.065628 -288.602929) (xy 324.009894 -288.600892)
			(xy 323.955051 -288.590762) (xy 323.902267 -288.572755) (xy 323.852667 -288.547254) (xy 323.807309 -288.514803)
			(xy 323.76716 -288.476094) (xy 323.733074 -288.431951) (xy 323.705778 -288.383316) (xy 323.685855 -288.331225)
			(xy 323.673729 -288.276788) (xy 323.669658 -288.221166) (xy 323.449442 -288.221166) (xy 323.448933 -288.249052)
			(xy 323.440813 -288.304228) (xy 323.424745 -288.357635) (xy 323.401073 -288.408132) (xy 323.3703 -288.454645)
			(xy 323.333083 -288.496182) (xy 323.290215 -288.531857) (xy 323.242609 -288.560911) (xy 323.19128 -288.582723)
			(xy 323.137323 -288.596829) (xy 323.081886 -288.602929) (xy 323.026152 -288.600892) (xy 322.971309 -288.590762)
			(xy 322.918525 -288.572755) (xy 322.868925 -288.547254) (xy 322.823567 -288.514803) (xy 322.783418 -288.476094)
			(xy 322.749332 -288.431951) (xy 322.722036 -288.383316) (xy 322.702113 -288.331225) (xy 322.689987 -288.276788)
			(xy 322.685916 -288.221166) (xy 322.433442 -288.221166) (xy 322.432933 -288.249052) (xy 322.424813 -288.304228)
			(xy 322.408745 -288.357635) (xy 322.385073 -288.408132) (xy 322.3543 -288.454645) (xy 322.317083 -288.496182)
			(xy 322.274215 -288.531857) (xy 322.226609 -288.560911) (xy 322.17528 -288.582723) (xy 322.121323 -288.596829)
			(xy 322.065886 -288.602929) (xy 322.010152 -288.600892) (xy 321.955309 -288.590762) (xy 321.902525 -288.572755)
			(xy 321.852925 -288.547254) (xy 321.807567 -288.514803) (xy 321.767418 -288.476094) (xy 321.733332 -288.431951)
			(xy 321.706036 -288.383316) (xy 321.686113 -288.331225) (xy 321.673987 -288.276788) (xy 321.669916 -288.221166)
			(xy 321.417442 -288.221166) (xy 321.417442 -288.22396) (xy 321.416768 -288.251081) (xy 321.408694 -288.304726)
			(xy 321.3931 -288.356687) (xy 321.370303 -288.405914) (xy 321.34076 -288.451414) (xy 321.305069 -288.49227)
			(xy 321.26395 -288.527657) (xy 321.218232 -288.556862) (xy 321.168837 -288.579294) (xy 321.116763 -288.594502)
			(xy 321.063059 -288.602179) (xy 321.035934 -288.602674) (xy 321.009791 -288.602247) (xy 320.957994 -288.595112)
			(xy 320.907657 -288.580973) (xy 320.859721 -288.560092) (xy 320.815086 -288.532862) (xy 320.774586 -288.499793)
			(xy 320.738981 -288.461504) (xy 320.708938 -288.418711) (xy 320.69659 -288.395664) (xy 320.692018 -288.386774)
			(xy 320.67754 -288.374074) (xy 320.601594 -288.347658) (xy 320.592252 -288.34486) (xy 320.572791 -288.345784)
			(xy 320.563748 -288.349436) (xy 320.539872 -288.360358) (xy 320.526918 -288.373058) (xy 320.523108 -288.38144)
			(xy 320.51128 -288.405859) (xy 320.481743 -288.451372) (xy 320.446056 -288.492242) (xy 320.404939 -288.527642)
			(xy 320.35922 -288.55686) (xy 320.309823 -288.579306) (xy 320.257745 -288.594527) (xy 320.204035 -288.602215)
			(xy 320.176906 -288.602674) (xy 320.176652 -288.602674) (xy 320.150335 -288.602217) (xy 320.098203 -288.594958)
			(xy 320.072766 -288.588196) (xy 320.072004 -288.587942) (xy 320.063291 -288.585963) (xy 320.045495 -288.587399)
			(xy 320.037206 -288.590736) (xy 319.650364 -288.768028) (xy 319.646304 -288.770054) (xy 319.638897 -288.775292)
			(xy 319.635632 -288.778442) (xy 318.220344 -290.19373) (xy 318.212978 -290.200842) (xy 318.205358 -290.219638)
			(xy 318.205358 -290.237164) (xy 321.364354 -290.237164) (xy 321.368425 -290.181542) (xy 321.380551 -290.127105)
			(xy 321.400474 -290.075014) (xy 321.42777 -290.026379) (xy 321.461856 -289.982236) (xy 321.502005 -289.943527)
			(xy 321.547363 -289.911076) (xy 321.596963 -289.885575) (xy 321.649747 -289.867568) (xy 321.70459 -289.857438)
			(xy 321.760324 -289.855401) (xy 321.815761 -289.861501) (xy 321.869718 -289.875607) (xy 321.921047 -289.897419)
			(xy 321.968653 -289.926473) (xy 322.011521 -289.962148) (xy 322.048738 -290.003685) (xy 322.079511 -290.050198)
			(xy 322.103183 -290.100695) (xy 322.119251 -290.154102) (xy 322.127371 -290.209278) (xy 322.12788 -290.237164)
			(xy 322.127371 -290.26505) (xy 322.119251 -290.320226) (xy 322.103183 -290.373633) (xy 322.079511 -290.42413)
			(xy 322.048738 -290.470643) (xy 322.011521 -290.51218) (xy 321.968653 -290.547855) (xy 321.921047 -290.576909)
			(xy 321.869718 -290.598721) (xy 321.815761 -290.612827) (xy 321.760324 -290.618927) (xy 321.70459 -290.61689)
			(xy 321.649747 -290.60676) (xy 321.596963 -290.588753) (xy 321.547363 -290.563252) (xy 321.502005 -290.530801)
			(xy 321.461856 -290.492092) (xy 321.42777 -290.447949) (xy 321.400474 -290.399314) (xy 321.380551 -290.347223)
			(xy 321.368425 -290.292786) (xy 321.364354 -290.237164) (xy 318.205358 -290.237164) (xy 318.205358 -290.829238)
			(xy 318.205726 -290.838313) (xy 318.212075 -290.855316) (xy 318.223989 -290.869008) (xy 318.231774 -290.873688)
			(xy 318.322198 -290.923218) (xy 318.34963 -290.922456) (xy 318.361568 -290.914836) (xy 318.384663 -290.900647)
			(xy 318.434014 -290.878231) (xy 318.486042 -290.863031) (xy 318.539699 -290.855354) (xy 318.5668 -290.854892)
			(xy 318.594051 -290.855378) (xy 318.647999 -290.863134) (xy 318.700294 -290.878489) (xy 318.749871 -290.901131)
			(xy 318.795721 -290.930597) (xy 318.836912 -290.966288) (xy 318.872603 -291.007479) (xy 318.902069 -291.053329)
			(xy 318.924711 -291.102906) (xy 318.940066 -291.155201) (xy 318.947822 -291.209149) (xy 318.947822 -291.263651)
			(xy 318.940066 -291.317599) (xy 318.924711 -291.369894) (xy 318.902069 -291.419471) (xy 318.872603 -291.465321)
			(xy 318.836912 -291.506512) (xy 318.795721 -291.542203) (xy 318.749871 -291.571669) (xy 318.700294 -291.594311)
			(xy 318.647999 -291.609666) (xy 318.594051 -291.617422) (xy 318.5668 -291.617908) (xy 318.539699 -291.617432)
			(xy 318.486044 -291.609757) (xy 318.434016 -291.594561) (xy 318.384664 -291.57215) (xy 318.361568 -291.557964)
			(xy 318.34963 -291.550344) (xy 318.322198 -291.549582) (xy 318.231774 -291.599112) (xy 318.224009 -291.603805)
			(xy 318.212149 -291.617521) (xy 318.205782 -291.634498) (xy 318.205358 -291.643562) (xy 318.205358 -292.10889)
			(xy 318.205758 -292.118089) (xy 318.212245 -292.135306) (xy 318.224363 -292.149151) (xy 318.232282 -292.153848)
			(xy 318.295274 -292.187376) (xy 318.300859 -292.190111) (xy 318.312934 -292.19307) (xy 318.31915 -292.193218)
			(xy 318.356234 -292.193218) (xy 318.36995 -292.189408) (xy 318.376046 -292.185344) (xy 318.398903 -292.171561)
			(xy 318.447647 -292.149817) (xy 318.498945 -292.135076) (xy 318.551797 -292.127625) (xy 318.578484 -292.127178)
			(xy 318.605739 -292.12764) (xy 318.659693 -292.135395) (xy 318.711995 -292.15075) (xy 318.761579 -292.173393)
			(xy 318.807436 -292.202862) (xy 318.848632 -292.238557) (xy 318.884329 -292.279751) (xy 318.913799 -292.325607)
			(xy 318.936444 -292.37519) (xy 318.951801 -292.427491) (xy 318.959559 -292.481445) (xy 318.959559 -292.535955)
			(xy 318.951801 -292.589909) (xy 318.936444 -292.64221) (xy 318.913799 -292.691793) (xy 318.884329 -292.737649)
			(xy 318.848632 -292.778843) (xy 318.807436 -292.814538) (xy 318.761579 -292.844007) (xy 318.711995 -292.86665)
			(xy 318.659693 -292.882005) (xy 318.605739 -292.88976) (xy 318.578484 -292.890194) (xy 318.550045 -292.889625)
			(xy 318.493806 -292.881102) (xy 318.439452 -292.864336) (xy 318.388185 -292.839698) (xy 318.364362 -292.824154)
			(xy 318.352424 -292.816026) (xy 318.324738 -292.814502) (xy 318.232282 -292.863524) (xy 318.224328 -292.868183)
			(xy 318.212166 -292.882017) (xy 318.205716 -292.89927) (xy 318.205358 -292.908482) (xy 318.205358 -294.016176)
			(xy 321.840604 -294.016176) (xy 321.844675 -293.960554) (xy 321.856801 -293.906117) (xy 321.876724 -293.854026)
			(xy 321.90402 -293.805391) (xy 321.938106 -293.761248) (xy 321.978255 -293.722539) (xy 322.023613 -293.690088)
			(xy 322.073213 -293.664587) (xy 322.125997 -293.64658) (xy 322.18084 -293.63645) (xy 322.236574 -293.634413)
			(xy 322.292011 -293.640513) (xy 322.345968 -293.654619) (xy 322.397297 -293.676431) (xy 322.444903 -293.705485)
			(xy 322.487771 -293.74116) (xy 322.524988 -293.782697) (xy 322.555761 -293.82921) (xy 322.579433 -293.879707)
			(xy 322.595501 -293.933114) (xy 322.602492 -293.980616) (xy 323.480682 -293.980616) (xy 323.484753 -293.924994)
			(xy 323.496879 -293.870557) (xy 323.516802 -293.818466) (xy 323.544098 -293.769831) (xy 323.578184 -293.725688)
			(xy 323.618333 -293.686979) (xy 323.663691 -293.654528) (xy 323.713291 -293.629027) (xy 323.766075 -293.61102)
			(xy 323.820918 -293.60089) (xy 323.876652 -293.598853) (xy 323.932089 -293.604953) (xy 323.986046 -293.619059)
			(xy 324.037375 -293.640871) (xy 324.084981 -293.669925) (xy 324.127849 -293.7056) (xy 324.165066 -293.747137)
			(xy 324.195839 -293.79365) (xy 324.219511 -293.844147) (xy 324.235579 -293.897554) (xy 324.243699 -293.95273)
			(xy 324.244208 -293.980616) (xy 324.243699 -294.008502) (xy 324.235579 -294.063678) (xy 324.219511 -294.117085)
			(xy 324.195839 -294.167582) (xy 324.165066 -294.214095) (xy 324.127849 -294.255632) (xy 324.084981 -294.291307)
			(xy 324.037375 -294.320361) (xy 323.986046 -294.342173) (xy 323.932089 -294.356279) (xy 323.876652 -294.362379)
			(xy 323.820918 -294.360342) (xy 323.766075 -294.350212) (xy 323.713291 -294.332205) (xy 323.663691 -294.306704)
			(xy 323.618333 -294.274253) (xy 323.578184 -294.235544) (xy 323.544098 -294.191401) (xy 323.516802 -294.142766)
			(xy 323.496879 -294.090675) (xy 323.484753 -294.036238) (xy 323.480682 -293.980616) (xy 322.602492 -293.980616)
			(xy 322.603621 -293.98829) (xy 322.60413 -294.016176) (xy 322.603621 -294.044062) (xy 322.595501 -294.099238)
			(xy 322.579433 -294.152645) (xy 322.555761 -294.203142) (xy 322.524988 -294.249655) (xy 322.487771 -294.291192)
			(xy 322.444903 -294.326867) (xy 322.397297 -294.355921) (xy 322.345968 -294.377733) (xy 322.292011 -294.391839)
			(xy 322.236574 -294.397939) (xy 322.18084 -294.395902) (xy 322.125997 -294.385772) (xy 322.073213 -294.367765)
			(xy 322.023613 -294.342264) (xy 321.978255 -294.309813) (xy 321.938106 -294.271104) (xy 321.90402 -294.226961)
			(xy 321.876724 -294.178326) (xy 321.856801 -294.126235) (xy 321.844675 -294.071798) (xy 321.840604 -294.016176)
			(xy 318.205358 -294.016176) (xy 318.205358 -296.613072) (xy 321.462398 -296.613072) (xy 321.466469 -296.55745)
			(xy 321.478595 -296.503013) (xy 321.498518 -296.450922) (xy 321.525814 -296.402287) (xy 321.5599 -296.358144)
			(xy 321.600049 -296.319435) (xy 321.645407 -296.286984) (xy 321.695007 -296.261483) (xy 321.747791 -296.243476)
			(xy 321.802634 -296.233346) (xy 321.858368 -296.231309) (xy 321.913805 -296.237409) (xy 321.967762 -296.251515)
			(xy 322.019091 -296.273327) (xy 322.066697 -296.302381) (xy 322.109565 -296.338056) (xy 322.146782 -296.379593)
			(xy 322.177555 -296.426106) (xy 322.201227 -296.476603) (xy 322.217295 -296.53001) (xy 322.225415 -296.585186)
			(xy 322.225924 -296.613072) (xy 322.737224 -296.613072) (xy 322.741295 -296.55745) (xy 322.753421 -296.503013)
			(xy 322.773344 -296.450922) (xy 322.80064 -296.402287) (xy 322.834726 -296.358144) (xy 322.874875 -296.319435)
			(xy 322.920233 -296.286984) (xy 322.969833 -296.261483) (xy 323.022617 -296.243476) (xy 323.07746 -296.233346)
			(xy 323.133194 -296.231309) (xy 323.188631 -296.237409) (xy 323.242588 -296.251515) (xy 323.293917 -296.273327)
			(xy 323.341523 -296.302381) (xy 323.384391 -296.338056) (xy 323.421608 -296.379593) (xy 323.452381 -296.426106)
			(xy 323.476053 -296.476603) (xy 323.492121 -296.53001) (xy 323.500241 -296.585186) (xy 323.50075 -296.613072)
			(xy 323.500241 -296.640958) (xy 323.492121 -296.696134) (xy 323.476053 -296.749541) (xy 323.452381 -296.800038)
			(xy 323.421608 -296.846551) (xy 323.384391 -296.888088) (xy 323.341523 -296.923763) (xy 323.293917 -296.952817)
			(xy 323.242588 -296.974629) (xy 323.188631 -296.988735) (xy 323.133194 -296.994835) (xy 323.07746 -296.992798)
			(xy 323.022617 -296.982668) (xy 322.969833 -296.964661) (xy 322.920233 -296.93916) (xy 322.874875 -296.906709)
			(xy 322.834726 -296.868) (xy 322.80064 -296.823857) (xy 322.773344 -296.775222) (xy 322.753421 -296.723131)
			(xy 322.741295 -296.668694) (xy 322.737224 -296.613072) (xy 322.225924 -296.613072) (xy 322.225415 -296.640958)
			(xy 322.217295 -296.696134) (xy 322.201227 -296.749541) (xy 322.177555 -296.800038) (xy 322.146782 -296.846551)
			(xy 322.109565 -296.888088) (xy 322.066697 -296.923763) (xy 322.019091 -296.952817) (xy 321.967762 -296.974629)
			(xy 321.913805 -296.988735) (xy 321.858368 -296.994835) (xy 321.802634 -296.992798) (xy 321.747791 -296.982668)
			(xy 321.695007 -296.964661) (xy 321.645407 -296.93916) (xy 321.600049 -296.906709) (xy 321.5599 -296.868)
			(xy 321.525814 -296.823857) (xy 321.498518 -296.775222) (xy 321.478595 -296.723131) (xy 321.466469 -296.668694)
			(xy 321.462398 -296.613072) (xy 318.205358 -296.613072) (xy 318.205358 -297.690032) (xy 318.499488 -297.690032)
			(xy 318.503559 -297.63441) (xy 318.515685 -297.579973) (xy 318.535608 -297.527882) (xy 318.562904 -297.479247)
			(xy 318.59699 -297.435104) (xy 318.637139 -297.396395) (xy 318.682497 -297.363944) (xy 318.732097 -297.338443)
			(xy 318.784881 -297.320436) (xy 318.839724 -297.310306) (xy 318.895458 -297.308269) (xy 318.950895 -297.314369)
			(xy 319.004852 -297.328475) (xy 319.056181 -297.350287) (xy 319.096376 -297.374818) (xy 324.815706 -297.374818)
			(xy 324.819777 -297.319196) (xy 324.831903 -297.264759) (xy 324.851826 -297.212668) (xy 324.879122 -297.164033)
			(xy 324.913208 -297.11989) (xy 324.953357 -297.081181) (xy 324.998715 -297.04873) (xy 325.048315 -297.023229)
			(xy 325.101099 -297.005222) (xy 325.155942 -296.995092) (xy 325.211676 -296.993055) (xy 325.267113 -296.999155)
			(xy 325.32107 -297.013261) (xy 325.372399 -297.035073) (xy 325.420005 -297.064127) (xy 325.462873 -297.099802)
			(xy 325.50009 -297.141339) (xy 325.530863 -297.187852) (xy 325.554535 -297.238349) (xy 325.570603 -297.291756)
			(xy 325.578723 -297.346932) (xy 325.579232 -297.374818) (xy 325.578723 -297.402704) (xy 325.570603 -297.45788)
			(xy 325.554535 -297.511287) (xy 325.530863 -297.561784) (xy 325.50009 -297.608297) (xy 325.462873 -297.649834)
			(xy 325.420005 -297.685509) (xy 325.372399 -297.714563) (xy 325.32107 -297.736375) (xy 325.267113 -297.750481)
			(xy 325.211676 -297.756581) (xy 325.155942 -297.754544) (xy 325.101099 -297.744414) (xy 325.048315 -297.726407)
			(xy 324.998715 -297.700906) (xy 324.953357 -297.668455) (xy 324.913208 -297.629746) (xy 324.879122 -297.585603)
			(xy 324.851826 -297.536968) (xy 324.831903 -297.484877) (xy 324.819777 -297.43044) (xy 324.815706 -297.374818)
			(xy 319.096376 -297.374818) (xy 319.103787 -297.379341) (xy 319.146655 -297.415016) (xy 319.183872 -297.456553)
			(xy 319.214645 -297.503066) (xy 319.238317 -297.553563) (xy 319.254385 -297.60697) (xy 319.262505 -297.662146)
			(xy 319.263014 -297.690032) (xy 319.262505 -297.717918) (xy 319.254385 -297.773094) (xy 319.238317 -297.826501)
			(xy 319.214645 -297.876998) (xy 319.183872 -297.923511) (xy 319.146655 -297.965048) (xy 319.103787 -298.000723)
			(xy 319.056181 -298.029777) (xy 319.004852 -298.051589) (xy 318.950895 -298.065695) (xy 318.895458 -298.071795)
			(xy 318.839724 -298.069758) (xy 318.784881 -298.059628) (xy 318.732097 -298.041621) (xy 318.682497 -298.01612)
			(xy 318.637139 -297.983669) (xy 318.59699 -297.94496) (xy 318.562904 -297.900817) (xy 318.535608 -297.852182)
			(xy 318.515685 -297.800091) (xy 318.503559 -297.745654) (xy 318.499488 -297.690032) (xy 318.205358 -297.690032)
			(xy 318.205358 -298.700698) (xy 318.697354 -298.700698) (xy 318.701425 -298.645076) (xy 318.713551 -298.590639)
			(xy 318.733474 -298.538548) (xy 318.76077 -298.489913) (xy 318.794856 -298.44577) (xy 318.835005 -298.407061)
			(xy 318.880363 -298.37461) (xy 318.929963 -298.349109) (xy 318.982747 -298.331102) (xy 319.03759 -298.320972)
			(xy 319.093324 -298.318935) (xy 319.148761 -298.325035) (xy 319.202718 -298.339141) (xy 319.254047 -298.360953)
			(xy 319.301653 -298.390007) (xy 319.344521 -298.425682) (xy 319.381738 -298.467219) (xy 319.412511 -298.513732)
			(xy 319.436183 -298.564229) (xy 319.452251 -298.617636) (xy 319.460371 -298.672812) (xy 319.46088 -298.700698)
			(xy 319.460371 -298.728584) (xy 319.452251 -298.78376) (xy 319.436183 -298.837167) (xy 319.412511 -298.887664)
			(xy 319.381738 -298.934177) (xy 319.344521 -298.975714) (xy 319.301653 -299.011389) (xy 319.254047 -299.040443)
			(xy 319.202718 -299.062255) (xy 319.148761 -299.076361) (xy 319.093324 -299.082461) (xy 319.03759 -299.080424)
			(xy 318.982747 -299.070294) (xy 318.929963 -299.052287) (xy 318.880363 -299.026786) (xy 318.835005 -298.994335)
			(xy 318.794856 -298.955626) (xy 318.76077 -298.911483) (xy 318.733474 -298.862848) (xy 318.713551 -298.810757)
			(xy 318.701425 -298.75632) (xy 318.697354 -298.700698) (xy 318.205358 -298.700698) (xy 318.205358 -299.27296)
			(xy 322.514466 -299.27296) (xy 322.518537 -299.217338) (xy 322.530663 -299.162901) (xy 322.550586 -299.11081)
			(xy 322.577882 -299.062175) (xy 322.611968 -299.018032) (xy 322.652117 -298.979323) (xy 322.697475 -298.946872)
			(xy 322.747075 -298.921371) (xy 322.799859 -298.903364) (xy 322.854702 -298.893234) (xy 322.910436 -298.891197)
			(xy 322.965873 -298.897297) (xy 323.01983 -298.911403) (xy 323.071159 -298.933215) (xy 323.118765 -298.962269)
			(xy 323.161633 -298.997944) (xy 323.19885 -299.039481) (xy 323.229623 -299.085994) (xy 323.253295 -299.136491)
			(xy 323.269363 -299.189898) (xy 323.277483 -299.245074) (xy 323.277992 -299.27296) (xy 323.277483 -299.300846)
			(xy 323.269363 -299.356022) (xy 323.253295 -299.409429) (xy 323.229623 -299.459926) (xy 323.19885 -299.506439)
			(xy 323.161633 -299.547976) (xy 323.118765 -299.583651) (xy 323.071159 -299.612705) (xy 323.01983 -299.634517)
			(xy 322.965873 -299.648623) (xy 322.910436 -299.654723) (xy 322.854702 -299.652686) (xy 322.799859 -299.642556)
			(xy 322.747075 -299.624549) (xy 322.697475 -299.599048) (xy 322.652117 -299.566597) (xy 322.611968 -299.527888)
			(xy 322.577882 -299.483745) (xy 322.550586 -299.43511) (xy 322.530663 -299.383019) (xy 322.518537 -299.328582)
			(xy 322.514466 -299.27296) (xy 318.205358 -299.27296) (xy 318.205358 -299.76445) (xy 320.241674 -299.76445)
			(xy 320.245745 -299.708828) (xy 320.257871 -299.654391) (xy 320.277794 -299.6023) (xy 320.30509 -299.553665)
			(xy 320.339176 -299.509522) (xy 320.379325 -299.470813) (xy 320.424683 -299.438362) (xy 320.474283 -299.412861)
			(xy 320.527067 -299.394854) (xy 320.58191 -299.384724) (xy 320.637644 -299.382687) (xy 320.693081 -299.388787)
			(xy 320.747038 -299.402893) (xy 320.798367 -299.424705) (xy 320.845973 -299.453759) (xy 320.888841 -299.489434)
			(xy 320.926058 -299.530971) (xy 320.956831 -299.577484) (xy 320.980503 -299.627981) (xy 320.996571 -299.681388)
			(xy 321.004691 -299.736564) (xy 321.0052 -299.76445) (xy 321.004922 -299.77969) (xy 324.838312 -299.77969)
			(xy 324.842383 -299.724068) (xy 324.854509 -299.669631) (xy 324.874432 -299.61754) (xy 324.901728 -299.568905)
			(xy 324.935814 -299.524762) (xy 324.975963 -299.486053) (xy 325.021321 -299.453602) (xy 325.070921 -299.428101)
			(xy 325.123705 -299.410094) (xy 325.178548 -299.399964) (xy 325.234282 -299.397927) (xy 325.289719 -299.404027)
			(xy 325.343676 -299.418133) (xy 325.395005 -299.439945) (xy 325.442611 -299.468999) (xy 325.485479 -299.504674)
			(xy 325.522696 -299.546211) (xy 325.553469 -299.592724) (xy 325.577141 -299.643221) (xy 325.593209 -299.696628)
			(xy 325.601329 -299.751804) (xy 325.601838 -299.77969) (xy 325.601329 -299.807576) (xy 325.593209 -299.862752)
			(xy 325.577141 -299.916159) (xy 325.553469 -299.966656) (xy 325.522696 -300.013169) (xy 325.485479 -300.054706)
			(xy 325.442611 -300.090381) (xy 325.395005 -300.119435) (xy 325.343676 -300.141247) (xy 325.289719 -300.155353)
			(xy 325.234282 -300.161453) (xy 325.178548 -300.159416) (xy 325.123705 -300.149286) (xy 325.070921 -300.131279)
			(xy 325.021321 -300.105778) (xy 324.975963 -300.073327) (xy 324.935814 -300.034618) (xy 324.901728 -299.990475)
			(xy 324.874432 -299.94184) (xy 324.854509 -299.889749) (xy 324.842383 -299.835312) (xy 324.838312 -299.77969)
			(xy 321.004922 -299.77969) (xy 321.004691 -299.792336) (xy 320.996571 -299.847512) (xy 320.980503 -299.900919)
			(xy 320.956831 -299.951416) (xy 320.926058 -299.997929) (xy 320.888841 -300.039466) (xy 320.845973 -300.075141)
			(xy 320.798367 -300.104195) (xy 320.747038 -300.126007) (xy 320.693081 -300.140113) (xy 320.637644 -300.146213)
			(xy 320.58191 -300.144176) (xy 320.527067 -300.134046) (xy 320.474283 -300.116039) (xy 320.424683 -300.090538)
			(xy 320.379325 -300.058087) (xy 320.339176 -300.019378) (xy 320.30509 -299.975235) (xy 320.277794 -299.9266)
			(xy 320.257871 -299.874509) (xy 320.245745 -299.820072) (xy 320.241674 -299.76445) (xy 318.205358 -299.76445)
			(xy 318.205358 -300.94936) (xy 318.205873 -300.959633) (xy 318.213988 -300.978513) (xy 318.221106 -300.985936)
			(xy 318.241065 -301.005681) (xy 318.269392 -301.04207) (xy 322.517006 -301.04207) (xy 322.521077 -300.986448)
			(xy 322.533203 -300.932011) (xy 322.553126 -300.87992) (xy 322.580422 -300.831285) (xy 322.614508 -300.787142)
			(xy 322.654657 -300.748433) (xy 322.700015 -300.715982) (xy 322.749615 -300.690481) (xy 322.802399 -300.672474)
			(xy 322.857242 -300.662344) (xy 322.912976 -300.660307) (xy 322.968413 -300.666407) (xy 323.02237 -300.680513)
			(xy 323.073699 -300.702325) (xy 323.121305 -300.731379) (xy 323.164173 -300.767054) (xy 323.20139 -300.808591)
			(xy 323.232163 -300.855104) (xy 323.255835 -300.905601) (xy 323.271903 -300.959008) (xy 323.280023 -301.014184)
			(xy 323.280532 -301.04207) (xy 323.280379 -301.050452) (xy 324.89089 -301.050452) (xy 324.894961 -300.99483)
			(xy 324.907087 -300.940393) (xy 324.92701 -300.888302) (xy 324.954306 -300.839667) (xy 324.988392 -300.795524)
			(xy 325.028541 -300.756815) (xy 325.073899 -300.724364) (xy 325.123499 -300.698863) (xy 325.176283 -300.680856)
			(xy 325.231126 -300.670726) (xy 325.28686 -300.668689) (xy 325.342297 -300.674789) (xy 325.396254 -300.688895)
			(xy 325.447583 -300.710707) (xy 325.495189 -300.739761) (xy 325.538057 -300.775436) (xy 325.575274 -300.816973)
			(xy 325.606047 -300.863486) (xy 325.629719 -300.913983) (xy 325.645787 -300.96739) (xy 325.653907 -301.022566)
			(xy 325.654416 -301.050452) (xy 325.653907 -301.078338) (xy 325.645787 -301.133514) (xy 325.629719 -301.186921)
			(xy 325.606047 -301.237418) (xy 325.575274 -301.283931) (xy 325.538057 -301.325468) (xy 325.495189 -301.361143)
			(xy 325.447583 -301.390197) (xy 325.396254 -301.412009) (xy 325.342297 -301.426115) (xy 325.28686 -301.432215)
			(xy 325.231126 -301.430178) (xy 325.176283 -301.420048) (xy 325.123499 -301.402041) (xy 325.073899 -301.37654)
			(xy 325.028541 -301.344089) (xy 324.988392 -301.30538) (xy 324.954306 -301.261237) (xy 324.92701 -301.212602)
			(xy 324.907087 -301.160511) (xy 324.894961 -301.106074) (xy 324.89089 -301.050452) (xy 323.280379 -301.050452)
			(xy 323.280023 -301.069956) (xy 323.271903 -301.125132) (xy 323.255835 -301.178539) (xy 323.232163 -301.229036)
			(xy 323.20139 -301.275549) (xy 323.164173 -301.317086) (xy 323.121305 -301.352761) (xy 323.073699 -301.381815)
			(xy 323.02237 -301.403627) (xy 322.968413 -301.417733) (xy 322.912976 -301.423833) (xy 322.857242 -301.421796)
			(xy 322.802399 -301.411666) (xy 322.749615 -301.393659) (xy 322.700015 -301.368158) (xy 322.654657 -301.335707)
			(xy 322.614508 -301.296998) (xy 322.580422 -301.252855) (xy 322.553126 -301.20422) (xy 322.533203 -301.152129)
			(xy 322.521077 -301.097692) (xy 322.517006 -301.04207) (xy 318.269392 -301.04207) (xy 318.275551 -301.049982)
			(xy 318.303177 -301.098856) (xy 318.323345 -301.15125) (xy 318.335622 -301.206033) (xy 318.339741 -301.262024)
			(xy 318.335615 -301.318013) (xy 318.323332 -301.372795) (xy 318.303157 -301.425186) (xy 318.275525 -301.474057)
			(xy 318.241033 -301.518354) (xy 318.221106 -301.538132) (xy 318.213981 -301.545554) (xy 318.20585 -301.564432)
			(xy 318.205358 -301.574708) (xy 318.205358 -301.83963) (xy 318.547494 -301.83963) (xy 318.551565 -301.784008)
			(xy 318.563691 -301.729571) (xy 318.583614 -301.67748) (xy 318.61091 -301.628845) (xy 318.644996 -301.584702)
			(xy 318.685145 -301.545993) (xy 318.730503 -301.513542) (xy 318.780103 -301.488041) (xy 318.832887 -301.470034)
			(xy 318.88773 -301.459904) (xy 318.943464 -301.457867) (xy 318.998901 -301.463967) (xy 319.052858 -301.478073)
			(xy 319.104187 -301.499885) (xy 319.151793 -301.528939) (xy 319.180237 -301.55261) (xy 320.319652 -301.55261)
			(xy 320.323723 -301.496988) (xy 320.335849 -301.442551) (xy 320.355772 -301.39046) (xy 320.383068 -301.341825)
			(xy 320.417154 -301.297682) (xy 320.457303 -301.258973) (xy 320.502661 -301.226522) (xy 320.552261 -301.201021)
			(xy 320.605045 -301.183014) (xy 320.659888 -301.172884) (xy 320.715622 -301.170847) (xy 320.771059 -301.176947)
			(xy 320.825016 -301.191053) (xy 320.876345 -301.212865) (xy 320.923951 -301.241919) (xy 320.966819 -301.277594)
			(xy 321.004036 -301.319131) (xy 321.034809 -301.365644) (xy 321.058481 -301.416141) (xy 321.074549 -301.469548)
			(xy 321.082669 -301.524724) (xy 321.083178 -301.55261) (xy 321.083099 -301.556928) (xy 323.713092 -301.556928)
			(xy 323.717163 -301.501306) (xy 323.729289 -301.446869) (xy 323.749212 -301.394778) (xy 323.776508 -301.346143)
			(xy 323.810594 -301.302) (xy 323.850743 -301.263291) (xy 323.896101 -301.23084) (xy 323.945701 -301.205339)
			(xy 323.998485 -301.187332) (xy 324.053328 -301.177202) (xy 324.109062 -301.175165) (xy 324.164499 -301.181265)
			(xy 324.218456 -301.195371) (xy 324.269785 -301.217183) (xy 324.317391 -301.246237) (xy 324.360259 -301.281912)
			(xy 324.397476 -301.323449) (xy 324.428249 -301.369962) (xy 324.451921 -301.420459) (xy 324.467989 -301.473866)
			(xy 324.476109 -301.529042) (xy 324.476618 -301.556928) (xy 324.476109 -301.584814) (xy 324.467989 -301.63999)
			(xy 324.451921 -301.693397) (xy 324.428249 -301.743894) (xy 324.397476 -301.790407) (xy 324.360259 -301.831944)
			(xy 324.317391 -301.867619) (xy 324.269785 -301.896673) (xy 324.218456 -301.918485) (xy 324.164499 -301.932591)
			(xy 324.109062 -301.938691) (xy 324.053328 -301.936654) (xy 323.998485 -301.926524) (xy 323.945701 -301.908517)
			(xy 323.896101 -301.883016) (xy 323.850743 -301.850565) (xy 323.810594 -301.811856) (xy 323.776508 -301.767713)
			(xy 323.749212 -301.719078) (xy 323.729289 -301.666987) (xy 323.717163 -301.61255) (xy 323.713092 -301.556928)
			(xy 321.083099 -301.556928) (xy 321.082669 -301.580496) (xy 321.074549 -301.635672) (xy 321.058481 -301.689079)
			(xy 321.034809 -301.739576) (xy 321.004036 -301.786089) (xy 320.966819 -301.827626) (xy 320.923951 -301.863301)
			(xy 320.876345 -301.892355) (xy 320.825016 -301.914167) (xy 320.771059 -301.928273) (xy 320.715622 -301.934373)
			(xy 320.659888 -301.932336) (xy 320.605045 -301.922206) (xy 320.552261 -301.904199) (xy 320.502661 -301.878698)
			(xy 320.457303 -301.846247) (xy 320.417154 -301.807538) (xy 320.383068 -301.763395) (xy 320.355772 -301.71476)
			(xy 320.335849 -301.662669) (xy 320.323723 -301.608232) (xy 320.319652 -301.55261) (xy 319.180237 -301.55261)
			(xy 319.194661 -301.564614) (xy 319.231878 -301.606151) (xy 319.262651 -301.652664) (xy 319.286323 -301.703161)
			(xy 319.302391 -301.756568) (xy 319.310511 -301.811744) (xy 319.31102 -301.83963) (xy 319.310511 -301.867516)
			(xy 319.302391 -301.922692) (xy 319.286323 -301.976099) (xy 319.262651 -302.026596) (xy 319.231878 -302.073109)
			(xy 319.194661 -302.114646) (xy 319.151793 -302.150321) (xy 319.104187 -302.179375) (xy 319.052858 -302.201187)
			(xy 318.998901 -302.215293) (xy 318.943464 -302.221393) (xy 318.88773 -302.219356) (xy 318.832887 -302.209226)
			(xy 318.780103 -302.191219) (xy 318.730503 -302.165718) (xy 318.685145 -302.133267) (xy 318.644996 -302.094558)
			(xy 318.61091 -302.050415) (xy 318.583614 -302.00178) (xy 318.563691 -301.949689) (xy 318.551565 -301.895252)
			(xy 318.547494 -301.83963) (xy 318.205358 -301.83963) (xy 318.205358 -302.455072) (xy 318.205827 -302.464946)
			(xy 318.213279 -302.483234) (xy 318.219836 -302.490632) (xy 318.22009 -302.490886) (xy 318.240664 -302.51146)
			(xy 318.247505 -302.51886) (xy 318.255223 -302.537459) (xy 318.255262 -302.538384) (xy 319.861182 -302.538384)
			(xy 319.865253 -302.482762) (xy 319.877379 -302.428325) (xy 319.897302 -302.376234) (xy 319.924598 -302.327599)
			(xy 319.958684 -302.283456) (xy 319.998833 -302.244747) (xy 320.044191 -302.212296) (xy 320.093791 -302.186795)
			(xy 320.146575 -302.168788) (xy 320.201418 -302.158658) (xy 320.257152 -302.156621) (xy 320.312589 -302.162721)
			(xy 320.366546 -302.176827) (xy 320.417875 -302.198639) (xy 320.465481 -302.227693) (xy 320.508349 -302.263368)
			(xy 320.545566 -302.304905) (xy 320.576339 -302.351418) (xy 320.600011 -302.401915) (xy 320.616079 -302.455322)
			(xy 320.624199 -302.510498) (xy 320.624708 -302.538384) (xy 320.624199 -302.56627) (xy 320.616079 -302.621446)
			(xy 320.600011 -302.674853) (xy 320.576339 -302.72535) (xy 320.545566 -302.771863) (xy 320.508349 -302.8134)
			(xy 320.465481 -302.849075) (xy 320.417875 -302.878129) (xy 320.366546 -302.899941) (xy 320.312589 -302.914047)
			(xy 320.257152 -302.920147) (xy 320.201418 -302.91811) (xy 320.146575 -302.90798) (xy 320.093791 -302.889973)
			(xy 320.044191 -302.864472) (xy 319.998833 -302.832021) (xy 319.958684 -302.793312) (xy 319.924598 -302.749169)
			(xy 319.897302 -302.700534) (xy 319.877379 -302.648443) (xy 319.865253 -302.594006) (xy 319.861182 -302.538384)
			(xy 318.255262 -302.538384) (xy 318.25565 -302.547528) (xy 318.25565 -303.05756) (xy 318.256062 -303.06717)
			(xy 318.263111 -303.085051) (xy 318.269366 -303.092358) (xy 318.289686 -303.114202) (xy 318.296072 -303.120493)
			(xy 318.312073 -303.128552) (xy 318.320928 -303.12995) (xy 318.349979 -303.133919) (xy 318.406469 -303.149617)
			(xy 318.459894 -303.173772) (xy 318.508995 -303.205814) (xy 318.552616 -303.24499) (xy 318.589732 -303.290378)
			(xy 318.619468 -303.340909) (xy 318.630808 -303.367948) (xy 318.63411 -303.376584) (xy 318.646302 -303.390046)
			(xy 318.723264 -303.429162) (xy 318.741044 -303.43094) (xy 318.750442 -303.428654) (xy 318.773726 -303.423057)
			(xy 318.821239 -303.417076) (xy 318.845184 -303.416716) (xy 318.872436 -303.417178) (xy 318.926385 -303.424933)
			(xy 318.978682 -303.440287) (xy 319.028261 -303.462927) (xy 319.074113 -303.492392) (xy 319.115305 -303.528084)
			(xy 319.150998 -303.569274) (xy 319.180466 -303.615125) (xy 319.203108 -303.664703) (xy 319.218464 -303.716999)
			(xy 319.226221 -303.770948) (xy 319.226221 -303.825452) (xy 319.218464 -303.879401) (xy 319.203108 -303.931697)
			(xy 319.180466 -303.981275) (xy 319.150998 -304.027126) (xy 319.115305 -304.068316) (xy 319.074113 -304.104008)
			(xy 319.028261 -304.133473) (xy 318.978682 -304.156113) (xy 318.926385 -304.171467) (xy 318.872436 -304.179222)
			(xy 318.845184 -304.179732) (xy 318.81953 -304.17897) (xy 318.810117 -304.17869) (xy 318.79214 -304.184257)
			(xy 318.777393 -304.195948) (xy 318.772286 -304.203862) (xy 318.757494 -304.228088) (xy 318.721869 -304.272277)
			(xy 318.680091 -304.310702) (xy 318.633083 -304.342515) (xy 318.581881 -304.367014) (xy 318.527615 -304.383658)
			(xy 318.471482 -304.392081) (xy 318.443102 -304.392584) (xy 318.426053 -304.392402) (xy 318.392092 -304.389348)
			(xy 318.375284 -304.386488) (xy 318.37503 -304.386488) (xy 318.363911 -304.385091) (xy 318.342287 -304.390873)
			(xy 318.333374 -304.397664) (xy 318.273684 -304.447702) (xy 318.26554 -304.455288) (xy 318.256166 -304.475447)
			(xy 318.25565 -304.486564) (xy 318.25565 -304.780052) (xy 320.049634 -304.780052) (xy 320.049634 -304.725548)
			(xy 320.05739 -304.671598) (xy 320.072744 -304.619301) (xy 320.095385 -304.569721) (xy 320.12485 -304.523868)
			(xy 320.16054 -304.482674) (xy 320.20173 -304.446979) (xy 320.247579 -304.417508) (xy 320.297156 -304.394861)
			(xy 320.349451 -304.3795) (xy 320.4034 -304.371737) (xy 320.430652 -304.371248) (xy 320.457798 -304.371686)
			(xy 320.511542 -304.379369) (xy 320.563653 -304.394598) (xy 320.613075 -304.417068) (xy 320.65881 -304.446323)
			(xy 320.699931 -304.481771) (xy 320.735606 -304.522694) (xy 320.765115 -304.568266) (xy 320.787858 -304.617563)
			(xy 320.803377 -304.669588) (xy 320.807842 -304.696368) (xy 320.810662 -304.711198) (xy 320.823697 -304.738407)
			(xy 320.844104 -304.760628) (xy 320.870107 -304.775928) (xy 320.899443 -304.782974) (xy 320.929558 -304.781155)
			(xy 320.957832 -304.770627) (xy 320.970148 -304.7619) (xy 320.990212 -304.747097) (xy 321.033428 -304.722226)
			(xy 321.079513 -304.703192) (xy 321.127683 -304.690317) (xy 321.177119 -304.683822) (xy 321.20205 -304.683414)
			(xy 321.229307 -304.683829) (xy 321.283266 -304.691581) (xy 321.335573 -304.706934) (xy 321.385163 -304.729575)
			(xy 321.431025 -304.759043) (xy 321.472226 -304.794739) (xy 321.507927 -304.835935) (xy 321.537401 -304.881793)
			(xy 321.560049 -304.93138) (xy 321.575408 -304.983685) (xy 321.583167 -305.037643) (xy 321.583167 -305.064922)
			(xy 321.835016 -305.064922) (xy 321.839087 -305.0093) (xy 321.851213 -304.954863) (xy 321.871136 -304.902772)
			(xy 321.898432 -304.854137) (xy 321.932518 -304.809994) (xy 321.972667 -304.771285) (xy 322.018025 -304.738834)
			(xy 322.067625 -304.713333) (xy 322.120409 -304.695326) (xy 322.175252 -304.685196) (xy 322.230986 -304.683159)
			(xy 322.286423 -304.689259) (xy 322.34038 -304.703365) (xy 322.391709 -304.725177) (xy 322.439315 -304.754231)
			(xy 322.482183 -304.789906) (xy 322.5194 -304.831443) (xy 322.550173 -304.877956) (xy 322.573845 -304.928453)
			(xy 322.589913 -304.98186) (xy 322.598033 -305.037036) (xy 322.598542 -305.064922) (xy 322.843396 -305.064922)
			(xy 322.847467 -305.0093) (xy 322.859593 -304.954863) (xy 322.879516 -304.902772) (xy 322.906812 -304.854137)
			(xy 322.940898 -304.809994) (xy 322.981047 -304.771285) (xy 323.026405 -304.738834) (xy 323.076005 -304.713333)
			(xy 323.128789 -304.695326) (xy 323.183632 -304.685196) (xy 323.239366 -304.683159) (xy 323.294803 -304.689259)
			(xy 323.34876 -304.703365) (xy 323.400089 -304.725177) (xy 323.447695 -304.754231) (xy 323.490563 -304.789906)
			(xy 323.52778 -304.831443) (xy 323.558553 -304.877956) (xy 323.582225 -304.928453) (xy 323.598293 -304.98186)
			(xy 323.606413 -305.037036) (xy 323.606903 -305.063906) (xy 323.868032 -305.063906) (xy 323.872103 -305.008284)
			(xy 323.884229 -304.953847) (xy 323.904152 -304.901756) (xy 323.931448 -304.853121) (xy 323.965534 -304.808978)
			(xy 324.005683 -304.770269) (xy 324.051041 -304.737818) (xy 324.100641 -304.712317) (xy 324.153425 -304.69431)
			(xy 324.208268 -304.68418) (xy 324.264002 -304.682143) (xy 324.319439 -304.688243) (xy 324.373396 -304.702349)
			(xy 324.424725 -304.724161) (xy 324.472331 -304.753215) (xy 324.515199 -304.78889) (xy 324.552416 -304.830427)
			(xy 324.583189 -304.87694) (xy 324.606861 -304.927437) (xy 324.622929 -304.980844) (xy 324.631049 -305.03602)
			(xy 324.631233 -305.046126) (xy 324.884032 -305.046126) (xy 324.888103 -304.990504) (xy 324.900229 -304.936067)
			(xy 324.920152 -304.883976) (xy 324.947448 -304.835341) (xy 324.981534 -304.791198) (xy 325.021683 -304.752489)
			(xy 325.067041 -304.720038) (xy 325.116641 -304.694537) (xy 325.169425 -304.67653) (xy 325.224268 -304.6664)
			(xy 325.280002 -304.664363) (xy 325.335439 -304.670463) (xy 325.389396 -304.684569) (xy 325.440725 -304.706381)
			(xy 325.488331 -304.735435) (xy 325.531199 -304.77111) (xy 325.568416 -304.812647) (xy 325.599189 -304.85916)
			(xy 325.622861 -304.909657) (xy 325.638929 -304.963064) (xy 325.647049 -305.01824) (xy 325.647558 -305.046126)
			(xy 325.647049 -305.074012) (xy 325.638929 -305.129188) (xy 325.622861 -305.182595) (xy 325.599189 -305.233092)
			(xy 325.568416 -305.279605) (xy 325.531199 -305.321142) (xy 325.488331 -305.356817) (xy 325.440725 -305.385871)
			(xy 325.389396 -305.407683) (xy 325.335439 -305.421789) (xy 325.280002 -305.427889) (xy 325.224268 -305.425852)
			(xy 325.169425 -305.415722) (xy 325.116641 -305.397715) (xy 325.067041 -305.372214) (xy 325.021683 -305.339763)
			(xy 324.981534 -305.301054) (xy 324.947448 -305.256911) (xy 324.920152 -305.208276) (xy 324.900229 -305.156185)
			(xy 324.888103 -305.101748) (xy 324.884032 -305.046126) (xy 324.631233 -305.046126) (xy 324.631558 -305.063906)
			(xy 324.631049 -305.091792) (xy 324.622929 -305.146968) (xy 324.606861 -305.200375) (xy 324.583189 -305.250872)
			(xy 324.552416 -305.297385) (xy 324.515199 -305.338922) (xy 324.472331 -305.374597) (xy 324.424725 -305.403651)
			(xy 324.373396 -305.425463) (xy 324.319439 -305.439569) (xy 324.264002 -305.445669) (xy 324.208268 -305.443632)
			(xy 324.153425 -305.433502) (xy 324.100641 -305.415495) (xy 324.051041 -305.389994) (xy 324.005683 -305.357543)
			(xy 323.965534 -305.318834) (xy 323.931448 -305.274691) (xy 323.904152 -305.226056) (xy 323.884229 -305.173965)
			(xy 323.872103 -305.119528) (xy 323.868032 -305.063906) (xy 323.606903 -305.063906) (xy 323.606922 -305.064922)
			(xy 323.606413 -305.092808) (xy 323.598293 -305.147984) (xy 323.582225 -305.201391) (xy 323.558553 -305.251888)
			(xy 323.52778 -305.298401) (xy 323.490563 -305.339938) (xy 323.447695 -305.375613) (xy 323.400089 -305.404667)
			(xy 323.34876 -305.426479) (xy 323.294803 -305.440585) (xy 323.239366 -305.446685) (xy 323.183632 -305.444648)
			(xy 323.128789 -305.434518) (xy 323.076005 -305.416511) (xy 323.026405 -305.39101) (xy 322.981047 -305.358559)
			(xy 322.940898 -305.31985) (xy 322.906812 -305.275707) (xy 322.879516 -305.227072) (xy 322.859593 -305.174981)
			(xy 322.847467 -305.120544) (xy 322.843396 -305.064922) (xy 322.598542 -305.064922) (xy 322.598033 -305.092808)
			(xy 322.589913 -305.147984) (xy 322.573845 -305.201391) (xy 322.550173 -305.251888) (xy 322.5194 -305.298401)
			(xy 322.482183 -305.339938) (xy 322.439315 -305.375613) (xy 322.391709 -305.404667) (xy 322.34038 -305.426479)
			(xy 322.286423 -305.440585) (xy 322.230986 -305.446685) (xy 322.175252 -305.444648) (xy 322.120409 -305.434518)
			(xy 322.067625 -305.416511) (xy 322.018025 -305.39101) (xy 321.972667 -305.358559) (xy 321.932518 -305.31985)
			(xy 321.898432 -305.275707) (xy 321.871136 -305.227072) (xy 321.851213 -305.174981) (xy 321.839087 -305.120544)
			(xy 321.835016 -305.064922) (xy 321.583167 -305.064922) (xy 321.583167 -305.092157) (xy 321.575408 -305.146115)
			(xy 321.560049 -305.19842) (xy 321.537401 -305.248007) (xy 321.507927 -305.293865) (xy 321.472226 -305.335061)
			(xy 321.431025 -305.370757) (xy 321.385163 -305.400225) (xy 321.335573 -305.422866) (xy 321.283266 -305.438219)
			(xy 321.229307 -305.445971) (xy 321.20205 -305.44643) (xy 321.174904 -305.446009) (xy 321.121158 -305.438326)
			(xy 321.069045 -305.423095) (xy 321.019622 -305.400624) (xy 320.973886 -305.371368) (xy 320.932765 -305.335918)
			(xy 320.89709 -305.294992) (xy 320.867582 -305.249418) (xy 320.84484 -305.200119) (xy 320.829323 -305.148091)
			(xy 320.82486 -305.12131) (xy 320.822048 -305.106479) (xy 320.809009 -305.079273) (xy 320.788599 -305.057054)
			(xy 320.762596 -305.041756) (xy 320.733261 -305.03471) (xy 320.703146 -305.036528) (xy 320.674871 -305.047052)
			(xy 320.662554 -305.055778) (xy 320.642497 -305.070592) (xy 320.599278 -305.095458) (xy 320.553191 -305.114489)
			(xy 320.50502 -305.127362) (xy 320.455583 -305.133857) (xy 320.430652 -305.134264) (xy 320.4034 -305.133863)
			(xy 320.349451 -305.1261) (xy 320.297156 -305.110739) (xy 320.247579 -305.088092) (xy 320.20173 -305.058621)
			(xy 320.16054 -305.022926) (xy 320.12485 -304.981732) (xy 320.095385 -304.935879) (xy 320.072744 -304.886299)
			(xy 320.05739 -304.834002) (xy 320.049634 -304.780052) (xy 318.25565 -304.780052) (xy 318.25565 -307.084222)
			(xy 324.914258 -307.084222) (xy 324.918329 -307.0286) (xy 324.930455 -306.974163) (xy 324.950378 -306.922072)
			(xy 324.977674 -306.873437) (xy 325.01176 -306.829294) (xy 325.051909 -306.790585) (xy 325.097267 -306.758134)
			(xy 325.146867 -306.732633) (xy 325.199651 -306.714626) (xy 325.254494 -306.704496) (xy 325.310228 -306.702459)
			(xy 325.365665 -306.708559) (xy 325.419622 -306.722665) (xy 325.470951 -306.744477) (xy 325.518557 -306.773531)
			(xy 325.561425 -306.809206) (xy 325.598642 -306.850743) (xy 325.629415 -306.897256) (xy 325.653087 -306.947753)
			(xy 325.669155 -307.00116) (xy 325.677275 -307.056336) (xy 325.677784 -307.084222) (xy 325.677275 -307.112108)
			(xy 325.669155 -307.167284) (xy 325.653087 -307.220691) (xy 325.629415 -307.271188) (xy 325.598642 -307.317701)
			(xy 325.561425 -307.359238) (xy 325.518557 -307.394913) (xy 325.470951 -307.423967) (xy 325.419622 -307.445779)
			(xy 325.365665 -307.459885) (xy 325.310228 -307.465985) (xy 325.254494 -307.463948) (xy 325.199651 -307.453818)
			(xy 325.146867 -307.435811) (xy 325.097267 -307.41031) (xy 325.051909 -307.377859) (xy 325.01176 -307.33915)
			(xy 324.977674 -307.295007) (xy 324.950378 -307.246372) (xy 324.930455 -307.194281) (xy 324.918329 -307.139844)
			(xy 324.914258 -307.084222) (xy 318.25565 -307.084222) (xy 318.25565 -309.175912) (xy 320.534028 -309.175912)
			(xy 320.538099 -309.12029) (xy 320.550225 -309.065853) (xy 320.570148 -309.013762) (xy 320.597444 -308.965127)
			(xy 320.63153 -308.920984) (xy 320.671679 -308.882275) (xy 320.717037 -308.849824) (xy 320.766637 -308.824323)
			(xy 320.819421 -308.806316) (xy 320.874264 -308.796186) (xy 320.929998 -308.794149) (xy 320.985435 -308.800249)
			(xy 321.039392 -308.814355) (xy 321.090721 -308.836167) (xy 321.138327 -308.865221) (xy 321.181195 -308.900896)
			(xy 321.218412 -308.942433) (xy 321.249185 -308.988946) (xy 321.272857 -309.039443) (xy 321.288925 -309.09285)
			(xy 321.297045 -309.148026) (xy 321.297554 -309.175912) (xy 321.297045 -309.203798) (xy 321.288925 -309.258974)
			(xy 321.272857 -309.312381) (xy 321.249185 -309.362878) (xy 321.218412 -309.409391) (xy 321.181195 -309.450928)
			(xy 321.138327 -309.486603) (xy 321.090721 -309.515657) (xy 321.039392 -309.537469) (xy 320.985435 -309.551575)
			(xy 320.929998 -309.557675) (xy 320.874264 -309.555638) (xy 320.819421 -309.545508) (xy 320.766637 -309.527501)
			(xy 320.717037 -309.502) (xy 320.671679 -309.469549) (xy 320.63153 -309.43084) (xy 320.597444 -309.386697)
			(xy 320.570148 -309.338062) (xy 320.550225 -309.285971) (xy 320.538099 -309.231534) (xy 320.534028 -309.175912)
			(xy 318.25565 -309.175912) (xy 318.25565 -309.85333) (xy 321.210684 -309.85333) (xy 321.214755 -309.797708)
			(xy 321.226881 -309.743271) (xy 321.246804 -309.69118) (xy 321.2741 -309.642545) (xy 321.308186 -309.598402)
			(xy 321.348335 -309.559693) (xy 321.393693 -309.527242) (xy 321.443293 -309.501741) (xy 321.496077 -309.483734)
			(xy 321.55092 -309.473604) (xy 321.606654 -309.471567) (xy 321.662091 -309.477667) (xy 321.716048 -309.491773)
			(xy 321.767377 -309.513585) (xy 321.814983 -309.542639) (xy 321.857851 -309.578314) (xy 321.895068 -309.619851)
			(xy 321.925841 -309.666364) (xy 321.949513 -309.716861) (xy 321.965581 -309.770268) (xy 321.973701 -309.825444)
			(xy 321.97421 -309.85333) (xy 321.973701 -309.881216) (xy 321.965581 -309.936392) (xy 321.949513 -309.989799)
			(xy 321.925841 -310.040296) (xy 321.895068 -310.086809) (xy 321.857851 -310.128346) (xy 321.814983 -310.164021)
			(xy 321.767377 -310.193075) (xy 321.716048 -310.214887) (xy 321.662091 -310.228993) (xy 321.606654 -310.235093)
			(xy 321.55092 -310.233056) (xy 321.496077 -310.222926) (xy 321.443293 -310.204919) (xy 321.393693 -310.179418)
			(xy 321.348335 -310.146967) (xy 321.308186 -310.108258) (xy 321.2741 -310.064115) (xy 321.246804 -310.01548)
			(xy 321.226881 -309.963389) (xy 321.214755 -309.908952) (xy 321.210684 -309.85333) (xy 318.25565 -309.85333)
			(xy 318.25565 -310.68518) (xy 322.042534 -310.68518) (xy 322.046605 -310.629558) (xy 322.058731 -310.575121)
			(xy 322.078654 -310.52303) (xy 322.10595 -310.474395) (xy 322.140036 -310.430252) (xy 322.180185 -310.391543)
			(xy 322.225543 -310.359092) (xy 322.275143 -310.333591) (xy 322.327927 -310.315584) (xy 322.38277 -310.305454)
			(xy 322.438504 -310.303417) (xy 322.493941 -310.309517) (xy 322.547898 -310.323623) (xy 322.599227 -310.345435)
			(xy 322.646833 -310.374489) (xy 322.689701 -310.410164) (xy 322.726918 -310.451701) (xy 322.757691 -310.498214)
			(xy 322.781363 -310.548711) (xy 322.797431 -310.602118) (xy 322.805551 -310.657294) (xy 322.80606 -310.68518)
			(xy 322.805551 -310.713066) (xy 322.797431 -310.768242) (xy 322.781363 -310.821649) (xy 322.757691 -310.872146)
			(xy 322.726918 -310.918659) (xy 322.689701 -310.960196) (xy 322.646833 -310.995871) (xy 322.599227 -311.024925)
			(xy 322.547898 -311.046737) (xy 322.493941 -311.060843) (xy 322.438504 -311.066943) (xy 322.38277 -311.064906)
			(xy 322.327927 -311.054776) (xy 322.275143 -311.036769) (xy 322.225543 -311.011268) (xy 322.180185 -310.978817)
			(xy 322.140036 -310.940108) (xy 322.10595 -310.895965) (xy 322.078654 -310.84733) (xy 322.058731 -310.795239)
			(xy 322.046605 -310.740802) (xy 322.042534 -310.68518) (xy 318.25565 -310.68518) (xy 318.25565 -311.380856)
			(xy 322.766688 -311.380856) (xy 322.774443 -311.326911) (xy 322.789796 -311.274618) (xy 322.812435 -311.225043)
			(xy 322.841898 -311.179194) (xy 322.877587 -311.138005) (xy 322.918773 -311.102314) (xy 322.96462 -311.072847)
			(xy 323.014194 -311.050205) (xy 323.066485 -311.034849) (xy 323.12043 -311.02709) (xy 323.174929 -311.027087)
			(xy 323.228874 -311.03484) (xy 323.281167 -311.050191) (xy 323.330743 -311.072828) (xy 323.376593 -311.102289)
			(xy 323.417784 -311.137976) (xy 323.453477 -311.179161) (xy 323.482945 -311.225007) (xy 323.498341 -311.258712)
			(xy 332.67218 -311.258712) (xy 332.676251 -311.20309) (xy 332.688377 -311.148653) (xy 332.7083 -311.096562)
			(xy 332.735596 -311.047927) (xy 332.769682 -311.003784) (xy 332.809831 -310.965075) (xy 332.855189 -310.932624)
			(xy 332.904789 -310.907123) (xy 332.957573 -310.889116) (xy 333.012416 -310.878986) (xy 333.06815 -310.876949)
			(xy 333.123587 -310.883049) (xy 333.177544 -310.897155) (xy 333.228873 -310.918967) (xy 333.276479 -310.948021)
			(xy 333.319347 -310.983696) (xy 333.356564 -311.025233) (xy 333.387337 -311.071746) (xy 333.411009 -311.122243)
			(xy 333.427077 -311.17565) (xy 333.435197 -311.230826) (xy 333.435706 -311.258712) (xy 333.68818 -311.258712)
			(xy 333.692251 -311.20309) (xy 333.704377 -311.148653) (xy 333.7243 -311.096562) (xy 333.751596 -311.047927)
			(xy 333.785682 -311.003784) (xy 333.825831 -310.965075) (xy 333.871189 -310.932624) (xy 333.920789 -310.907123)
			(xy 333.973573 -310.889116) (xy 334.028416 -310.878986) (xy 334.08415 -310.876949) (xy 334.139587 -310.883049)
			(xy 334.193544 -310.897155) (xy 334.244873 -310.918967) (xy 334.292479 -310.948021) (xy 334.335347 -310.983696)
			(xy 334.372564 -311.025233) (xy 334.403337 -311.071746) (xy 334.427009 -311.122243) (xy 334.443077 -311.17565)
			(xy 334.451197 -311.230826) (xy 334.451706 -311.258712) (xy 334.70418 -311.258712) (xy 334.708251 -311.20309)
			(xy 334.720377 -311.148653) (xy 334.7403 -311.096562) (xy 334.767596 -311.047927) (xy 334.801682 -311.003784)
			(xy 334.841831 -310.965075) (xy 334.887189 -310.932624) (xy 334.936789 -310.907123) (xy 334.989573 -310.889116)
			(xy 335.044416 -310.878986) (xy 335.10015 -310.876949) (xy 335.155587 -310.883049) (xy 335.209544 -310.897155)
			(xy 335.260873 -310.918967) (xy 335.308479 -310.948021) (xy 335.351347 -310.983696) (xy 335.388564 -311.025233)
			(xy 335.419337 -311.071746) (xy 335.443009 -311.122243) (xy 335.459077 -311.17565) (xy 335.467197 -311.230826)
			(xy 335.467706 -311.258712) (xy 335.72018 -311.258712) (xy 335.724251 -311.20309) (xy 335.736377 -311.148653)
			(xy 335.7563 -311.096562) (xy 335.783596 -311.047927) (xy 335.817682 -311.003784) (xy 335.857831 -310.965075)
			(xy 335.903189 -310.932624) (xy 335.952789 -310.907123) (xy 336.005573 -310.889116) (xy 336.060416 -310.878986)
			(xy 336.11615 -310.876949) (xy 336.171587 -310.883049) (xy 336.225544 -310.897155) (xy 336.276873 -310.918967)
			(xy 336.324479 -310.948021) (xy 336.367347 -310.983696) (xy 336.404564 -311.025233) (xy 336.435337 -311.071746)
			(xy 336.459009 -311.122243) (xy 336.475077 -311.17565) (xy 336.483197 -311.230826) (xy 336.483706 -311.258712)
			(xy 336.73618 -311.258712) (xy 336.740251 -311.20309) (xy 336.752377 -311.148653) (xy 336.7723 -311.096562)
			(xy 336.799596 -311.047927) (xy 336.833682 -311.003784) (xy 336.873831 -310.965075) (xy 336.919189 -310.932624)
			(xy 336.968789 -310.907123) (xy 337.021573 -310.889116) (xy 337.076416 -310.878986) (xy 337.13215 -310.876949)
			(xy 337.187587 -310.883049) (xy 337.241544 -310.897155) (xy 337.292873 -310.918967) (xy 337.340479 -310.948021)
			(xy 337.383347 -310.983696) (xy 337.420564 -311.025233) (xy 337.451337 -311.071746) (xy 337.475009 -311.122243)
			(xy 337.491077 -311.17565) (xy 337.499197 -311.230826) (xy 337.499706 -311.258712) (xy 337.75218 -311.258712)
			(xy 337.756251 -311.20309) (xy 337.768377 -311.148653) (xy 337.7883 -311.096562) (xy 337.815596 -311.047927)
			(xy 337.849682 -311.003784) (xy 337.889831 -310.965075) (xy 337.935189 -310.932624) (xy 337.984789 -310.907123)
			(xy 338.037573 -310.889116) (xy 338.092416 -310.878986) (xy 338.14815 -310.876949) (xy 338.203587 -310.883049)
			(xy 338.257544 -310.897155) (xy 338.308873 -310.918967) (xy 338.356479 -310.948021) (xy 338.399347 -310.983696)
			(xy 338.436564 -311.025233) (xy 338.467337 -311.071746) (xy 338.491009 -311.122243) (xy 338.507077 -311.17565)
			(xy 338.515197 -311.230826) (xy 338.515706 -311.258712) (xy 338.76818 -311.258712) (xy 338.772251 -311.20309)
			(xy 338.784377 -311.148653) (xy 338.8043 -311.096562) (xy 338.831596 -311.047927) (xy 338.865682 -311.003784)
			(xy 338.905831 -310.965075) (xy 338.951189 -310.932624) (xy 339.000789 -310.907123) (xy 339.053573 -310.889116)
			(xy 339.108416 -310.878986) (xy 339.16415 -310.876949) (xy 339.219587 -310.883049) (xy 339.273544 -310.897155)
			(xy 339.324873 -310.918967) (xy 339.372479 -310.948021) (xy 339.415347 -310.983696) (xy 339.452564 -311.025233)
			(xy 339.483337 -311.071746) (xy 339.507009 -311.122243) (xy 339.523077 -311.17565) (xy 339.531197 -311.230826)
			(xy 339.531706 -311.258712) (xy 339.78418 -311.258712) (xy 339.788251 -311.20309) (xy 339.800377 -311.148653)
			(xy 339.8203 -311.096562) (xy 339.847596 -311.047927) (xy 339.881682 -311.003784) (xy 339.921831 -310.965075)
			(xy 339.967189 -310.932624) (xy 340.016789 -310.907123) (xy 340.069573 -310.889116) (xy 340.124416 -310.878986)
			(xy 340.18015 -310.876949) (xy 340.235587 -310.883049) (xy 340.289544 -310.897155) (xy 340.340873 -310.918967)
			(xy 340.388479 -310.948021) (xy 340.431347 -310.983696) (xy 340.468564 -311.025233) (xy 340.499337 -311.071746)
			(xy 340.523009 -311.122243) (xy 340.539077 -311.17565) (xy 340.547197 -311.230826) (xy 340.547706 -311.258712)
			(xy 340.547197 -311.286598) (xy 340.539077 -311.341774) (xy 340.523009 -311.395181) (xy 340.499337 -311.445678)
			(xy 340.49431 -311.453276) (xy 357.436926 -311.453276) (xy 357.440997 -311.397654) (xy 357.453123 -311.343217)
			(xy 357.473046 -311.291126) (xy 357.500342 -311.242491) (xy 357.534428 -311.198348) (xy 357.574577 -311.159639)
			(xy 357.619935 -311.127188) (xy 357.669535 -311.101687) (xy 357.722319 -311.08368) (xy 357.777162 -311.07355)
			(xy 357.832896 -311.071513) (xy 357.888333 -311.077613) (xy 357.94229 -311.091719) (xy 357.993619 -311.113531)
			(xy 358.041225 -311.142585) (xy 358.084093 -311.17826) (xy 358.12131 -311.219797) (xy 358.152083 -311.26631)
			(xy 358.175755 -311.316807) (xy 358.191823 -311.370214) (xy 358.199943 -311.42539) (xy 358.200452 -311.453276)
			(xy 358.452926 -311.453276) (xy 358.456997 -311.397654) (xy 358.469123 -311.343217) (xy 358.489046 -311.291126)
			(xy 358.516342 -311.242491) (xy 358.550428 -311.198348) (xy 358.590577 -311.159639) (xy 358.635935 -311.127188)
			(xy 358.685535 -311.101687) (xy 358.738319 -311.08368) (xy 358.793162 -311.07355) (xy 358.848896 -311.071513)
			(xy 358.904333 -311.077613) (xy 358.95829 -311.091719) (xy 359.009619 -311.113531) (xy 359.057225 -311.142585)
			(xy 359.100093 -311.17826) (xy 359.13731 -311.219797) (xy 359.168083 -311.26631) (xy 359.191755 -311.316807)
			(xy 359.207823 -311.370214) (xy 359.215943 -311.42539) (xy 359.216452 -311.453276) (xy 359.468926 -311.453276)
			(xy 359.472997 -311.397654) (xy 359.485123 -311.343217) (xy 359.505046 -311.291126) (xy 359.532342 -311.242491)
			(xy 359.566428 -311.198348) (xy 359.606577 -311.159639) (xy 359.651935 -311.127188) (xy 359.701535 -311.101687)
			(xy 359.754319 -311.08368) (xy 359.809162 -311.07355) (xy 359.864896 -311.071513) (xy 359.920333 -311.077613)
			(xy 359.97429 -311.091719) (xy 360.025619 -311.113531) (xy 360.073225 -311.142585) (xy 360.116093 -311.17826)
			(xy 360.15331 -311.219797) (xy 360.184083 -311.26631) (xy 360.207755 -311.316807) (xy 360.223823 -311.370214)
			(xy 360.231943 -311.42539) (xy 360.232452 -311.453276) (xy 360.484926 -311.453276) (xy 360.488997 -311.397654)
			(xy 360.501123 -311.343217) (xy 360.521046 -311.291126) (xy 360.548342 -311.242491) (xy 360.582428 -311.198348)
			(xy 360.622577 -311.159639) (xy 360.667935 -311.127188) (xy 360.717535 -311.101687) (xy 360.770319 -311.08368)
			(xy 360.825162 -311.07355) (xy 360.880896 -311.071513) (xy 360.936333 -311.077613) (xy 360.99029 -311.091719)
			(xy 361.041619 -311.113531) (xy 361.089225 -311.142585) (xy 361.132093 -311.17826) (xy 361.16931 -311.219797)
			(xy 361.200083 -311.26631) (xy 361.223755 -311.316807) (xy 361.239823 -311.370214) (xy 361.247943 -311.42539)
			(xy 361.248452 -311.453276) (xy 361.500926 -311.453276) (xy 361.504997 -311.397654) (xy 361.517123 -311.343217)
			(xy 361.537046 -311.291126) (xy 361.564342 -311.242491) (xy 361.598428 -311.198348) (xy 361.638577 -311.159639)
			(xy 361.683935 -311.127188) (xy 361.733535 -311.101687) (xy 361.786319 -311.08368) (xy 361.841162 -311.07355)
			(xy 361.896896 -311.071513) (xy 361.952333 -311.077613) (xy 362.00629 -311.091719) (xy 362.057619 -311.113531)
			(xy 362.105225 -311.142585) (xy 362.148093 -311.17826) (xy 362.18531 -311.219797) (xy 362.216083 -311.26631)
			(xy 362.239755 -311.316807) (xy 362.255823 -311.370214) (xy 362.263943 -311.42539) (xy 362.264452 -311.453276)
			(xy 362.516926 -311.453276) (xy 362.520997 -311.397654) (xy 362.533123 -311.343217) (xy 362.553046 -311.291126)
			(xy 362.580342 -311.242491) (xy 362.614428 -311.198348) (xy 362.654577 -311.159639) (xy 362.699935 -311.127188)
			(xy 362.749535 -311.101687) (xy 362.802319 -311.08368) (xy 362.857162 -311.07355) (xy 362.912896 -311.071513)
			(xy 362.968333 -311.077613) (xy 363.02229 -311.091719) (xy 363.073619 -311.113531) (xy 363.121225 -311.142585)
			(xy 363.164093 -311.17826) (xy 363.20131 -311.219797) (xy 363.232083 -311.26631) (xy 363.255755 -311.316807)
			(xy 363.271823 -311.370214) (xy 363.279943 -311.42539) (xy 363.280452 -311.453276) (xy 363.532926 -311.453276)
			(xy 363.536997 -311.397654) (xy 363.549123 -311.343217) (xy 363.569046 -311.291126) (xy 363.596342 -311.242491)
			(xy 363.630428 -311.198348) (xy 363.670577 -311.159639) (xy 363.715935 -311.127188) (xy 363.765535 -311.101687)
			(xy 363.818319 -311.08368) (xy 363.873162 -311.07355) (xy 363.928896 -311.071513) (xy 363.984333 -311.077613)
			(xy 364.03829 -311.091719) (xy 364.089619 -311.113531) (xy 364.137225 -311.142585) (xy 364.180093 -311.17826)
			(xy 364.21731 -311.219797) (xy 364.248083 -311.26631) (xy 364.271755 -311.316807) (xy 364.287823 -311.370214)
			(xy 364.295943 -311.42539) (xy 364.296452 -311.453276) (xy 364.548926 -311.453276) (xy 364.552997 -311.397654)
			(xy 364.565123 -311.343217) (xy 364.585046 -311.291126) (xy 364.612342 -311.242491) (xy 364.646428 -311.198348)
			(xy 364.686577 -311.159639) (xy 364.731935 -311.127188) (xy 364.781535 -311.101687) (xy 364.834319 -311.08368)
			(xy 364.889162 -311.07355) (xy 364.944896 -311.071513) (xy 365.000333 -311.077613) (xy 365.05429 -311.091719)
			(xy 365.105619 -311.113531) (xy 365.153225 -311.142585) (xy 365.196093 -311.17826) (xy 365.23331 -311.219797)
			(xy 365.264083 -311.26631) (xy 365.287755 -311.316807) (xy 365.303823 -311.370214) (xy 365.311943 -311.42539)
			(xy 365.312452 -311.453276) (xy 365.311943 -311.481162) (xy 365.303823 -311.536338) (xy 365.287755 -311.589745)
			(xy 365.264083 -311.640242) (xy 365.23331 -311.686755) (xy 365.196093 -311.728292) (xy 365.153225 -311.763967)
			(xy 365.105619 -311.793021) (xy 365.05429 -311.814833) (xy 365.000333 -311.828939) (xy 364.944896 -311.835039)
			(xy 364.889162 -311.833002) (xy 364.834319 -311.822872) (xy 364.781535 -311.804865) (xy 364.731935 -311.779364)
			(xy 364.686577 -311.746913) (xy 364.646428 -311.708204) (xy 364.612342 -311.664061) (xy 364.585046 -311.615426)
			(xy 364.565123 -311.563335) (xy 364.552997 -311.508898) (xy 364.548926 -311.453276) (xy 364.296452 -311.453276)
			(xy 364.295943 -311.481162) (xy 364.287823 -311.536338) (xy 364.271755 -311.589745) (xy 364.248083 -311.640242)
			(xy 364.21731 -311.686755) (xy 364.180093 -311.728292) (xy 364.137225 -311.763967) (xy 364.089619 -311.793021)
			(xy 364.03829 -311.814833) (xy 363.984333 -311.828939) (xy 363.928896 -311.835039) (xy 363.873162 -311.833002)
			(xy 363.818319 -311.822872) (xy 363.765535 -311.804865) (xy 363.715935 -311.779364) (xy 363.670577 -311.746913)
			(xy 363.630428 -311.708204) (xy 363.596342 -311.664061) (xy 363.569046 -311.615426) (xy 363.549123 -311.563335)
			(xy 363.536997 -311.508898) (xy 363.532926 -311.453276) (xy 363.280452 -311.453276) (xy 363.279943 -311.481162)
			(xy 363.271823 -311.536338) (xy 363.255755 -311.589745) (xy 363.232083 -311.640242) (xy 363.20131 -311.686755)
			(xy 363.164093 -311.728292) (xy 363.121225 -311.763967) (xy 363.073619 -311.793021) (xy 363.02229 -311.814833)
			(xy 362.968333 -311.828939) (xy 362.912896 -311.835039) (xy 362.857162 -311.833002) (xy 362.802319 -311.822872)
			(xy 362.749535 -311.804865) (xy 362.699935 -311.779364) (xy 362.654577 -311.746913) (xy 362.614428 -311.708204)
			(xy 362.580342 -311.664061) (xy 362.553046 -311.615426) (xy 362.533123 -311.563335) (xy 362.520997 -311.508898)
			(xy 362.516926 -311.453276) (xy 362.264452 -311.453276) (xy 362.263943 -311.481162) (xy 362.255823 -311.536338)
			(xy 362.239755 -311.589745) (xy 362.216083 -311.640242) (xy 362.18531 -311.686755) (xy 362.148093 -311.728292)
			(xy 362.105225 -311.763967) (xy 362.057619 -311.793021) (xy 362.00629 -311.814833) (xy 361.952333 -311.828939)
			(xy 361.896896 -311.835039) (xy 361.841162 -311.833002) (xy 361.786319 -311.822872) (xy 361.733535 -311.804865)
			(xy 361.683935 -311.779364) (xy 361.638577 -311.746913) (xy 361.598428 -311.708204) (xy 361.564342 -311.664061)
			(xy 361.537046 -311.615426) (xy 361.517123 -311.563335) (xy 361.504997 -311.508898) (xy 361.500926 -311.453276)
			(xy 361.248452 -311.453276) (xy 361.247943 -311.481162) (xy 361.239823 -311.536338) (xy 361.223755 -311.589745)
			(xy 361.200083 -311.640242) (xy 361.16931 -311.686755) (xy 361.132093 -311.728292) (xy 361.089225 -311.763967)
			(xy 361.041619 -311.793021) (xy 360.99029 -311.814833) (xy 360.936333 -311.828939) (xy 360.880896 -311.835039)
			(xy 360.825162 -311.833002) (xy 360.770319 -311.822872) (xy 360.717535 -311.804865) (xy 360.667935 -311.779364)
			(xy 360.622577 -311.746913) (xy 360.582428 -311.708204) (xy 360.548342 -311.664061) (xy 360.521046 -311.615426)
			(xy 360.501123 -311.563335) (xy 360.488997 -311.508898) (xy 360.484926 -311.453276) (xy 360.232452 -311.453276)
			(xy 360.231943 -311.481162) (xy 360.223823 -311.536338) (xy 360.207755 -311.589745) (xy 360.184083 -311.640242)
			(xy 360.15331 -311.686755) (xy 360.116093 -311.728292) (xy 360.073225 -311.763967) (xy 360.025619 -311.793021)
			(xy 359.97429 -311.814833) (xy 359.920333 -311.828939) (xy 359.864896 -311.835039) (xy 359.809162 -311.833002)
			(xy 359.754319 -311.822872) (xy 359.701535 -311.804865) (xy 359.651935 -311.779364) (xy 359.606577 -311.746913)
			(xy 359.566428 -311.708204) (xy 359.532342 -311.664061) (xy 359.505046 -311.615426) (xy 359.485123 -311.563335)
			(xy 359.472997 -311.508898) (xy 359.468926 -311.453276) (xy 359.216452 -311.453276) (xy 359.215943 -311.481162)
			(xy 359.207823 -311.536338) (xy 359.191755 -311.589745) (xy 359.168083 -311.640242) (xy 359.13731 -311.686755)
			(xy 359.100093 -311.728292) (xy 359.057225 -311.763967) (xy 359.009619 -311.793021) (xy 358.95829 -311.814833)
			(xy 358.904333 -311.828939) (xy 358.848896 -311.835039) (xy 358.793162 -311.833002) (xy 358.738319 -311.822872)
			(xy 358.685535 -311.804865) (xy 358.635935 -311.779364) (xy 358.590577 -311.746913) (xy 358.550428 -311.708204)
			(xy 358.516342 -311.664061) (xy 358.489046 -311.615426) (xy 358.469123 -311.563335) (xy 358.456997 -311.508898)
			(xy 358.452926 -311.453276) (xy 358.200452 -311.453276) (xy 358.199943 -311.481162) (xy 358.191823 -311.536338)
			(xy 358.175755 -311.589745) (xy 358.152083 -311.640242) (xy 358.12131 -311.686755) (xy 358.084093 -311.728292)
			(xy 358.041225 -311.763967) (xy 357.993619 -311.793021) (xy 357.94229 -311.814833) (xy 357.888333 -311.828939)
			(xy 357.832896 -311.835039) (xy 357.777162 -311.833002) (xy 357.722319 -311.822872) (xy 357.669535 -311.804865)
			(xy 357.619935 -311.779364) (xy 357.574577 -311.746913) (xy 357.534428 -311.708204) (xy 357.500342 -311.664061)
			(xy 357.473046 -311.615426) (xy 357.453123 -311.563335) (xy 357.440997 -311.508898) (xy 357.436926 -311.453276)
			(xy 340.49431 -311.453276) (xy 340.468564 -311.492191) (xy 340.431347 -311.533728) (xy 340.388479 -311.569403)
			(xy 340.340873 -311.598457) (xy 340.289544 -311.620269) (xy 340.235587 -311.634375) (xy 340.18015 -311.640475)
			(xy 340.124416 -311.638438) (xy 340.069573 -311.628308) (xy 340.016789 -311.610301) (xy 339.967189 -311.5848)
			(xy 339.921831 -311.552349) (xy 339.881682 -311.51364) (xy 339.847596 -311.469497) (xy 339.8203 -311.420862)
			(xy 339.800377 -311.368771) (xy 339.788251 -311.314334) (xy 339.78418 -311.258712) (xy 339.531706 -311.258712)
			(xy 339.531197 -311.286598) (xy 339.523077 -311.341774) (xy 339.507009 -311.395181) (xy 339.483337 -311.445678)
			(xy 339.452564 -311.492191) (xy 339.415347 -311.533728) (xy 339.372479 -311.569403) (xy 339.324873 -311.598457)
			(xy 339.273544 -311.620269) (xy 339.219587 -311.634375) (xy 339.16415 -311.640475) (xy 339.108416 -311.638438)
			(xy 339.053573 -311.628308) (xy 339.000789 -311.610301) (xy 338.951189 -311.5848) (xy 338.905831 -311.552349)
			(xy 338.865682 -311.51364) (xy 338.831596 -311.469497) (xy 338.8043 -311.420862) (xy 338.784377 -311.368771)
			(xy 338.772251 -311.314334) (xy 338.76818 -311.258712) (xy 338.515706 -311.258712) (xy 338.515197 -311.286598)
			(xy 338.507077 -311.341774) (xy 338.491009 -311.395181) (xy 338.467337 -311.445678) (xy 338.436564 -311.492191)
			(xy 338.399347 -311.533728) (xy 338.356479 -311.569403) (xy 338.308873 -311.598457) (xy 338.257544 -311.620269)
			(xy 338.203587 -311.634375) (xy 338.14815 -311.640475) (xy 338.092416 -311.638438) (xy 338.037573 -311.628308)
			(xy 337.984789 -311.610301) (xy 337.935189 -311.5848) (xy 337.889831 -311.552349) (xy 337.849682 -311.51364)
			(xy 337.815596 -311.469497) (xy 337.7883 -311.420862) (xy 337.768377 -311.368771) (xy 337.756251 -311.314334)
			(xy 337.75218 -311.258712) (xy 337.499706 -311.258712) (xy 337.499197 -311.286598) (xy 337.491077 -311.341774)
			(xy 337.475009 -311.395181) (xy 337.451337 -311.445678) (xy 337.420564 -311.492191) (xy 337.383347 -311.533728)
			(xy 337.340479 -311.569403) (xy 337.292873 -311.598457) (xy 337.241544 -311.620269) (xy 337.187587 -311.634375)
			(xy 337.13215 -311.640475) (xy 337.076416 -311.638438) (xy 337.021573 -311.628308) (xy 336.968789 -311.610301)
			(xy 336.919189 -311.5848) (xy 336.873831 -311.552349) (xy 336.833682 -311.51364) (xy 336.799596 -311.469497)
			(xy 336.7723 -311.420862) (xy 336.752377 -311.368771) (xy 336.740251 -311.314334) (xy 336.73618 -311.258712)
			(xy 336.483706 -311.258712) (xy 336.483197 -311.286598) (xy 336.475077 -311.341774) (xy 336.459009 -311.395181)
			(xy 336.435337 -311.445678) (xy 336.404564 -311.492191) (xy 336.367347 -311.533728) (xy 336.324479 -311.569403)
			(xy 336.276873 -311.598457) (xy 336.225544 -311.620269) (xy 336.171587 -311.634375) (xy 336.11615 -311.640475)
			(xy 336.060416 -311.638438) (xy 336.005573 -311.628308) (xy 335.952789 -311.610301) (xy 335.903189 -311.5848)
			(xy 335.857831 -311.552349) (xy 335.817682 -311.51364) (xy 335.783596 -311.469497) (xy 335.7563 -311.420862)
			(xy 335.736377 -311.368771) (xy 335.724251 -311.314334) (xy 335.72018 -311.258712) (xy 335.467706 -311.258712)
			(xy 335.467197 -311.286598) (xy 335.459077 -311.341774) (xy 335.443009 -311.395181) (xy 335.419337 -311.445678)
			(xy 335.388564 -311.492191) (xy 335.351347 -311.533728) (xy 335.308479 -311.569403) (xy 335.260873 -311.598457)
			(xy 335.209544 -311.620269) (xy 335.155587 -311.634375) (xy 335.10015 -311.640475) (xy 335.044416 -311.638438)
			(xy 334.989573 -311.628308) (xy 334.936789 -311.610301) (xy 334.887189 -311.5848) (xy 334.841831 -311.552349)
			(xy 334.801682 -311.51364) (xy 334.767596 -311.469497) (xy 334.7403 -311.420862) (xy 334.720377 -311.368771)
			(xy 334.708251 -311.314334) (xy 334.70418 -311.258712) (xy 334.451706 -311.258712) (xy 334.451197 -311.286598)
			(xy 334.443077 -311.341774) (xy 334.427009 -311.395181) (xy 334.403337 -311.445678) (xy 334.372564 -311.492191)
			(xy 334.335347 -311.533728) (xy 334.292479 -311.569403) (xy 334.244873 -311.598457) (xy 334.193544 -311.620269)
			(xy 334.139587 -311.634375) (xy 334.08415 -311.640475) (xy 334.028416 -311.638438) (xy 333.973573 -311.628308)
			(xy 333.920789 -311.610301) (xy 333.871189 -311.5848) (xy 333.825831 -311.552349) (xy 333.785682 -311.51364)
			(xy 333.751596 -311.469497) (xy 333.7243 -311.420862) (xy 333.704377 -311.368771) (xy 333.692251 -311.314334)
			(xy 333.68818 -311.258712) (xy 333.435706 -311.258712) (xy 333.435197 -311.286598) (xy 333.427077 -311.341774)
			(xy 333.411009 -311.395181) (xy 333.387337 -311.445678) (xy 333.356564 -311.492191) (xy 333.319347 -311.533728)
			(xy 333.276479 -311.569403) (xy 333.228873 -311.598457) (xy 333.177544 -311.620269) (xy 333.123587 -311.634375)
			(xy 333.06815 -311.640475) (xy 333.012416 -311.638438) (xy 332.957573 -311.628308) (xy 332.904789 -311.610301)
			(xy 332.855189 -311.5848) (xy 332.809831 -311.552349) (xy 332.769682 -311.51364) (xy 332.735596 -311.469497)
			(xy 332.7083 -311.420862) (xy 332.688377 -311.368771) (xy 332.676251 -311.314334) (xy 332.67218 -311.258712)
			(xy 323.498341 -311.258712) (xy 323.505589 -311.274579) (xy 323.520948 -311.32687) (xy 323.528709 -311.380814)
			(xy 323.529198 -311.408064) (xy 323.529002 -311.425112) (xy 323.525947 -311.459072) (xy 323.523102 -311.475882)
			(xy 323.521061 -311.489765) (xy 323.523783 -311.517684) (xy 323.53399 -311.543811) (xy 323.550916 -311.566181)
			(xy 323.573284 -311.583107) (xy 323.599411 -311.593316) (xy 323.62733 -311.596039) (xy 323.641212 -311.593992)
			(xy 323.658083 -311.591119) (xy 323.692171 -311.588068) (xy 323.709284 -311.587896) (xy 323.736538 -311.588338)
			(xy 323.790492 -311.596093) (xy 323.842793 -311.611448) (xy 323.892377 -311.634089) (xy 323.938233 -311.663557)
			(xy 323.979429 -311.699251) (xy 324.015126 -311.740444) (xy 324.044597 -311.786299) (xy 324.067243 -311.835881)
			(xy 324.082601 -311.88818) (xy 324.09036 -311.942134) (xy 324.090362 -311.996642) (xy 324.082606 -312.050596)
			(xy 324.067251 -312.102897) (xy 324.044609 -312.15248) (xy 324.015141 -312.198336) (xy 323.979446 -312.239532)
			(xy 323.938849 -312.274712) (xy 332.67218 -312.274712) (xy 332.676251 -312.21909) (xy 332.688377 -312.164653)
			(xy 332.7083 -312.112562) (xy 332.735596 -312.063927) (xy 332.769682 -312.019784) (xy 332.809831 -311.981075)
			(xy 332.855189 -311.948624) (xy 332.904789 -311.923123) (xy 332.957573 -311.905116) (xy 333.012416 -311.894986)
			(xy 333.06815 -311.892949) (xy 333.123587 -311.899049) (xy 333.177544 -311.913155) (xy 333.228873 -311.934967)
			(xy 333.276479 -311.964021) (xy 333.319347 -311.999696) (xy 333.356564 -312.041233) (xy 333.387337 -312.087746)
			(xy 333.411009 -312.138243) (xy 333.427077 -312.19165) (xy 333.435197 -312.246826) (xy 333.435706 -312.274712)
			(xy 333.68818 -312.274712) (xy 333.692251 -312.21909) (xy 333.704377 -312.164653) (xy 333.7243 -312.112562)
			(xy 333.751596 -312.063927) (xy 333.785682 -312.019784) (xy 333.825831 -311.981075) (xy 333.871189 -311.948624)
			(xy 333.920789 -311.923123) (xy 333.973573 -311.905116) (xy 334.028416 -311.894986) (xy 334.08415 -311.892949)
			(xy 334.139587 -311.899049) (xy 334.193544 -311.913155) (xy 334.244873 -311.934967) (xy 334.292479 -311.964021)
			(xy 334.335347 -311.999696) (xy 334.372564 -312.041233) (xy 334.403337 -312.087746) (xy 334.427009 -312.138243)
			(xy 334.443077 -312.19165) (xy 334.451197 -312.246826) (xy 334.451706 -312.274712) (xy 334.70418 -312.274712)
			(xy 334.708251 -312.21909) (xy 334.720377 -312.164653) (xy 334.7403 -312.112562) (xy 334.767596 -312.063927)
			(xy 334.801682 -312.019784) (xy 334.841831 -311.981075) (xy 334.887189 -311.948624) (xy 334.936789 -311.923123)
			(xy 334.989573 -311.905116) (xy 335.044416 -311.894986) (xy 335.10015 -311.892949) (xy 335.155587 -311.899049)
			(xy 335.209544 -311.913155) (xy 335.260873 -311.934967) (xy 335.308479 -311.964021) (xy 335.351347 -311.999696)
			(xy 335.388564 -312.041233) (xy 335.419337 -312.087746) (xy 335.443009 -312.138243) (xy 335.459077 -312.19165)
			(xy 335.467197 -312.246826) (xy 335.467706 -312.274712) (xy 335.72018 -312.274712) (xy 335.724251 -312.21909)
			(xy 335.736377 -312.164653) (xy 335.7563 -312.112562) (xy 335.783596 -312.063927) (xy 335.817682 -312.019784)
			(xy 335.857831 -311.981075) (xy 335.903189 -311.948624) (xy 335.952789 -311.923123) (xy 336.005573 -311.905116)
			(xy 336.060416 -311.894986) (xy 336.11615 -311.892949) (xy 336.171587 -311.899049) (xy 336.225544 -311.913155)
			(xy 336.276873 -311.934967) (xy 336.324479 -311.964021) (xy 336.367347 -311.999696) (xy 336.404564 -312.041233)
			(xy 336.435337 -312.087746) (xy 336.459009 -312.138243) (xy 336.475077 -312.19165) (xy 336.483197 -312.246826)
			(xy 336.483706 -312.274712) (xy 336.73618 -312.274712) (xy 336.740251 -312.21909) (xy 336.752377 -312.164653)
			(xy 336.7723 -312.112562) (xy 336.799596 -312.063927) (xy 336.833682 -312.019784) (xy 336.873831 -311.981075)
			(xy 336.919189 -311.948624) (xy 336.968789 -311.923123) (xy 337.021573 -311.905116) (xy 337.076416 -311.894986)
			(xy 337.13215 -311.892949) (xy 337.187587 -311.899049) (xy 337.241544 -311.913155) (xy 337.292873 -311.934967)
			(xy 337.340479 -311.964021) (xy 337.383347 -311.999696) (xy 337.420564 -312.041233) (xy 337.451337 -312.087746)
			(xy 337.475009 -312.138243) (xy 337.491077 -312.19165) (xy 337.499197 -312.246826) (xy 337.499706 -312.274712)
			(xy 337.75218 -312.274712) (xy 337.756251 -312.21909) (xy 337.768377 -312.164653) (xy 337.7883 -312.112562)
			(xy 337.815596 -312.063927) (xy 337.849682 -312.019784) (xy 337.889831 -311.981075) (xy 337.935189 -311.948624)
			(xy 337.984789 -311.923123) (xy 338.037573 -311.905116) (xy 338.092416 -311.894986) (xy 338.14815 -311.892949)
			(xy 338.203587 -311.899049) (xy 338.257544 -311.913155) (xy 338.308873 -311.934967) (xy 338.356479 -311.964021)
			(xy 338.399347 -311.999696) (xy 338.436564 -312.041233) (xy 338.467337 -312.087746) (xy 338.491009 -312.138243)
			(xy 338.507077 -312.19165) (xy 338.515197 -312.246826) (xy 338.515706 -312.274712) (xy 338.76818 -312.274712)
			(xy 338.772251 -312.21909) (xy 338.784377 -312.164653) (xy 338.8043 -312.112562) (xy 338.831596 -312.063927)
			(xy 338.865682 -312.019784) (xy 338.905831 -311.981075) (xy 338.951189 -311.948624) (xy 339.000789 -311.923123)
			(xy 339.053573 -311.905116) (xy 339.108416 -311.894986) (xy 339.16415 -311.892949) (xy 339.219587 -311.899049)
			(xy 339.273544 -311.913155) (xy 339.324873 -311.934967) (xy 339.372479 -311.964021) (xy 339.415347 -311.999696)
			(xy 339.452564 -312.041233) (xy 339.483337 -312.087746) (xy 339.507009 -312.138243) (xy 339.523077 -312.19165)
			(xy 339.531197 -312.246826) (xy 339.531706 -312.274712) (xy 339.78418 -312.274712) (xy 339.788251 -312.21909)
			(xy 339.800377 -312.164653) (xy 339.8203 -312.112562) (xy 339.847596 -312.063927) (xy 339.881682 -312.019784)
			(xy 339.921831 -311.981075) (xy 339.967189 -311.948624) (xy 340.016789 -311.923123) (xy 340.069573 -311.905116)
			(xy 340.124416 -311.894986) (xy 340.18015 -311.892949) (xy 340.235587 -311.899049) (xy 340.289544 -311.913155)
			(xy 340.340873 -311.934967) (xy 340.388479 -311.964021) (xy 340.431347 -311.999696) (xy 340.468564 -312.041233)
			(xy 340.499337 -312.087746) (xy 340.523009 -312.138243) (xy 340.539077 -312.19165) (xy 340.547197 -312.246826)
			(xy 340.547706 -312.274712) (xy 340.80018 -312.274712) (xy 340.804251 -312.21909) (xy 340.816377 -312.164653)
			(xy 340.8363 -312.112562) (xy 340.863596 -312.063927) (xy 340.897682 -312.019784) (xy 340.937831 -311.981075)
			(xy 340.983189 -311.948624) (xy 341.032789 -311.923123) (xy 341.085573 -311.905116) (xy 341.140416 -311.894986)
			(xy 341.19615 -311.892949) (xy 341.251587 -311.899049) (xy 341.305544 -311.913155) (xy 341.356873 -311.934967)
			(xy 341.404479 -311.964021) (xy 341.447347 -311.999696) (xy 341.484564 -312.041233) (xy 341.515337 -312.087746)
			(xy 341.539009 -312.138243) (xy 341.555077 -312.19165) (xy 341.563197 -312.246826) (xy 341.563706 -312.274712)
			(xy 341.81618 -312.274712) (xy 341.820251 -312.21909) (xy 341.832377 -312.164653) (xy 341.8523 -312.112562)
			(xy 341.879596 -312.063927) (xy 341.913682 -312.019784) (xy 341.953831 -311.981075) (xy 341.999189 -311.948624)
			(xy 342.048789 -311.923123) (xy 342.101573 -311.905116) (xy 342.156416 -311.894986) (xy 342.21215 -311.892949)
			(xy 342.267587 -311.899049) (xy 342.321544 -311.913155) (xy 342.372873 -311.934967) (xy 342.420479 -311.964021)
			(xy 342.463347 -311.999696) (xy 342.500564 -312.041233) (xy 342.531337 -312.087746) (xy 342.555009 -312.138243)
			(xy 342.571077 -312.19165) (xy 342.579197 -312.246826) (xy 342.579706 -312.274712) (xy 342.579197 -312.302598)
			(xy 342.571077 -312.357774) (xy 342.555009 -312.411181) (xy 342.531337 -312.461678) (xy 342.52631 -312.469276)
			(xy 357.436926 -312.469276) (xy 357.440997 -312.413654) (xy 357.453123 -312.359217) (xy 357.473046 -312.307126)
			(xy 357.500342 -312.258491) (xy 357.534428 -312.214348) (xy 357.574577 -312.175639) (xy 357.619935 -312.143188)
			(xy 357.669535 -312.117687) (xy 357.722319 -312.09968) (xy 357.777162 -312.08955) (xy 357.832896 -312.087513)
			(xy 357.888333 -312.093613) (xy 357.94229 -312.107719) (xy 357.993619 -312.129531) (xy 358.041225 -312.158585)
			(xy 358.084093 -312.19426) (xy 358.12131 -312.235797) (xy 358.152083 -312.28231) (xy 358.175755 -312.332807)
			(xy 358.191823 -312.386214) (xy 358.199943 -312.44139) (xy 358.200452 -312.469276) (xy 358.452926 -312.469276)
			(xy 358.456997 -312.413654) (xy 358.469123 -312.359217) (xy 358.489046 -312.307126) (xy 358.516342 -312.258491)
			(xy 358.550428 -312.214348) (xy 358.590577 -312.175639) (xy 358.635935 -312.143188) (xy 358.685535 -312.117687)
			(xy 358.738319 -312.09968) (xy 358.793162 -312.08955) (xy 358.848896 -312.087513) (xy 358.904333 -312.093613)
			(xy 358.95829 -312.107719) (xy 359.009619 -312.129531) (xy 359.057225 -312.158585) (xy 359.100093 -312.19426)
			(xy 359.13731 -312.235797) (xy 359.168083 -312.28231) (xy 359.191755 -312.332807) (xy 359.207823 -312.386214)
			(xy 359.215943 -312.44139) (xy 359.216452 -312.469276) (xy 359.468926 -312.469276) (xy 359.472997 -312.413654)
			(xy 359.485123 -312.359217) (xy 359.505046 -312.307126) (xy 359.532342 -312.258491) (xy 359.566428 -312.214348)
			(xy 359.606577 -312.175639) (xy 359.651935 -312.143188) (xy 359.701535 -312.117687) (xy 359.754319 -312.09968)
			(xy 359.809162 -312.08955) (xy 359.864896 -312.087513) (xy 359.920333 -312.093613) (xy 359.97429 -312.107719)
			(xy 360.025619 -312.129531) (xy 360.073225 -312.158585) (xy 360.116093 -312.19426) (xy 360.15331 -312.235797)
			(xy 360.184083 -312.28231) (xy 360.207755 -312.332807) (xy 360.223823 -312.386214) (xy 360.231943 -312.44139)
			(xy 360.232452 -312.469276) (xy 360.484926 -312.469276) (xy 360.488997 -312.413654) (xy 360.501123 -312.359217)
			(xy 360.521046 -312.307126) (xy 360.548342 -312.258491) (xy 360.582428 -312.214348) (xy 360.622577 -312.175639)
			(xy 360.667935 -312.143188) (xy 360.717535 -312.117687) (xy 360.770319 -312.09968) (xy 360.825162 -312.08955)
			(xy 360.880896 -312.087513) (xy 360.936333 -312.093613) (xy 360.99029 -312.107719) (xy 361.041619 -312.129531)
			(xy 361.089225 -312.158585) (xy 361.132093 -312.19426) (xy 361.16931 -312.235797) (xy 361.200083 -312.28231)
			(xy 361.223755 -312.332807) (xy 361.239823 -312.386214) (xy 361.247943 -312.44139) (xy 361.248452 -312.469276)
			(xy 361.500926 -312.469276) (xy 361.504997 -312.413654) (xy 361.517123 -312.359217) (xy 361.537046 -312.307126)
			(xy 361.564342 -312.258491) (xy 361.598428 -312.214348) (xy 361.638577 -312.175639) (xy 361.683935 -312.143188)
			(xy 361.733535 -312.117687) (xy 361.786319 -312.09968) (xy 361.841162 -312.08955) (xy 361.896896 -312.087513)
			(xy 361.952333 -312.093613) (xy 362.00629 -312.107719) (xy 362.057619 -312.129531) (xy 362.105225 -312.158585)
			(xy 362.148093 -312.19426) (xy 362.18531 -312.235797) (xy 362.216083 -312.28231) (xy 362.239755 -312.332807)
			(xy 362.255823 -312.386214) (xy 362.263943 -312.44139) (xy 362.264452 -312.469276) (xy 362.516926 -312.469276)
			(xy 362.520997 -312.413654) (xy 362.533123 -312.359217) (xy 362.553046 -312.307126) (xy 362.580342 -312.258491)
			(xy 362.614428 -312.214348) (xy 362.654577 -312.175639) (xy 362.699935 -312.143188) (xy 362.749535 -312.117687)
			(xy 362.802319 -312.09968) (xy 362.857162 -312.08955) (xy 362.912896 -312.087513) (xy 362.968333 -312.093613)
			(xy 363.02229 -312.107719) (xy 363.073619 -312.129531) (xy 363.121225 -312.158585) (xy 363.164093 -312.19426)
			(xy 363.20131 -312.235797) (xy 363.232083 -312.28231) (xy 363.255755 -312.332807) (xy 363.271823 -312.386214)
			(xy 363.279943 -312.44139) (xy 363.280452 -312.469276) (xy 363.532926 -312.469276) (xy 363.536997 -312.413654)
			(xy 363.549123 -312.359217) (xy 363.569046 -312.307126) (xy 363.596342 -312.258491) (xy 363.630428 -312.214348)
			(xy 363.670577 -312.175639) (xy 363.715935 -312.143188) (xy 363.765535 -312.117687) (xy 363.818319 -312.09968)
			(xy 363.873162 -312.08955) (xy 363.928896 -312.087513) (xy 363.984333 -312.093613) (xy 364.03829 -312.107719)
			(xy 364.089619 -312.129531) (xy 364.137225 -312.158585) (xy 364.180093 -312.19426) (xy 364.21731 -312.235797)
			(xy 364.248083 -312.28231) (xy 364.271755 -312.332807) (xy 364.287823 -312.386214) (xy 364.295943 -312.44139)
			(xy 364.296452 -312.469276) (xy 364.295943 -312.497162) (xy 364.287823 -312.552338) (xy 364.271755 -312.605745)
			(xy 364.248083 -312.656242) (xy 364.21731 -312.702755) (xy 364.180093 -312.744292) (xy 364.137225 -312.779967)
			(xy 364.089619 -312.809021) (xy 364.03829 -312.830833) (xy 363.984333 -312.844939) (xy 363.928896 -312.851039)
			(xy 363.873162 -312.849002) (xy 363.818319 -312.838872) (xy 363.765535 -312.820865) (xy 363.715935 -312.795364)
			(xy 363.670577 -312.762913) (xy 363.630428 -312.724204) (xy 363.596342 -312.680061) (xy 363.569046 -312.631426)
			(xy 363.549123 -312.579335) (xy 363.536997 -312.524898) (xy 363.532926 -312.469276) (xy 363.280452 -312.469276)
			(xy 363.279943 -312.497162) (xy 363.271823 -312.552338) (xy 363.255755 -312.605745) (xy 363.232083 -312.656242)
			(xy 363.20131 -312.702755) (xy 363.164093 -312.744292) (xy 363.121225 -312.779967) (xy 363.073619 -312.809021)
			(xy 363.02229 -312.830833) (xy 362.968333 -312.844939) (xy 362.912896 -312.851039) (xy 362.857162 -312.849002)
			(xy 362.802319 -312.838872) (xy 362.749535 -312.820865) (xy 362.699935 -312.795364) (xy 362.654577 -312.762913)
			(xy 362.614428 -312.724204) (xy 362.580342 -312.680061) (xy 362.553046 -312.631426) (xy 362.533123 -312.579335)
			(xy 362.520997 -312.524898) (xy 362.516926 -312.469276) (xy 362.264452 -312.469276) (xy 362.263943 -312.497162)
			(xy 362.255823 -312.552338) (xy 362.239755 -312.605745) (xy 362.216083 -312.656242) (xy 362.18531 -312.702755)
			(xy 362.148093 -312.744292) (xy 362.105225 -312.779967) (xy 362.057619 -312.809021) (xy 362.00629 -312.830833)
			(xy 361.952333 -312.844939) (xy 361.896896 -312.851039) (xy 361.841162 -312.849002) (xy 361.786319 -312.838872)
			(xy 361.733535 -312.820865) (xy 361.683935 -312.795364) (xy 361.638577 -312.762913) (xy 361.598428 -312.724204)
			(xy 361.564342 -312.680061) (xy 361.537046 -312.631426) (xy 361.517123 -312.579335) (xy 361.504997 -312.524898)
			(xy 361.500926 -312.469276) (xy 361.248452 -312.469276) (xy 361.247943 -312.497162) (xy 361.239823 -312.552338)
			(xy 361.223755 -312.605745) (xy 361.200083 -312.656242) (xy 361.16931 -312.702755) (xy 361.132093 -312.744292)
			(xy 361.089225 -312.779967) (xy 361.041619 -312.809021) (xy 360.99029 -312.830833) (xy 360.936333 -312.844939)
			(xy 360.880896 -312.851039) (xy 360.825162 -312.849002) (xy 360.770319 -312.838872) (xy 360.717535 -312.820865)
			(xy 360.667935 -312.795364) (xy 360.622577 -312.762913) (xy 360.582428 -312.724204) (xy 360.548342 -312.680061)
			(xy 360.521046 -312.631426) (xy 360.501123 -312.579335) (xy 360.488997 -312.524898) (xy 360.484926 -312.469276)
			(xy 360.232452 -312.469276) (xy 360.231943 -312.497162) (xy 360.223823 -312.552338) (xy 360.207755 -312.605745)
			(xy 360.184083 -312.656242) (xy 360.15331 -312.702755) (xy 360.116093 -312.744292) (xy 360.073225 -312.779967)
			(xy 360.025619 -312.809021) (xy 359.97429 -312.830833) (xy 359.920333 -312.844939) (xy 359.864896 -312.851039)
			(xy 359.809162 -312.849002) (xy 359.754319 -312.838872) (xy 359.701535 -312.820865) (xy 359.651935 -312.795364)
			(xy 359.606577 -312.762913) (xy 359.566428 -312.724204) (xy 359.532342 -312.680061) (xy 359.505046 -312.631426)
			(xy 359.485123 -312.579335) (xy 359.472997 -312.524898) (xy 359.468926 -312.469276) (xy 359.216452 -312.469276)
			(xy 359.215943 -312.497162) (xy 359.207823 -312.552338) (xy 359.191755 -312.605745) (xy 359.168083 -312.656242)
			(xy 359.13731 -312.702755) (xy 359.100093 -312.744292) (xy 359.057225 -312.779967) (xy 359.009619 -312.809021)
			(xy 358.95829 -312.830833) (xy 358.904333 -312.844939) (xy 358.848896 -312.851039) (xy 358.793162 -312.849002)
			(xy 358.738319 -312.838872) (xy 358.685535 -312.820865) (xy 358.635935 -312.795364) (xy 358.590577 -312.762913)
			(xy 358.550428 -312.724204) (xy 358.516342 -312.680061) (xy 358.489046 -312.631426) (xy 358.469123 -312.579335)
			(xy 358.456997 -312.524898) (xy 358.452926 -312.469276) (xy 358.200452 -312.469276) (xy 358.199943 -312.497162)
			(xy 358.191823 -312.552338) (xy 358.175755 -312.605745) (xy 358.152083 -312.656242) (xy 358.12131 -312.702755)
			(xy 358.084093 -312.744292) (xy 358.041225 -312.779967) (xy 357.993619 -312.809021) (xy 357.94229 -312.830833)
			(xy 357.888333 -312.844939) (xy 357.832896 -312.851039) (xy 357.777162 -312.849002) (xy 357.722319 -312.838872)
			(xy 357.669535 -312.820865) (xy 357.619935 -312.795364) (xy 357.574577 -312.762913) (xy 357.534428 -312.724204)
			(xy 357.500342 -312.680061) (xy 357.473046 -312.631426) (xy 357.453123 -312.579335) (xy 357.440997 -312.524898)
			(xy 357.436926 -312.469276) (xy 342.52631 -312.469276) (xy 342.500564 -312.508191) (xy 342.463347 -312.549728)
			(xy 342.420479 -312.585403) (xy 342.372873 -312.614457) (xy 342.321544 -312.636269) (xy 342.267587 -312.650375)
			(xy 342.21215 -312.656475) (xy 342.156416 -312.654438) (xy 342.101573 -312.644308) (xy 342.048789 -312.626301)
			(xy 341.999189 -312.6008) (xy 341.953831 -312.568349) (xy 341.913682 -312.52964) (xy 341.879596 -312.485497)
			(xy 341.8523 -312.436862) (xy 341.832377 -312.384771) (xy 341.820251 -312.330334) (xy 341.81618 -312.274712)
			(xy 341.563706 -312.274712) (xy 341.563197 -312.302598) (xy 341.555077 -312.357774) (xy 341.539009 -312.411181)
			(xy 341.515337 -312.461678) (xy 341.484564 -312.508191) (xy 341.447347 -312.549728) (xy 341.404479 -312.585403)
			(xy 341.356873 -312.614457) (xy 341.305544 -312.636269) (xy 341.251587 -312.650375) (xy 341.19615 -312.656475)
			(xy 341.140416 -312.654438) (xy 341.085573 -312.644308) (xy 341.032789 -312.626301) (xy 340.983189 -312.6008)
			(xy 340.937831 -312.568349) (xy 340.897682 -312.52964) (xy 340.863596 -312.485497) (xy 340.8363 -312.436862)
			(xy 340.816377 -312.384771) (xy 340.804251 -312.330334) (xy 340.80018 -312.274712) (xy 340.547706 -312.274712)
			(xy 340.547197 -312.302598) (xy 340.539077 -312.357774) (xy 340.523009 -312.411181) (xy 340.499337 -312.461678)
			(xy 340.468564 -312.508191) (xy 340.431347 -312.549728) (xy 340.388479 -312.585403) (xy 340.340873 -312.614457)
			(xy 340.289544 -312.636269) (xy 340.235587 -312.650375) (xy 340.18015 -312.656475) (xy 340.124416 -312.654438)
			(xy 340.069573 -312.644308) (xy 340.016789 -312.626301) (xy 339.967189 -312.6008) (xy 339.921831 -312.568349)
			(xy 339.881682 -312.52964) (xy 339.847596 -312.485497) (xy 339.8203 -312.436862) (xy 339.800377 -312.384771)
			(xy 339.788251 -312.330334) (xy 339.78418 -312.274712) (xy 339.531706 -312.274712) (xy 339.531197 -312.302598)
			(xy 339.523077 -312.357774) (xy 339.507009 -312.411181) (xy 339.483337 -312.461678) (xy 339.452564 -312.508191)
			(xy 339.415347 -312.549728) (xy 339.372479 -312.585403) (xy 339.324873 -312.614457) (xy 339.273544 -312.636269)
			(xy 339.219587 -312.650375) (xy 339.16415 -312.656475) (xy 339.108416 -312.654438) (xy 339.053573 -312.644308)
			(xy 339.000789 -312.626301) (xy 338.951189 -312.6008) (xy 338.905831 -312.568349) (xy 338.865682 -312.52964)
			(xy 338.831596 -312.485497) (xy 338.8043 -312.436862) (xy 338.784377 -312.384771) (xy 338.772251 -312.330334)
			(xy 338.76818 -312.274712) (xy 338.515706 -312.274712) (xy 338.515197 -312.302598) (xy 338.507077 -312.357774)
			(xy 338.491009 -312.411181) (xy 338.467337 -312.461678) (xy 338.436564 -312.508191) (xy 338.399347 -312.549728)
			(xy 338.356479 -312.585403) (xy 338.308873 -312.614457) (xy 338.257544 -312.636269) (xy 338.203587 -312.650375)
			(xy 338.14815 -312.656475) (xy 338.092416 -312.654438) (xy 338.037573 -312.644308) (xy 337.984789 -312.626301)
			(xy 337.935189 -312.6008) (xy 337.889831 -312.568349) (xy 337.849682 -312.52964) (xy 337.815596 -312.485497)
			(xy 337.7883 -312.436862) (xy 337.768377 -312.384771) (xy 337.756251 -312.330334) (xy 337.75218 -312.274712)
			(xy 337.499706 -312.274712) (xy 337.499197 -312.302598) (xy 337.491077 -312.357774) (xy 337.475009 -312.411181)
			(xy 337.451337 -312.461678) (xy 337.420564 -312.508191) (xy 337.383347 -312.549728) (xy 337.340479 -312.585403)
			(xy 337.292873 -312.614457) (xy 337.241544 -312.636269) (xy 337.187587 -312.650375) (xy 337.13215 -312.656475)
			(xy 337.076416 -312.654438) (xy 337.021573 -312.644308) (xy 336.968789 -312.626301) (xy 336.919189 -312.6008)
			(xy 336.873831 -312.568349) (xy 336.833682 -312.52964) (xy 336.799596 -312.485497) (xy 336.7723 -312.436862)
			(xy 336.752377 -312.384771) (xy 336.740251 -312.330334) (xy 336.73618 -312.274712) (xy 336.483706 -312.274712)
			(xy 336.483197 -312.302598) (xy 336.475077 -312.357774) (xy 336.459009 -312.411181) (xy 336.435337 -312.461678)
			(xy 336.404564 -312.508191) (xy 336.367347 -312.549728) (xy 336.324479 -312.585403) (xy 336.276873 -312.614457)
			(xy 336.225544 -312.636269) (xy 336.171587 -312.650375) (xy 336.11615 -312.656475) (xy 336.060416 -312.654438)
			(xy 336.005573 -312.644308) (xy 335.952789 -312.626301) (xy 335.903189 -312.6008) (xy 335.857831 -312.568349)
			(xy 335.817682 -312.52964) (xy 335.783596 -312.485497) (xy 335.7563 -312.436862) (xy 335.736377 -312.384771)
			(xy 335.724251 -312.330334) (xy 335.72018 -312.274712) (xy 335.467706 -312.274712) (xy 335.467197 -312.302598)
			(xy 335.459077 -312.357774) (xy 335.443009 -312.411181) (xy 335.419337 -312.461678) (xy 335.388564 -312.508191)
			(xy 335.351347 -312.549728) (xy 335.308479 -312.585403) (xy 335.260873 -312.614457) (xy 335.209544 -312.636269)
			(xy 335.155587 -312.650375) (xy 335.10015 -312.656475) (xy 335.044416 -312.654438) (xy 334.989573 -312.644308)
			(xy 334.936789 -312.626301) (xy 334.887189 -312.6008) (xy 334.841831 -312.568349) (xy 334.801682 -312.52964)
			(xy 334.767596 -312.485497) (xy 334.7403 -312.436862) (xy 334.720377 -312.384771) (xy 334.708251 -312.330334)
			(xy 334.70418 -312.274712) (xy 334.451706 -312.274712) (xy 334.451197 -312.302598) (xy 334.443077 -312.357774)
			(xy 334.427009 -312.411181) (xy 334.403337 -312.461678) (xy 334.372564 -312.508191) (xy 334.335347 -312.549728)
			(xy 334.292479 -312.585403) (xy 334.244873 -312.614457) (xy 334.193544 -312.636269) (xy 334.139587 -312.650375)
			(xy 334.08415 -312.656475) (xy 334.028416 -312.654438) (xy 333.973573 -312.644308) (xy 333.920789 -312.626301)
			(xy 333.871189 -312.6008) (xy 333.825831 -312.568349) (xy 333.785682 -312.52964) (xy 333.751596 -312.485497)
			(xy 333.7243 -312.436862) (xy 333.704377 -312.384771) (xy 333.692251 -312.330334) (xy 333.68818 -312.274712)
			(xy 333.435706 -312.274712) (xy 333.435197 -312.302598) (xy 333.427077 -312.357774) (xy 333.411009 -312.411181)
			(xy 333.387337 -312.461678) (xy 333.356564 -312.508191) (xy 333.319347 -312.549728) (xy 333.276479 -312.585403)
			(xy 333.228873 -312.614457) (xy 333.177544 -312.636269) (xy 333.123587 -312.650375) (xy 333.06815 -312.656475)
			(xy 333.012416 -312.654438) (xy 332.957573 -312.644308) (xy 332.904789 -312.626301) (xy 332.855189 -312.6008)
			(xy 332.809831 -312.568349) (xy 332.769682 -312.52964) (xy 332.735596 -312.485497) (xy 332.7083 -312.436862)
			(xy 332.688377 -312.384771) (xy 332.676251 -312.330334) (xy 332.67218 -312.274712) (xy 323.938849 -312.274712)
			(xy 323.938252 -312.275229) (xy 323.892398 -312.304699) (xy 323.842816 -312.327344) (xy 323.790516 -312.342702)
			(xy 323.736562 -312.350461) (xy 323.682054 -312.350462) (xy 323.6281 -312.342705) (xy 323.575799 -312.32735)
			(xy 323.526216 -312.304707) (xy 323.48036 -312.275238) (xy 323.439165 -312.239543) (xy 323.403469 -312.198349)
			(xy 323.373999 -312.152494) (xy 323.351355 -312.102912) (xy 323.335997 -312.050612) (xy 323.328239 -311.996658)
			(xy 323.327776 -311.969404) (xy 323.327981 -311.952356) (xy 323.33103 -311.918397) (xy 323.333872 -311.901586)
			(xy 323.335976 -311.88771) (xy 323.333247 -311.859783) (xy 323.323029 -311.833649) (xy 323.306093 -311.811277)
			(xy 323.283714 -311.79435) (xy 323.257576 -311.784144) (xy 323.229648 -311.781425) (xy 323.215762 -311.783476)
			(xy 323.19889 -311.78634) (xy 323.164802 -311.789396) (xy 323.14769 -311.789572) (xy 323.12044 -311.789111)
			(xy 323.066496 -311.781354) (xy 323.014204 -311.765998) (xy 322.96463 -311.743358) (xy 322.918782 -311.713893)
			(xy 322.877594 -311.678203) (xy 322.841905 -311.637014) (xy 322.81244 -311.591166) (xy 322.7898 -311.541592)
			(xy 322.774445 -311.4893) (xy 322.766689 -311.435355) (xy 322.766688 -311.380856) (xy 318.25565 -311.380856)
			(xy 318.25565 -313.290712) (xy 332.67218 -313.290712) (xy 332.676251 -313.23509) (xy 332.688377 -313.180653)
			(xy 332.7083 -313.128562) (xy 332.735596 -313.079927) (xy 332.769682 -313.035784) (xy 332.809831 -312.997075)
			(xy 332.855189 -312.964624) (xy 332.904789 -312.939123) (xy 332.957573 -312.921116) (xy 333.012416 -312.910986)
			(xy 333.06815 -312.908949) (xy 333.123587 -312.915049) (xy 333.177544 -312.929155) (xy 333.228873 -312.950967)
			(xy 333.276479 -312.980021) (xy 333.319347 -313.015696) (xy 333.356564 -313.057233) (xy 333.387337 -313.103746)
			(xy 333.411009 -313.154243) (xy 333.427077 -313.20765) (xy 333.435197 -313.262826) (xy 333.435706 -313.290712)
			(xy 333.68818 -313.290712) (xy 333.692251 -313.23509) (xy 333.704377 -313.180653) (xy 333.7243 -313.128562)
			(xy 333.751596 -313.079927) (xy 333.785682 -313.035784) (xy 333.825831 -312.997075) (xy 333.871189 -312.964624)
			(xy 333.920789 -312.939123) (xy 333.973573 -312.921116) (xy 334.028416 -312.910986) (xy 334.08415 -312.908949)
			(xy 334.139587 -312.915049) (xy 334.193544 -312.929155) (xy 334.244873 -312.950967) (xy 334.292479 -312.980021)
			(xy 334.335347 -313.015696) (xy 334.372564 -313.057233) (xy 334.403337 -313.103746) (xy 334.427009 -313.154243)
			(xy 334.443077 -313.20765) (xy 334.451197 -313.262826) (xy 334.451706 -313.290712) (xy 334.70418 -313.290712)
			(xy 334.708251 -313.23509) (xy 334.720377 -313.180653) (xy 334.7403 -313.128562) (xy 334.767596 -313.079927)
			(xy 334.801682 -313.035784) (xy 334.841831 -312.997075) (xy 334.887189 -312.964624) (xy 334.936789 -312.939123)
			(xy 334.989573 -312.921116) (xy 335.044416 -312.910986) (xy 335.10015 -312.908949) (xy 335.155587 -312.915049)
			(xy 335.209544 -312.929155) (xy 335.260873 -312.950967) (xy 335.308479 -312.980021) (xy 335.351347 -313.015696)
			(xy 335.388564 -313.057233) (xy 335.419337 -313.103746) (xy 335.443009 -313.154243) (xy 335.459077 -313.20765)
			(xy 335.467197 -313.262826) (xy 335.467706 -313.290712) (xy 335.72018 -313.290712) (xy 335.724251 -313.23509)
			(xy 335.736377 -313.180653) (xy 335.7563 -313.128562) (xy 335.783596 -313.079927) (xy 335.817682 -313.035784)
			(xy 335.857831 -312.997075) (xy 335.903189 -312.964624) (xy 335.952789 -312.939123) (xy 336.005573 -312.921116)
			(xy 336.060416 -312.910986) (xy 336.11615 -312.908949) (xy 336.171587 -312.915049) (xy 336.225544 -312.929155)
			(xy 336.276873 -312.950967) (xy 336.324479 -312.980021) (xy 336.367347 -313.015696) (xy 336.404564 -313.057233)
			(xy 336.435337 -313.103746) (xy 336.459009 -313.154243) (xy 336.475077 -313.20765) (xy 336.483197 -313.262826)
			(xy 336.483706 -313.290712) (xy 336.73618 -313.290712) (xy 336.740251 -313.23509) (xy 336.752377 -313.180653)
			(xy 336.7723 -313.128562) (xy 336.799596 -313.079927) (xy 336.833682 -313.035784) (xy 336.873831 -312.997075)
			(xy 336.919189 -312.964624) (xy 336.968789 -312.939123) (xy 337.021573 -312.921116) (xy 337.076416 -312.910986)
			(xy 337.13215 -312.908949) (xy 337.187587 -312.915049) (xy 337.241544 -312.929155) (xy 337.292873 -312.950967)
			(xy 337.340479 -312.980021) (xy 337.383347 -313.015696) (xy 337.420564 -313.057233) (xy 337.451337 -313.103746)
			(xy 337.475009 -313.154243) (xy 337.491077 -313.20765) (xy 337.499197 -313.262826) (xy 337.499706 -313.290712)
			(xy 337.75218 -313.290712) (xy 337.756251 -313.23509) (xy 337.768377 -313.180653) (xy 337.7883 -313.128562)
			(xy 337.815596 -313.079927) (xy 337.849682 -313.035784) (xy 337.889831 -312.997075) (xy 337.935189 -312.964624)
			(xy 337.984789 -312.939123) (xy 338.037573 -312.921116) (xy 338.092416 -312.910986) (xy 338.14815 -312.908949)
			(xy 338.203587 -312.915049) (xy 338.257544 -312.929155) (xy 338.308873 -312.950967) (xy 338.356479 -312.980021)
			(xy 338.399347 -313.015696) (xy 338.436564 -313.057233) (xy 338.467337 -313.103746) (xy 338.491009 -313.154243)
			(xy 338.507077 -313.20765) (xy 338.515197 -313.262826) (xy 338.515706 -313.290712) (xy 338.76818 -313.290712)
			(xy 338.772251 -313.23509) (xy 338.784377 -313.180653) (xy 338.8043 -313.128562) (xy 338.831596 -313.079927)
			(xy 338.865682 -313.035784) (xy 338.905831 -312.997075) (xy 338.951189 -312.964624) (xy 339.000789 -312.939123)
			(xy 339.053573 -312.921116) (xy 339.108416 -312.910986) (xy 339.16415 -312.908949) (xy 339.219587 -312.915049)
			(xy 339.273544 -312.929155) (xy 339.324873 -312.950967) (xy 339.372479 -312.980021) (xy 339.415347 -313.015696)
			(xy 339.452564 -313.057233) (xy 339.483337 -313.103746) (xy 339.507009 -313.154243) (xy 339.523077 -313.20765)
			(xy 339.531197 -313.262826) (xy 339.531706 -313.290712) (xy 339.78418 -313.290712) (xy 339.788251 -313.23509)
			(xy 339.800377 -313.180653) (xy 339.8203 -313.128562) (xy 339.847596 -313.079927) (xy 339.881682 -313.035784)
			(xy 339.921831 -312.997075) (xy 339.967189 -312.964624) (xy 340.016789 -312.939123) (xy 340.069573 -312.921116)
			(xy 340.124416 -312.910986) (xy 340.18015 -312.908949) (xy 340.235587 -312.915049) (xy 340.289544 -312.929155)
			(xy 340.340873 -312.950967) (xy 340.388479 -312.980021) (xy 340.431347 -313.015696) (xy 340.468564 -313.057233)
			(xy 340.499337 -313.103746) (xy 340.523009 -313.154243) (xy 340.539077 -313.20765) (xy 340.547197 -313.262826)
			(xy 340.547706 -313.290712) (xy 340.80018 -313.290712) (xy 340.804251 -313.23509) (xy 340.816377 -313.180653)
			(xy 340.8363 -313.128562) (xy 340.863596 -313.079927) (xy 340.897682 -313.035784) (xy 340.937831 -312.997075)
			(xy 340.983189 -312.964624) (xy 341.032789 -312.939123) (xy 341.085573 -312.921116) (xy 341.140416 -312.910986)
			(xy 341.19615 -312.908949) (xy 341.251587 -312.915049) (xy 341.305544 -312.929155) (xy 341.356873 -312.950967)
			(xy 341.404479 -312.980021) (xy 341.447347 -313.015696) (xy 341.484564 -313.057233) (xy 341.515337 -313.103746)
			(xy 341.539009 -313.154243) (xy 341.555077 -313.20765) (xy 341.563197 -313.262826) (xy 341.563706 -313.290712)
			(xy 341.81618 -313.290712) (xy 341.820251 -313.23509) (xy 341.832377 -313.180653) (xy 341.8523 -313.128562)
			(xy 341.879596 -313.079927) (xy 341.913682 -313.035784) (xy 341.953831 -312.997075) (xy 341.999189 -312.964624)
			(xy 342.048789 -312.939123) (xy 342.101573 -312.921116) (xy 342.156416 -312.910986) (xy 342.21215 -312.908949)
			(xy 342.267587 -312.915049) (xy 342.321544 -312.929155) (xy 342.372873 -312.950967) (xy 342.420479 -312.980021)
			(xy 342.463347 -313.015696) (xy 342.500564 -313.057233) (xy 342.531337 -313.103746) (xy 342.555009 -313.154243)
			(xy 342.571077 -313.20765) (xy 342.579197 -313.262826) (xy 342.579706 -313.290712) (xy 342.579197 -313.318598)
			(xy 342.571077 -313.373774) (xy 342.555009 -313.427181) (xy 342.531337 -313.477678) (xy 342.52631 -313.485276)
			(xy 357.436926 -313.485276) (xy 357.440997 -313.429654) (xy 357.453123 -313.375217) (xy 357.473046 -313.323126)
			(xy 357.500342 -313.274491) (xy 357.534428 -313.230348) (xy 357.574577 -313.191639) (xy 357.619935 -313.159188)
			(xy 357.669535 -313.133687) (xy 357.722319 -313.11568) (xy 357.777162 -313.10555) (xy 357.832896 -313.103513)
			(xy 357.888333 -313.109613) (xy 357.94229 -313.123719) (xy 357.993619 -313.145531) (xy 358.041225 -313.174585)
			(xy 358.084093 -313.21026) (xy 358.12131 -313.251797) (xy 358.152083 -313.29831) (xy 358.175755 -313.348807)
			(xy 358.191823 -313.402214) (xy 358.199943 -313.45739) (xy 358.200452 -313.485276) (xy 358.452926 -313.485276)
			(xy 358.456997 -313.429654) (xy 358.469123 -313.375217) (xy 358.489046 -313.323126) (xy 358.516342 -313.274491)
			(xy 358.550428 -313.230348) (xy 358.590577 -313.191639) (xy 358.635935 -313.159188) (xy 358.685535 -313.133687)
			(xy 358.738319 -313.11568) (xy 358.793162 -313.10555) (xy 358.848896 -313.103513) (xy 358.904333 -313.109613)
			(xy 358.95829 -313.123719) (xy 359.009619 -313.145531) (xy 359.057225 -313.174585) (xy 359.100093 -313.21026)
			(xy 359.13731 -313.251797) (xy 359.168083 -313.29831) (xy 359.191755 -313.348807) (xy 359.207823 -313.402214)
			(xy 359.215943 -313.45739) (xy 359.216452 -313.485276) (xy 359.468926 -313.485276) (xy 359.472997 -313.429654)
			(xy 359.485123 -313.375217) (xy 359.505046 -313.323126) (xy 359.532342 -313.274491) (xy 359.566428 -313.230348)
			(xy 359.606577 -313.191639) (xy 359.651935 -313.159188) (xy 359.701535 -313.133687) (xy 359.754319 -313.11568)
			(xy 359.809162 -313.10555) (xy 359.864896 -313.103513) (xy 359.920333 -313.109613) (xy 359.97429 -313.123719)
			(xy 360.025619 -313.145531) (xy 360.073225 -313.174585) (xy 360.116093 -313.21026) (xy 360.15331 -313.251797)
			(xy 360.184083 -313.29831) (xy 360.207755 -313.348807) (xy 360.223823 -313.402214) (xy 360.231943 -313.45739)
			(xy 360.232452 -313.485276) (xy 360.484926 -313.485276) (xy 360.488997 -313.429654) (xy 360.501123 -313.375217)
			(xy 360.521046 -313.323126) (xy 360.548342 -313.274491) (xy 360.582428 -313.230348) (xy 360.622577 -313.191639)
			(xy 360.667935 -313.159188) (xy 360.717535 -313.133687) (xy 360.770319 -313.11568) (xy 360.825162 -313.10555)
			(xy 360.880896 -313.103513) (xy 360.936333 -313.109613) (xy 360.99029 -313.123719) (xy 361.041619 -313.145531)
			(xy 361.089225 -313.174585) (xy 361.132093 -313.21026) (xy 361.16931 -313.251797) (xy 361.200083 -313.29831)
			(xy 361.223755 -313.348807) (xy 361.239823 -313.402214) (xy 361.247943 -313.45739) (xy 361.248452 -313.485276)
			(xy 361.500926 -313.485276) (xy 361.504997 -313.429654) (xy 361.517123 -313.375217) (xy 361.537046 -313.323126)
			(xy 361.564342 -313.274491) (xy 361.598428 -313.230348) (xy 361.638577 -313.191639) (xy 361.683935 -313.159188)
			(xy 361.733535 -313.133687) (xy 361.786319 -313.11568) (xy 361.841162 -313.10555) (xy 361.896896 -313.103513)
			(xy 361.952333 -313.109613) (xy 362.00629 -313.123719) (xy 362.057619 -313.145531) (xy 362.105225 -313.174585)
			(xy 362.148093 -313.21026) (xy 362.18531 -313.251797) (xy 362.216083 -313.29831) (xy 362.239755 -313.348807)
			(xy 362.255823 -313.402214) (xy 362.263943 -313.45739) (xy 362.264452 -313.485276) (xy 362.516926 -313.485276)
			(xy 362.520997 -313.429654) (xy 362.533123 -313.375217) (xy 362.553046 -313.323126) (xy 362.580342 -313.274491)
			(xy 362.614428 -313.230348) (xy 362.654577 -313.191639) (xy 362.699935 -313.159188) (xy 362.749535 -313.133687)
			(xy 362.802319 -313.11568) (xy 362.857162 -313.10555) (xy 362.912896 -313.103513) (xy 362.968333 -313.109613)
			(xy 363.02229 -313.123719) (xy 363.073619 -313.145531) (xy 363.121225 -313.174585) (xy 363.164093 -313.21026)
			(xy 363.20131 -313.251797) (xy 363.232083 -313.29831) (xy 363.255755 -313.348807) (xy 363.271823 -313.402214)
			(xy 363.279943 -313.45739) (xy 363.280452 -313.485276) (xy 363.532926 -313.485276) (xy 363.536997 -313.429654)
			(xy 363.549123 -313.375217) (xy 363.569046 -313.323126) (xy 363.596342 -313.274491) (xy 363.630428 -313.230348)
			(xy 363.670577 -313.191639) (xy 363.715935 -313.159188) (xy 363.765535 -313.133687) (xy 363.818319 -313.11568)
			(xy 363.873162 -313.10555) (xy 363.928896 -313.103513) (xy 363.984333 -313.109613) (xy 364.03829 -313.123719)
			(xy 364.089619 -313.145531) (xy 364.137225 -313.174585) (xy 364.180093 -313.21026) (xy 364.21731 -313.251797)
			(xy 364.248083 -313.29831) (xy 364.271755 -313.348807) (xy 364.287823 -313.402214) (xy 364.295943 -313.45739)
			(xy 364.296452 -313.485276) (xy 364.295943 -313.513162) (xy 364.287823 -313.568338) (xy 364.271755 -313.621745)
			(xy 364.248083 -313.672242) (xy 364.21731 -313.718755) (xy 364.180093 -313.760292) (xy 364.137225 -313.795967)
			(xy 364.089619 -313.825021) (xy 364.03829 -313.846833) (xy 363.984333 -313.860939) (xy 363.928896 -313.867039)
			(xy 363.873162 -313.865002) (xy 363.818319 -313.854872) (xy 363.765535 -313.836865) (xy 363.715935 -313.811364)
			(xy 363.670577 -313.778913) (xy 363.630428 -313.740204) (xy 363.596342 -313.696061) (xy 363.569046 -313.647426)
			(xy 363.549123 -313.595335) (xy 363.536997 -313.540898) (xy 363.532926 -313.485276) (xy 363.280452 -313.485276)
			(xy 363.279943 -313.513162) (xy 363.271823 -313.568338) (xy 363.255755 -313.621745) (xy 363.232083 -313.672242)
			(xy 363.20131 -313.718755) (xy 363.164093 -313.760292) (xy 363.121225 -313.795967) (xy 363.073619 -313.825021)
			(xy 363.02229 -313.846833) (xy 362.968333 -313.860939) (xy 362.912896 -313.867039) (xy 362.857162 -313.865002)
			(xy 362.802319 -313.854872) (xy 362.749535 -313.836865) (xy 362.699935 -313.811364) (xy 362.654577 -313.778913)
			(xy 362.614428 -313.740204) (xy 362.580342 -313.696061) (xy 362.553046 -313.647426) (xy 362.533123 -313.595335)
			(xy 362.520997 -313.540898) (xy 362.516926 -313.485276) (xy 362.264452 -313.485276) (xy 362.263943 -313.513162)
			(xy 362.255823 -313.568338) (xy 362.239755 -313.621745) (xy 362.216083 -313.672242) (xy 362.18531 -313.718755)
			(xy 362.148093 -313.760292) (xy 362.105225 -313.795967) (xy 362.057619 -313.825021) (xy 362.00629 -313.846833)
			(xy 361.952333 -313.860939) (xy 361.896896 -313.867039) (xy 361.841162 -313.865002) (xy 361.786319 -313.854872)
			(xy 361.733535 -313.836865) (xy 361.683935 -313.811364) (xy 361.638577 -313.778913) (xy 361.598428 -313.740204)
			(xy 361.564342 -313.696061) (xy 361.537046 -313.647426) (xy 361.517123 -313.595335) (xy 361.504997 -313.540898)
			(xy 361.500926 -313.485276) (xy 361.248452 -313.485276) (xy 361.247943 -313.513162) (xy 361.239823 -313.568338)
			(xy 361.223755 -313.621745) (xy 361.200083 -313.672242) (xy 361.16931 -313.718755) (xy 361.132093 -313.760292)
			(xy 361.089225 -313.795967) (xy 361.041619 -313.825021) (xy 360.99029 -313.846833) (xy 360.936333 -313.860939)
			(xy 360.880896 -313.867039) (xy 360.825162 -313.865002) (xy 360.770319 -313.854872) (xy 360.717535 -313.836865)
			(xy 360.667935 -313.811364) (xy 360.622577 -313.778913) (xy 360.582428 -313.740204) (xy 360.548342 -313.696061)
			(xy 360.521046 -313.647426) (xy 360.501123 -313.595335) (xy 360.488997 -313.540898) (xy 360.484926 -313.485276)
			(xy 360.232452 -313.485276) (xy 360.231943 -313.513162) (xy 360.223823 -313.568338) (xy 360.207755 -313.621745)
			(xy 360.184083 -313.672242) (xy 360.15331 -313.718755) (xy 360.116093 -313.760292) (xy 360.073225 -313.795967)
			(xy 360.025619 -313.825021) (xy 359.97429 -313.846833) (xy 359.920333 -313.860939) (xy 359.864896 -313.867039)
			(xy 359.809162 -313.865002) (xy 359.754319 -313.854872) (xy 359.701535 -313.836865) (xy 359.651935 -313.811364)
			(xy 359.606577 -313.778913) (xy 359.566428 -313.740204) (xy 359.532342 -313.696061) (xy 359.505046 -313.647426)
			(xy 359.485123 -313.595335) (xy 359.472997 -313.540898) (xy 359.468926 -313.485276) (xy 359.216452 -313.485276)
			(xy 359.215943 -313.513162) (xy 359.207823 -313.568338) (xy 359.191755 -313.621745) (xy 359.168083 -313.672242)
			(xy 359.13731 -313.718755) (xy 359.100093 -313.760292) (xy 359.057225 -313.795967) (xy 359.009619 -313.825021)
			(xy 358.95829 -313.846833) (xy 358.904333 -313.860939) (xy 358.848896 -313.867039) (xy 358.793162 -313.865002)
			(xy 358.738319 -313.854872) (xy 358.685535 -313.836865) (xy 358.635935 -313.811364) (xy 358.590577 -313.778913)
			(xy 358.550428 -313.740204) (xy 358.516342 -313.696061) (xy 358.489046 -313.647426) (xy 358.469123 -313.595335)
			(xy 358.456997 -313.540898) (xy 358.452926 -313.485276) (xy 358.200452 -313.485276) (xy 358.199943 -313.513162)
			(xy 358.191823 -313.568338) (xy 358.175755 -313.621745) (xy 358.152083 -313.672242) (xy 358.12131 -313.718755)
			(xy 358.084093 -313.760292) (xy 358.041225 -313.795967) (xy 357.993619 -313.825021) (xy 357.94229 -313.846833)
			(xy 357.888333 -313.860939) (xy 357.832896 -313.867039) (xy 357.777162 -313.865002) (xy 357.722319 -313.854872)
			(xy 357.669535 -313.836865) (xy 357.619935 -313.811364) (xy 357.574577 -313.778913) (xy 357.534428 -313.740204)
			(xy 357.500342 -313.696061) (xy 357.473046 -313.647426) (xy 357.453123 -313.595335) (xy 357.440997 -313.540898)
			(xy 357.436926 -313.485276) (xy 342.52631 -313.485276) (xy 342.500564 -313.524191) (xy 342.463347 -313.565728)
			(xy 342.420479 -313.601403) (xy 342.372873 -313.630457) (xy 342.321544 -313.652269) (xy 342.267587 -313.666375)
			(xy 342.21215 -313.672475) (xy 342.156416 -313.670438) (xy 342.101573 -313.660308) (xy 342.048789 -313.642301)
			(xy 341.999189 -313.6168) (xy 341.953831 -313.584349) (xy 341.913682 -313.54564) (xy 341.879596 -313.501497)
			(xy 341.8523 -313.452862) (xy 341.832377 -313.400771) (xy 341.820251 -313.346334) (xy 341.81618 -313.290712)
			(xy 341.563706 -313.290712) (xy 341.563197 -313.318598) (xy 341.555077 -313.373774) (xy 341.539009 -313.427181)
			(xy 341.515337 -313.477678) (xy 341.484564 -313.524191) (xy 341.447347 -313.565728) (xy 341.404479 -313.601403)
			(xy 341.356873 -313.630457) (xy 341.305544 -313.652269) (xy 341.251587 -313.666375) (xy 341.19615 -313.672475)
			(xy 341.140416 -313.670438) (xy 341.085573 -313.660308) (xy 341.032789 -313.642301) (xy 340.983189 -313.6168)
			(xy 340.937831 -313.584349) (xy 340.897682 -313.54564) (xy 340.863596 -313.501497) (xy 340.8363 -313.452862)
			(xy 340.816377 -313.400771) (xy 340.804251 -313.346334) (xy 340.80018 -313.290712) (xy 340.547706 -313.290712)
			(xy 340.547197 -313.318598) (xy 340.539077 -313.373774) (xy 340.523009 -313.427181) (xy 340.499337 -313.477678)
			(xy 340.468564 -313.524191) (xy 340.431347 -313.565728) (xy 340.388479 -313.601403) (xy 340.340873 -313.630457)
			(xy 340.289544 -313.652269) (xy 340.235587 -313.666375) (xy 340.18015 -313.672475) (xy 340.124416 -313.670438)
			(xy 340.069573 -313.660308) (xy 340.016789 -313.642301) (xy 339.967189 -313.6168) (xy 339.921831 -313.584349)
			(xy 339.881682 -313.54564) (xy 339.847596 -313.501497) (xy 339.8203 -313.452862) (xy 339.800377 -313.400771)
			(xy 339.788251 -313.346334) (xy 339.78418 -313.290712) (xy 339.531706 -313.290712) (xy 339.531197 -313.318598)
			(xy 339.523077 -313.373774) (xy 339.507009 -313.427181) (xy 339.483337 -313.477678) (xy 339.452564 -313.524191)
			(xy 339.415347 -313.565728) (xy 339.372479 -313.601403) (xy 339.324873 -313.630457) (xy 339.273544 -313.652269)
			(xy 339.219587 -313.666375) (xy 339.16415 -313.672475) (xy 339.108416 -313.670438) (xy 339.053573 -313.660308)
			(xy 339.000789 -313.642301) (xy 338.951189 -313.6168) (xy 338.905831 -313.584349) (xy 338.865682 -313.54564)
			(xy 338.831596 -313.501497) (xy 338.8043 -313.452862) (xy 338.784377 -313.400771) (xy 338.772251 -313.346334)
			(xy 338.76818 -313.290712) (xy 338.515706 -313.290712) (xy 338.515197 -313.318598) (xy 338.507077 -313.373774)
			(xy 338.491009 -313.427181) (xy 338.467337 -313.477678) (xy 338.436564 -313.524191) (xy 338.399347 -313.565728)
			(xy 338.356479 -313.601403) (xy 338.308873 -313.630457) (xy 338.257544 -313.652269) (xy 338.203587 -313.666375)
			(xy 338.14815 -313.672475) (xy 338.092416 -313.670438) (xy 338.037573 -313.660308) (xy 337.984789 -313.642301)
			(xy 337.935189 -313.6168) (xy 337.889831 -313.584349) (xy 337.849682 -313.54564) (xy 337.815596 -313.501497)
			(xy 337.7883 -313.452862) (xy 337.768377 -313.400771) (xy 337.756251 -313.346334) (xy 337.75218 -313.290712)
			(xy 337.499706 -313.290712) (xy 337.499197 -313.318598) (xy 337.491077 -313.373774) (xy 337.475009 -313.427181)
			(xy 337.451337 -313.477678) (xy 337.420564 -313.524191) (xy 337.383347 -313.565728) (xy 337.340479 -313.601403)
			(xy 337.292873 -313.630457) (xy 337.241544 -313.652269) (xy 337.187587 -313.666375) (xy 337.13215 -313.672475)
			(xy 337.076416 -313.670438) (xy 337.021573 -313.660308) (xy 336.968789 -313.642301) (xy 336.919189 -313.6168)
			(xy 336.873831 -313.584349) (xy 336.833682 -313.54564) (xy 336.799596 -313.501497) (xy 336.7723 -313.452862)
			(xy 336.752377 -313.400771) (xy 336.740251 -313.346334) (xy 336.73618 -313.290712) (xy 336.483706 -313.290712)
			(xy 336.483197 -313.318598) (xy 336.475077 -313.373774) (xy 336.459009 -313.427181) (xy 336.435337 -313.477678)
			(xy 336.404564 -313.524191) (xy 336.367347 -313.565728) (xy 336.324479 -313.601403) (xy 336.276873 -313.630457)
			(xy 336.225544 -313.652269) (xy 336.171587 -313.666375) (xy 336.11615 -313.672475) (xy 336.060416 -313.670438)
			(xy 336.005573 -313.660308) (xy 335.952789 -313.642301) (xy 335.903189 -313.6168) (xy 335.857831 -313.584349)
			(xy 335.817682 -313.54564) (xy 335.783596 -313.501497) (xy 335.7563 -313.452862) (xy 335.736377 -313.400771)
			(xy 335.724251 -313.346334) (xy 335.72018 -313.290712) (xy 335.467706 -313.290712) (xy 335.467197 -313.318598)
			(xy 335.459077 -313.373774) (xy 335.443009 -313.427181) (xy 335.419337 -313.477678) (xy 335.388564 -313.524191)
			(xy 335.351347 -313.565728) (xy 335.308479 -313.601403) (xy 335.260873 -313.630457) (xy 335.209544 -313.652269)
			(xy 335.155587 -313.666375) (xy 335.10015 -313.672475) (xy 335.044416 -313.670438) (xy 334.989573 -313.660308)
			(xy 334.936789 -313.642301) (xy 334.887189 -313.6168) (xy 334.841831 -313.584349) (xy 334.801682 -313.54564)
			(xy 334.767596 -313.501497) (xy 334.7403 -313.452862) (xy 334.720377 -313.400771) (xy 334.708251 -313.346334)
			(xy 334.70418 -313.290712) (xy 334.451706 -313.290712) (xy 334.451197 -313.318598) (xy 334.443077 -313.373774)
			(xy 334.427009 -313.427181) (xy 334.403337 -313.477678) (xy 334.372564 -313.524191) (xy 334.335347 -313.565728)
			(xy 334.292479 -313.601403) (xy 334.244873 -313.630457) (xy 334.193544 -313.652269) (xy 334.139587 -313.666375)
			(xy 334.08415 -313.672475) (xy 334.028416 -313.670438) (xy 333.973573 -313.660308) (xy 333.920789 -313.642301)
			(xy 333.871189 -313.6168) (xy 333.825831 -313.584349) (xy 333.785682 -313.54564) (xy 333.751596 -313.501497)
			(xy 333.7243 -313.452862) (xy 333.704377 -313.400771) (xy 333.692251 -313.346334) (xy 333.68818 -313.290712)
			(xy 333.435706 -313.290712) (xy 333.435197 -313.318598) (xy 333.427077 -313.373774) (xy 333.411009 -313.427181)
			(xy 333.387337 -313.477678) (xy 333.356564 -313.524191) (xy 333.319347 -313.565728) (xy 333.276479 -313.601403)
			(xy 333.228873 -313.630457) (xy 333.177544 -313.652269) (xy 333.123587 -313.666375) (xy 333.06815 -313.672475)
			(xy 333.012416 -313.670438) (xy 332.957573 -313.660308) (xy 332.904789 -313.642301) (xy 332.855189 -313.6168)
			(xy 332.809831 -313.584349) (xy 332.769682 -313.54564) (xy 332.735596 -313.501497) (xy 332.7083 -313.452862)
			(xy 332.688377 -313.400771) (xy 332.676251 -313.346334) (xy 332.67218 -313.290712) (xy 318.25565 -313.290712)
			(xy 318.25565 -314.306712) (xy 333.68818 -314.306712) (xy 333.692251 -314.25109) (xy 333.704377 -314.196653)
			(xy 333.7243 -314.144562) (xy 333.751596 -314.095927) (xy 333.785682 -314.051784) (xy 333.825831 -314.013075)
			(xy 333.871189 -313.980624) (xy 333.920789 -313.955123) (xy 333.973573 -313.937116) (xy 334.028416 -313.926986)
			(xy 334.08415 -313.924949) (xy 334.139587 -313.931049) (xy 334.193544 -313.945155) (xy 334.244873 -313.966967)
			(xy 334.292479 -313.996021) (xy 334.335347 -314.031696) (xy 334.372564 -314.073233) (xy 334.403337 -314.119746)
			(xy 334.427009 -314.170243) (xy 334.443077 -314.22365) (xy 334.451197 -314.278826) (xy 334.451706 -314.306712)
			(xy 334.70418 -314.306712) (xy 334.708251 -314.25109) (xy 334.720377 -314.196653) (xy 334.7403 -314.144562)
			(xy 334.767596 -314.095927) (xy 334.801682 -314.051784) (xy 334.841831 -314.013075) (xy 334.887189 -313.980624)
			(xy 334.936789 -313.955123) (xy 334.989573 -313.937116) (xy 335.044416 -313.926986) (xy 335.10015 -313.924949)
			(xy 335.155587 -313.931049) (xy 335.209544 -313.945155) (xy 335.260873 -313.966967) (xy 335.308479 -313.996021)
			(xy 335.351347 -314.031696) (xy 335.388564 -314.073233) (xy 335.419337 -314.119746) (xy 335.443009 -314.170243)
			(xy 335.459077 -314.22365) (xy 335.467197 -314.278826) (xy 335.467706 -314.306712) (xy 335.72018 -314.306712)
			(xy 335.724251 -314.25109) (xy 335.736377 -314.196653) (xy 335.7563 -314.144562) (xy 335.783596 -314.095927)
			(xy 335.817682 -314.051784) (xy 335.857831 -314.013075) (xy 335.903189 -313.980624) (xy 335.952789 -313.955123)
			(xy 336.005573 -313.937116) (xy 336.060416 -313.926986) (xy 336.11615 -313.924949) (xy 336.171587 -313.931049)
			(xy 336.225544 -313.945155) (xy 336.276873 -313.966967) (xy 336.324479 -313.996021) (xy 336.367347 -314.031696)
			(xy 336.404564 -314.073233) (xy 336.435337 -314.119746) (xy 336.459009 -314.170243) (xy 336.475077 -314.22365)
			(xy 336.483197 -314.278826) (xy 336.483706 -314.306712) (xy 336.73618 -314.306712) (xy 336.740251 -314.25109)
			(xy 336.752377 -314.196653) (xy 336.7723 -314.144562) (xy 336.799596 -314.095927) (xy 336.833682 -314.051784)
			(xy 336.873831 -314.013075) (xy 336.919189 -313.980624) (xy 336.968789 -313.955123) (xy 337.021573 -313.937116)
			(xy 337.076416 -313.926986) (xy 337.13215 -313.924949) (xy 337.187587 -313.931049) (xy 337.241544 -313.945155)
			(xy 337.292873 -313.966967) (xy 337.340479 -313.996021) (xy 337.383347 -314.031696) (xy 337.420564 -314.073233)
			(xy 337.451337 -314.119746) (xy 337.475009 -314.170243) (xy 337.491077 -314.22365) (xy 337.499197 -314.278826)
			(xy 337.499706 -314.306712) (xy 337.75218 -314.306712) (xy 337.756251 -314.25109) (xy 337.768377 -314.196653)
			(xy 337.7883 -314.144562) (xy 337.815596 -314.095927) (xy 337.849682 -314.051784) (xy 337.889831 -314.013075)
			(xy 337.935189 -313.980624) (xy 337.984789 -313.955123) (xy 338.037573 -313.937116) (xy 338.092416 -313.926986)
			(xy 338.14815 -313.924949) (xy 338.203587 -313.931049) (xy 338.257544 -313.945155) (xy 338.308873 -313.966967)
			(xy 338.356479 -313.996021) (xy 338.399347 -314.031696) (xy 338.436564 -314.073233) (xy 338.467337 -314.119746)
			(xy 338.491009 -314.170243) (xy 338.507077 -314.22365) (xy 338.515197 -314.278826) (xy 338.515706 -314.306712)
			(xy 338.76818 -314.306712) (xy 338.772251 -314.25109) (xy 338.784377 -314.196653) (xy 338.8043 -314.144562)
			(xy 338.831596 -314.095927) (xy 338.865682 -314.051784) (xy 338.905831 -314.013075) (xy 338.951189 -313.980624)
			(xy 339.000789 -313.955123) (xy 339.053573 -313.937116) (xy 339.108416 -313.926986) (xy 339.16415 -313.924949)
			(xy 339.219587 -313.931049) (xy 339.273544 -313.945155) (xy 339.324873 -313.966967) (xy 339.372479 -313.996021)
			(xy 339.415347 -314.031696) (xy 339.452564 -314.073233) (xy 339.483337 -314.119746) (xy 339.507009 -314.170243)
			(xy 339.523077 -314.22365) (xy 339.531197 -314.278826) (xy 339.531706 -314.306712) (xy 339.78418 -314.306712)
			(xy 339.788251 -314.25109) (xy 339.800377 -314.196653) (xy 339.8203 -314.144562) (xy 339.847596 -314.095927)
			(xy 339.881682 -314.051784) (xy 339.921831 -314.013075) (xy 339.967189 -313.980624) (xy 340.016789 -313.955123)
			(xy 340.069573 -313.937116) (xy 340.124416 -313.926986) (xy 340.18015 -313.924949) (xy 340.235587 -313.931049)
			(xy 340.289544 -313.945155) (xy 340.340873 -313.966967) (xy 340.388479 -313.996021) (xy 340.431347 -314.031696)
			(xy 340.468564 -314.073233) (xy 340.499337 -314.119746) (xy 340.523009 -314.170243) (xy 340.539077 -314.22365)
			(xy 340.547197 -314.278826) (xy 340.547706 -314.306712) (xy 340.80018 -314.306712) (xy 340.804251 -314.25109)
			(xy 340.816377 -314.196653) (xy 340.8363 -314.144562) (xy 340.863596 -314.095927) (xy 340.897682 -314.051784)
			(xy 340.937831 -314.013075) (xy 340.983189 -313.980624) (xy 341.032789 -313.955123) (xy 341.085573 -313.937116)
			(xy 341.140416 -313.926986) (xy 341.19615 -313.924949) (xy 341.251587 -313.931049) (xy 341.305544 -313.945155)
			(xy 341.356873 -313.966967) (xy 341.404479 -313.996021) (xy 341.447347 -314.031696) (xy 341.484564 -314.073233)
			(xy 341.515337 -314.119746) (xy 341.539009 -314.170243) (xy 341.555077 -314.22365) (xy 341.563197 -314.278826)
			(xy 341.563706 -314.306712) (xy 341.81618 -314.306712) (xy 341.820251 -314.25109) (xy 341.832377 -314.196653)
			(xy 341.8523 -314.144562) (xy 341.879596 -314.095927) (xy 341.913682 -314.051784) (xy 341.953831 -314.013075)
			(xy 341.999189 -313.980624) (xy 342.048789 -313.955123) (xy 342.101573 -313.937116) (xy 342.156416 -313.926986)
			(xy 342.21215 -313.924949) (xy 342.267587 -313.931049) (xy 342.321544 -313.945155) (xy 342.372873 -313.966967)
			(xy 342.420479 -313.996021) (xy 342.463347 -314.031696) (xy 342.500564 -314.073233) (xy 342.531337 -314.119746)
			(xy 342.555009 -314.170243) (xy 342.571077 -314.22365) (xy 342.579197 -314.278826) (xy 342.579706 -314.306712)
			(xy 342.579197 -314.334598) (xy 342.571077 -314.389774) (xy 342.555009 -314.443181) (xy 342.531337 -314.493678)
			(xy 342.52631 -314.501276) (xy 357.436926 -314.501276) (xy 357.440997 -314.445654) (xy 357.453123 -314.391217)
			(xy 357.473046 -314.339126) (xy 357.500342 -314.290491) (xy 357.534428 -314.246348) (xy 357.574577 -314.207639)
			(xy 357.619935 -314.175188) (xy 357.669535 -314.149687) (xy 357.722319 -314.13168) (xy 357.777162 -314.12155)
			(xy 357.832896 -314.119513) (xy 357.888333 -314.125613) (xy 357.94229 -314.139719) (xy 357.993619 -314.161531)
			(xy 358.041225 -314.190585) (xy 358.084093 -314.22626) (xy 358.12131 -314.267797) (xy 358.152083 -314.31431)
			(xy 358.175755 -314.364807) (xy 358.191823 -314.418214) (xy 358.199943 -314.47339) (xy 358.200452 -314.501276)
			(xy 358.452926 -314.501276) (xy 358.456997 -314.445654) (xy 358.469123 -314.391217) (xy 358.489046 -314.339126)
			(xy 358.516342 -314.290491) (xy 358.550428 -314.246348) (xy 358.590577 -314.207639) (xy 358.635935 -314.175188)
			(xy 358.685535 -314.149687) (xy 358.738319 -314.13168) (xy 358.793162 -314.12155) (xy 358.848896 -314.119513)
			(xy 358.904333 -314.125613) (xy 358.95829 -314.139719) (xy 359.009619 -314.161531) (xy 359.057225 -314.190585)
			(xy 359.100093 -314.22626) (xy 359.13731 -314.267797) (xy 359.168083 -314.31431) (xy 359.191755 -314.364807)
			(xy 359.207823 -314.418214) (xy 359.215943 -314.47339) (xy 359.216452 -314.501276) (xy 359.468926 -314.501276)
			(xy 359.472997 -314.445654) (xy 359.485123 -314.391217) (xy 359.505046 -314.339126) (xy 359.532342 -314.290491)
			(xy 359.566428 -314.246348) (xy 359.606577 -314.207639) (xy 359.651935 -314.175188) (xy 359.701535 -314.149687)
			(xy 359.754319 -314.13168) (xy 359.809162 -314.12155) (xy 359.864896 -314.119513) (xy 359.920333 -314.125613)
			(xy 359.97429 -314.139719) (xy 360.025619 -314.161531) (xy 360.073225 -314.190585) (xy 360.116093 -314.22626)
			(xy 360.15331 -314.267797) (xy 360.184083 -314.31431) (xy 360.207755 -314.364807) (xy 360.223823 -314.418214)
			(xy 360.231943 -314.47339) (xy 360.232452 -314.501276) (xy 360.484926 -314.501276) (xy 360.488997 -314.445654)
			(xy 360.501123 -314.391217) (xy 360.521046 -314.339126) (xy 360.548342 -314.290491) (xy 360.582428 -314.246348)
			(xy 360.622577 -314.207639) (xy 360.667935 -314.175188) (xy 360.717535 -314.149687) (xy 360.770319 -314.13168)
			(xy 360.825162 -314.12155) (xy 360.880896 -314.119513) (xy 360.936333 -314.125613) (xy 360.99029 -314.139719)
			(xy 361.041619 -314.161531) (xy 361.089225 -314.190585) (xy 361.132093 -314.22626) (xy 361.16931 -314.267797)
			(xy 361.200083 -314.31431) (xy 361.223755 -314.364807) (xy 361.239823 -314.418214) (xy 361.247943 -314.47339)
			(xy 361.248452 -314.501276) (xy 361.500926 -314.501276) (xy 361.504997 -314.445654) (xy 361.517123 -314.391217)
			(xy 361.537046 -314.339126) (xy 361.564342 -314.290491) (xy 361.598428 -314.246348) (xy 361.638577 -314.207639)
			(xy 361.683935 -314.175188) (xy 361.733535 -314.149687) (xy 361.786319 -314.13168) (xy 361.841162 -314.12155)
			(xy 361.896896 -314.119513) (xy 361.952333 -314.125613) (xy 362.00629 -314.139719) (xy 362.057619 -314.161531)
			(xy 362.105225 -314.190585) (xy 362.148093 -314.22626) (xy 362.18531 -314.267797) (xy 362.216083 -314.31431)
			(xy 362.239755 -314.364807) (xy 362.255823 -314.418214) (xy 362.263943 -314.47339) (xy 362.264452 -314.501276)
			(xy 362.516926 -314.501276) (xy 362.520997 -314.445654) (xy 362.533123 -314.391217) (xy 362.553046 -314.339126)
			(xy 362.580342 -314.290491) (xy 362.614428 -314.246348) (xy 362.654577 -314.207639) (xy 362.699935 -314.175188)
			(xy 362.749535 -314.149687) (xy 362.802319 -314.13168) (xy 362.857162 -314.12155) (xy 362.912896 -314.119513)
			(xy 362.968333 -314.125613) (xy 363.02229 -314.139719) (xy 363.073619 -314.161531) (xy 363.121225 -314.190585)
			(xy 363.164093 -314.22626) (xy 363.20131 -314.267797) (xy 363.232083 -314.31431) (xy 363.255755 -314.364807)
			(xy 363.271823 -314.418214) (xy 363.279943 -314.47339) (xy 363.280452 -314.501276) (xy 363.279943 -314.529162)
			(xy 363.271823 -314.584338) (xy 363.255755 -314.637745) (xy 363.232083 -314.688242) (xy 363.20131 -314.734755)
			(xy 363.164093 -314.776292) (xy 363.121225 -314.811967) (xy 363.073619 -314.841021) (xy 363.02229 -314.862833)
			(xy 362.968333 -314.876939) (xy 362.912896 -314.883039) (xy 362.857162 -314.881002) (xy 362.802319 -314.870872)
			(xy 362.749535 -314.852865) (xy 362.699935 -314.827364) (xy 362.654577 -314.794913) (xy 362.614428 -314.756204)
			(xy 362.580342 -314.712061) (xy 362.553046 -314.663426) (xy 362.533123 -314.611335) (xy 362.520997 -314.556898)
			(xy 362.516926 -314.501276) (xy 362.264452 -314.501276) (xy 362.263943 -314.529162) (xy 362.255823 -314.584338)
			(xy 362.239755 -314.637745) (xy 362.216083 -314.688242) (xy 362.18531 -314.734755) (xy 362.148093 -314.776292)
			(xy 362.105225 -314.811967) (xy 362.057619 -314.841021) (xy 362.00629 -314.862833) (xy 361.952333 -314.876939)
			(xy 361.896896 -314.883039) (xy 361.841162 -314.881002) (xy 361.786319 -314.870872) (xy 361.733535 -314.852865)
			(xy 361.683935 -314.827364) (xy 361.638577 -314.794913) (xy 361.598428 -314.756204) (xy 361.564342 -314.712061)
			(xy 361.537046 -314.663426) (xy 361.517123 -314.611335) (xy 361.504997 -314.556898) (xy 361.500926 -314.501276)
			(xy 361.248452 -314.501276) (xy 361.247943 -314.529162) (xy 361.239823 -314.584338) (xy 361.223755 -314.637745)
			(xy 361.200083 -314.688242) (xy 361.16931 -314.734755) (xy 361.132093 -314.776292) (xy 361.089225 -314.811967)
			(xy 361.041619 -314.841021) (xy 360.99029 -314.862833) (xy 360.936333 -314.876939) (xy 360.880896 -314.883039)
			(xy 360.825162 -314.881002) (xy 360.770319 -314.870872) (xy 360.717535 -314.852865) (xy 360.667935 -314.827364)
			(xy 360.622577 -314.794913) (xy 360.582428 -314.756204) (xy 360.548342 -314.712061) (xy 360.521046 -314.663426)
			(xy 360.501123 -314.611335) (xy 360.488997 -314.556898) (xy 360.484926 -314.501276) (xy 360.232452 -314.501276)
			(xy 360.231943 -314.529162) (xy 360.223823 -314.584338) (xy 360.207755 -314.637745) (xy 360.184083 -314.688242)
			(xy 360.15331 -314.734755) (xy 360.116093 -314.776292) (xy 360.073225 -314.811967) (xy 360.025619 -314.841021)
			(xy 359.97429 -314.862833) (xy 359.920333 -314.876939) (xy 359.864896 -314.883039) (xy 359.809162 -314.881002)
			(xy 359.754319 -314.870872) (xy 359.701535 -314.852865) (xy 359.651935 -314.827364) (xy 359.606577 -314.794913)
			(xy 359.566428 -314.756204) (xy 359.532342 -314.712061) (xy 359.505046 -314.663426) (xy 359.485123 -314.611335)
			(xy 359.472997 -314.556898) (xy 359.468926 -314.501276) (xy 359.216452 -314.501276) (xy 359.215943 -314.529162)
			(xy 359.207823 -314.584338) (xy 359.191755 -314.637745) (xy 359.168083 -314.688242) (xy 359.13731 -314.734755)
			(xy 359.100093 -314.776292) (xy 359.057225 -314.811967) (xy 359.009619 -314.841021) (xy 358.95829 -314.862833)
			(xy 358.904333 -314.876939) (xy 358.848896 -314.883039) (xy 358.793162 -314.881002) (xy 358.738319 -314.870872)
			(xy 358.685535 -314.852865) (xy 358.635935 -314.827364) (xy 358.590577 -314.794913) (xy 358.550428 -314.756204)
			(xy 358.516342 -314.712061) (xy 358.489046 -314.663426) (xy 358.469123 -314.611335) (xy 358.456997 -314.556898)
			(xy 358.452926 -314.501276) (xy 358.200452 -314.501276) (xy 358.199943 -314.529162) (xy 358.191823 -314.584338)
			(xy 358.175755 -314.637745) (xy 358.152083 -314.688242) (xy 358.12131 -314.734755) (xy 358.084093 -314.776292)
			(xy 358.041225 -314.811967) (xy 357.993619 -314.841021) (xy 357.94229 -314.862833) (xy 357.888333 -314.876939)
			(xy 357.832896 -314.883039) (xy 357.777162 -314.881002) (xy 357.722319 -314.870872) (xy 357.669535 -314.852865)
			(xy 357.619935 -314.827364) (xy 357.574577 -314.794913) (xy 357.534428 -314.756204) (xy 357.500342 -314.712061)
			(xy 357.473046 -314.663426) (xy 357.453123 -314.611335) (xy 357.440997 -314.556898) (xy 357.436926 -314.501276)
			(xy 342.52631 -314.501276) (xy 342.500564 -314.540191) (xy 342.463347 -314.581728) (xy 342.420479 -314.617403)
			(xy 342.372873 -314.646457) (xy 342.321544 -314.668269) (xy 342.267587 -314.682375) (xy 342.21215 -314.688475)
			(xy 342.156416 -314.686438) (xy 342.101573 -314.676308) (xy 342.048789 -314.658301) (xy 341.999189 -314.6328)
			(xy 341.953831 -314.600349) (xy 341.913682 -314.56164) (xy 341.879596 -314.517497) (xy 341.8523 -314.468862)
			(xy 341.832377 -314.416771) (xy 341.820251 -314.362334) (xy 341.81618 -314.306712) (xy 341.563706 -314.306712)
			(xy 341.563197 -314.334598) (xy 341.555077 -314.389774) (xy 341.539009 -314.443181) (xy 341.515337 -314.493678)
			(xy 341.484564 -314.540191) (xy 341.447347 -314.581728) (xy 341.404479 -314.617403) (xy 341.356873 -314.646457)
			(xy 341.305544 -314.668269) (xy 341.251587 -314.682375) (xy 341.19615 -314.688475) (xy 341.140416 -314.686438)
			(xy 341.085573 -314.676308) (xy 341.032789 -314.658301) (xy 340.983189 -314.6328) (xy 340.937831 -314.600349)
			(xy 340.897682 -314.56164) (xy 340.863596 -314.517497) (xy 340.8363 -314.468862) (xy 340.816377 -314.416771)
			(xy 340.804251 -314.362334) (xy 340.80018 -314.306712) (xy 340.547706 -314.306712) (xy 340.547197 -314.334598)
			(xy 340.539077 -314.389774) (xy 340.523009 -314.443181) (xy 340.499337 -314.493678) (xy 340.468564 -314.540191)
			(xy 340.431347 -314.581728) (xy 340.388479 -314.617403) (xy 340.340873 -314.646457) (xy 340.289544 -314.668269)
			(xy 340.235587 -314.682375) (xy 340.18015 -314.688475) (xy 340.124416 -314.686438) (xy 340.069573 -314.676308)
			(xy 340.016789 -314.658301) (xy 339.967189 -314.6328) (xy 339.921831 -314.600349) (xy 339.881682 -314.56164)
			(xy 339.847596 -314.517497) (xy 339.8203 -314.468862) (xy 339.800377 -314.416771) (xy 339.788251 -314.362334)
			(xy 339.78418 -314.306712) (xy 339.531706 -314.306712) (xy 339.531197 -314.334598) (xy 339.523077 -314.389774)
			(xy 339.507009 -314.443181) (xy 339.483337 -314.493678) (xy 339.452564 -314.540191) (xy 339.415347 -314.581728)
			(xy 339.372479 -314.617403) (xy 339.324873 -314.646457) (xy 339.273544 -314.668269) (xy 339.219587 -314.682375)
			(xy 339.16415 -314.688475) (xy 339.108416 -314.686438) (xy 339.053573 -314.676308) (xy 339.000789 -314.658301)
			(xy 338.951189 -314.6328) (xy 338.905831 -314.600349) (xy 338.865682 -314.56164) (xy 338.831596 -314.517497)
			(xy 338.8043 -314.468862) (xy 338.784377 -314.416771) (xy 338.772251 -314.362334) (xy 338.76818 -314.306712)
			(xy 338.515706 -314.306712) (xy 338.515197 -314.334598) (xy 338.507077 -314.389774) (xy 338.491009 -314.443181)
			(xy 338.467337 -314.493678) (xy 338.436564 -314.540191) (xy 338.399347 -314.581728) (xy 338.356479 -314.617403)
			(xy 338.308873 -314.646457) (xy 338.257544 -314.668269) (xy 338.203587 -314.682375) (xy 338.14815 -314.688475)
			(xy 338.092416 -314.686438) (xy 338.037573 -314.676308) (xy 337.984789 -314.658301) (xy 337.935189 -314.6328)
			(xy 337.889831 -314.600349) (xy 337.849682 -314.56164) (xy 337.815596 -314.517497) (xy 337.7883 -314.468862)
			(xy 337.768377 -314.416771) (xy 337.756251 -314.362334) (xy 337.75218 -314.306712) (xy 337.499706 -314.306712)
			(xy 337.499197 -314.334598) (xy 337.491077 -314.389774) (xy 337.475009 -314.443181) (xy 337.451337 -314.493678)
			(xy 337.420564 -314.540191) (xy 337.383347 -314.581728) (xy 337.340479 -314.617403) (xy 337.292873 -314.646457)
			(xy 337.241544 -314.668269) (xy 337.187587 -314.682375) (xy 337.13215 -314.688475) (xy 337.076416 -314.686438)
			(xy 337.021573 -314.676308) (xy 336.968789 -314.658301) (xy 336.919189 -314.6328) (xy 336.873831 -314.600349)
			(xy 336.833682 -314.56164) (xy 336.799596 -314.517497) (xy 336.7723 -314.468862) (xy 336.752377 -314.416771)
			(xy 336.740251 -314.362334) (xy 336.73618 -314.306712) (xy 336.483706 -314.306712) (xy 336.483197 -314.334598)
			(xy 336.475077 -314.389774) (xy 336.459009 -314.443181) (xy 336.435337 -314.493678) (xy 336.404564 -314.540191)
			(xy 336.367347 -314.581728) (xy 336.324479 -314.617403) (xy 336.276873 -314.646457) (xy 336.225544 -314.668269)
			(xy 336.171587 -314.682375) (xy 336.11615 -314.688475) (xy 336.060416 -314.686438) (xy 336.005573 -314.676308)
			(xy 335.952789 -314.658301) (xy 335.903189 -314.6328) (xy 335.857831 -314.600349) (xy 335.817682 -314.56164)
			(xy 335.783596 -314.517497) (xy 335.7563 -314.468862) (xy 335.736377 -314.416771) (xy 335.724251 -314.362334)
			(xy 335.72018 -314.306712) (xy 335.467706 -314.306712) (xy 335.467197 -314.334598) (xy 335.459077 -314.389774)
			(xy 335.443009 -314.443181) (xy 335.419337 -314.493678) (xy 335.388564 -314.540191) (xy 335.351347 -314.581728)
			(xy 335.308479 -314.617403) (xy 335.260873 -314.646457) (xy 335.209544 -314.668269) (xy 335.155587 -314.682375)
			(xy 335.10015 -314.688475) (xy 335.044416 -314.686438) (xy 334.989573 -314.676308) (xy 334.936789 -314.658301)
			(xy 334.887189 -314.6328) (xy 334.841831 -314.600349) (xy 334.801682 -314.56164) (xy 334.767596 -314.517497)
			(xy 334.7403 -314.468862) (xy 334.720377 -314.416771) (xy 334.708251 -314.362334) (xy 334.70418 -314.306712)
			(xy 334.451706 -314.306712) (xy 334.451197 -314.334598) (xy 334.443077 -314.389774) (xy 334.427009 -314.443181)
			(xy 334.403337 -314.493678) (xy 334.372564 -314.540191) (xy 334.335347 -314.581728) (xy 334.292479 -314.617403)
			(xy 334.244873 -314.646457) (xy 334.193544 -314.668269) (xy 334.139587 -314.682375) (xy 334.08415 -314.688475)
			(xy 334.028416 -314.686438) (xy 333.973573 -314.676308) (xy 333.920789 -314.658301) (xy 333.871189 -314.6328)
			(xy 333.825831 -314.600349) (xy 333.785682 -314.56164) (xy 333.751596 -314.517497) (xy 333.7243 -314.468862)
			(xy 333.704377 -314.416771) (xy 333.692251 -314.362334) (xy 333.68818 -314.306712) (xy 318.25565 -314.306712)
			(xy 318.25565 -314.554362) (xy 318.255214 -314.564426) (xy 318.247478 -314.583009) (xy 318.240664 -314.59043)
			(xy 317.508382 -315.322712) (xy 333.68818 -315.322712) (xy 333.692251 -315.26709) (xy 333.704377 -315.212653)
			(xy 333.7243 -315.160562) (xy 333.751596 -315.111927) (xy 333.785682 -315.067784) (xy 333.825831 -315.029075)
			(xy 333.871189 -314.996624) (xy 333.920789 -314.971123) (xy 333.973573 -314.953116) (xy 334.028416 -314.942986)
			(xy 334.08415 -314.940949) (xy 334.139587 -314.947049) (xy 334.193544 -314.961155) (xy 334.244873 -314.982967)
			(xy 334.292479 -315.012021) (xy 334.335347 -315.047696) (xy 334.372564 -315.089233) (xy 334.403337 -315.135746)
			(xy 334.427009 -315.186243) (xy 334.443077 -315.23965) (xy 334.451197 -315.294826) (xy 334.451706 -315.322712)
			(xy 334.70418 -315.322712) (xy 334.708251 -315.26709) (xy 334.720377 -315.212653) (xy 334.7403 -315.160562)
			(xy 334.767596 -315.111927) (xy 334.801682 -315.067784) (xy 334.841831 -315.029075) (xy 334.887189 -314.996624)
			(xy 334.936789 -314.971123) (xy 334.989573 -314.953116) (xy 335.044416 -314.942986) (xy 335.10015 -314.940949)
			(xy 335.155587 -314.947049) (xy 335.209544 -314.961155) (xy 335.260873 -314.982967) (xy 335.308479 -315.012021)
			(xy 335.351347 -315.047696) (xy 335.388564 -315.089233) (xy 335.419337 -315.135746) (xy 335.443009 -315.186243)
			(xy 335.459077 -315.23965) (xy 335.467197 -315.294826) (xy 335.467706 -315.322712) (xy 335.72018 -315.322712)
			(xy 335.724251 -315.26709) (xy 335.736377 -315.212653) (xy 335.7563 -315.160562) (xy 335.783596 -315.111927)
			(xy 335.817682 -315.067784) (xy 335.857831 -315.029075) (xy 335.903189 -314.996624) (xy 335.952789 -314.971123)
			(xy 336.005573 -314.953116) (xy 336.060416 -314.942986) (xy 336.11615 -314.940949) (xy 336.171587 -314.947049)
			(xy 336.225544 -314.961155) (xy 336.276873 -314.982967) (xy 336.324479 -315.012021) (xy 336.367347 -315.047696)
			(xy 336.404564 -315.089233) (xy 336.435337 -315.135746) (xy 336.459009 -315.186243) (xy 336.475077 -315.23965)
			(xy 336.483197 -315.294826) (xy 336.483706 -315.322712) (xy 336.73618 -315.322712) (xy 336.740251 -315.26709)
			(xy 336.752377 -315.212653) (xy 336.7723 -315.160562) (xy 336.799596 -315.111927) (xy 336.833682 -315.067784)
			(xy 336.873831 -315.029075) (xy 336.919189 -314.996624) (xy 336.968789 -314.971123) (xy 337.021573 -314.953116)
			(xy 337.076416 -314.942986) (xy 337.13215 -314.940949) (xy 337.187587 -314.947049) (xy 337.241544 -314.961155)
			(xy 337.292873 -314.982967) (xy 337.340479 -315.012021) (xy 337.383347 -315.047696) (xy 337.420564 -315.089233)
			(xy 337.451337 -315.135746) (xy 337.475009 -315.186243) (xy 337.491077 -315.23965) (xy 337.499197 -315.294826)
			(xy 337.499706 -315.322712) (xy 337.75218 -315.322712) (xy 337.756251 -315.26709) (xy 337.768377 -315.212653)
			(xy 337.7883 -315.160562) (xy 337.815596 -315.111927) (xy 337.849682 -315.067784) (xy 337.889831 -315.029075)
			(xy 337.935189 -314.996624) (xy 337.984789 -314.971123) (xy 338.037573 -314.953116) (xy 338.092416 -314.942986)
			(xy 338.14815 -314.940949) (xy 338.203587 -314.947049) (xy 338.257544 -314.961155) (xy 338.308873 -314.982967)
			(xy 338.356479 -315.012021) (xy 338.399347 -315.047696) (xy 338.436564 -315.089233) (xy 338.467337 -315.135746)
			(xy 338.491009 -315.186243) (xy 338.507077 -315.23965) (xy 338.515197 -315.294826) (xy 338.515706 -315.322712)
			(xy 338.76818 -315.322712) (xy 338.772251 -315.26709) (xy 338.784377 -315.212653) (xy 338.8043 -315.160562)
			(xy 338.831596 -315.111927) (xy 338.865682 -315.067784) (xy 338.905831 -315.029075) (xy 338.951189 -314.996624)
			(xy 339.000789 -314.971123) (xy 339.053573 -314.953116) (xy 339.108416 -314.942986) (xy 339.16415 -314.940949)
			(xy 339.219587 -314.947049) (xy 339.273544 -314.961155) (xy 339.324873 -314.982967) (xy 339.372479 -315.012021)
			(xy 339.415347 -315.047696) (xy 339.452564 -315.089233) (xy 339.483337 -315.135746) (xy 339.507009 -315.186243)
			(xy 339.523077 -315.23965) (xy 339.531197 -315.294826) (xy 339.531706 -315.322712) (xy 339.78418 -315.322712)
			(xy 339.788251 -315.26709) (xy 339.800377 -315.212653) (xy 339.8203 -315.160562) (xy 339.847596 -315.111927)
			(xy 339.881682 -315.067784) (xy 339.921831 -315.029075) (xy 339.967189 -314.996624) (xy 340.016789 -314.971123)
			(xy 340.069573 -314.953116) (xy 340.124416 -314.942986) (xy 340.18015 -314.940949) (xy 340.235587 -314.947049)
			(xy 340.289544 -314.961155) (xy 340.340873 -314.982967) (xy 340.388479 -315.012021) (xy 340.431347 -315.047696)
			(xy 340.468564 -315.089233) (xy 340.499337 -315.135746) (xy 340.523009 -315.186243) (xy 340.539077 -315.23965)
			(xy 340.547197 -315.294826) (xy 340.547706 -315.322712) (xy 340.80018 -315.322712) (xy 340.804251 -315.26709)
			(xy 340.816377 -315.212653) (xy 340.8363 -315.160562) (xy 340.863596 -315.111927) (xy 340.897682 -315.067784)
			(xy 340.937831 -315.029075) (xy 340.983189 -314.996624) (xy 341.032789 -314.971123) (xy 341.085573 -314.953116)
			(xy 341.140416 -314.942986) (xy 341.19615 -314.940949) (xy 341.251587 -314.947049) (xy 341.305544 -314.961155)
			(xy 341.356873 -314.982967) (xy 341.404479 -315.012021) (xy 341.447347 -315.047696) (xy 341.484564 -315.089233)
			(xy 341.515337 -315.135746) (xy 341.539009 -315.186243) (xy 341.555077 -315.23965) (xy 341.563197 -315.294826)
			(xy 341.563706 -315.322712) (xy 341.81618 -315.322712) (xy 341.820251 -315.26709) (xy 341.832377 -315.212653)
			(xy 341.8523 -315.160562) (xy 341.879596 -315.111927) (xy 341.913682 -315.067784) (xy 341.953831 -315.029075)
			(xy 341.999189 -314.996624) (xy 342.048789 -314.971123) (xy 342.101573 -314.953116) (xy 342.156416 -314.942986)
			(xy 342.21215 -314.940949) (xy 342.267587 -314.947049) (xy 342.321544 -314.961155) (xy 342.372873 -314.982967)
			(xy 342.420479 -315.012021) (xy 342.463347 -315.047696) (xy 342.500564 -315.089233) (xy 342.531337 -315.135746)
			(xy 342.555009 -315.186243) (xy 342.571077 -315.23965) (xy 342.579197 -315.294826) (xy 342.579706 -315.322712)
			(xy 342.579197 -315.350598) (xy 342.571077 -315.405774) (xy 342.555009 -315.459181) (xy 342.531337 -315.509678)
			(xy 342.52631 -315.517276) (xy 357.436926 -315.517276) (xy 357.440997 -315.461654) (xy 357.453123 -315.407217)
			(xy 357.473046 -315.355126) (xy 357.500342 -315.306491) (xy 357.534428 -315.262348) (xy 357.574577 -315.223639)
			(xy 357.619935 -315.191188) (xy 357.669535 -315.165687) (xy 357.722319 -315.14768) (xy 357.777162 -315.13755)
			(xy 357.832896 -315.135513) (xy 357.888333 -315.141613) (xy 357.94229 -315.155719) (xy 357.993619 -315.177531)
			(xy 358.041225 -315.206585) (xy 358.084093 -315.24226) (xy 358.12131 -315.283797) (xy 358.152083 -315.33031)
			(xy 358.175755 -315.380807) (xy 358.191823 -315.434214) (xy 358.199943 -315.48939) (xy 358.200452 -315.517276)
			(xy 358.452926 -315.517276) (xy 358.456997 -315.461654) (xy 358.469123 -315.407217) (xy 358.489046 -315.355126)
			(xy 358.516342 -315.306491) (xy 358.550428 -315.262348) (xy 358.590577 -315.223639) (xy 358.635935 -315.191188)
			(xy 358.685535 -315.165687) (xy 358.738319 -315.14768) (xy 358.793162 -315.13755) (xy 358.848896 -315.135513)
			(xy 358.904333 -315.141613) (xy 358.95829 -315.155719) (xy 359.009619 -315.177531) (xy 359.057225 -315.206585)
			(xy 359.100093 -315.24226) (xy 359.13731 -315.283797) (xy 359.168083 -315.33031) (xy 359.191755 -315.380807)
			(xy 359.207823 -315.434214) (xy 359.215943 -315.48939) (xy 359.216452 -315.517276) (xy 359.468926 -315.517276)
			(xy 359.472997 -315.461654) (xy 359.485123 -315.407217) (xy 359.505046 -315.355126) (xy 359.532342 -315.306491)
			(xy 359.566428 -315.262348) (xy 359.606577 -315.223639) (xy 359.651935 -315.191188) (xy 359.701535 -315.165687)
			(xy 359.754319 -315.14768) (xy 359.809162 -315.13755) (xy 359.864896 -315.135513) (xy 359.920333 -315.141613)
			(xy 359.97429 -315.155719) (xy 360.025619 -315.177531) (xy 360.073225 -315.206585) (xy 360.116093 -315.24226)
			(xy 360.15331 -315.283797) (xy 360.184083 -315.33031) (xy 360.207755 -315.380807) (xy 360.223823 -315.434214)
			(xy 360.231943 -315.48939) (xy 360.232452 -315.517276) (xy 360.484926 -315.517276) (xy 360.488997 -315.461654)
			(xy 360.501123 -315.407217) (xy 360.521046 -315.355126) (xy 360.548342 -315.306491) (xy 360.582428 -315.262348)
			(xy 360.622577 -315.223639) (xy 360.667935 -315.191188) (xy 360.717535 -315.165687) (xy 360.770319 -315.14768)
			(xy 360.825162 -315.13755) (xy 360.880896 -315.135513) (xy 360.936333 -315.141613) (xy 360.99029 -315.155719)
			(xy 361.041619 -315.177531) (xy 361.089225 -315.206585) (xy 361.132093 -315.24226) (xy 361.16931 -315.283797)
			(xy 361.200083 -315.33031) (xy 361.223755 -315.380807) (xy 361.239823 -315.434214) (xy 361.247943 -315.48939)
			(xy 361.248452 -315.517276) (xy 361.500926 -315.517276) (xy 361.504997 -315.461654) (xy 361.517123 -315.407217)
			(xy 361.537046 -315.355126) (xy 361.564342 -315.306491) (xy 361.598428 -315.262348) (xy 361.638577 -315.223639)
			(xy 361.683935 -315.191188) (xy 361.733535 -315.165687) (xy 361.786319 -315.14768) (xy 361.841162 -315.13755)
			(xy 361.896896 -315.135513) (xy 361.952333 -315.141613) (xy 362.00629 -315.155719) (xy 362.057619 -315.177531)
			(xy 362.105225 -315.206585) (xy 362.148093 -315.24226) (xy 362.18531 -315.283797) (xy 362.216083 -315.33031)
			(xy 362.239755 -315.380807) (xy 362.255823 -315.434214) (xy 362.263943 -315.48939) (xy 362.264452 -315.517276)
			(xy 362.516926 -315.517276) (xy 362.520997 -315.461654) (xy 362.533123 -315.407217) (xy 362.553046 -315.355126)
			(xy 362.580342 -315.306491) (xy 362.614428 -315.262348) (xy 362.654577 -315.223639) (xy 362.699935 -315.191188)
			(xy 362.749535 -315.165687) (xy 362.802319 -315.14768) (xy 362.857162 -315.13755) (xy 362.912896 -315.135513)
			(xy 362.968333 -315.141613) (xy 363.02229 -315.155719) (xy 363.073619 -315.177531) (xy 363.121225 -315.206585)
			(xy 363.164093 -315.24226) (xy 363.20131 -315.283797) (xy 363.232083 -315.33031) (xy 363.255755 -315.380807)
			(xy 363.271823 -315.434214) (xy 363.279943 -315.48939) (xy 363.280452 -315.517276) (xy 363.279943 -315.545162)
			(xy 363.271823 -315.600338) (xy 363.255755 -315.653745) (xy 363.232083 -315.704242) (xy 363.20131 -315.750755)
			(xy 363.164093 -315.792292) (xy 363.121225 -315.827967) (xy 363.073619 -315.857021) (xy 363.02229 -315.878833)
			(xy 362.968333 -315.892939) (xy 362.912896 -315.899039) (xy 362.857162 -315.897002) (xy 362.802319 -315.886872)
			(xy 362.749535 -315.868865) (xy 362.699935 -315.843364) (xy 362.654577 -315.810913) (xy 362.614428 -315.772204)
			(xy 362.580342 -315.728061) (xy 362.553046 -315.679426) (xy 362.533123 -315.627335) (xy 362.520997 -315.572898)
			(xy 362.516926 -315.517276) (xy 362.264452 -315.517276) (xy 362.263943 -315.545162) (xy 362.255823 -315.600338)
			(xy 362.239755 -315.653745) (xy 362.216083 -315.704242) (xy 362.18531 -315.750755) (xy 362.148093 -315.792292)
			(xy 362.105225 -315.827967) (xy 362.057619 -315.857021) (xy 362.00629 -315.878833) (xy 361.952333 -315.892939)
			(xy 361.896896 -315.899039) (xy 361.841162 -315.897002) (xy 361.786319 -315.886872) (xy 361.733535 -315.868865)
			(xy 361.683935 -315.843364) (xy 361.638577 -315.810913) (xy 361.598428 -315.772204) (xy 361.564342 -315.728061)
			(xy 361.537046 -315.679426) (xy 361.517123 -315.627335) (xy 361.504997 -315.572898) (xy 361.500926 -315.517276)
			(xy 361.248452 -315.517276) (xy 361.247943 -315.545162) (xy 361.239823 -315.600338) (xy 361.223755 -315.653745)
			(xy 361.200083 -315.704242) (xy 361.16931 -315.750755) (xy 361.132093 -315.792292) (xy 361.089225 -315.827967)
			(xy 361.041619 -315.857021) (xy 360.99029 -315.878833) (xy 360.936333 -315.892939) (xy 360.880896 -315.899039)
			(xy 360.825162 -315.897002) (xy 360.770319 -315.886872) (xy 360.717535 -315.868865) (xy 360.667935 -315.843364)
			(xy 360.622577 -315.810913) (xy 360.582428 -315.772204) (xy 360.548342 -315.728061) (xy 360.521046 -315.679426)
			(xy 360.501123 -315.627335) (xy 360.488997 -315.572898) (xy 360.484926 -315.517276) (xy 360.232452 -315.517276)
			(xy 360.231943 -315.545162) (xy 360.223823 -315.600338) (xy 360.207755 -315.653745) (xy 360.184083 -315.704242)
			(xy 360.15331 -315.750755) (xy 360.116093 -315.792292) (xy 360.073225 -315.827967) (xy 360.025619 -315.857021)
			(xy 359.97429 -315.878833) (xy 359.920333 -315.892939) (xy 359.864896 -315.899039) (xy 359.809162 -315.897002)
			(xy 359.754319 -315.886872) (xy 359.701535 -315.868865) (xy 359.651935 -315.843364) (xy 359.606577 -315.810913)
			(xy 359.566428 -315.772204) (xy 359.532342 -315.728061) (xy 359.505046 -315.679426) (xy 359.485123 -315.627335)
			(xy 359.472997 -315.572898) (xy 359.468926 -315.517276) (xy 359.216452 -315.517276) (xy 359.215943 -315.545162)
			(xy 359.207823 -315.600338) (xy 359.191755 -315.653745) (xy 359.168083 -315.704242) (xy 359.13731 -315.750755)
			(xy 359.100093 -315.792292) (xy 359.057225 -315.827967) (xy 359.009619 -315.857021) (xy 358.95829 -315.878833)
			(xy 358.904333 -315.892939) (xy 358.848896 -315.899039) (xy 358.793162 -315.897002) (xy 358.738319 -315.886872)
			(xy 358.685535 -315.868865) (xy 358.635935 -315.843364) (xy 358.590577 -315.810913) (xy 358.550428 -315.772204)
			(xy 358.516342 -315.728061) (xy 358.489046 -315.679426) (xy 358.469123 -315.627335) (xy 358.456997 -315.572898)
			(xy 358.452926 -315.517276) (xy 358.200452 -315.517276) (xy 358.199943 -315.545162) (xy 358.191823 -315.600338)
			(xy 358.175755 -315.653745) (xy 358.152083 -315.704242) (xy 358.12131 -315.750755) (xy 358.084093 -315.792292)
			(xy 358.041225 -315.827967) (xy 357.993619 -315.857021) (xy 357.94229 -315.878833) (xy 357.888333 -315.892939)
			(xy 357.832896 -315.899039) (xy 357.777162 -315.897002) (xy 357.722319 -315.886872) (xy 357.669535 -315.868865)
			(xy 357.619935 -315.843364) (xy 357.574577 -315.810913) (xy 357.534428 -315.772204) (xy 357.500342 -315.728061)
			(xy 357.473046 -315.679426) (xy 357.453123 -315.627335) (xy 357.440997 -315.572898) (xy 357.436926 -315.517276)
			(xy 342.52631 -315.517276) (xy 342.500564 -315.556191) (xy 342.463347 -315.597728) (xy 342.420479 -315.633403)
			(xy 342.372873 -315.662457) (xy 342.321544 -315.684269) (xy 342.267587 -315.698375) (xy 342.21215 -315.704475)
			(xy 342.156416 -315.702438) (xy 342.101573 -315.692308) (xy 342.048789 -315.674301) (xy 341.999189 -315.6488)
			(xy 341.953831 -315.616349) (xy 341.913682 -315.57764) (xy 341.879596 -315.533497) (xy 341.8523 -315.484862)
			(xy 341.832377 -315.432771) (xy 341.820251 -315.378334) (xy 341.81618 -315.322712) (xy 341.563706 -315.322712)
			(xy 341.563197 -315.350598) (xy 341.555077 -315.405774) (xy 341.539009 -315.459181) (xy 341.515337 -315.509678)
			(xy 341.484564 -315.556191) (xy 341.447347 -315.597728) (xy 341.404479 -315.633403) (xy 341.356873 -315.662457)
			(xy 341.305544 -315.684269) (xy 341.251587 -315.698375) (xy 341.19615 -315.704475) (xy 341.140416 -315.702438)
			(xy 341.085573 -315.692308) (xy 341.032789 -315.674301) (xy 340.983189 -315.6488) (xy 340.937831 -315.616349)
			(xy 340.897682 -315.57764) (xy 340.863596 -315.533497) (xy 340.8363 -315.484862) (xy 340.816377 -315.432771)
			(xy 340.804251 -315.378334) (xy 340.80018 -315.322712) (xy 340.547706 -315.322712) (xy 340.547197 -315.350598)
			(xy 340.539077 -315.405774) (xy 340.523009 -315.459181) (xy 340.499337 -315.509678) (xy 340.468564 -315.556191)
			(xy 340.431347 -315.597728) (xy 340.388479 -315.633403) (xy 340.340873 -315.662457) (xy 340.289544 -315.684269)
			(xy 340.235587 -315.698375) (xy 340.18015 -315.704475) (xy 340.124416 -315.702438) (xy 340.069573 -315.692308)
			(xy 340.016789 -315.674301) (xy 339.967189 -315.6488) (xy 339.921831 -315.616349) (xy 339.881682 -315.57764)
			(xy 339.847596 -315.533497) (xy 339.8203 -315.484862) (xy 339.800377 -315.432771) (xy 339.788251 -315.378334)
			(xy 339.78418 -315.322712) (xy 339.531706 -315.322712) (xy 339.531197 -315.350598) (xy 339.523077 -315.405774)
			(xy 339.507009 -315.459181) (xy 339.483337 -315.509678) (xy 339.452564 -315.556191) (xy 339.415347 -315.597728)
			(xy 339.372479 -315.633403) (xy 339.324873 -315.662457) (xy 339.273544 -315.684269) (xy 339.219587 -315.698375)
			(xy 339.16415 -315.704475) (xy 339.108416 -315.702438) (xy 339.053573 -315.692308) (xy 339.000789 -315.674301)
			(xy 338.951189 -315.6488) (xy 338.905831 -315.616349) (xy 338.865682 -315.57764) (xy 338.831596 -315.533497)
			(xy 338.8043 -315.484862) (xy 338.784377 -315.432771) (xy 338.772251 -315.378334) (xy 338.76818 -315.322712)
			(xy 338.515706 -315.322712) (xy 338.515197 -315.350598) (xy 338.507077 -315.405774) (xy 338.491009 -315.459181)
			(xy 338.467337 -315.509678) (xy 338.436564 -315.556191) (xy 338.399347 -315.597728) (xy 338.356479 -315.633403)
			(xy 338.308873 -315.662457) (xy 338.257544 -315.684269) (xy 338.203587 -315.698375) (xy 338.14815 -315.704475)
			(xy 338.092416 -315.702438) (xy 338.037573 -315.692308) (xy 337.984789 -315.674301) (xy 337.935189 -315.6488)
			(xy 337.889831 -315.616349) (xy 337.849682 -315.57764) (xy 337.815596 -315.533497) (xy 337.7883 -315.484862)
			(xy 337.768377 -315.432771) (xy 337.756251 -315.378334) (xy 337.75218 -315.322712) (xy 337.499706 -315.322712)
			(xy 337.499197 -315.350598) (xy 337.491077 -315.405774) (xy 337.475009 -315.459181) (xy 337.451337 -315.509678)
			(xy 337.420564 -315.556191) (xy 337.383347 -315.597728) (xy 337.340479 -315.633403) (xy 337.292873 -315.662457)
			(xy 337.241544 -315.684269) (xy 337.187587 -315.698375) (xy 337.13215 -315.704475) (xy 337.076416 -315.702438)
			(xy 337.021573 -315.692308) (xy 336.968789 -315.674301) (xy 336.919189 -315.6488) (xy 336.873831 -315.616349)
			(xy 336.833682 -315.57764) (xy 336.799596 -315.533497) (xy 336.7723 -315.484862) (xy 336.752377 -315.432771)
			(xy 336.740251 -315.378334) (xy 336.73618 -315.322712) (xy 336.483706 -315.322712) (xy 336.483197 -315.350598)
			(xy 336.475077 -315.405774) (xy 336.459009 -315.459181) (xy 336.435337 -315.509678) (xy 336.404564 -315.556191)
			(xy 336.367347 -315.597728) (xy 336.324479 -315.633403) (xy 336.276873 -315.662457) (xy 336.225544 -315.684269)
			(xy 336.171587 -315.698375) (xy 336.11615 -315.704475) (xy 336.060416 -315.702438) (xy 336.005573 -315.692308)
			(xy 335.952789 -315.674301) (xy 335.903189 -315.6488) (xy 335.857831 -315.616349) (xy 335.817682 -315.57764)
			(xy 335.783596 -315.533497) (xy 335.7563 -315.484862) (xy 335.736377 -315.432771) (xy 335.724251 -315.378334)
			(xy 335.72018 -315.322712) (xy 335.467706 -315.322712) (xy 335.467197 -315.350598) (xy 335.459077 -315.405774)
			(xy 335.443009 -315.459181) (xy 335.419337 -315.509678) (xy 335.388564 -315.556191) (xy 335.351347 -315.597728)
			(xy 335.308479 -315.633403) (xy 335.260873 -315.662457) (xy 335.209544 -315.684269) (xy 335.155587 -315.698375)
			(xy 335.10015 -315.704475) (xy 335.044416 -315.702438) (xy 334.989573 -315.692308) (xy 334.936789 -315.674301)
			(xy 334.887189 -315.6488) (xy 334.841831 -315.616349) (xy 334.801682 -315.57764) (xy 334.767596 -315.533497)
			(xy 334.7403 -315.484862) (xy 334.720377 -315.432771) (xy 334.708251 -315.378334) (xy 334.70418 -315.322712)
			(xy 334.451706 -315.322712) (xy 334.451197 -315.350598) (xy 334.443077 -315.405774) (xy 334.427009 -315.459181)
			(xy 334.403337 -315.509678) (xy 334.372564 -315.556191) (xy 334.335347 -315.597728) (xy 334.292479 -315.633403)
			(xy 334.244873 -315.662457) (xy 334.193544 -315.684269) (xy 334.139587 -315.698375) (xy 334.08415 -315.704475)
			(xy 334.028416 -315.702438) (xy 333.973573 -315.692308) (xy 333.920789 -315.674301) (xy 333.871189 -315.6488)
			(xy 333.825831 -315.616349) (xy 333.785682 -315.57764) (xy 333.751596 -315.533497) (xy 333.7243 -315.484862)
			(xy 333.704377 -315.432771) (xy 333.692251 -315.378334) (xy 333.68818 -315.322712) (xy 317.508382 -315.322712)
			(xy 317.027052 -315.804042) (xy 317.019654 -315.810887) (xy 317.001055 -315.818613) (xy 316.990984 -315.819028)
			(xy 312.135012 -315.819028) (xy 312.105802 -315.846714) (xy 312.104532 -315.867034) (xy 312.102681 -315.891312)
			(xy 312.092247 -315.938868) (xy 312.074397 -315.984164) (xy 312.049584 -316.026054) (xy 312.018437 -316.063475)
			(xy 311.981745 -316.095477) (xy 311.94044 -316.121251) (xy 311.895567 -316.140142) (xy 311.848265 -316.151672)
			(xy 311.799732 -316.155547) (xy 311.751199 -316.151672) (xy 311.703897 -316.140142) (xy 311.659024 -316.121251)
			(xy 311.617719 -316.095477) (xy 311.581027 -316.063475) (xy 311.54988 -316.026054) (xy 311.525067 -315.984164)
			(xy 311.507217 -315.938868) (xy 311.496783 -315.891312) (xy 311.494932 -315.867034) (xy 311.493662 -315.846714)
			(xy 311.464452 -315.819028) (xy 310.235092 -315.819028) (xy 310.205882 -315.846714) (xy 310.204612 -315.867034)
			(xy 310.202761 -315.891312) (xy 310.192327 -315.938868) (xy 310.174477 -315.984164) (xy 310.149664 -316.026054)
			(xy 310.118517 -316.063475) (xy 310.081825 -316.095477) (xy 310.04052 -316.121251) (xy 309.995647 -316.140142)
			(xy 309.948345 -316.151672) (xy 309.899812 -316.155547) (xy 309.851279 -316.151672) (xy 309.803977 -316.140142)
			(xy 309.759104 -316.121251) (xy 309.717799 -316.095477) (xy 309.681107 -316.063475) (xy 309.64996 -316.026054)
			(xy 309.625147 -315.984164) (xy 309.607297 -315.938868) (xy 309.596863 -315.891312) (xy 309.595012 -315.867034)
			(xy 309.593742 -315.846714) (xy 309.564532 -315.819028) (xy 308.335172 -315.819028) (xy 308.305962 -315.846714)
			(xy 308.304692 -315.867034) (xy 308.302841 -315.891312) (xy 308.292407 -315.938868) (xy 308.274557 -315.984164)
			(xy 308.249744 -316.026054) (xy 308.218597 -316.063475) (xy 308.181905 -316.095477) (xy 308.1406 -316.121251)
			(xy 308.095727 -316.140142) (xy 308.048425 -316.151672) (xy 307.999892 -316.155547) (xy 307.951359 -316.151672)
			(xy 307.904057 -316.140142) (xy 307.859184 -316.121251) (xy 307.817879 -316.095477) (xy 307.781187 -316.063475)
			(xy 307.75004 -316.026054) (xy 307.725227 -315.984164) (xy 307.707377 -315.938868) (xy 307.696943 -315.891312)
			(xy 307.695092 -315.867034) (xy 307.693822 -315.846714) (xy 307.664612 -315.819028) (xy 306.434998 -315.819028)
			(xy 306.405788 -315.846714) (xy 306.404518 -315.867034) (xy 306.402667 -315.891312) (xy 306.392233 -315.938868)
			(xy 306.374383 -315.984164) (xy 306.34957 -316.026054) (xy 306.318423 -316.063475) (xy 306.281731 -316.095477)
			(xy 306.240426 -316.121251) (xy 306.195553 -316.140142) (xy 306.148251 -316.151672) (xy 306.099718 -316.155547)
			(xy 306.051185 -316.151672) (xy 306.003883 -316.140142) (xy 305.95901 -316.121251) (xy 305.917705 -316.095477)
			(xy 305.881013 -316.063475) (xy 305.849866 -316.026054) (xy 305.825053 -315.984164) (xy 305.807203 -315.938868)
			(xy 305.796769 -315.891312) (xy 305.794918 -315.867034) (xy 305.793648 -315.846714) (xy 305.764438 -315.819028)
			(xy 304.556668 -315.819028) (xy 304.527458 -315.846714) (xy 304.526442 -315.867034) (xy 304.52453 -315.893104)
			(xy 304.513465 -315.944191) (xy 304.494416 -315.992867) (xy 304.467869 -316.037895) (xy 304.434499 -316.078128)
			(xy 304.395156 -316.112542) (xy 304.35084 -316.140262) (xy 304.302681 -316.160582) (xy 304.251902 -316.172984)
			(xy 304.199798 -316.177154) (xy 304.147694 -316.172984) (xy 304.096915 -316.160582) (xy 304.048756 -316.140262)
			(xy 304.00444 -316.112542) (xy 303.965097 -316.078128) (xy 303.931727 -316.037895) (xy 303.90518 -315.992867)
			(xy 303.886131 -315.944191) (xy 303.875066 -315.893104) (xy 303.873154 -315.867034) (xy 303.872138 -315.846714)
			(xy 303.842928 -315.819028) (xy 302.656748 -315.819028) (xy 302.627538 -315.846714) (xy 302.626522 -315.867034)
			(xy 302.62461 -315.893104) (xy 302.613545 -315.944191) (xy 302.594496 -315.992867) (xy 302.567949 -316.037895)
			(xy 302.534579 -316.078128) (xy 302.495236 -316.112542) (xy 302.45092 -316.140262) (xy 302.402761 -316.160582)
			(xy 302.351982 -316.172984) (xy 302.299878 -316.177154) (xy 302.247774 -316.172984) (xy 302.196995 -316.160582)
			(xy 302.148836 -316.140262) (xy 302.10452 -316.112542) (xy 302.065177 -316.078128) (xy 302.031807 -316.037895)
			(xy 302.00526 -315.992867) (xy 301.986211 -315.944191) (xy 301.975146 -315.893104) (xy 301.973234 -315.867034)
			(xy 301.972218 -315.846714) (xy 301.943008 -315.819028) (xy 300.756574 -315.819028) (xy 300.727364 -315.846714)
			(xy 300.726348 -315.867034) (xy 300.724436 -315.893104) (xy 300.713371 -315.944191) (xy 300.694322 -315.992867)
			(xy 300.667775 -316.037895) (xy 300.634405 -316.078128) (xy 300.595062 -316.112542) (xy 300.550746 -316.140262)
			(xy 300.502587 -316.160582) (xy 300.451808 -316.172984) (xy 300.399704 -316.177154) (xy 300.3476 -316.172984)
			(xy 300.296821 -316.160582) (xy 300.248662 -316.140262) (xy 300.204346 -316.112542) (xy 300.165003 -316.078128)
			(xy 300.131633 -316.037895) (xy 300.105086 -315.992867) (xy 300.086037 -315.944191) (xy 300.074972 -315.893104)
			(xy 300.07306 -315.867034) (xy 300.072044 -315.846714) (xy 300.042834 -315.819028) (xy 298.856654 -315.819028)
			(xy 298.827444 -315.846714) (xy 298.826428 -315.867034) (xy 298.824904 -315.884306) (xy 298.823634 -315.895736)
			(xy 298.831508 -315.917326) (xy 298.904152 -315.989716) (xy 298.925996 -315.997082) (xy 298.937426 -315.995812)
			(xy 298.94673 -315.994842) (xy 298.96541 -315.993824) (xy 298.974764 -315.99378) (xy 299.000741 -315.994286)
			(xy 299.052056 -316.002404) (xy 299.10147 -316.018446) (xy 299.147768 -316.042018) (xy 299.189811 -316.072539)
			(xy 299.226565 -316.109259) (xy 299.257124 -316.151274) (xy 299.280738 -316.19755) (xy 299.296825 -316.24695)
			(xy 299.30499 -316.298258) (xy 299.305472 -316.324234) (xy 299.305472 -316.338712) (xy 335.72018 -316.338712)
			(xy 335.724251 -316.28309) (xy 335.736377 -316.228653) (xy 335.7563 -316.176562) (xy 335.783596 -316.127927)
			(xy 335.817682 -316.083784) (xy 335.857831 -316.045075) (xy 335.903189 -316.012624) (xy 335.952789 -315.987123)
			(xy 336.005573 -315.969116) (xy 336.060416 -315.958986) (xy 336.11615 -315.956949) (xy 336.171587 -315.963049)
			(xy 336.225544 -315.977155) (xy 336.276873 -315.998967) (xy 336.324479 -316.028021) (xy 336.367347 -316.063696)
			(xy 336.404564 -316.105233) (xy 336.435337 -316.151746) (xy 336.459009 -316.202243) (xy 336.475077 -316.25565)
			(xy 336.483197 -316.310826) (xy 336.483706 -316.338712) (xy 336.73618 -316.338712) (xy 336.740251 -316.28309)
			(xy 336.752377 -316.228653) (xy 336.7723 -316.176562) (xy 336.799596 -316.127927) (xy 336.833682 -316.083784)
			(xy 336.873831 -316.045075) (xy 336.919189 -316.012624) (xy 336.968789 -315.987123) (xy 337.021573 -315.969116)
			(xy 337.076416 -315.958986) (xy 337.13215 -315.956949) (xy 337.187587 -315.963049) (xy 337.241544 -315.977155)
			(xy 337.292873 -315.998967) (xy 337.340479 -316.028021) (xy 337.383347 -316.063696) (xy 337.420564 -316.105233)
			(xy 337.451337 -316.151746) (xy 337.475009 -316.202243) (xy 337.491077 -316.25565) (xy 337.499197 -316.310826)
			(xy 337.499706 -316.338712) (xy 337.75218 -316.338712) (xy 337.756251 -316.28309) (xy 337.768377 -316.228653)
			(xy 337.7883 -316.176562) (xy 337.815596 -316.127927) (xy 337.849682 -316.083784) (xy 337.889831 -316.045075)
			(xy 337.935189 -316.012624) (xy 337.984789 -315.987123) (xy 338.037573 -315.969116) (xy 338.092416 -315.958986)
			(xy 338.14815 -315.956949) (xy 338.203587 -315.963049) (xy 338.257544 -315.977155) (xy 338.308873 -315.998967)
			(xy 338.356479 -316.028021) (xy 338.399347 -316.063696) (xy 338.436564 -316.105233) (xy 338.467337 -316.151746)
			(xy 338.491009 -316.202243) (xy 338.507077 -316.25565) (xy 338.515197 -316.310826) (xy 338.515706 -316.338712)
			(xy 338.76818 -316.338712) (xy 338.772251 -316.28309) (xy 338.784377 -316.228653) (xy 338.8043 -316.176562)
			(xy 338.831596 -316.127927) (xy 338.865682 -316.083784) (xy 338.905831 -316.045075) (xy 338.951189 -316.012624)
			(xy 339.000789 -315.987123) (xy 339.053573 -315.969116) (xy 339.108416 -315.958986) (xy 339.16415 -315.956949)
			(xy 339.219587 -315.963049) (xy 339.273544 -315.977155) (xy 339.324873 -315.998967) (xy 339.372479 -316.028021)
			(xy 339.415347 -316.063696) (xy 339.452564 -316.105233) (xy 339.483337 -316.151746) (xy 339.507009 -316.202243)
			(xy 339.523077 -316.25565) (xy 339.531197 -316.310826) (xy 339.531706 -316.338712) (xy 339.78418 -316.338712)
			(xy 339.788251 -316.28309) (xy 339.800377 -316.228653) (xy 339.8203 -316.176562) (xy 339.847596 -316.127927)
			(xy 339.881682 -316.083784) (xy 339.921831 -316.045075) (xy 339.967189 -316.012624) (xy 340.016789 -315.987123)
			(xy 340.069573 -315.969116) (xy 340.124416 -315.958986) (xy 340.18015 -315.956949) (xy 340.235587 -315.963049)
			(xy 340.289544 -315.977155) (xy 340.340873 -315.998967) (xy 340.388479 -316.028021) (xy 340.431347 -316.063696)
			(xy 340.468564 -316.105233) (xy 340.499337 -316.151746) (xy 340.523009 -316.202243) (xy 340.539077 -316.25565)
			(xy 340.547197 -316.310826) (xy 340.547706 -316.338712) (xy 340.80018 -316.338712) (xy 340.804251 -316.28309)
			(xy 340.816377 -316.228653) (xy 340.8363 -316.176562) (xy 340.863596 -316.127927) (xy 340.897682 -316.083784)
			(xy 340.937831 -316.045075) (xy 340.983189 -316.012624) (xy 341.032789 -315.987123) (xy 341.085573 -315.969116)
			(xy 341.140416 -315.958986) (xy 341.19615 -315.956949) (xy 341.251587 -315.963049) (xy 341.305544 -315.977155)
			(xy 341.356873 -315.998967) (xy 341.404479 -316.028021) (xy 341.447347 -316.063696) (xy 341.484564 -316.105233)
			(xy 341.515337 -316.151746) (xy 341.539009 -316.202243) (xy 341.555077 -316.25565) (xy 341.563197 -316.310826)
			(xy 341.563706 -316.338712) (xy 341.81618 -316.338712) (xy 341.820251 -316.28309) (xy 341.832377 -316.228653)
			(xy 341.8523 -316.176562) (xy 341.879596 -316.127927) (xy 341.913682 -316.083784) (xy 341.953831 -316.045075)
			(xy 341.999189 -316.012624) (xy 342.048789 -315.987123) (xy 342.101573 -315.969116) (xy 342.156416 -315.958986)
			(xy 342.21215 -315.956949) (xy 342.267587 -315.963049) (xy 342.321544 -315.977155) (xy 342.372873 -315.998967)
			(xy 342.420479 -316.028021) (xy 342.463347 -316.063696) (xy 342.500564 -316.105233) (xy 342.531337 -316.151746)
			(xy 342.555009 -316.202243) (xy 342.571077 -316.25565) (xy 342.579197 -316.310826) (xy 342.579706 -316.338712)
			(xy 342.579197 -316.366598) (xy 342.571077 -316.421774) (xy 342.555009 -316.475181) (xy 342.531337 -316.525678)
			(xy 342.52631 -316.533276) (xy 357.436926 -316.533276) (xy 357.440997 -316.477654) (xy 357.453123 -316.423217)
			(xy 357.473046 -316.371126) (xy 357.500342 -316.322491) (xy 357.534428 -316.278348) (xy 357.574577 -316.239639)
			(xy 357.619935 -316.207188) (xy 357.669535 -316.181687) (xy 357.722319 -316.16368) (xy 357.777162 -316.15355)
			(xy 357.832896 -316.151513) (xy 357.888333 -316.157613) (xy 357.94229 -316.171719) (xy 357.993619 -316.193531)
			(xy 358.041225 -316.222585) (xy 358.084093 -316.25826) (xy 358.12131 -316.299797) (xy 358.152083 -316.34631)
			(xy 358.175755 -316.396807) (xy 358.191823 -316.450214) (xy 358.199943 -316.50539) (xy 358.200452 -316.533276)
			(xy 358.452926 -316.533276) (xy 358.456997 -316.477654) (xy 358.469123 -316.423217) (xy 358.489046 -316.371126)
			(xy 358.516342 -316.322491) (xy 358.550428 -316.278348) (xy 358.590577 -316.239639) (xy 358.635935 -316.207188)
			(xy 358.685535 -316.181687) (xy 358.738319 -316.16368) (xy 358.793162 -316.15355) (xy 358.848896 -316.151513)
			(xy 358.904333 -316.157613) (xy 358.95829 -316.171719) (xy 359.009619 -316.193531) (xy 359.057225 -316.222585)
			(xy 359.100093 -316.25826) (xy 359.13731 -316.299797) (xy 359.168083 -316.34631) (xy 359.191755 -316.396807)
			(xy 359.207823 -316.450214) (xy 359.215943 -316.50539) (xy 359.216452 -316.533276) (xy 359.468926 -316.533276)
			(xy 359.472997 -316.477654) (xy 359.485123 -316.423217) (xy 359.505046 -316.371126) (xy 359.532342 -316.322491)
			(xy 359.566428 -316.278348) (xy 359.606577 -316.239639) (xy 359.651935 -316.207188) (xy 359.701535 -316.181687)
			(xy 359.754319 -316.16368) (xy 359.809162 -316.15355) (xy 359.864896 -316.151513) (xy 359.920333 -316.157613)
			(xy 359.97429 -316.171719) (xy 360.025619 -316.193531) (xy 360.073225 -316.222585) (xy 360.116093 -316.25826)
			(xy 360.15331 -316.299797) (xy 360.184083 -316.34631) (xy 360.207755 -316.396807) (xy 360.223823 -316.450214)
			(xy 360.231943 -316.50539) (xy 360.232452 -316.533276) (xy 360.484926 -316.533276) (xy 360.488997 -316.477654)
			(xy 360.501123 -316.423217) (xy 360.521046 -316.371126) (xy 360.548342 -316.322491) (xy 360.582428 -316.278348)
			(xy 360.622577 -316.239639) (xy 360.667935 -316.207188) (xy 360.717535 -316.181687) (xy 360.770319 -316.16368)
			(xy 360.825162 -316.15355) (xy 360.880896 -316.151513) (xy 360.936333 -316.157613) (xy 360.99029 -316.171719)
			(xy 361.041619 -316.193531) (xy 361.089225 -316.222585) (xy 361.132093 -316.25826) (xy 361.16931 -316.299797)
			(xy 361.200083 -316.34631) (xy 361.223755 -316.396807) (xy 361.239823 -316.450214) (xy 361.247943 -316.50539)
			(xy 361.248452 -316.533276) (xy 361.500926 -316.533276) (xy 361.504997 -316.477654) (xy 361.517123 -316.423217)
			(xy 361.537046 -316.371126) (xy 361.564342 -316.322491) (xy 361.598428 -316.278348) (xy 361.638577 -316.239639)
			(xy 361.683935 -316.207188) (xy 361.733535 -316.181687) (xy 361.786319 -316.16368) (xy 361.841162 -316.15355)
			(xy 361.896896 -316.151513) (xy 361.952333 -316.157613) (xy 362.00629 -316.171719) (xy 362.057619 -316.193531)
			(xy 362.105225 -316.222585) (xy 362.148093 -316.25826) (xy 362.18531 -316.299797) (xy 362.216083 -316.34631)
			(xy 362.239755 -316.396807) (xy 362.255823 -316.450214) (xy 362.263943 -316.50539) (xy 362.264452 -316.533276)
			(xy 362.516926 -316.533276) (xy 362.520997 -316.477654) (xy 362.533123 -316.423217) (xy 362.553046 -316.371126)
			(xy 362.580342 -316.322491) (xy 362.614428 -316.278348) (xy 362.654577 -316.239639) (xy 362.699935 -316.207188)
			(xy 362.749535 -316.181687) (xy 362.802319 -316.16368) (xy 362.857162 -316.15355) (xy 362.912896 -316.151513)
			(xy 362.968333 -316.157613) (xy 363.02229 -316.171719) (xy 363.073619 -316.193531) (xy 363.121225 -316.222585)
			(xy 363.164093 -316.25826) (xy 363.20131 -316.299797) (xy 363.232083 -316.34631) (xy 363.255755 -316.396807)
			(xy 363.271823 -316.450214) (xy 363.279943 -316.50539) (xy 363.280452 -316.533276) (xy 363.279943 -316.561162)
			(xy 363.271823 -316.616338) (xy 363.255755 -316.669745) (xy 363.232083 -316.720242) (xy 363.20131 -316.766755)
			(xy 363.164093 -316.808292) (xy 363.121225 -316.843967) (xy 363.073619 -316.873021) (xy 363.02229 -316.894833)
			(xy 362.968333 -316.908939) (xy 362.912896 -316.915039) (xy 362.857162 -316.913002) (xy 362.802319 -316.902872)
			(xy 362.749535 -316.884865) (xy 362.699935 -316.859364) (xy 362.654577 -316.826913) (xy 362.614428 -316.788204)
			(xy 362.580342 -316.744061) (xy 362.553046 -316.695426) (xy 362.533123 -316.643335) (xy 362.520997 -316.588898)
			(xy 362.516926 -316.533276) (xy 362.264452 -316.533276) (xy 362.263943 -316.561162) (xy 362.255823 -316.616338)
			(xy 362.239755 -316.669745) (xy 362.216083 -316.720242) (xy 362.18531 -316.766755) (xy 362.148093 -316.808292)
			(xy 362.105225 -316.843967) (xy 362.057619 -316.873021) (xy 362.00629 -316.894833) (xy 361.952333 -316.908939)
			(xy 361.896896 -316.915039) (xy 361.841162 -316.913002) (xy 361.786319 -316.902872) (xy 361.733535 -316.884865)
			(xy 361.683935 -316.859364) (xy 361.638577 -316.826913) (xy 361.598428 -316.788204) (xy 361.564342 -316.744061)
			(xy 361.537046 -316.695426) (xy 361.517123 -316.643335) (xy 361.504997 -316.588898) (xy 361.500926 -316.533276)
			(xy 361.248452 -316.533276) (xy 361.247943 -316.561162) (xy 361.239823 -316.616338) (xy 361.223755 -316.669745)
			(xy 361.200083 -316.720242) (xy 361.16931 -316.766755) (xy 361.132093 -316.808292) (xy 361.089225 -316.843967)
			(xy 361.041619 -316.873021) (xy 360.99029 -316.894833) (xy 360.936333 -316.908939) (xy 360.880896 -316.915039)
			(xy 360.825162 -316.913002) (xy 360.770319 -316.902872) (xy 360.717535 -316.884865) (xy 360.667935 -316.859364)
			(xy 360.622577 -316.826913) (xy 360.582428 -316.788204) (xy 360.548342 -316.744061) (xy 360.521046 -316.695426)
			(xy 360.501123 -316.643335) (xy 360.488997 -316.588898) (xy 360.484926 -316.533276) (xy 360.232452 -316.533276)
			(xy 360.231943 -316.561162) (xy 360.223823 -316.616338) (xy 360.207755 -316.669745) (xy 360.184083 -316.720242)
			(xy 360.15331 -316.766755) (xy 360.116093 -316.808292) (xy 360.073225 -316.843967) (xy 360.025619 -316.873021)
			(xy 359.97429 -316.894833) (xy 359.920333 -316.908939) (xy 359.864896 -316.915039) (xy 359.809162 -316.913002)
			(xy 359.754319 -316.902872) (xy 359.701535 -316.884865) (xy 359.651935 -316.859364) (xy 359.606577 -316.826913)
			(xy 359.566428 -316.788204) (xy 359.532342 -316.744061) (xy 359.505046 -316.695426) (xy 359.485123 -316.643335)
			(xy 359.472997 -316.588898) (xy 359.468926 -316.533276) (xy 359.216452 -316.533276) (xy 359.215943 -316.561162)
			(xy 359.207823 -316.616338) (xy 359.191755 -316.669745) (xy 359.168083 -316.720242) (xy 359.13731 -316.766755)
			(xy 359.100093 -316.808292) (xy 359.057225 -316.843967) (xy 359.009619 -316.873021) (xy 358.95829 -316.894833)
			(xy 358.904333 -316.908939) (xy 358.848896 -316.915039) (xy 358.793162 -316.913002) (xy 358.738319 -316.902872)
			(xy 358.685535 -316.884865) (xy 358.635935 -316.859364) (xy 358.590577 -316.826913) (xy 358.550428 -316.788204)
			(xy 358.516342 -316.744061) (xy 358.489046 -316.695426) (xy 358.469123 -316.643335) (xy 358.456997 -316.588898)
			(xy 358.452926 -316.533276) (xy 358.200452 -316.533276) (xy 358.199943 -316.561162) (xy 358.191823 -316.616338)
			(xy 358.175755 -316.669745) (xy 358.152083 -316.720242) (xy 358.12131 -316.766755) (xy 358.084093 -316.808292)
			(xy 358.041225 -316.843967) (xy 357.993619 -316.873021) (xy 357.94229 -316.894833) (xy 357.888333 -316.908939)
			(xy 357.832896 -316.915039) (xy 357.777162 -316.913002) (xy 357.722319 -316.902872) (xy 357.669535 -316.884865)
			(xy 357.619935 -316.859364) (xy 357.574577 -316.826913) (xy 357.534428 -316.788204) (xy 357.500342 -316.744061)
			(xy 357.473046 -316.695426) (xy 357.453123 -316.643335) (xy 357.440997 -316.588898) (xy 357.436926 -316.533276)
			(xy 342.52631 -316.533276) (xy 342.500564 -316.572191) (xy 342.463347 -316.613728) (xy 342.420479 -316.649403)
			(xy 342.372873 -316.678457) (xy 342.321544 -316.700269) (xy 342.267587 -316.714375) (xy 342.21215 -316.720475)
			(xy 342.156416 -316.718438) (xy 342.101573 -316.708308) (xy 342.048789 -316.690301) (xy 341.999189 -316.6648)
			(xy 341.953831 -316.632349) (xy 341.913682 -316.59364) (xy 341.879596 -316.549497) (xy 341.8523 -316.500862)
			(xy 341.832377 -316.448771) (xy 341.820251 -316.394334) (xy 341.81618 -316.338712) (xy 341.563706 -316.338712)
			(xy 341.563197 -316.366598) (xy 341.555077 -316.421774) (xy 341.539009 -316.475181) (xy 341.515337 -316.525678)
			(xy 341.484564 -316.572191) (xy 341.447347 -316.613728) (xy 341.404479 -316.649403) (xy 341.356873 -316.678457)
			(xy 341.305544 -316.700269) (xy 341.251587 -316.714375) (xy 341.19615 -316.720475) (xy 341.140416 -316.718438)
			(xy 341.085573 -316.708308) (xy 341.032789 -316.690301) (xy 340.983189 -316.6648) (xy 340.937831 -316.632349)
			(xy 340.897682 -316.59364) (xy 340.863596 -316.549497) (xy 340.8363 -316.500862) (xy 340.816377 -316.448771)
			(xy 340.804251 -316.394334) (xy 340.80018 -316.338712) (xy 340.547706 -316.338712) (xy 340.547197 -316.366598)
			(xy 340.539077 -316.421774) (xy 340.523009 -316.475181) (xy 340.499337 -316.525678) (xy 340.468564 -316.572191)
			(xy 340.431347 -316.613728) (xy 340.388479 -316.649403) (xy 340.340873 -316.678457) (xy 340.289544 -316.700269)
			(xy 340.235587 -316.714375) (xy 340.18015 -316.720475) (xy 340.124416 -316.718438) (xy 340.069573 -316.708308)
			(xy 340.016789 -316.690301) (xy 339.967189 -316.6648) (xy 339.921831 -316.632349) (xy 339.881682 -316.59364)
			(xy 339.847596 -316.549497) (xy 339.8203 -316.500862) (xy 339.800377 -316.448771) (xy 339.788251 -316.394334)
			(xy 339.78418 -316.338712) (xy 339.531706 -316.338712) (xy 339.531197 -316.366598) (xy 339.523077 -316.421774)
			(xy 339.507009 -316.475181) (xy 339.483337 -316.525678) (xy 339.452564 -316.572191) (xy 339.415347 -316.613728)
			(xy 339.372479 -316.649403) (xy 339.324873 -316.678457) (xy 339.273544 -316.700269) (xy 339.219587 -316.714375)
			(xy 339.16415 -316.720475) (xy 339.108416 -316.718438) (xy 339.053573 -316.708308) (xy 339.000789 -316.690301)
			(xy 338.951189 -316.6648) (xy 338.905831 -316.632349) (xy 338.865682 -316.59364) (xy 338.831596 -316.549497)
			(xy 338.8043 -316.500862) (xy 338.784377 -316.448771) (xy 338.772251 -316.394334) (xy 338.76818 -316.338712)
			(xy 338.515706 -316.338712) (xy 338.515197 -316.366598) (xy 338.507077 -316.421774) (xy 338.491009 -316.475181)
			(xy 338.467337 -316.525678) (xy 338.436564 -316.572191) (xy 338.399347 -316.613728) (xy 338.356479 -316.649403)
			(xy 338.308873 -316.678457) (xy 338.257544 -316.700269) (xy 338.203587 -316.714375) (xy 338.14815 -316.720475)
			(xy 338.092416 -316.718438) (xy 338.037573 -316.708308) (xy 337.984789 -316.690301) (xy 337.935189 -316.6648)
			(xy 337.889831 -316.632349) (xy 337.849682 -316.59364) (xy 337.815596 -316.549497) (xy 337.7883 -316.500862)
			(xy 337.768377 -316.448771) (xy 337.756251 -316.394334) (xy 337.75218 -316.338712) (xy 337.499706 -316.338712)
			(xy 337.499197 -316.366598) (xy 337.491077 -316.421774) (xy 337.475009 -316.475181) (xy 337.451337 -316.525678)
			(xy 337.420564 -316.572191) (xy 337.383347 -316.613728) (xy 337.340479 -316.649403) (xy 337.292873 -316.678457)
			(xy 337.241544 -316.700269) (xy 337.187587 -316.714375) (xy 337.13215 -316.720475) (xy 337.076416 -316.718438)
			(xy 337.021573 -316.708308) (xy 336.968789 -316.690301) (xy 336.919189 -316.6648) (xy 336.873831 -316.632349)
			(xy 336.833682 -316.59364) (xy 336.799596 -316.549497) (xy 336.7723 -316.500862) (xy 336.752377 -316.448771)
			(xy 336.740251 -316.394334) (xy 336.73618 -316.338712) (xy 336.483706 -316.338712) (xy 336.483197 -316.366598)
			(xy 336.475077 -316.421774) (xy 336.459009 -316.475181) (xy 336.435337 -316.525678) (xy 336.404564 -316.572191)
			(xy 336.367347 -316.613728) (xy 336.324479 -316.649403) (xy 336.276873 -316.678457) (xy 336.225544 -316.700269)
			(xy 336.171587 -316.714375) (xy 336.11615 -316.720475) (xy 336.060416 -316.718438) (xy 336.005573 -316.708308)
			(xy 335.952789 -316.690301) (xy 335.903189 -316.6648) (xy 335.857831 -316.632349) (xy 335.817682 -316.59364)
			(xy 335.783596 -316.549497) (xy 335.7563 -316.500862) (xy 335.736377 -316.448771) (xy 335.724251 -316.394334)
			(xy 335.72018 -316.338712) (xy 299.305472 -316.338712) (xy 299.305472 -316.82543) (xy 300.073056 -316.82543)
			(xy 300.073056 -316.774014) (xy 300.081099 -316.723232) (xy 300.096987 -316.674333) (xy 300.12033 -316.628521)
			(xy 300.150551 -316.586925) (xy 300.186907 -316.550569) (xy 300.228503 -316.520348) (xy 300.274315 -316.497005)
			(xy 300.323214 -316.481117) (xy 300.373996 -316.473074) (xy 300.425412 -316.473074) (xy 300.476194 -316.481117)
			(xy 300.525093 -316.497005) (xy 300.570905 -316.520348) (xy 300.612501 -316.550569) (xy 300.648857 -316.586925)
			(xy 300.679078 -316.628521) (xy 300.702421 -316.674333) (xy 300.718309 -316.723232) (xy 300.726352 -316.774014)
			(xy 300.726856 -316.799722) (xy 300.726352 -316.82543) (xy 301.97323 -316.82543) (xy 301.97323 -316.774014)
			(xy 301.981273 -316.723232) (xy 301.997161 -316.674333) (xy 302.020504 -316.628521) (xy 302.050725 -316.586925)
			(xy 302.087081 -316.550569) (xy 302.128677 -316.520348) (xy 302.174489 -316.497005) (xy 302.223388 -316.481117)
			(xy 302.27417 -316.473074) (xy 302.325586 -316.473074) (xy 302.376368 -316.481117) (xy 302.425267 -316.497005)
			(xy 302.471079 -316.520348) (xy 302.512675 -316.550569) (xy 302.549031 -316.586925) (xy 302.579252 -316.628521)
			(xy 302.602595 -316.674333) (xy 302.618483 -316.723232) (xy 302.626526 -316.774014) (xy 302.62703 -316.799722)
			(xy 302.626526 -316.82543) (xy 303.87315 -316.82543) (xy 303.87315 -316.774014) (xy 303.881193 -316.723232)
			(xy 303.897081 -316.674333) (xy 303.920424 -316.628521) (xy 303.950645 -316.586925) (xy 303.987001 -316.550569)
			(xy 304.028597 -316.520348) (xy 304.074409 -316.497005) (xy 304.123308 -316.481117) (xy 304.17409 -316.473074)
			(xy 304.225506 -316.473074) (xy 304.276288 -316.481117) (xy 304.325187 -316.497005) (xy 304.370999 -316.520348)
			(xy 304.412595 -316.550569) (xy 304.448951 -316.586925) (xy 304.479172 -316.628521) (xy 304.502515 -316.674333)
			(xy 304.518403 -316.723232) (xy 304.526446 -316.774014) (xy 304.52695 -316.799722) (xy 305.793914 -316.799722)
			(xy 305.797874 -316.750668) (xy 305.809651 -316.702884) (xy 305.828942 -316.657608) (xy 305.855245 -316.616012)
			(xy 305.88788 -316.579175) (xy 305.926001 -316.54805) (xy 305.968622 -316.523443) (xy 306.014638 -316.505991)
			(xy 306.062857 -316.496147) (xy 306.112032 -316.494166) (xy 306.160887 -316.500098) (xy 306.208158 -316.51379)
			(xy 306.25262 -316.534888) (xy 306.293123 -316.562844) (xy 306.328616 -316.596936) (xy 306.358181 -316.63628)
			(xy 306.381052 -316.679857) (xy 306.396636 -316.726538) (xy 306.404531 -316.775115) (xy 306.405026 -316.799722)
			(xy 307.694088 -316.799722) (xy 307.698048 -316.750668) (xy 307.709825 -316.702884) (xy 307.729116 -316.657608)
			(xy 307.755419 -316.616012) (xy 307.788054 -316.579175) (xy 307.826175 -316.54805) (xy 307.868796 -316.523443)
			(xy 307.914812 -316.505991) (xy 307.963031 -316.496147) (xy 308.012206 -316.494166) (xy 308.061061 -316.500098)
			(xy 308.108332 -316.51379) (xy 308.152794 -316.534888) (xy 308.193297 -316.562844) (xy 308.22879 -316.596936)
			(xy 308.258355 -316.63628) (xy 308.281226 -316.679857) (xy 308.29681 -316.726538) (xy 308.304705 -316.775115)
			(xy 308.3052 -316.799722) (xy 309.594008 -316.799722) (xy 309.597968 -316.750668) (xy 309.609745 -316.702884)
			(xy 309.629036 -316.657608) (xy 309.655339 -316.616012) (xy 309.687974 -316.579175) (xy 309.726095 -316.54805)
			(xy 309.768716 -316.523443) (xy 309.814732 -316.505991) (xy 309.862951 -316.496147) (xy 309.912126 -316.494166)
			(xy 309.960981 -316.500098) (xy 310.008252 -316.51379) (xy 310.052714 -316.534888) (xy 310.093217 -316.562844)
			(xy 310.12871 -316.596936) (xy 310.158275 -316.63628) (xy 310.181146 -316.679857) (xy 310.19673 -316.726538)
			(xy 310.204625 -316.775115) (xy 310.20512 -316.799722) (xy 311.493928 -316.799722) (xy 311.497888 -316.750668)
			(xy 311.509665 -316.702884) (xy 311.528956 -316.657608) (xy 311.555259 -316.616012) (xy 311.587894 -316.579175)
			(xy 311.626015 -316.54805) (xy 311.668636 -316.523443) (xy 311.714652 -316.505991) (xy 311.762871 -316.496147)
			(xy 311.812046 -316.494166) (xy 311.860901 -316.500098) (xy 311.908172 -316.51379) (xy 311.952634 -316.534888)
			(xy 311.993137 -316.562844) (xy 312.02863 -316.596936) (xy 312.058195 -316.63628) (xy 312.081066 -316.679857)
			(xy 312.09665 -316.726538) (xy 312.104545 -316.775115) (xy 312.10504 -316.799722) (xy 313.394102 -316.799722)
			(xy 313.398062 -316.750668) (xy 313.409839 -316.702884) (xy 313.42913 -316.657608) (xy 313.455433 -316.616012)
			(xy 313.488068 -316.579175) (xy 313.526189 -316.54805) (xy 313.56881 -316.523443) (xy 313.614826 -316.505991)
			(xy 313.663045 -316.496147) (xy 313.71222 -316.494166) (xy 313.761075 -316.500098) (xy 313.808346 -316.51379)
			(xy 313.852808 -316.534888) (xy 313.893311 -316.562844) (xy 313.928804 -316.596936) (xy 313.958369 -316.63628)
			(xy 313.98124 -316.679857) (xy 313.996824 -316.726538) (xy 314.004719 -316.775115) (xy 314.005214 -316.799722)
			(xy 314.344062 -316.799722) (xy 314.348022 -316.750668) (xy 314.359799 -316.702884) (xy 314.37909 -316.657608)
			(xy 314.405393 -316.616012) (xy 314.438028 -316.579175) (xy 314.476149 -316.54805) (xy 314.51877 -316.523443)
			(xy 314.564786 -316.505991) (xy 314.613005 -316.496147) (xy 314.66218 -316.494166) (xy 314.711035 -316.500098)
			(xy 314.758306 -316.51379) (xy 314.802768 -316.534888) (xy 314.843271 -316.562844) (xy 314.878764 -316.596936)
			(xy 314.908329 -316.63628) (xy 314.9312 -316.679857) (xy 314.946784 -316.726538) (xy 314.954679 -316.775115)
			(xy 314.955174 -316.799722) (xy 314.954679 -316.824329) (xy 314.946784 -316.872906) (xy 314.9312 -316.919587)
			(xy 314.908329 -316.963164) (xy 314.878764 -317.002508) (xy 314.843271 -317.0366) (xy 314.802768 -317.064556)
			(xy 314.758306 -317.085654) (xy 314.711035 -317.099346) (xy 314.66218 -317.105278) (xy 314.613005 -317.103297)
			(xy 314.564786 -317.093453) (xy 314.51877 -317.076001) (xy 314.476149 -317.051394) (xy 314.438028 -317.020269)
			(xy 314.405393 -316.983432) (xy 314.37909 -316.941836) (xy 314.359799 -316.89656) (xy 314.348022 -316.848776)
			(xy 314.344062 -316.799722) (xy 314.005214 -316.799722) (xy 314.004719 -316.824329) (xy 313.996824 -316.872906)
			(xy 313.98124 -316.919587) (xy 313.958369 -316.963164) (xy 313.928804 -317.002508) (xy 313.893311 -317.0366)
			(xy 313.852808 -317.064556) (xy 313.808346 -317.085654) (xy 313.761075 -317.099346) (xy 313.71222 -317.105278)
			(xy 313.663045 -317.103297) (xy 313.614826 -317.093453) (xy 313.56881 -317.076001) (xy 313.526189 -317.051394)
			(xy 313.488068 -317.020269) (xy 313.455433 -316.983432) (xy 313.42913 -316.941836) (xy 313.409839 -316.89656)
			(xy 313.398062 -316.848776) (xy 313.394102 -316.799722) (xy 312.10504 -316.799722) (xy 312.104545 -316.824329)
			(xy 312.09665 -316.872906) (xy 312.081066 -316.919587) (xy 312.058195 -316.963164) (xy 312.02863 -317.002508)
			(xy 311.993137 -317.0366) (xy 311.952634 -317.064556) (xy 311.908172 -317.085654) (xy 311.860901 -317.099346)
			(xy 311.812046 -317.105278) (xy 311.762871 -317.103297) (xy 311.714652 -317.093453) (xy 311.668636 -317.076001)
			(xy 311.626015 -317.051394) (xy 311.587894 -317.020269) (xy 311.555259 -316.983432) (xy 311.528956 -316.941836)
			(xy 311.509665 -316.89656) (xy 311.497888 -316.848776) (xy 311.493928 -316.799722) (xy 310.20512 -316.799722)
			(xy 310.204625 -316.824329) (xy 310.19673 -316.872906) (xy 310.181146 -316.919587) (xy 310.158275 -316.963164)
			(xy 310.12871 -317.002508) (xy 310.093217 -317.0366) (xy 310.052714 -317.064556) (xy 310.008252 -317.085654)
			(xy 309.960981 -317.099346) (xy 309.912126 -317.105278) (xy 309.862951 -317.103297) (xy 309.814732 -317.093453)
			(xy 309.768716 -317.076001) (xy 309.726095 -317.051394) (xy 309.687974 -317.020269) (xy 309.655339 -316.983432)
			(xy 309.629036 -316.941836) (xy 309.609745 -316.89656) (xy 309.597968 -316.848776) (xy 309.594008 -316.799722)
			(xy 308.3052 -316.799722) (xy 308.304705 -316.824329) (xy 308.29681 -316.872906) (xy 308.281226 -316.919587)
			(xy 308.258355 -316.963164) (xy 308.22879 -317.002508) (xy 308.193297 -317.0366) (xy 308.152794 -317.064556)
			(xy 308.108332 -317.085654) (xy 308.061061 -317.099346) (xy 308.012206 -317.105278) (xy 307.963031 -317.103297)
			(xy 307.914812 -317.093453) (xy 307.868796 -317.076001) (xy 307.826175 -317.051394) (xy 307.788054 -317.020269)
			(xy 307.755419 -316.983432) (xy 307.729116 -316.941836) (xy 307.709825 -316.89656) (xy 307.698048 -316.848776)
			(xy 307.694088 -316.799722) (xy 306.405026 -316.799722) (xy 306.404531 -316.824329) (xy 306.396636 -316.872906)
			(xy 306.381052 -316.919587) (xy 306.358181 -316.963164) (xy 306.328616 -317.002508) (xy 306.293123 -317.0366)
			(xy 306.25262 -317.064556) (xy 306.208158 -317.085654) (xy 306.160887 -317.099346) (xy 306.112032 -317.105278)
			(xy 306.062857 -317.103297) (xy 306.014638 -317.093453) (xy 305.968622 -317.076001) (xy 305.926001 -317.051394)
			(xy 305.88788 -317.020269) (xy 305.855245 -316.983432) (xy 305.828942 -316.941836) (xy 305.809651 -316.89656)
			(xy 305.797874 -316.848776) (xy 305.793914 -316.799722) (xy 304.52695 -316.799722) (xy 304.526446 -316.82543)
			(xy 304.518403 -316.876212) (xy 304.502515 -316.925111) (xy 304.479172 -316.970923) (xy 304.448951 -317.012519)
			(xy 304.412595 -317.048875) (xy 304.370999 -317.079096) (xy 304.325187 -317.102439) (xy 304.276288 -317.118327)
			(xy 304.225506 -317.12637) (xy 304.17409 -317.12637) (xy 304.123308 -317.118327) (xy 304.074409 -317.102439)
			(xy 304.028597 -317.079096) (xy 303.987001 -317.048875) (xy 303.950645 -317.012519) (xy 303.920424 -316.970923)
			(xy 303.897081 -316.925111) (xy 303.881193 -316.876212) (xy 303.87315 -316.82543) (xy 302.626526 -316.82543)
			(xy 302.618483 -316.876212) (xy 302.602595 -316.925111) (xy 302.579252 -316.970923) (xy 302.549031 -317.012519)
			(xy 302.512675 -317.048875) (xy 302.471079 -317.079096) (xy 302.425267 -317.102439) (xy 302.376368 -317.118327)
			(xy 302.325586 -317.12637) (xy 302.27417 -317.12637) (xy 302.223388 -317.118327) (xy 302.174489 -317.102439)
			(xy 302.128677 -317.079096) (xy 302.087081 -317.048875) (xy 302.050725 -317.012519) (xy 302.020504 -316.970923)
			(xy 301.997161 -316.925111) (xy 301.981273 -316.876212) (xy 301.97323 -316.82543) (xy 300.726352 -316.82543)
			(xy 300.718309 -316.876212) (xy 300.702421 -316.925111) (xy 300.679078 -316.970923) (xy 300.648857 -317.012519)
			(xy 300.612501 -317.048875) (xy 300.570905 -317.079096) (xy 300.525093 -317.102439) (xy 300.476194 -317.118327)
			(xy 300.425412 -317.12637) (xy 300.373996 -317.12637) (xy 300.323214 -317.118327) (xy 300.274315 -317.102439)
			(xy 300.228503 -317.079096) (xy 300.186907 -317.048875) (xy 300.150551 -317.012519) (xy 300.12033 -316.970923)
			(xy 300.096987 -316.925111) (xy 300.081099 -316.876212) (xy 300.073056 -316.82543) (xy 299.305472 -316.82543)
			(xy 299.305472 -317.274702) (xy 299.305437 -317.28412) (xy 299.304423 -317.302928) (xy 299.30344 -317.312294)
			(xy 299.301916 -317.323724) (xy 299.309536 -317.345568) (xy 299.381926 -317.418212) (xy 299.403516 -317.426086)
			(xy 299.414946 -317.424816) (xy 299.449744 -317.422784) (xy 299.475448 -317.423291) (xy 299.526224 -317.43134)
			(xy 299.575114 -317.447233) (xy 299.620917 -317.470578) (xy 299.662504 -317.500801) (xy 299.698851 -317.537157)
			(xy 299.729064 -317.578751) (xy 299.752398 -317.62456) (xy 299.768278 -317.673454) (xy 299.776315 -317.724231)
			(xy 299.776896 -317.749936) (xy 299.775384 -317.775644) (xy 301.02327 -317.775644) (xy 301.02327 -317.724228)
			(xy 301.031313 -317.673446) (xy 301.047201 -317.624547) (xy 301.070544 -317.578735) (xy 301.100765 -317.537139)
			(xy 301.137121 -317.500783) (xy 301.178717 -317.470562) (xy 301.224529 -317.447219) (xy 301.273428 -317.431331)
			(xy 301.32421 -317.423288) (xy 301.375626 -317.423288) (xy 301.426408 -317.431331) (xy 301.475307 -317.447219)
			(xy 301.521119 -317.470562) (xy 301.562715 -317.500783) (xy 301.599071 -317.537139) (xy 301.629292 -317.578735)
			(xy 301.652635 -317.624547) (xy 301.668523 -317.673446) (xy 301.676566 -317.724228) (xy 301.67707 -317.749936)
			(xy 301.676566 -317.775644) (xy 302.92319 -317.775644) (xy 302.92319 -317.724228) (xy 302.931233 -317.673446)
			(xy 302.947121 -317.624547) (xy 302.970464 -317.578735) (xy 303.000685 -317.537139) (xy 303.037041 -317.500783)
			(xy 303.078637 -317.470562) (xy 303.124449 -317.447219) (xy 303.173348 -317.431331) (xy 303.22413 -317.423288)
			(xy 303.275546 -317.423288) (xy 303.326328 -317.431331) (xy 303.375227 -317.447219) (xy 303.421039 -317.470562)
			(xy 303.462635 -317.500783) (xy 303.498991 -317.537139) (xy 303.529212 -317.578735) (xy 303.552555 -317.624547)
			(xy 303.568443 -317.673446) (xy 303.576486 -317.724228) (xy 303.57699 -317.749936) (xy 303.576486 -317.775644)
			(xy 304.82311 -317.775644) (xy 304.82311 -317.724228) (xy 304.831153 -317.673446) (xy 304.847041 -317.624547)
			(xy 304.870384 -317.578735) (xy 304.900605 -317.537139) (xy 304.936961 -317.500783) (xy 304.978557 -317.470562)
			(xy 305.024369 -317.447219) (xy 305.073268 -317.431331) (xy 305.12405 -317.423288) (xy 305.175466 -317.423288)
			(xy 305.226248 -317.431331) (xy 305.275147 -317.447219) (xy 305.320959 -317.470562) (xy 305.362555 -317.500783)
			(xy 305.398911 -317.537139) (xy 305.429132 -317.578735) (xy 305.452475 -317.624547) (xy 305.468363 -317.673446)
			(xy 305.476406 -317.724228) (xy 305.47691 -317.749936) (xy 306.744128 -317.749936) (xy 306.748088 -317.700882)
			(xy 306.759865 -317.653098) (xy 306.779156 -317.607822) (xy 306.805459 -317.566226) (xy 306.838094 -317.529389)
			(xy 306.876215 -317.498264) (xy 306.918836 -317.473657) (xy 306.964852 -317.456205) (xy 307.013071 -317.446361)
			(xy 307.062246 -317.44438) (xy 307.111101 -317.450312) (xy 307.158372 -317.464004) (xy 307.202834 -317.485102)
			(xy 307.243337 -317.513058) (xy 307.27883 -317.54715) (xy 307.308395 -317.586494) (xy 307.331266 -317.630071)
			(xy 307.34685 -317.676752) (xy 307.354745 -317.725329) (xy 307.35524 -317.749936) (xy 308.644048 -317.749936)
			(xy 308.648008 -317.700882) (xy 308.659785 -317.653098) (xy 308.679076 -317.607822) (xy 308.705379 -317.566226)
			(xy 308.738014 -317.529389) (xy 308.776135 -317.498264) (xy 308.818756 -317.473657) (xy 308.864772 -317.456205)
			(xy 308.912991 -317.446361) (xy 308.962166 -317.44438) (xy 309.011021 -317.450312) (xy 309.058292 -317.464004)
			(xy 309.102754 -317.485102) (xy 309.143257 -317.513058) (xy 309.17875 -317.54715) (xy 309.208315 -317.586494)
			(xy 309.231186 -317.630071) (xy 309.24677 -317.676752) (xy 309.254665 -317.725329) (xy 309.25516 -317.749936)
			(xy 310.543968 -317.749936) (xy 310.547928 -317.700882) (xy 310.559705 -317.653098) (xy 310.578996 -317.607822)
			(xy 310.605299 -317.566226) (xy 310.637934 -317.529389) (xy 310.676055 -317.498264) (xy 310.718676 -317.473657)
			(xy 310.764692 -317.456205) (xy 310.812911 -317.446361) (xy 310.862086 -317.44438) (xy 310.910941 -317.450312)
			(xy 310.958212 -317.464004) (xy 311.002674 -317.485102) (xy 311.043177 -317.513058) (xy 311.07867 -317.54715)
			(xy 311.108235 -317.586494) (xy 311.131106 -317.630071) (xy 311.14669 -317.676752) (xy 311.154585 -317.725329)
			(xy 311.15508 -317.749936) (xy 312.443888 -317.749936) (xy 312.447848 -317.700882) (xy 312.459625 -317.653098)
			(xy 312.478916 -317.607822) (xy 312.505219 -317.566226) (xy 312.537854 -317.529389) (xy 312.575975 -317.498264)
			(xy 312.618596 -317.473657) (xy 312.664612 -317.456205) (xy 312.712831 -317.446361) (xy 312.762006 -317.44438)
			(xy 312.810861 -317.450312) (xy 312.858132 -317.464004) (xy 312.902594 -317.485102) (xy 312.943097 -317.513058)
			(xy 312.97859 -317.54715) (xy 313.008155 -317.586494) (xy 313.031026 -317.630071) (xy 313.04661 -317.676752)
			(xy 313.054505 -317.725329) (xy 313.055 -317.749936) (xy 313.054505 -317.774543) (xy 313.04661 -317.82312)
			(xy 313.031026 -317.869801) (xy 313.008155 -317.913378) (xy 312.97859 -317.952722) (xy 312.943097 -317.986814)
			(xy 312.902594 -318.01477) (xy 312.858132 -318.035868) (xy 312.810861 -318.04956) (xy 312.762006 -318.055492)
			(xy 312.712831 -318.053511) (xy 312.664612 -318.043667) (xy 312.618596 -318.026215) (xy 312.575975 -318.001608)
			(xy 312.537854 -317.970483) (xy 312.505219 -317.933646) (xy 312.478916 -317.89205) (xy 312.459625 -317.846774)
			(xy 312.447848 -317.79899) (xy 312.443888 -317.749936) (xy 311.15508 -317.749936) (xy 311.154585 -317.774543)
			(xy 311.14669 -317.82312) (xy 311.131106 -317.869801) (xy 311.108235 -317.913378) (xy 311.07867 -317.952722)
			(xy 311.043177 -317.986814) (xy 311.002674 -318.01477) (xy 310.958212 -318.035868) (xy 310.910941 -318.04956)
			(xy 310.862086 -318.055492) (xy 310.812911 -318.053511) (xy 310.764692 -318.043667) (xy 310.718676 -318.026215)
			(xy 310.676055 -318.001608) (xy 310.637934 -317.970483) (xy 310.605299 -317.933646) (xy 310.578996 -317.89205)
			(xy 310.559705 -317.846774) (xy 310.547928 -317.79899) (xy 310.543968 -317.749936) (xy 309.25516 -317.749936)
			(xy 309.254665 -317.774543) (xy 309.24677 -317.82312) (xy 309.231186 -317.869801) (xy 309.208315 -317.913378)
			(xy 309.17875 -317.952722) (xy 309.143257 -317.986814) (xy 309.102754 -318.01477) (xy 309.058292 -318.035868)
			(xy 309.011021 -318.04956) (xy 308.962166 -318.055492) (xy 308.912991 -318.053511) (xy 308.864772 -318.043667)
			(xy 308.818756 -318.026215) (xy 308.776135 -318.001608) (xy 308.738014 -317.970483) (xy 308.705379 -317.933646)
			(xy 308.679076 -317.89205) (xy 308.659785 -317.846774) (xy 308.648008 -317.79899) (xy 308.644048 -317.749936)
			(xy 307.35524 -317.749936) (xy 307.354745 -317.774543) (xy 307.34685 -317.82312) (xy 307.331266 -317.869801)
			(xy 307.308395 -317.913378) (xy 307.27883 -317.952722) (xy 307.243337 -317.986814) (xy 307.202834 -318.01477)
			(xy 307.158372 -318.035868) (xy 307.111101 -318.04956) (xy 307.062246 -318.055492) (xy 307.013071 -318.053511)
			(xy 306.964852 -318.043667) (xy 306.918836 -318.026215) (xy 306.876215 -318.001608) (xy 306.838094 -317.970483)
			(xy 306.805459 -317.933646) (xy 306.779156 -317.89205) (xy 306.759865 -317.846774) (xy 306.748088 -317.79899)
			(xy 306.744128 -317.749936) (xy 305.47691 -317.749936) (xy 305.476406 -317.775644) (xy 305.468363 -317.826426)
			(xy 305.452475 -317.875325) (xy 305.429132 -317.921137) (xy 305.398911 -317.962733) (xy 305.362555 -317.999089)
			(xy 305.320959 -318.02931) (xy 305.275147 -318.052653) (xy 305.226248 -318.068541) (xy 305.175466 -318.076584)
			(xy 305.12405 -318.076584) (xy 305.073268 -318.068541) (xy 305.024369 -318.052653) (xy 304.978557 -318.02931)
			(xy 304.936961 -317.999089) (xy 304.900605 -317.962733) (xy 304.870384 -317.921137) (xy 304.847041 -317.875325)
			(xy 304.831153 -317.826426) (xy 304.82311 -317.775644) (xy 303.576486 -317.775644) (xy 303.568443 -317.826426)
			(xy 303.552555 -317.875325) (xy 303.529212 -317.921137) (xy 303.498991 -317.962733) (xy 303.462635 -317.999089)
			(xy 303.421039 -318.02931) (xy 303.375227 -318.052653) (xy 303.326328 -318.068541) (xy 303.275546 -318.076584)
			(xy 303.22413 -318.076584) (xy 303.173348 -318.068541) (xy 303.124449 -318.052653) (xy 303.078637 -318.02931)
			(xy 303.037041 -317.999089) (xy 303.000685 -317.962733) (xy 302.970464 -317.921137) (xy 302.947121 -317.875325)
			(xy 302.931233 -317.826426) (xy 302.92319 -317.775644) (xy 301.676566 -317.775644) (xy 301.668523 -317.826426)
			(xy 301.652635 -317.875325) (xy 301.629292 -317.921137) (xy 301.599071 -317.962733) (xy 301.562715 -317.999089)
			(xy 301.521119 -318.02931) (xy 301.475307 -318.052653) (xy 301.426408 -318.068541) (xy 301.375626 -318.076584)
			(xy 301.32421 -318.076584) (xy 301.273428 -318.068541) (xy 301.224529 -318.052653) (xy 301.178717 -318.02931)
			(xy 301.137121 -317.999089) (xy 301.100765 -317.962733) (xy 301.070544 -317.921137) (xy 301.047201 -317.875325)
			(xy 301.031313 -317.826426) (xy 301.02327 -317.775644) (xy 299.775384 -317.775644) (xy 299.774864 -317.78448)
			(xy 299.773594 -317.796164) (xy 299.781468 -317.817754) (xy 299.854112 -317.890144) (xy 299.875702 -317.897764)
			(xy 299.887386 -317.89624) (xy 299.89669 -317.895271) (xy 299.91537 -317.894253) (xy 299.924724 -317.894208)
			(xy 299.950709 -317.894719) (xy 300.00204 -317.902853) (xy 300.051466 -317.918916) (xy 300.097771 -317.942514)
			(xy 300.139815 -317.973064) (xy 300.176562 -318.009815) (xy 300.207107 -318.051863) (xy 300.230699 -318.098171)
			(xy 300.246756 -318.147599) (xy 300.254884 -318.19893) (xy 300.255432 -318.224916) (xy 300.255432 -318.725604)
			(xy 301.02327 -318.725604) (xy 301.02327 -318.674188) (xy 301.031313 -318.623406) (xy 301.047201 -318.574507)
			(xy 301.070544 -318.528695) (xy 301.100765 -318.487099) (xy 301.137121 -318.450743) (xy 301.178717 -318.420522)
			(xy 301.224529 -318.397179) (xy 301.273428 -318.381291) (xy 301.32421 -318.373248) (xy 301.375626 -318.373248)
			(xy 301.426408 -318.381291) (xy 301.475307 -318.397179) (xy 301.521119 -318.420522) (xy 301.562715 -318.450743)
			(xy 301.599071 -318.487099) (xy 301.629292 -318.528695) (xy 301.652635 -318.574507) (xy 301.668523 -318.623406)
			(xy 301.676566 -318.674188) (xy 301.67707 -318.699896) (xy 301.676566 -318.725604) (xy 302.92319 -318.725604)
			(xy 302.92319 -318.674188) (xy 302.931233 -318.623406) (xy 302.947121 -318.574507) (xy 302.970464 -318.528695)
			(xy 303.000685 -318.487099) (xy 303.037041 -318.450743) (xy 303.078637 -318.420522) (xy 303.124449 -318.397179)
			(xy 303.173348 -318.381291) (xy 303.22413 -318.373248) (xy 303.275546 -318.373248) (xy 303.326328 -318.381291)
			(xy 303.375227 -318.397179) (xy 303.421039 -318.420522) (xy 303.462635 -318.450743) (xy 303.498991 -318.487099)
			(xy 303.529212 -318.528695) (xy 303.552555 -318.574507) (xy 303.568443 -318.623406) (xy 303.576486 -318.674188)
			(xy 303.57699 -318.699896) (xy 303.576486 -318.725604) (xy 304.82311 -318.725604) (xy 304.82311 -318.674188)
			(xy 304.831153 -318.623406) (xy 304.847041 -318.574507) (xy 304.870384 -318.528695) (xy 304.900605 -318.487099)
			(xy 304.936961 -318.450743) (xy 304.978557 -318.420522) (xy 305.024369 -318.397179) (xy 305.073268 -318.381291)
			(xy 305.12405 -318.373248) (xy 305.175466 -318.373248) (xy 305.226248 -318.381291) (xy 305.275147 -318.397179)
			(xy 305.320959 -318.420522) (xy 305.362555 -318.450743) (xy 305.398911 -318.487099) (xy 305.429132 -318.528695)
			(xy 305.452475 -318.574507) (xy 305.468363 -318.623406) (xy 305.476406 -318.674188) (xy 305.47691 -318.699896)
			(xy 306.744128 -318.699896) (xy 306.748088 -318.650842) (xy 306.759865 -318.603058) (xy 306.779156 -318.557782)
			(xy 306.805459 -318.516186) (xy 306.838094 -318.479349) (xy 306.876215 -318.448224) (xy 306.918836 -318.423617)
			(xy 306.964852 -318.406165) (xy 307.013071 -318.396321) (xy 307.062246 -318.39434) (xy 307.111101 -318.400272)
			(xy 307.158372 -318.413964) (xy 307.202834 -318.435062) (xy 307.243337 -318.463018) (xy 307.27883 -318.49711)
			(xy 307.308395 -318.536454) (xy 307.331266 -318.580031) (xy 307.34685 -318.626712) (xy 307.354745 -318.675289)
			(xy 307.35524 -318.699896) (xy 308.644048 -318.699896) (xy 308.648008 -318.650842) (xy 308.659785 -318.603058)
			(xy 308.679076 -318.557782) (xy 308.705379 -318.516186) (xy 308.738014 -318.479349) (xy 308.776135 -318.448224)
			(xy 308.818756 -318.423617) (xy 308.864772 -318.406165) (xy 308.912991 -318.396321) (xy 308.962166 -318.39434)
			(xy 309.011021 -318.400272) (xy 309.058292 -318.413964) (xy 309.102754 -318.435062) (xy 309.143257 -318.463018)
			(xy 309.17875 -318.49711) (xy 309.208315 -318.536454) (xy 309.231186 -318.580031) (xy 309.24677 -318.626712)
			(xy 309.254665 -318.675289) (xy 309.25516 -318.699896) (xy 310.543968 -318.699896) (xy 310.547928 -318.650842)
			(xy 310.559705 -318.603058) (xy 310.578996 -318.557782) (xy 310.605299 -318.516186) (xy 310.637934 -318.479349)
			(xy 310.676055 -318.448224) (xy 310.718676 -318.423617) (xy 310.764692 -318.406165) (xy 310.812911 -318.396321)
			(xy 310.862086 -318.39434) (xy 310.910941 -318.400272) (xy 310.958212 -318.413964) (xy 311.002674 -318.435062)
			(xy 311.043177 -318.463018) (xy 311.07867 -318.49711) (xy 311.108235 -318.536454) (xy 311.131106 -318.580031)
			(xy 311.14669 -318.626712) (xy 311.154585 -318.675289) (xy 311.15508 -318.699896) (xy 312.443888 -318.699896)
			(xy 312.447848 -318.650842) (xy 312.459625 -318.603058) (xy 312.478916 -318.557782) (xy 312.505219 -318.516186)
			(xy 312.537854 -318.479349) (xy 312.575975 -318.448224) (xy 312.618596 -318.423617) (xy 312.664612 -318.406165)
			(xy 312.712831 -318.396321) (xy 312.762006 -318.39434) (xy 312.810861 -318.400272) (xy 312.858132 -318.413964)
			(xy 312.902594 -318.435062) (xy 312.943097 -318.463018) (xy 312.97859 -318.49711) (xy 313.008155 -318.536454)
			(xy 313.031026 -318.580031) (xy 313.04661 -318.626712) (xy 313.054505 -318.675289) (xy 313.055 -318.699896)
			(xy 313.054505 -318.724503) (xy 313.04661 -318.77308) (xy 313.031026 -318.819761) (xy 313.008155 -318.863338)
			(xy 312.97859 -318.902682) (xy 312.943097 -318.936774) (xy 312.902594 -318.96473) (xy 312.858132 -318.985828)
			(xy 312.810861 -318.99952) (xy 312.762006 -319.005452) (xy 312.712831 -319.003471) (xy 312.664612 -318.993627)
			(xy 312.618596 -318.976175) (xy 312.575975 -318.951568) (xy 312.537854 -318.920443) (xy 312.505219 -318.883606)
			(xy 312.478916 -318.84201) (xy 312.459625 -318.796734) (xy 312.447848 -318.74895) (xy 312.443888 -318.699896)
			(xy 311.15508 -318.699896) (xy 311.154585 -318.724503) (xy 311.14669 -318.77308) (xy 311.131106 -318.819761)
			(xy 311.108235 -318.863338) (xy 311.07867 -318.902682) (xy 311.043177 -318.936774) (xy 311.002674 -318.96473)
			(xy 310.958212 -318.985828) (xy 310.910941 -318.99952) (xy 310.862086 -319.005452) (xy 310.812911 -319.003471)
			(xy 310.764692 -318.993627) (xy 310.718676 -318.976175) (xy 310.676055 -318.951568) (xy 310.637934 -318.920443)
			(xy 310.605299 -318.883606) (xy 310.578996 -318.84201) (xy 310.559705 -318.796734) (xy 310.547928 -318.74895)
			(xy 310.543968 -318.699896) (xy 309.25516 -318.699896) (xy 309.254665 -318.724503) (xy 309.24677 -318.77308)
			(xy 309.231186 -318.819761) (xy 309.208315 -318.863338) (xy 309.17875 -318.902682) (xy 309.143257 -318.936774)
			(xy 309.102754 -318.96473) (xy 309.058292 -318.985828) (xy 309.011021 -318.99952) (xy 308.962166 -319.005452)
			(xy 308.912991 -319.003471) (xy 308.864772 -318.993627) (xy 308.818756 -318.976175) (xy 308.776135 -318.951568)
			(xy 308.738014 -318.920443) (xy 308.705379 -318.883606) (xy 308.679076 -318.84201) (xy 308.659785 -318.796734)
			(xy 308.648008 -318.74895) (xy 308.644048 -318.699896) (xy 307.35524 -318.699896) (xy 307.354745 -318.724503)
			(xy 307.34685 -318.77308) (xy 307.331266 -318.819761) (xy 307.308395 -318.863338) (xy 307.27883 -318.902682)
			(xy 307.243337 -318.936774) (xy 307.202834 -318.96473) (xy 307.158372 -318.985828) (xy 307.111101 -318.99952)
			(xy 307.062246 -319.005452) (xy 307.013071 -319.003471) (xy 306.964852 -318.993627) (xy 306.918836 -318.976175)
			(xy 306.876215 -318.951568) (xy 306.838094 -318.920443) (xy 306.805459 -318.883606) (xy 306.779156 -318.84201)
			(xy 306.759865 -318.796734) (xy 306.748088 -318.74895) (xy 306.744128 -318.699896) (xy 305.47691 -318.699896)
			(xy 305.476406 -318.725604) (xy 305.468363 -318.776386) (xy 305.452475 -318.825285) (xy 305.429132 -318.871097)
			(xy 305.398911 -318.912693) (xy 305.362555 -318.949049) (xy 305.320959 -318.97927) (xy 305.275147 -319.002613)
			(xy 305.226248 -319.018501) (xy 305.175466 -319.026544) (xy 305.12405 -319.026544) (xy 305.073268 -319.018501)
			(xy 305.024369 -319.002613) (xy 304.978557 -318.97927) (xy 304.936961 -318.949049) (xy 304.900605 -318.912693)
			(xy 304.870384 -318.871097) (xy 304.847041 -318.825285) (xy 304.831153 -318.776386) (xy 304.82311 -318.725604)
			(xy 303.576486 -318.725604) (xy 303.568443 -318.776386) (xy 303.552555 -318.825285) (xy 303.529212 -318.871097)
			(xy 303.498991 -318.912693) (xy 303.462635 -318.949049) (xy 303.421039 -318.97927) (xy 303.375227 -319.002613)
			(xy 303.326328 -319.018501) (xy 303.275546 -319.026544) (xy 303.22413 -319.026544) (xy 303.173348 -319.018501)
			(xy 303.124449 -319.002613) (xy 303.078637 -318.97927) (xy 303.037041 -318.949049) (xy 303.000685 -318.912693)
			(xy 302.970464 -318.871097) (xy 302.947121 -318.825285) (xy 302.931233 -318.776386) (xy 302.92319 -318.725604)
			(xy 301.676566 -318.725604) (xy 301.668523 -318.776386) (xy 301.652635 -318.825285) (xy 301.629292 -318.871097)
			(xy 301.599071 -318.912693) (xy 301.562715 -318.949049) (xy 301.521119 -318.97927) (xy 301.475307 -319.002613)
			(xy 301.426408 -319.018501) (xy 301.375626 -319.026544) (xy 301.32421 -319.026544) (xy 301.273428 -319.018501)
			(xy 301.224529 -319.002613) (xy 301.178717 -318.97927) (xy 301.137121 -318.949049) (xy 301.100765 -318.912693)
			(xy 301.070544 -318.871097) (xy 301.047201 -318.825285) (xy 301.031313 -318.776386) (xy 301.02327 -318.725604)
			(xy 300.255432 -318.725604) (xy 300.255432 -319.175384) (xy 300.255022 -319.198368) (xy 300.248617 -319.243888)
			(xy 300.235957 -319.288078) (xy 300.226984 -319.309242) (xy 300.222666 -319.318894) (xy 300.222412 -319.339976)
			(xy 300.255686 -319.417954) (xy 300.260252 -319.427407) (xy 300.275467 -319.441838) (xy 300.28515 -319.445894)
			(xy 300.31563 -319.45707) (xy 300.32325 -319.457324) (xy 300.365986 -319.459761) (xy 300.450836 -319.471105)
			(xy 300.534387 -319.489745) (xy 300.616013 -319.515543) (xy 300.655736 -319.531492) (xy 301.645828 -319.941448)
			(xy 301.64786 -319.942464) (xy 304.276366 -320.900044) (xy 319.082429 -320.900044) (xy 319.086418 -320.751504)
			(xy 319.098375 -320.603391) (xy 319.118265 -320.456134) (xy 319.14603 -320.310158) (xy 319.181591 -320.165881)
			(xy 319.224845 -320.023722) (xy 319.275667 -319.884089) (xy 319.333911 -319.747386) (xy 319.399409 -319.614006)
			(xy 319.471972 -319.484334) (xy 319.55139 -319.358744) (xy 319.637435 -319.237597) (xy 319.729859 -319.121244)
			(xy 319.828395 -319.01002) (xy 319.932759 -318.904245) (xy 320.042651 -318.804225) (xy 320.157752 -318.710247)
			(xy 320.277732 -318.622583) (xy 320.402245 -318.541486) (xy 320.530931 -318.467189) (xy 320.66342 -318.399907)
			(xy 320.799329 -318.339833) (xy 320.938267 -318.287141) (xy 321.079833 -318.241982) (xy 321.223619 -318.204487)
			(xy 321.36921 -318.174765) (xy 321.516186 -318.1529) (xy 321.664125 -318.138956) (xy 321.812598 -318.132972)
			(xy 321.961179 -318.134967) (xy 322.109438 -318.144935) (xy 322.256949 -318.162846) (xy 322.403285 -318.188649)
			(xy 322.548026 -318.222269) (xy 322.690753 -318.263611) (xy 322.831056 -318.312554) (xy 322.968529 -318.368957)
			(xy 323.102776 -318.432658) (xy 323.233411 -318.503474) (xy 323.360056 -318.581199) (xy 323.482346 -318.66561)
			(xy 323.599929 -318.756463) (xy 323.712466 -318.853497) (xy 323.819633 -318.956432) (xy 323.92112 -319.064971)
			(xy 324.016634 -319.1788) (xy 324.105901 -319.297593) (xy 324.188662 -319.421005) (xy 324.26468 -319.548683)
			(xy 324.333735 -319.680256) (xy 324.395628 -319.815347) (xy 324.450181 -319.953564) (xy 324.492605 -320.08064)
			(xy 338.422996 -320.08064) (xy 338.423507 -320.051722) (xy 338.432232 -319.994549) (xy 338.449489 -319.939349)
			(xy 338.474882 -319.887386) (xy 338.507829 -319.839853) (xy 338.547574 -319.797838) (xy 338.570062 -319.77965)
			(xy 338.578807 -319.772073) (xy 338.588997 -319.751325) (xy 338.58962 -319.739772) (xy 338.58962 -319.659508)
			(xy 338.589038 -319.647942) (xy 338.578851 -319.627171) (xy 338.570062 -319.61963) (xy 338.547585 -319.601432)
			(xy 338.507851 -319.559412) (xy 338.474912 -319.511879) (xy 338.449523 -319.459919) (xy 338.432265 -319.404723)
			(xy 338.423533 -319.347555) (xy 338.422996 -319.31864) (xy 338.423493 -319.291388) (xy 338.431244 -319.237438)
			(xy 338.446595 -319.185141) (xy 338.469233 -319.13556) (xy 338.498698 -319.089707) (xy 338.534388 -319.048514)
			(xy 338.575578 -319.012819) (xy 338.621429 -318.983351) (xy 338.671007 -318.960708) (xy 338.723303 -318.945352)
			(xy 338.777252 -318.937595) (xy 338.804504 -318.937132) (xy 338.833422 -318.937635) (xy 338.890594 -318.946366)
			(xy 338.945794 -318.963626) (xy 338.997756 -318.98902) (xy 339.045289 -319.021967) (xy 339.087305 -319.061711)
			(xy 339.105494 -319.084198) (xy 339.113063 -319.092952) (xy 339.133816 -319.10314) (xy 339.145372 -319.103756)
			(xy 339.225636 -319.103756) (xy 339.237201 -319.103164) (xy 339.257974 -319.092986) (xy 339.265514 -319.084198)
			(xy 339.282267 -319.063415) (xy 339.320621 -319.026285) (xy 339.363775 -318.994863) (xy 339.410889 -318.969764)
			(xy 339.461041 -318.951478) (xy 339.513252 -318.940361) (xy 339.566504 -318.936631) (xy 339.619756 -318.940361)
			(xy 339.671967 -318.951478) (xy 339.722119 -318.969764) (xy 339.769233 -318.994863) (xy 339.812387 -319.026285)
			(xy 339.850741 -319.063415) (xy 339.867494 -319.084198) (xy 339.875063 -319.092952) (xy 339.895816 -319.10314)
			(xy 339.907372 -319.103756) (xy 339.987636 -319.103756) (xy 339.999201 -319.103164) (xy 340.019974 -319.092986)
			(xy 340.027514 -319.084198) (xy 340.044267 -319.063415) (xy 340.082621 -319.026285) (xy 340.125775 -318.994863)
			(xy 340.172889 -318.969764) (xy 340.223041 -318.951478) (xy 340.275252 -318.940361) (xy 340.328504 -318.936631)
			(xy 340.381756 -318.940361) (xy 340.433967 -318.951478) (xy 340.484119 -318.969764) (xy 340.531233 -318.994863)
			(xy 340.574387 -319.026285) (xy 340.612741 -319.063415) (xy 340.629494 -319.084198) (xy 340.637063 -319.092952)
			(xy 340.657816 -319.10314) (xy 340.669372 -319.103756) (xy 340.749636 -319.103756) (xy 340.761201 -319.103164)
			(xy 340.781974 -319.092986) (xy 340.789514 -319.084198) (xy 340.806267 -319.063415) (xy 340.844621 -319.026285)
			(xy 340.887775 -318.994863) (xy 340.934889 -318.969764) (xy 340.985041 -318.951478) (xy 341.037252 -318.940361)
			(xy 341.090504 -318.936631) (xy 341.143756 -318.940361) (xy 341.195967 -318.951478) (xy 341.246119 -318.969764)
			(xy 341.293233 -318.994863) (xy 341.336387 -319.026285) (xy 341.374741 -319.063415) (xy 341.391494 -319.084198)
			(xy 341.399063 -319.092952) (xy 341.419816 -319.10314) (xy 341.431372 -319.103756) (xy 341.511636 -319.103756)
			(xy 341.523201 -319.103164) (xy 341.543974 -319.092986) (xy 341.551514 -319.084198) (xy 341.568267 -319.063415)
			(xy 341.606621 -319.026285) (xy 341.649775 -318.994863) (xy 341.696889 -318.969764) (xy 341.747041 -318.951478)
			(xy 341.799252 -318.940361) (xy 341.852504 -318.936631) (xy 341.905756 -318.940361) (xy 341.957967 -318.951478)
			(xy 342.008119 -318.969764) (xy 342.055233 -318.994863) (xy 342.098387 -319.026285) (xy 342.136741 -319.063415)
			(xy 342.153494 -319.084198) (xy 342.161063 -319.092952) (xy 342.181816 -319.10314) (xy 342.193372 -319.103756)
			(xy 342.273636 -319.103756) (xy 342.285201 -319.103164) (xy 342.305974 -319.092986) (xy 342.313514 -319.084198)
			(xy 342.330267 -319.063415) (xy 342.368621 -319.026285) (xy 342.411775 -318.994863) (xy 342.458889 -318.969764)
			(xy 342.509041 -318.951478) (xy 342.561252 -318.940361) (xy 342.614504 -318.936631) (xy 342.667756 -318.940361)
			(xy 342.719967 -318.951478) (xy 342.770119 -318.969764) (xy 342.817233 -318.994863) (xy 342.860387 -319.026285)
			(xy 342.898741 -319.063415) (xy 342.915494 -319.084198) (xy 342.923063 -319.092952) (xy 342.943816 -319.10314)
			(xy 342.955372 -319.103756) (xy 343.035636 -319.103756) (xy 343.047201 -319.103164) (xy 343.067974 -319.092986)
			(xy 343.075514 -319.084198) (xy 343.092267 -319.063415) (xy 343.130621 -319.026285) (xy 343.173775 -318.994863)
			(xy 343.220889 -318.969764) (xy 343.271041 -318.951478) (xy 343.323252 -318.940361) (xy 343.376504 -318.936631)
			(xy 343.429756 -318.940361) (xy 343.481967 -318.951478) (xy 343.532119 -318.969764) (xy 343.579233 -318.994863)
			(xy 343.622387 -319.026285) (xy 343.660741 -319.063415) (xy 343.677494 -319.084198) (xy 343.685063 -319.092952)
			(xy 343.705816 -319.10314) (xy 343.717372 -319.103756) (xy 343.797636 -319.103756) (xy 343.809201 -319.103164)
			(xy 343.829974 -319.092986) (xy 343.837514 -319.084198) (xy 343.854267 -319.063415) (xy 343.892621 -319.026285)
			(xy 343.935775 -318.994863) (xy 343.982889 -318.969764) (xy 344.033041 -318.951478) (xy 344.085252 -318.940361)
			(xy 344.138504 -318.936631) (xy 344.191756 -318.940361) (xy 344.243967 -318.951478) (xy 344.294119 -318.969764)
			(xy 344.341233 -318.994863) (xy 344.384387 -319.026285) (xy 344.422741 -319.063415) (xy 344.439494 -319.084198)
			(xy 344.447063 -319.092952) (xy 344.467816 -319.10314) (xy 344.479372 -319.103756) (xy 344.559636 -319.103756)
			(xy 344.571201 -319.103164) (xy 344.591974 -319.092986) (xy 344.599514 -319.084198) (xy 344.616267 -319.063415)
			(xy 344.654621 -319.026285) (xy 344.697775 -318.994863) (xy 344.744889 -318.969764) (xy 344.795041 -318.951478)
			(xy 344.847252 -318.940361) (xy 344.900504 -318.936631) (xy 344.953756 -318.940361) (xy 345.005967 -318.951478)
			(xy 345.056119 -318.969764) (xy 345.103233 -318.994863) (xy 345.146387 -319.026285) (xy 345.184741 -319.063415)
			(xy 345.201494 -319.084198) (xy 345.209063 -319.092952) (xy 345.229816 -319.10314) (xy 345.241372 -319.103756)
			(xy 345.321636 -319.103756) (xy 345.333201 -319.103164) (xy 345.353974 -319.092986) (xy 345.361514 -319.084198)
			(xy 345.378267 -319.063415) (xy 345.416621 -319.026285) (xy 345.459775 -318.994863) (xy 345.506889 -318.969764)
			(xy 345.557041 -318.951478) (xy 345.609252 -318.940361) (xy 345.662504 -318.936631) (xy 345.715756 -318.940361)
			(xy 345.767967 -318.951478) (xy 345.818119 -318.969764) (xy 345.865233 -318.994863) (xy 345.908387 -319.026285)
			(xy 345.946741 -319.063415) (xy 345.963494 -319.084198) (xy 345.971063 -319.092952) (xy 345.991816 -319.10314)
			(xy 346.003372 -319.103756) (xy 346.083636 -319.103756) (xy 346.095201 -319.103164) (xy 346.115974 -319.092986)
			(xy 346.123514 -319.084198) (xy 346.140267 -319.063415) (xy 346.178621 -319.026285) (xy 346.221775 -318.994863)
			(xy 346.268889 -318.969764) (xy 346.319041 -318.951478) (xy 346.371252 -318.940361) (xy 346.424504 -318.936631)
			(xy 346.477756 -318.940361) (xy 346.529967 -318.951478) (xy 346.580119 -318.969764) (xy 346.627233 -318.994863)
			(xy 346.670387 -319.026285) (xy 346.708741 -319.063415) (xy 346.725494 -319.084198) (xy 346.733063 -319.092952)
			(xy 346.753816 -319.10314) (xy 346.765372 -319.103756) (xy 346.845636 -319.103756) (xy 346.857201 -319.103164)
			(xy 346.877974 -319.092986) (xy 346.885514 -319.084198) (xy 346.903697 -319.061707) (xy 346.945718 -319.021973)
			(xy 346.993255 -318.989035) (xy 347.045218 -318.963647) (xy 347.100417 -318.946393) (xy 347.157588 -318.937666)
			(xy 347.186504 -318.937132) (xy 347.213759 -318.937552) (xy 347.267713 -318.94531) (xy 347.320014 -318.960669)
			(xy 347.369597 -318.983315) (xy 347.415452 -319.012787) (xy 347.456646 -319.048485) (xy 347.49234 -319.089683)
			(xy 347.521806 -319.135541) (xy 347.544447 -319.185127) (xy 347.559799 -319.23743) (xy 347.567551 -319.291385)
			(xy 347.568012 -319.31864) (xy 347.567484 -319.347557) (xy 347.558761 -319.404729) (xy 347.541508 -319.459929)
			(xy 347.516118 -319.511892) (xy 347.483174 -319.559426) (xy 347.443432 -319.601441) (xy 347.420946 -319.61963)
			(xy 347.412166 -319.627174) (xy 347.401994 -319.647947) (xy 347.401388 -319.659508) (xy 347.401388 -319.739772)
			(xy 347.401979 -319.751337) (xy 347.41216 -319.772108) (xy 347.420946 -319.77965) (xy 347.443415 -319.797858)
			(xy 347.483149 -319.839875) (xy 347.516088 -319.887407) (xy 347.541479 -319.939365) (xy 347.558739 -319.994559)
			(xy 347.567474 -320.051725) (xy 347.568012 -320.08064) (xy 351.617026 -320.08064) (xy 351.617563 -320.051724)
			(xy 351.626287 -319.994553) (xy 351.64354 -319.939354) (xy 351.668928 -319.887392) (xy 351.701869 -319.839858)
			(xy 351.741608 -319.79784) (xy 351.764092 -319.77965) (xy 351.772826 -319.772061) (xy 351.783025 -319.751323)
			(xy 351.78365 -319.739772) (xy 351.78365 -319.659508) (xy 351.783092 -319.647938) (xy 351.772891 -319.627166)
			(xy 351.764092 -319.61963) (xy 351.741621 -319.601424) (xy 351.701886 -319.559407) (xy 351.668945 -319.511875)
			(xy 351.643555 -319.459917) (xy 351.626296 -319.404722) (xy 351.617563 -319.347555) (xy 351.617026 -319.31864)
			(xy 351.617493 -319.291387) (xy 351.625245 -319.237434) (xy 351.640598 -319.185134) (xy 351.663238 -319.135552)
			(xy 351.692705 -319.089697) (xy 351.728399 -319.048503) (xy 351.769592 -319.012809) (xy 351.815447 -318.983341)
			(xy 351.865028 -318.9607) (xy 351.917328 -318.945346) (xy 351.971281 -318.937593) (xy 351.998534 -318.937132)
			(xy 352.02745 -318.937685) (xy 352.08462 -318.946405) (xy 352.139819 -318.963656) (xy 352.191781 -318.989041)
			(xy 352.239315 -319.021979) (xy 352.281333 -319.061715) (xy 352.299524 -319.084198) (xy 352.30708 -319.092966)
			(xy 352.327843 -319.103146) (xy 352.339402 -319.103756) (xy 352.419666 -319.103756) (xy 352.431234 -319.103181)
			(xy 352.452006 -319.092991) (xy 352.459544 -319.084198) (xy 352.476297 -319.063415) (xy 352.514651 -319.026285)
			(xy 352.557805 -318.994863) (xy 352.604919 -318.969764) (xy 352.655071 -318.951478) (xy 352.707282 -318.940361)
			(xy 352.760534 -318.936631) (xy 352.813786 -318.940361) (xy 352.865997 -318.951478) (xy 352.916149 -318.969764)
			(xy 352.963263 -318.994863) (xy 353.006417 -319.026285) (xy 353.044771 -319.063415) (xy 353.061524 -319.084198)
			(xy 353.06908 -319.092966) (xy 353.089843 -319.103146) (xy 353.101402 -319.103756) (xy 353.181666 -319.103756)
			(xy 353.193234 -319.103181) (xy 353.214006 -319.092991) (xy 353.221544 -319.084198) (xy 353.238297 -319.063415)
			(xy 353.276651 -319.026285) (xy 353.319805 -318.994863) (xy 353.366919 -318.969764) (xy 353.417071 -318.951478)
			(xy 353.469282 -318.940361) (xy 353.522534 -318.936631) (xy 353.575786 -318.940361) (xy 353.627997 -318.951478)
			(xy 353.678149 -318.969764) (xy 353.725263 -318.994863) (xy 353.768417 -319.026285) (xy 353.806771 -319.063415)
			(xy 353.823524 -319.084198) (xy 353.83108 -319.092966) (xy 353.851843 -319.103146) (xy 353.863402 -319.103756)
			(xy 353.943666 -319.103756) (xy 353.955234 -319.103181) (xy 353.976006 -319.092991) (xy 353.983544 -319.084198)
			(xy 354.000297 -319.063415) (xy 354.038651 -319.026285) (xy 354.081805 -318.994863) (xy 354.128919 -318.969764)
			(xy 354.179071 -318.951478) (xy 354.231282 -318.940361) (xy 354.284534 -318.936631) (xy 354.337786 -318.940361)
			(xy 354.389997 -318.951478) (xy 354.440149 -318.969764) (xy 354.487263 -318.994863) (xy 354.530417 -319.026285)
			(xy 354.568771 -319.063415) (xy 354.585524 -319.084198) (xy 354.59308 -319.092966) (xy 354.613843 -319.103146)
			(xy 354.625402 -319.103756) (xy 354.705666 -319.103756) (xy 354.717234 -319.103181) (xy 354.738006 -319.092991)
			(xy 354.745544 -319.084198) (xy 354.762297 -319.063415) (xy 354.800651 -319.026285) (xy 354.843805 -318.994863)
			(xy 354.890919 -318.969764) (xy 354.941071 -318.951478) (xy 354.993282 -318.940361) (xy 355.046534 -318.936631)
			(xy 355.099786 -318.940361) (xy 355.151997 -318.951478) (xy 355.202149 -318.969764) (xy 355.249263 -318.994863)
			(xy 355.292417 -319.026285) (xy 355.330771 -319.063415) (xy 355.347524 -319.084198) (xy 355.35508 -319.092966)
			(xy 355.375843 -319.103146) (xy 355.387402 -319.103756) (xy 355.467666 -319.103756) (xy 355.479234 -319.103181)
			(xy 355.500006 -319.092991) (xy 355.507544 -319.084198) (xy 355.524297 -319.063415) (xy 355.562651 -319.026285)
			(xy 355.605805 -318.994863) (xy 355.652919 -318.969764) (xy 355.703071 -318.951478) (xy 355.755282 -318.940361)
			(xy 355.808534 -318.936631) (xy 355.861786 -318.940361) (xy 355.913997 -318.951478) (xy 355.964149 -318.969764)
			(xy 356.011263 -318.994863) (xy 356.054417 -319.026285) (xy 356.092771 -319.063415) (xy 356.109524 -319.084198)
			(xy 356.11708 -319.092966) (xy 356.137843 -319.103146) (xy 356.149402 -319.103756) (xy 356.229666 -319.103756)
			(xy 356.241234 -319.103181) (xy 356.262006 -319.092991) (xy 356.269544 -319.084198) (xy 356.286297 -319.063415)
			(xy 356.324651 -319.026285) (xy 356.367805 -318.994863) (xy 356.414919 -318.969764) (xy 356.465071 -318.951478)
			(xy 356.517282 -318.940361) (xy 356.570534 -318.936631) (xy 356.623786 -318.940361) (xy 356.675997 -318.951478)
			(xy 356.726149 -318.969764) (xy 356.773263 -318.994863) (xy 356.816417 -319.026285) (xy 356.854771 -319.063415)
			(xy 356.871524 -319.084198) (xy 356.87908 -319.092966) (xy 356.899843 -319.103146) (xy 356.911402 -319.103756)
			(xy 356.991666 -319.103756) (xy 357.003234 -319.103181) (xy 357.024006 -319.092991) (xy 357.031544 -319.084198)
			(xy 357.048297 -319.063415) (xy 357.086651 -319.026285) (xy 357.129805 -318.994863) (xy 357.176919 -318.969764)
			(xy 357.227071 -318.951478) (xy 357.279282 -318.940361) (xy 357.332534 -318.936631) (xy 357.385786 -318.940361)
			(xy 357.437997 -318.951478) (xy 357.488149 -318.969764) (xy 357.535263 -318.994863) (xy 357.578417 -319.026285)
			(xy 357.616771 -319.063415) (xy 357.633524 -319.084198) (xy 357.64108 -319.092966) (xy 357.661843 -319.103146)
			(xy 357.673402 -319.103756) (xy 357.753666 -319.103756) (xy 357.765234 -319.103181) (xy 357.786006 -319.092991)
			(xy 357.793544 -319.084198) (xy 357.810297 -319.063415) (xy 357.848651 -319.026285) (xy 357.891805 -318.994863)
			(xy 357.938919 -318.969764) (xy 357.989071 -318.951478) (xy 358.041282 -318.940361) (xy 358.094534 -318.936631)
			(xy 358.147786 -318.940361) (xy 358.199997 -318.951478) (xy 358.250149 -318.969764) (xy 358.297263 -318.994863)
			(xy 358.340417 -319.026285) (xy 358.378771 -319.063415) (xy 358.395524 -319.084198) (xy 358.40308 -319.092966)
			(xy 358.423843 -319.103146) (xy 358.435402 -319.103756) (xy 358.515666 -319.103756) (xy 358.527234 -319.103181)
			(xy 358.548006 -319.092991) (xy 358.555544 -319.084198) (xy 358.572297 -319.063415) (xy 358.610651 -319.026285)
			(xy 358.653805 -318.994863) (xy 358.700919 -318.969764) (xy 358.751071 -318.951478) (xy 358.803282 -318.940361)
			(xy 358.856534 -318.936631) (xy 358.909786 -318.940361) (xy 358.961997 -318.951478) (xy 359.012149 -318.969764)
			(xy 359.059263 -318.994863) (xy 359.102417 -319.026285) (xy 359.140771 -319.063415) (xy 359.157524 -319.084198)
			(xy 359.16508 -319.092966) (xy 359.185843 -319.103146) (xy 359.197402 -319.103756) (xy 359.277666 -319.103756)
			(xy 359.289234 -319.103181) (xy 359.310006 -319.092991) (xy 359.317544 -319.084198) (xy 359.334297 -319.063415)
			(xy 359.372651 -319.026285) (xy 359.415805 -318.994863) (xy 359.462919 -318.969764) (xy 359.513071 -318.951478)
			(xy 359.565282 -318.940361) (xy 359.618534 -318.936631) (xy 359.671786 -318.940361) (xy 359.723997 -318.951478)
			(xy 359.774149 -318.969764) (xy 359.821263 -318.994863) (xy 359.864417 -319.026285) (xy 359.902771 -319.063415)
			(xy 359.919524 -319.084198) (xy 359.92708 -319.092966) (xy 359.947843 -319.103146) (xy 359.959402 -319.103756)
			(xy 360.039666 -319.103756) (xy 360.051234 -319.103181) (xy 360.072006 -319.092991) (xy 360.079544 -319.084198)
			(xy 360.096297 -319.063415) (xy 360.134651 -319.026285) (xy 360.177805 -318.994863) (xy 360.224919 -318.969764)
			(xy 360.275071 -318.951478) (xy 360.327282 -318.940361) (xy 360.380534 -318.936631) (xy 360.433786 -318.940361)
			(xy 360.485997 -318.951478) (xy 360.536149 -318.969764) (xy 360.583263 -318.994863) (xy 360.626417 -319.026285)
			(xy 360.664771 -319.063415) (xy 360.681524 -319.084198) (xy 360.68908 -319.092966) (xy 360.709843 -319.103146)
			(xy 360.721402 -319.103756) (xy 360.801666 -319.103756) (xy 360.813234 -319.103181) (xy 360.834006 -319.092991)
			(xy 360.841544 -319.084198) (xy 360.85971 -319.061693) (xy 360.901735 -319.021959) (xy 360.949275 -318.989023)
			(xy 361.001241 -318.963638) (xy 361.056443 -318.946387) (xy 361.113617 -318.937664) (xy 361.142534 -318.937132)
			(xy 361.16979 -318.937523) (xy 361.223745 -318.945286) (xy 361.276047 -318.960648) (xy 361.32563 -318.983298)
			(xy 361.371485 -319.012773) (xy 361.412678 -319.048474) (xy 361.448371 -319.089675) (xy 361.477838 -319.135535)
			(xy 361.500478 -319.185123) (xy 361.51583 -319.237427) (xy 361.523582 -319.291384) (xy 361.524042 -319.31864)
			(xy 361.523502 -319.347556) (xy 361.514781 -319.404728) (xy 361.497528 -319.459927) (xy 361.472141 -319.511889)
			(xy 361.4392 -319.559423) (xy 361.399461 -319.60144) (xy 361.376976 -319.61963) (xy 361.368201 -319.627179)
			(xy 361.358026 -319.647948) (xy 361.357418 -319.659508) (xy 361.357418 -319.739772) (xy 361.357998 -319.751339)
			(xy 361.368185 -319.77211) (xy 361.376976 -319.77965) (xy 361.399431 -319.797875) (xy 361.439169 -319.839887)
			(xy 361.472112 -319.887415) (xy 361.497505 -319.939369) (xy 361.514768 -319.994561) (xy 361.523503 -320.051726)
			(xy 361.524042 -320.08064) (xy 361.52356 -320.107891) (xy 361.515798 -320.161837) (xy 361.50044 -320.214129)
			(xy 361.477797 -320.263705) (xy 361.448329 -320.309553) (xy 361.412638 -320.350742) (xy 361.371448 -320.386433)
			(xy 361.325599 -320.4159) (xy 361.276024 -320.438542) (xy 361.223731 -320.4539) (xy 361.169785 -320.46166)
			(xy 361.142534 -320.462148) (xy 361.113617 -320.461625) (xy 361.056445 -320.4529) (xy 361.001246 -320.435644)
			(xy 360.949283 -320.410253) (xy 360.901749 -320.37731) (xy 360.859733 -320.337568) (xy 360.841544 -320.315082)
			(xy 360.833962 -320.306341) (xy 360.813218 -320.296147) (xy 360.801666 -320.295524) (xy 360.721402 -320.295524)
			(xy 360.709833 -320.296087) (xy 360.689062 -320.306286) (xy 360.681524 -320.315082) (xy 360.664771 -320.335865)
			(xy 360.626417 -320.372995) (xy 360.583263 -320.404417) (xy 360.536149 -320.429516) (xy 360.485997 -320.447802)
			(xy 360.433786 -320.458919) (xy 360.380534 -320.462649) (xy 360.327282 -320.458919) (xy 360.275071 -320.447802)
			(xy 360.224919 -320.429516) (xy 360.177805 -320.404417) (xy 360.134651 -320.372995) (xy 360.096297 -320.335865)
			(xy 360.079544 -320.315082) (xy 360.071962 -320.306341) (xy 360.051218 -320.296147) (xy 360.039666 -320.295524)
			(xy 359.959402 -320.295524) (xy 359.947833 -320.296087) (xy 359.927062 -320.306286) (xy 359.919524 -320.315082)
			(xy 359.902771 -320.335865) (xy 359.864417 -320.372995) (xy 359.821263 -320.404417) (xy 359.774149 -320.429516)
			(xy 359.723997 -320.447802) (xy 359.671786 -320.458919) (xy 359.618534 -320.462649) (xy 359.565282 -320.458919)
			(xy 359.513071 -320.447802) (xy 359.462919 -320.429516) (xy 359.415805 -320.404417) (xy 359.372651 -320.372995)
			(xy 359.334297 -320.335865) (xy 359.317544 -320.315082) (xy 359.309962 -320.306341) (xy 359.289218 -320.296147)
			(xy 359.277666 -320.295524) (xy 359.197402 -320.295524) (xy 359.185833 -320.296087) (xy 359.165062 -320.306286)
			(xy 359.157524 -320.315082) (xy 359.140771 -320.335865) (xy 359.102417 -320.372995) (xy 359.059263 -320.404417)
			(xy 359.012149 -320.429516) (xy 358.961997 -320.447802) (xy 358.909786 -320.458919) (xy 358.856534 -320.462649)
			(xy 358.803282 -320.458919) (xy 358.751071 -320.447802) (xy 358.700919 -320.429516) (xy 358.653805 -320.404417)
			(xy 358.610651 -320.372995) (xy 358.572297 -320.335865) (xy 358.555544 -320.315082) (xy 358.547962 -320.306341)
			(xy 358.527218 -320.296147) (xy 358.515666 -320.295524) (xy 358.435402 -320.295524) (xy 358.423833 -320.296087)
			(xy 358.403062 -320.306286) (xy 358.395524 -320.315082) (xy 358.378771 -320.335865) (xy 358.340417 -320.372995)
			(xy 358.297263 -320.404417) (xy 358.250149 -320.429516) (xy 358.199997 -320.447802) (xy 358.147786 -320.458919)
			(xy 358.094534 -320.462649) (xy 358.041282 -320.458919) (xy 357.989071 -320.447802) (xy 357.938919 -320.429516)
			(xy 357.891805 -320.404417) (xy 357.848651 -320.372995) (xy 357.810297 -320.335865) (xy 357.793544 -320.315082)
			(xy 357.785962 -320.306341) (xy 357.765218 -320.296147) (xy 357.753666 -320.295524) (xy 357.673402 -320.295524)
			(xy 357.661833 -320.296087) (xy 357.641062 -320.306286) (xy 357.633524 -320.315082) (xy 357.616771 -320.335865)
			(xy 357.578417 -320.372995) (xy 357.535263 -320.404417) (xy 357.488149 -320.429516) (xy 357.437997 -320.447802)
			(xy 357.385786 -320.458919) (xy 357.332534 -320.462649) (xy 357.279282 -320.458919) (xy 357.227071 -320.447802)
			(xy 357.176919 -320.429516) (xy 357.129805 -320.404417) (xy 357.086651 -320.372995) (xy 357.048297 -320.335865)
			(xy 357.031544 -320.315082) (xy 357.023962 -320.306341) (xy 357.003218 -320.296147) (xy 356.991666 -320.295524)
			(xy 356.911402 -320.295524) (xy 356.899833 -320.296087) (xy 356.879062 -320.306286) (xy 356.871524 -320.315082)
			(xy 356.854771 -320.335865) (xy 356.816417 -320.372995) (xy 356.773263 -320.404417) (xy 356.726149 -320.429516)
			(xy 356.675997 -320.447802) (xy 356.623786 -320.458919) (xy 356.570534 -320.462649) (xy 356.517282 -320.458919)
			(xy 356.465071 -320.447802) (xy 356.414919 -320.429516) (xy 356.367805 -320.404417) (xy 356.324651 -320.372995)
			(xy 356.286297 -320.335865) (xy 356.269544 -320.315082) (xy 356.261962 -320.306341) (xy 356.241218 -320.296147)
			(xy 356.229666 -320.295524) (xy 356.149402 -320.295524) (xy 356.137833 -320.296087) (xy 356.117062 -320.306286)
			(xy 356.109524 -320.315082) (xy 356.092771 -320.335865) (xy 356.054417 -320.372995) (xy 356.011263 -320.404417)
			(xy 355.964149 -320.429516) (xy 355.913997 -320.447802) (xy 355.861786 -320.458919) (xy 355.808534 -320.462649)
			(xy 355.755282 -320.458919) (xy 355.703071 -320.447802) (xy 355.652919 -320.429516) (xy 355.605805 -320.404417)
			(xy 355.562651 -320.372995) (xy 355.524297 -320.335865) (xy 355.507544 -320.315082) (xy 355.499962 -320.306341)
			(xy 355.479218 -320.296147) (xy 355.467666 -320.295524) (xy 355.387402 -320.295524) (xy 355.375833 -320.296087)
			(xy 355.355062 -320.306286) (xy 355.347524 -320.315082) (xy 355.330771 -320.335865) (xy 355.292417 -320.372995)
			(xy 355.249263 -320.404417) (xy 355.202149 -320.429516) (xy 355.151997 -320.447802) (xy 355.099786 -320.458919)
			(xy 355.046534 -320.462649) (xy 354.993282 -320.458919) (xy 354.941071 -320.447802) (xy 354.890919 -320.429516)
			(xy 354.843805 -320.404417) (xy 354.800651 -320.372995) (xy 354.762297 -320.335865) (xy 354.745544 -320.315082)
			(xy 354.737962 -320.306341) (xy 354.717218 -320.296147) (xy 354.705666 -320.295524) (xy 354.625402 -320.295524)
			(xy 354.613833 -320.296087) (xy 354.593062 -320.306286) (xy 354.585524 -320.315082) (xy 354.568771 -320.335865)
			(xy 354.530417 -320.372995) (xy 354.487263 -320.404417) (xy 354.440149 -320.429516) (xy 354.389997 -320.447802)
			(xy 354.337786 -320.458919) (xy 354.284534 -320.462649) (xy 354.231282 -320.458919) (xy 354.179071 -320.447802)
			(xy 354.128919 -320.429516) (xy 354.081805 -320.404417) (xy 354.038651 -320.372995) (xy 354.000297 -320.335865)
			(xy 353.983544 -320.315082) (xy 353.975962 -320.306341) (xy 353.955218 -320.296147) (xy 353.943666 -320.295524)
			(xy 353.863402 -320.295524) (xy 353.851833 -320.296087) (xy 353.831062 -320.306286) (xy 353.823524 -320.315082)
			(xy 353.806771 -320.335865) (xy 353.768417 -320.372995) (xy 353.725263 -320.404417) (xy 353.678149 -320.429516)
			(xy 353.627997 -320.447802) (xy 353.575786 -320.458919) (xy 353.522534 -320.462649) (xy 353.469282 -320.458919)
			(xy 353.417071 -320.447802) (xy 353.366919 -320.429516) (xy 353.319805 -320.404417) (xy 353.276651 -320.372995)
			(xy 353.238297 -320.335865) (xy 353.221544 -320.315082) (xy 353.213962 -320.306341) (xy 353.193218 -320.296147)
			(xy 353.181666 -320.295524) (xy 353.101402 -320.295524) (xy 353.089833 -320.296087) (xy 353.069062 -320.306286)
			(xy 353.061524 -320.315082) (xy 353.044771 -320.335865) (xy 353.006417 -320.372995) (xy 352.963263 -320.404417)
			(xy 352.916149 -320.429516) (xy 352.865997 -320.447802) (xy 352.813786 -320.458919) (xy 352.760534 -320.462649)
			(xy 352.707282 -320.458919) (xy 352.655071 -320.447802) (xy 352.604919 -320.429516) (xy 352.557805 -320.404417)
			(xy 352.514651 -320.372995) (xy 352.476297 -320.335865) (xy 352.459544 -320.315082) (xy 352.451962 -320.306341)
			(xy 352.431218 -320.296147) (xy 352.419666 -320.295524) (xy 352.339402 -320.295524) (xy 352.327833 -320.296087)
			(xy 352.307062 -320.306286) (xy 352.299524 -320.315082) (xy 352.281315 -320.33755) (xy 352.239299 -320.377287)
			(xy 352.191768 -320.410229) (xy 352.139811 -320.43562) (xy 352.084616 -320.452879) (xy 352.027449 -320.461611)
			(xy 351.998534 -320.462148) (xy 351.971285 -320.46159) (xy 351.917342 -320.453839) (xy 351.865051 -320.438491)
			(xy 351.815477 -320.415856) (xy 351.769629 -320.386397) (xy 351.728439 -320.350713) (xy 351.692747 -320.309531)
			(xy 351.663279 -320.263688) (xy 351.640635 -320.214118) (xy 351.625276 -320.16183) (xy 351.617515 -320.107888)
			(xy 351.617026 -320.08064) (xy 347.568012 -320.08064) (xy 347.567559 -320.107892) (xy 347.559798 -320.161841)
			(xy 347.544438 -320.214136) (xy 347.521792 -320.263713) (xy 347.492322 -320.309563) (xy 347.456627 -320.350753)
			(xy 347.415434 -320.386444) (xy 347.369581 -320.415909) (xy 347.320002 -320.43855) (xy 347.267706 -320.453905)
			(xy 347.213756 -320.461662) (xy 347.186504 -320.462148) (xy 347.157586 -320.461646) (xy 347.100413 -320.452917)
			(xy 347.045213 -320.435657) (xy 346.993251 -320.410262) (xy 346.945718 -320.377315) (xy 346.903703 -320.33757)
			(xy 346.885514 -320.315082) (xy 346.877945 -320.306328) (xy 346.857192 -320.296141) (xy 346.845636 -320.295524)
			(xy 346.765372 -320.295524) (xy 346.753808 -320.296127) (xy 346.733036 -320.306298) (xy 346.725494 -320.315082)
			(xy 346.708741 -320.335865) (xy 346.670387 -320.372995) (xy 346.627233 -320.404417) (xy 346.580119 -320.429516)
			(xy 346.529967 -320.447802) (xy 346.477756 -320.458919) (xy 346.424504 -320.462649) (xy 346.371252 -320.458919)
			(xy 346.319041 -320.447802) (xy 346.268889 -320.429516) (xy 346.221775 -320.404417) (xy 346.178621 -320.372995)
			(xy 346.140267 -320.335865) (xy 346.123514 -320.315082) (xy 346.115945 -320.306328) (xy 346.095192 -320.296141)
			(xy 346.083636 -320.295524) (xy 346.003372 -320.295524) (xy 345.991808 -320.296127) (xy 345.971036 -320.306298)
			(xy 345.963494 -320.315082) (xy 345.946741 -320.335865) (xy 345.908387 -320.372995) (xy 345.865233 -320.404417)
			(xy 345.818119 -320.429516) (xy 345.767967 -320.447802) (xy 345.715756 -320.458919) (xy 345.662504 -320.462649)
			(xy 345.609252 -320.458919) (xy 345.557041 -320.447802) (xy 345.506889 -320.429516) (xy 345.459775 -320.404417)
			(xy 345.416621 -320.372995) (xy 345.378267 -320.335865) (xy 345.361514 -320.315082) (xy 345.353945 -320.306328)
			(xy 345.333192 -320.296141) (xy 345.321636 -320.295524) (xy 345.241372 -320.295524) (xy 345.229808 -320.296127)
			(xy 345.209036 -320.306298) (xy 345.201494 -320.315082) (xy 345.184741 -320.335865) (xy 345.146387 -320.372995)
			(xy 345.103233 -320.404417) (xy 345.056119 -320.429516) (xy 345.005967 -320.447802) (xy 344.953756 -320.458919)
			(xy 344.900504 -320.462649) (xy 344.847252 -320.458919) (xy 344.795041 -320.447802) (xy 344.744889 -320.429516)
			(xy 344.697775 -320.404417) (xy 344.654621 -320.372995) (xy 344.616267 -320.335865) (xy 344.599514 -320.315082)
			(xy 344.591945 -320.306328) (xy 344.571192 -320.296141) (xy 344.559636 -320.295524) (xy 344.479372 -320.295524)
			(xy 344.467808 -320.296127) (xy 344.447036 -320.306298) (xy 344.439494 -320.315082) (xy 344.422741 -320.335865)
			(xy 344.384387 -320.372995) (xy 344.341233 -320.404417) (xy 344.294119 -320.429516) (xy 344.243967 -320.447802)
			(xy 344.191756 -320.458919) (xy 344.138504 -320.462649) (xy 344.085252 -320.458919) (xy 344.033041 -320.447802)
			(xy 343.982889 -320.429516) (xy 343.935775 -320.404417) (xy 343.892621 -320.372995) (xy 343.854267 -320.335865)
			(xy 343.837514 -320.315082) (xy 343.829945 -320.306328) (xy 343.809192 -320.296141) (xy 343.797636 -320.295524)
			(xy 343.717372 -320.295524) (xy 343.705808 -320.296127) (xy 343.685036 -320.306298) (xy 343.677494 -320.315082)
			(xy 343.660741 -320.335865) (xy 343.622387 -320.372995) (xy 343.579233 -320.404417) (xy 343.532119 -320.429516)
			(xy 343.481967 -320.447802) (xy 343.429756 -320.458919) (xy 343.376504 -320.462649) (xy 343.323252 -320.458919)
			(xy 343.271041 -320.447802) (xy 343.220889 -320.429516) (xy 343.173775 -320.404417) (xy 343.130621 -320.372995)
			(xy 343.092267 -320.335865) (xy 343.075514 -320.315082) (xy 343.067945 -320.306328) (xy 343.047192 -320.296141)
			(xy 343.035636 -320.295524) (xy 342.955372 -320.295524) (xy 342.943808 -320.296127) (xy 342.923036 -320.306298)
			(xy 342.915494 -320.315082) (xy 342.898741 -320.335865) (xy 342.860387 -320.372995) (xy 342.817233 -320.404417)
			(xy 342.770119 -320.429516) (xy 342.719967 -320.447802) (xy 342.667756 -320.458919) (xy 342.614504 -320.462649)
			(xy 342.561252 -320.458919) (xy 342.509041 -320.447802) (xy 342.458889 -320.429516) (xy 342.411775 -320.404417)
			(xy 342.368621 -320.372995) (xy 342.330267 -320.335865) (xy 342.313514 -320.315082) (xy 342.305945 -320.306328)
			(xy 342.285192 -320.296141) (xy 342.273636 -320.295524) (xy 342.193372 -320.295524) (xy 342.181808 -320.296127)
			(xy 342.161036 -320.306298) (xy 342.153494 -320.315082) (xy 342.136741 -320.335865) (xy 342.098387 -320.372995)
			(xy 342.055233 -320.404417) (xy 342.008119 -320.429516) (xy 341.957967 -320.447802) (xy 341.905756 -320.458919)
			(xy 341.852504 -320.462649) (xy 341.799252 -320.458919) (xy 341.747041 -320.447802) (xy 341.696889 -320.429516)
			(xy 341.649775 -320.404417) (xy 341.606621 -320.372995) (xy 341.568267 -320.335865) (xy 341.551514 -320.315082)
			(xy 341.543945 -320.306328) (xy 341.523192 -320.296141) (xy 341.511636 -320.295524) (xy 341.431372 -320.295524)
			(xy 341.419808 -320.296127) (xy 341.399036 -320.306298) (xy 341.391494 -320.315082) (xy 341.374741 -320.335865)
			(xy 341.336387 -320.372995) (xy 341.293233 -320.404417) (xy 341.246119 -320.429516) (xy 341.195967 -320.447802)
			(xy 341.143756 -320.458919) (xy 341.090504 -320.462649) (xy 341.037252 -320.458919) (xy 340.985041 -320.447802)
			(xy 340.934889 -320.429516) (xy 340.887775 -320.404417) (xy 340.844621 -320.372995) (xy 340.806267 -320.335865)
			(xy 340.789514 -320.315082) (xy 340.781945 -320.306328) (xy 340.761192 -320.296141) (xy 340.749636 -320.295524)
			(xy 340.669372 -320.295524) (xy 340.657808 -320.296127) (xy 340.637036 -320.306298) (xy 340.629494 -320.315082)
			(xy 340.612741 -320.335865) (xy 340.574387 -320.372995) (xy 340.531233 -320.404417) (xy 340.484119 -320.429516)
			(xy 340.433967 -320.447802) (xy 340.381756 -320.458919) (xy 340.328504 -320.462649) (xy 340.275252 -320.458919)
			(xy 340.223041 -320.447802) (xy 340.172889 -320.429516) (xy 340.125775 -320.404417) (xy 340.082621 -320.372995)
			(xy 340.044267 -320.335865) (xy 340.027514 -320.315082) (xy 340.019945 -320.306328) (xy 339.999192 -320.296141)
			(xy 339.987636 -320.295524) (xy 339.907372 -320.295524) (xy 339.895808 -320.296127) (xy 339.875036 -320.306298)
			(xy 339.867494 -320.315082) (xy 339.850741 -320.335865) (xy 339.812387 -320.372995) (xy 339.769233 -320.404417)
			(xy 339.722119 -320.429516) (xy 339.671967 -320.447802) (xy 339.619756 -320.458919) (xy 339.566504 -320.462649)
			(xy 339.513252 -320.458919) (xy 339.461041 -320.447802) (xy 339.410889 -320.429516) (xy 339.363775 -320.404417)
			(xy 339.320621 -320.372995) (xy 339.282267 -320.335865) (xy 339.265514 -320.315082) (xy 339.257945 -320.306328)
			(xy 339.237192 -320.296141) (xy 339.225636 -320.295524) (xy 339.145372 -320.295524) (xy 339.133808 -320.296127)
			(xy 339.113036 -320.306298) (xy 339.105494 -320.315082) (xy 339.087302 -320.337565) (xy 339.045283 -320.377301)
			(xy 338.997748 -320.41024) (xy 338.945787 -320.435629) (xy 338.89059 -320.452885) (xy 338.83342 -320.461614)
			(xy 338.804504 -320.462148) (xy 338.777255 -320.461619) (xy 338.723311 -320.453864) (xy 338.671019 -320.438511)
			(xy 338.621445 -320.415873) (xy 338.575596 -320.386411) (xy 338.534407 -320.350724) (xy 338.498715 -320.309539)
			(xy 338.469248 -320.263694) (xy 338.446604 -320.214122) (xy 338.431246 -320.161832) (xy 338.423485 -320.107889)
			(xy 338.422996 -320.08064) (xy 324.492605 -320.08064) (xy 324.497236 -320.094511) (xy 324.536658 -320.237781)
			(xy 324.568332 -320.38296) (xy 324.592168 -320.529629) (xy 324.608097 -320.677367) (xy 324.616073 -320.825747)
			(xy 324.616572 -320.900044) (xy 324.616073 -320.974341) (xy 324.608097 -321.122721) (xy 324.592168 -321.270459)
			(xy 324.568332 -321.417128) (xy 324.536658 -321.562307) (xy 324.497236 -321.705577) (xy 324.450181 -321.846524)
			(xy 324.395628 -321.984741) (xy 324.333735 -322.119832) (xy 324.26468 -322.251405) (xy 324.188662 -322.379083)
			(xy 324.105901 -322.502495) (xy 324.016634 -322.621288) (xy 323.92112 -322.735117) (xy 323.819633 -322.843656)
			(xy 323.712466 -322.946591) (xy 323.599929 -323.043625) (xy 323.482346 -323.134478) (xy 323.360056 -323.218889)
			(xy 323.233411 -323.296614) (xy 323.102776 -323.36743) (xy 322.968529 -323.431131) (xy 322.831056 -323.487534)
			(xy 322.690753 -323.536477) (xy 322.548026 -323.577819) (xy 322.403285 -323.611439) (xy 322.256949 -323.637242)
			(xy 322.109438 -323.655153) (xy 321.961179 -323.665121) (xy 321.812598 -323.667116) (xy 321.664125 -323.661132)
			(xy 321.516186 -323.647188) (xy 321.36921 -323.625323) (xy 321.223619 -323.595601) (xy 321.079833 -323.558106)
			(xy 320.938267 -323.512947) (xy 320.799329 -323.460255) (xy 320.66342 -323.400181) (xy 320.530931 -323.332899)
			(xy 320.402245 -323.258602) (xy 320.277732 -323.177505) (xy 320.157752 -323.089841) (xy 320.042651 -322.995863)
			(xy 319.932759 -322.895843) (xy 319.828395 -322.790068) (xy 319.729859 -322.678844) (xy 319.637435 -322.562491)
			(xy 319.55139 -322.441344) (xy 319.471972 -322.315754) (xy 319.399409 -322.186082) (xy 319.333911 -322.052702)
			(xy 319.275667 -321.915999) (xy 319.224845 -321.776366) (xy 319.181591 -321.634207) (xy 319.14603 -321.48993)
			(xy 319.118265 -321.343954) (xy 319.098375 -321.196697) (xy 319.086418 -321.048584) (xy 319.082429 -320.900044)
			(xy 304.276366 -320.900044) (xy 321.437653 -327.152) (xy 330.808582 -327.152) (xy 330.812653 -327.096378)
			(xy 330.824779 -327.041941) (xy 330.844702 -326.98985) (xy 330.871998 -326.941215) (xy 330.906084 -326.897072)
			(xy 330.946233 -326.858363) (xy 330.991591 -326.825912) (xy 331.041191 -326.800411) (xy 331.093975 -326.782404)
			(xy 331.148818 -326.772274) (xy 331.204552 -326.770237) (xy 331.259989 -326.776337) (xy 331.313946 -326.790443)
			(xy 331.365275 -326.812255) (xy 331.412881 -326.841309) (xy 331.455749 -326.876984) (xy 331.492966 -326.918521)
			(xy 331.523739 -326.965034) (xy 331.547411 -327.015531) (xy 331.563479 -327.068938) (xy 331.571599 -327.124114)
			(xy 331.572108 -327.152) (xy 331.571599 -327.179886) (xy 331.563479 -327.235062) (xy 331.547411 -327.288469)
			(xy 331.523739 -327.338966) (xy 331.492966 -327.385479) (xy 331.455749 -327.427016) (xy 331.412881 -327.462691)
			(xy 331.365275 -327.491745) (xy 331.313946 -327.513557) (xy 331.259989 -327.527663) (xy 331.204552 -327.533763)
			(xy 331.148818 -327.531726) (xy 331.093975 -327.521596) (xy 331.041191 -327.503589) (xy 330.991591 -327.478088)
			(xy 330.946233 -327.445637) (xy 330.906084 -327.406928) (xy 330.871998 -327.362785) (xy 330.844702 -327.31415)
			(xy 330.824779 -327.262059) (xy 330.812653 -327.207622) (xy 330.808582 -327.152) (xy 321.437653 -327.152)
			(xy 326.583808 -329.026774) (xy 334.46288 -329.026774) (xy 334.466951 -328.971152) (xy 334.479077 -328.916715)
			(xy 334.499 -328.864624) (xy 334.526296 -328.815989) (xy 334.560382 -328.771846) (xy 334.600531 -328.733137)
			(xy 334.645889 -328.700686) (xy 334.695489 -328.675185) (xy 334.748273 -328.657178) (xy 334.803116 -328.647048)
			(xy 334.85885 -328.645011) (xy 334.914287 -328.651111) (xy 334.968244 -328.665217) (xy 335.019573 -328.687029)
			(xy 335.067179 -328.716083) (xy 335.110047 -328.751758) (xy 335.147264 -328.793295) (xy 335.178037 -328.839808)
			(xy 335.201709 -328.890305) (xy 335.217777 -328.943712) (xy 335.225897 -328.998888) (xy 335.226406 -329.026774)
			(xy 335.225897 -329.05466) (xy 335.217777 -329.109836) (xy 335.201709 -329.163243) (xy 335.178037 -329.21374)
			(xy 335.147264 -329.260253) (xy 335.110047 -329.30179) (xy 335.067179 -329.337465) (xy 335.019573 -329.366519)
			(xy 334.968244 -329.388331) (xy 334.914287 -329.402437) (xy 334.85885 -329.408537) (xy 334.803116 -329.4065)
			(xy 334.748273 -329.39637) (xy 334.695489 -329.378363) (xy 334.645889 -329.352862) (xy 334.600531 -329.320411)
			(xy 334.560382 -329.281702) (xy 334.526296 -329.237559) (xy 334.499 -329.188924) (xy 334.479077 -329.136833)
			(xy 334.466951 -329.082396) (xy 334.46288 -329.026774) (xy 326.583808 -329.026774) (xy 343.351866 -335.135474)
			(xy 343.389012 -335.1494) (xy 343.461173 -335.182371) (xy 343.530482 -335.220979) (xy 343.563702 -335.242662)
			(xy 345.862656 -336.775298) (xy 345.872816 -336.780632) (xy 350.064324 -338.372958) (xy 350.073576 -338.376012)
			(xy 350.09304 -338.375662) (xy 350.110977 -338.368095) (xy 350.118172 -338.361528) (xy 350.22917 -338.25053)
			(xy 350.236009 -338.243129) (xy 350.243722 -338.224531) (xy 350.244156 -338.214462) (xy 350.244156 -337.611212)
			(xy 350.24366 -337.601217) (xy 350.236024 -337.582742) (xy 350.221933 -337.56856) (xy 350.212914 -337.564222)
			(xy 341.317072 -333.879444) (xy 341.29712 -333.870831) (xy 341.259469 -333.849128) (xy 341.224978 -333.82269)
			(xy 341.209376 -333.807562) (xy 338.26069 -330.858876) (xy 338.253279 -330.852196) (xy 338.234843 -330.844621)
			(xy 338.224876 -330.844144) (xy 337.726782 -330.844144) (xy 337.700695 -330.843657) (xy 337.649166 -330.835487)
			(xy 337.59955 -330.819352) (xy 337.553071 -330.79565) (xy 337.510876 -330.764965) (xy 337.492086 -330.746862)
			(xy 336.739992 -329.994768) (xy 336.721911 -329.975974) (xy 336.691291 -329.93376) (xy 336.667654 -329.887275)
			(xy 336.651583 -329.837663) (xy 336.643473 -329.786147) (xy 336.642964 -329.760072) (xy 336.642964 -329.261978)
			(xy 336.642421 -329.251993) (xy 336.634698 -329.23357) (xy 336.627978 -329.226164) (xy 335.387442 -327.985374)
			(xy 335.380303 -327.978889) (xy 335.362576 -327.971325) (xy 335.34331 -327.970813) (xy 335.334102 -327.97369)
			(xy 335.244186 -328.006202) (xy 335.226152 -328.02957) (xy 335.224882 -328.044302) (xy 335.221878 -328.072441)
			(xy 335.208624 -328.127456) (xy 335.18739 -328.179911) (xy 335.158641 -328.228653) (xy 335.123009 -328.272615)
			(xy 335.081275 -328.310833) (xy 335.034354 -328.342467) (xy 334.983275 -328.366825) (xy 334.929159 -328.383371)
			(xy 334.873192 -328.391743) (xy 334.844898 -328.392282) (xy 334.817646 -328.391819) (xy 334.763697 -328.384061)
			(xy 334.7114 -328.368705) (xy 334.661822 -328.346062) (xy 334.615971 -328.316593) (xy 334.574781 -328.280899)
			(xy 334.53909 -328.239706) (xy 334.509625 -328.193853) (xy 334.486986 -328.144273) (xy 334.471633 -328.091976)
			(xy 334.463879 -328.038026) (xy 334.46339 -328.010774) (xy 334.4639 -327.982474) (xy 334.472253 -327.926495)
			(xy 334.488787 -327.872365) (xy 334.513139 -327.821273) (xy 334.544774 -327.77434) (xy 334.582997 -327.732598)
			(xy 334.626969 -327.696962) (xy 334.675725 -327.668216) (xy 334.728193 -327.646991) (xy 334.783222 -327.633752)
			(xy 334.81137 -327.63079) (xy 334.826102 -327.62952) (xy 334.84947 -327.611486) (xy 334.881982 -327.52157)
			(xy 334.884911 -327.512376) (xy 334.884389 -327.493102) (xy 334.876773 -327.475388) (xy 334.870298 -327.46823)
			(xy 333.536036 -326.133968) (xy 333.525368 -326.127618) (xy 333.519526 -326.12584) (xy 333.491249 -326.116466)
			(xy 333.437789 -326.090186) (xy 333.4131 -326.073516) (xy 333.406542 -326.069307) (xy 333.391677 -326.064655)
			(xy 333.38389 -326.064372) (xy 333.131414 -326.064372) (xy 333.119476 -326.067166) (xy 333.113888 -326.06996)
			(xy 333.08636 -326.083795) (xy 333.027947 -326.103373) (xy 332.967145 -326.113302) (xy 332.936342 -326.113902)
			(xy 332.905156 -326.113289) (xy 332.843616 -326.103148) (xy 332.78455 -326.083114) (xy 332.756764 -326.068944)
			(xy 332.746858 -326.063864) (xy 332.725776 -326.06234) (xy 332.633574 -326.096376) (xy 332.618334 -326.111108)
			(xy 332.61427 -326.121522) (xy 332.603393 -326.147936) (xy 332.574882 -326.197435) (xy 332.539303 -326.242125)
			(xy 332.497453 -326.281006) (xy 332.45027 -326.313205) (xy 332.39881 -326.338003) (xy 332.344226 -326.354844)
			(xy 332.28774 -326.36335) (xy 332.259178 -326.363838) (xy 332.231926 -326.363351) (xy 332.177976 -326.355591)
			(xy 332.12568 -326.340233) (xy 332.076101 -326.317589) (xy 332.03025 -326.288119) (xy 331.989059 -326.252425)
			(xy 331.953367 -326.211232) (xy 331.923901 -326.165379) (xy 331.90126 -326.1158) (xy 331.885904 -326.063502)
			(xy 331.878148 -326.009552) (xy 331.878148 -325.955048) (xy 331.885904 -325.901098) (xy 331.90126 -325.8488)
			(xy 331.923901 -325.799221) (xy 331.953367 -325.753368) (xy 331.989059 -325.712175) (xy 332.03025 -325.676481)
			(xy 332.076101 -325.647011) (xy 332.12568 -325.624367) (xy 332.177976 -325.609009) (xy 332.231926 -325.601249)
			(xy 332.259178 -325.600822) (xy 332.290363 -325.601436) (xy 332.351902 -325.611581) (xy 332.410965 -325.631619)
			(xy 332.438756 -325.64578) (xy 332.448662 -325.65086) (xy 332.469744 -325.652384) (xy 332.561946 -325.618348)
			(xy 332.577186 -325.603616) (xy 332.58125 -325.593202) (xy 332.592126 -325.566787) (xy 332.620636 -325.517287)
			(xy 332.656214 -325.472596) (xy 332.698064 -325.433716) (xy 332.745248 -325.401516) (xy 332.796708 -325.376719)
			(xy 332.851293 -325.35988) (xy 332.90778 -325.351376) (xy 332.936342 -325.350886) (xy 332.967143 -325.351501)
			(xy 333.027938 -325.361446) (xy 333.086348 -325.381021) (xy 333.113888 -325.394828) (xy 333.119476 -325.397622)
			(xy 333.131414 -325.400416) (xy 333.509366 -325.400416) (xy 333.516986 -325.39813) (xy 333.545199 -325.389712)
			(xy 333.603373 -325.380649) (xy 333.63281 -325.380096) (xy 333.659724 -325.380552) (xy 333.713018 -325.38811)
			(xy 333.76472 -325.403088) (xy 333.813802 -325.425188) (xy 333.859288 -325.45397) (xy 333.900274 -325.488864)
			(xy 333.935945 -325.529176) (xy 333.965592 -325.574103) (xy 333.988627 -325.622753) (xy 333.997046 -325.64832)
			(xy 333.998824 -325.654162) (xy 334.005174 -325.66483) (xy 337.209384 -328.868786) (xy 337.222745 -328.882533)
			(xy 337.246553 -328.912581) (xy 337.256882 -328.92873) (xy 337.25993 -328.93381) (xy 337.577684 -329.251564)
			(xy 337.613498 -329.255374) (xy 337.628738 -329.245468) (xy 337.652144 -329.230698) (xy 337.70232 -329.207344)
			(xy 337.755346 -329.191496) (xy 337.810108 -329.183486) (xy 337.83778 -329.182984) (xy 337.865034 -329.183446)
			(xy 337.918987 -329.191201) (xy 337.971288 -329.206555) (xy 338.020871 -329.229196) (xy 338.066728 -329.258663)
			(xy 338.107923 -329.294357) (xy 338.14362 -329.33555) (xy 338.173091 -329.381404) (xy 338.195735 -329.430986)
			(xy 338.211093 -329.483285) (xy 338.218852 -329.537238) (xy 338.219288 -329.564492) (xy 338.218776 -329.592163)
			(xy 338.210748 -329.646919) (xy 338.194902 -329.699944) (xy 338.17157 -329.750127) (xy 338.156804 -329.773534)
			(xy 338.146898 -329.788774) (xy 338.150708 -329.824588) (xy 338.553044 -330.226924) (xy 338.558124 -330.229972)
			(xy 338.574279 -330.240294) (xy 338.604329 -330.2641) (xy 338.618068 -330.27747) (xy 339.337904 -330.997306)
			(xy 351.42119 -330.997306) (xy 351.425261 -330.941684) (xy 351.437387 -330.887247) (xy 351.45731 -330.835156)
			(xy 351.484606 -330.786521) (xy 351.518692 -330.742378) (xy 351.558841 -330.703669) (xy 351.604199 -330.671218)
			(xy 351.653799 -330.645717) (xy 351.706583 -330.62771) (xy 351.761426 -330.61758) (xy 351.81716 -330.615543)
			(xy 351.872597 -330.621643) (xy 351.926554 -330.635749) (xy 351.977883 -330.657561) (xy 352.025489 -330.686615)
			(xy 352.068357 -330.72229) (xy 352.105574 -330.763827) (xy 352.136347 -330.81034) (xy 352.160019 -330.860837)
			(xy 352.176087 -330.914244) (xy 352.184207 -330.96942) (xy 352.184716 -330.997306) (xy 352.43719 -330.997306)
			(xy 352.441261 -330.941684) (xy 352.453387 -330.887247) (xy 352.47331 -330.835156) (xy 352.500606 -330.786521)
			(xy 352.534692 -330.742378) (xy 352.574841 -330.703669) (xy 352.620199 -330.671218) (xy 352.669799 -330.645717)
			(xy 352.722583 -330.62771) (xy 352.777426 -330.61758) (xy 352.83316 -330.615543) (xy 352.888597 -330.621643)
			(xy 352.942554 -330.635749) (xy 352.993883 -330.657561) (xy 353.041489 -330.686615) (xy 353.084357 -330.72229)
			(xy 353.121574 -330.763827) (xy 353.152347 -330.81034) (xy 353.176019 -330.860837) (xy 353.192087 -330.914244)
			(xy 353.200207 -330.96942) (xy 353.200716 -330.997306) (xy 353.200207 -331.025192) (xy 353.192087 -331.080368)
			(xy 353.176019 -331.133775) (xy 353.152347 -331.184272) (xy 353.121574 -331.230785) (xy 353.084357 -331.272322)
			(xy 353.041489 -331.307997) (xy 352.993883 -331.337051) (xy 352.942554 -331.358863) (xy 352.888597 -331.372969)
			(xy 352.83316 -331.379069) (xy 352.777426 -331.377032) (xy 352.722583 -331.366902) (xy 352.669799 -331.348895)
			(xy 352.620199 -331.323394) (xy 352.574841 -331.290943) (xy 352.534692 -331.252234) (xy 352.500606 -331.208091)
			(xy 352.47331 -331.159456) (xy 352.453387 -331.107365) (xy 352.441261 -331.052928) (xy 352.43719 -330.997306)
			(xy 352.184716 -330.997306) (xy 352.184207 -331.025192) (xy 352.176087 -331.080368) (xy 352.160019 -331.133775)
			(xy 352.136347 -331.184272) (xy 352.105574 -331.230785) (xy 352.068357 -331.272322) (xy 352.025489 -331.307997)
			(xy 351.977883 -331.337051) (xy 351.926554 -331.358863) (xy 351.872597 -331.372969) (xy 351.81716 -331.379069)
			(xy 351.761426 -331.377032) (xy 351.706583 -331.366902) (xy 351.653799 -331.348895) (xy 351.604199 -331.323394)
			(xy 351.558841 -331.290943) (xy 351.518692 -331.252234) (xy 351.484606 -331.208091) (xy 351.45731 -331.159456)
			(xy 351.437387 -331.107365) (xy 351.425261 -331.052928) (xy 351.42119 -330.997306) (xy 339.337904 -330.997306)
			(xy 341.62492 -333.284322) (xy 341.62853 -333.287814) (xy 341.636847 -333.293442) (xy 341.64143 -333.295498)
			(xy 354.313236 -338.544408) (xy 354.317923 -338.546203) (xy 354.327775 -338.548114) (xy 354.332794 -338.548218)
			(xy 361.940348 -338.548218) (xy 361.950415 -338.547787) (xy 361.969008 -338.540062) (xy 361.976416 -338.533232)
			(xy 362.54055 -337.969098) (xy 362.547402 -337.961702) (xy 362.555143 -337.943103) (xy 362.555536 -337.93303)
			(xy 362.555536 -335.685892) (xy 362.55511 -335.675824) (xy 362.547386 -335.657228) (xy 362.54055 -335.649824)
			(xy 359.067354 -332.176628) (xy 359.059949 -332.169932) (xy 359.041512 -332.162326) (xy 359.03154 -332.161896)
			(xy 358.347518 -332.161896) (xy 358.312104 -332.161362) (xy 358.241792 -332.152827) (xy 358.173022 -332.135879)
			(xy 358.106796 -332.110765) (xy 358.04408 -332.077852) (xy 357.985789 -332.037619) (xy 357.932772 -331.990653)
			(xy 357.885803 -331.937639) (xy 357.845567 -331.87935) (xy 357.812649 -331.816636) (xy 357.787531 -331.750412)
			(xy 357.770579 -331.681643) (xy 357.76204 -331.611332) (xy 357.76154 -331.575918) (xy 357.762098 -331.539868)
			(xy 357.770956 -331.468314) (xy 357.788528 -331.398388) (xy 357.814548 -331.331147) (xy 357.848623 -331.267608)
			(xy 357.890238 -331.20873) (xy 357.938764 -331.155404) (xy 357.993467 -331.108436) (xy 358.02316 -331.087984)
			(xy 358.027478 -331.08519) (xy 359.151682 -329.960986) (xy 359.159081 -329.954143) (xy 359.17768 -329.946425)
			(xy 359.18775 -329.946) (xy 363.706918 -329.946) (xy 363.716987 -329.946427) (xy 363.735586 -329.954146)
			(xy 363.742986 -329.960986) (xy 364.24235 -330.46035) (xy 364.249194 -330.467749) (xy 364.256918 -330.486348)
			(xy 364.257336 -330.496418) (xy 364.257336 -330.90485) (xy 364.257769 -330.914915) (xy 364.2655 -330.933503)
			(xy 364.272322 -330.940918) (xy 364.700312 -331.368908) (xy 364.707723 -331.37559) (xy 364.726159 -331.383166)
			(xy 364.736126 -331.38364) (xy 367.079276 -331.38364) (xy 367.105364 -331.384124) (xy 367.156897 -331.392288)
			(xy 367.206518 -331.408417) (xy 367.253002 -331.432115) (xy 367.295203 -331.462796) (xy 367.313972 -331.480922)
			(xy 367.868708 -332.035658) (xy 367.886793 -332.054451) (xy 367.917423 -332.096662) (xy 367.94107 -332.143147)
			(xy 367.957153 -332.192759) (xy 367.965274 -332.244277) (xy 367.965736 -332.270354) (xy 367.965736 -334.613504)
			(xy 367.966275 -334.62349) (xy 367.973994 -334.641918) (xy 367.980722 -334.649318) (xy 370.809012 -337.477608)
			(xy 370.816423 -337.48429) (xy 370.834859 -337.491866) (xy 370.844826 -337.49234) (xy 378.830078 -337.49234)
			(xy 378.856166 -337.492824) (xy 378.907699 -337.500988) (xy 378.957319 -337.517118) (xy 379.003803 -337.540815)
			(xy 379.046005 -337.571497) (xy 379.064774 -337.589622) (xy 382.75006 -341.274908) (xy 382.773174 -341.300816)
			(xy 382.780842 -341.309254) (xy 382.801412 -341.319023) (xy 382.812798 -341.319612) (xy 385.313174 -341.319612)
			(xy 385.323198 -341.320027) (xy 385.341722 -341.327693) (xy 385.355899 -341.341867) (xy 385.36357 -341.360388)
			(xy 385.363974 -341.370412) (xy 385.363974 -341.746078) (xy 385.364374 -341.75536) (xy 385.371018 -341.772692)
			(xy 385.376928 -341.77986) (xy 385.392152 -341.797635) (xy 385.417837 -341.836757) (xy 385.437592 -341.879184)
			(xy 385.451001 -341.924022) (xy 385.457782 -341.970328) (xy 385.458208 -341.993728) (xy 385.458208 -342.466769)
			(xy 386.351522 -342.466769) (xy 386.351522 -342.412231) (xy 386.359284 -342.358249) (xy 386.374648 -342.305921)
			(xy 386.397303 -342.256312) (xy 386.426787 -342.210432) (xy 386.4625 -342.169214) (xy 386.503716 -342.133499)
			(xy 386.549594 -342.104012) (xy 386.599202 -342.081355) (xy 386.65153 -342.065988) (xy 386.705511 -342.058224)
			(xy 386.73278 -342.057736) (xy 387.59638 -342.057736) (xy 387.623652 -342.058202) (xy 387.677641 -342.065962)
			(xy 387.729975 -342.081326) (xy 387.779591 -342.103983) (xy 387.825477 -342.13347) (xy 387.866699 -342.169187)
			(xy 387.902418 -342.210407) (xy 387.931908 -342.256292) (xy 387.954567 -342.305906) (xy 387.969934 -342.35824)
			(xy 387.977696 -342.412228) (xy 387.977696 -342.466772) (xy 387.977696 -342.466773) (xy 389.4604 -342.466773)
			(xy 389.4604 -342.412227) (xy 389.468163 -342.358236) (xy 389.483531 -342.3059) (xy 389.506192 -342.256284)
			(xy 389.535683 -342.210398) (xy 389.571405 -342.169177) (xy 389.61263 -342.133459) (xy 389.658519 -342.103973)
			(xy 389.708138 -342.081317) (xy 389.760476 -342.065954) (xy 389.814467 -342.058197) (xy 389.84174 -342.057736)
			(xy 390.70534 -342.057736) (xy 390.732607 -342.058229) (xy 390.786586 -342.065995) (xy 390.838911 -342.081364)
			(xy 390.888516 -342.104022) (xy 390.934391 -342.133509) (xy 390.975604 -342.169224) (xy 391.011315 -342.210441)
			(xy 391.040797 -342.256319) (xy 391.06345 -342.305927) (xy 391.078813 -342.358253) (xy 391.086574 -342.412233)
			(xy 391.086574 -342.466767) (xy 391.086574 -342.46677) (xy 392.569422 -342.46677) (xy 392.569422 -342.41223)
			(xy 392.577184 -342.358247) (xy 392.59255 -342.305917) (xy 392.615206 -342.256306) (xy 392.644692 -342.210425)
			(xy 392.680407 -342.169207) (xy 392.721625 -342.133492) (xy 392.767506 -342.104006) (xy 392.817117 -342.08135)
			(xy 392.869447 -342.065984) (xy 392.92343 -342.058222) (xy 392.9507 -342.057736) (xy 393.8143 -342.057736)
			(xy 393.841569 -342.058226) (xy 393.895553 -342.065988) (xy 393.947882 -342.081353) (xy 393.997492 -342.104009)
			(xy 394.043372 -342.133495) (xy 394.08459 -342.16921) (xy 394.120305 -342.210428) (xy 394.149791 -342.256308)
			(xy 394.172447 -342.305918) (xy 394.187812 -342.358247) (xy 394.195574 -342.412231) (xy 394.195574 -342.466768)
			(xy 395.678422 -342.466768) (xy 395.678422 -342.412232) (xy 395.686183 -342.358252) (xy 395.701546 -342.305925)
			(xy 395.7242 -342.256318) (xy 395.753682 -342.210438) (xy 395.789393 -342.169222) (xy 395.830606 -342.133506)
			(xy 395.876482 -342.104019) (xy 395.926088 -342.08136) (xy 395.978413 -342.065991) (xy 396.032392 -342.058225)
			(xy 396.05966 -342.057736) (xy 396.92326 -342.057736) (xy 396.950533 -342.058201) (xy 397.004524 -342.065958)
			(xy 397.056861 -342.081321) (xy 397.106479 -342.103976) (xy 397.152367 -342.133463) (xy 397.193592 -342.16918)
			(xy 397.229313 -342.210401) (xy 397.258805 -342.256286) (xy 397.281465 -342.305902) (xy 397.296833 -342.358237)
			(xy 397.304596 -342.412227) (xy 397.304596 -342.466773) (xy 397.296833 -342.520763) (xy 397.281465 -342.573098)
			(xy 397.258805 -342.622714) (xy 397.229313 -342.668599) (xy 397.193592 -342.70982) (xy 397.152367 -342.745537)
			(xy 397.106479 -342.775024) (xy 397.056861 -342.797679) (xy 397.004524 -342.813042) (xy 396.950533 -342.820799)
			(xy 396.92326 -342.82126) (xy 396.05966 -342.82126) (xy 396.032392 -342.820775) (xy 395.978413 -342.813009)
			(xy 395.926088 -342.79764) (xy 395.876482 -342.774981) (xy 395.830606 -342.745494) (xy 395.789393 -342.709778)
			(xy 395.753682 -342.668562) (xy 395.7242 -342.622682) (xy 395.701546 -342.573075) (xy 395.686183 -342.520748)
			(xy 395.678422 -342.466768) (xy 394.195574 -342.466768) (xy 394.195574 -342.466769) (xy 394.187812 -342.520753)
			(xy 394.172447 -342.573082) (xy 394.149791 -342.622692) (xy 394.120305 -342.668572) (xy 394.08459 -342.70979)
			(xy 394.043372 -342.745505) (xy 393.997492 -342.774991) (xy 393.947882 -342.797647) (xy 393.895553 -342.813012)
			(xy 393.841569 -342.820774) (xy 393.8143 -342.82126) (xy 392.9507 -342.82126) (xy 392.92343 -342.820778)
			(xy 392.869447 -342.813016) (xy 392.817117 -342.79765) (xy 392.767506 -342.774994) (xy 392.721625 -342.745508)
			(xy 392.680407 -342.709793) (xy 392.644692 -342.668575) (xy 392.615206 -342.622694) (xy 392.59255 -342.573083)
			(xy 392.577184 -342.520753) (xy 392.569422 -342.46677) (xy 391.086574 -342.46677) (xy 391.078813 -342.520747)
			(xy 391.06345 -342.573073) (xy 391.040797 -342.622681) (xy 391.011315 -342.668559) (xy 390.975604 -342.709776)
			(xy 390.934391 -342.745491) (xy 390.888516 -342.774978) (xy 390.838911 -342.797636) (xy 390.786586 -342.813005)
			(xy 390.732607 -342.820771) (xy 390.70534 -342.82126) (xy 389.84174 -342.82126) (xy 389.814467 -342.820803)
			(xy 389.760476 -342.813046) (xy 389.708138 -342.797683) (xy 389.658519 -342.775027) (xy 389.61263 -342.745541)
			(xy 389.571405 -342.709823) (xy 389.535683 -342.668602) (xy 389.506192 -342.622716) (xy 389.483531 -342.5731)
			(xy 389.468163 -342.520764) (xy 389.4604 -342.466773) (xy 387.977696 -342.466773) (xy 387.969934 -342.52076)
			(xy 387.954567 -342.573094) (xy 387.931908 -342.622708) (xy 387.902418 -342.668593) (xy 387.866699 -342.709813)
			(xy 387.825477 -342.74553) (xy 387.779591 -342.775017) (xy 387.729975 -342.797674) (xy 387.677641 -342.813038)
			(xy 387.623652 -342.820798) (xy 387.59638 -342.82126) (xy 386.73278 -342.82126) (xy 386.705511 -342.820776)
			(xy 386.65153 -342.813012) (xy 386.599202 -342.797645) (xy 386.549594 -342.774988) (xy 386.503716 -342.745501)
			(xy 386.4625 -342.709786) (xy 386.426787 -342.668568) (xy 386.397303 -342.622688) (xy 386.374648 -342.573079)
			(xy 386.359284 -342.520751) (xy 386.351522 -342.466769) (xy 385.458208 -342.466769) (xy 385.458208 -345.492365)
			(xy 386.35157 -345.492365) (xy 386.35157 -345.437835) (xy 386.35933 -345.383859) (xy 386.374693 -345.331538)
			(xy 386.397345 -345.281935) (xy 386.426825 -345.236061) (xy 386.462534 -345.194848) (xy 386.503745 -345.159137)
			(xy 386.549617 -345.129655) (xy 386.599219 -345.107) (xy 386.65154 -345.091635) (xy 386.705515 -345.083872)
			(xy 386.73278 -345.083384) (xy 387.59638 -345.083384) (xy 387.623655 -345.083754) (xy 387.677651 -345.091515)
			(xy 387.729992 -345.106881) (xy 387.779614 -345.129541) (xy 387.825505 -345.159031) (xy 387.866733 -345.194753)
			(xy 387.902457 -345.235978) (xy 387.93195 -345.281869) (xy 387.954612 -345.331489) (xy 387.969981 -345.38383)
			(xy 387.977744 -345.437825) (xy 387.977744 -345.49237) (xy 389.460447 -345.49237) (xy 389.460447 -345.43783)
			(xy 389.46821 -345.383847) (xy 389.483576 -345.331517) (xy 389.506234 -345.281907) (xy 389.535722 -345.236027)
			(xy 389.571439 -345.194811) (xy 389.612659 -345.159098) (xy 389.658542 -345.129615) (xy 389.708155 -345.106962)
			(xy 389.760486 -345.091601) (xy 389.81447 -345.083845) (xy 389.84174 -345.083384) (xy 390.70534 -345.083384)
			(xy 390.732611 -345.083781) (xy 390.786597 -345.091549) (xy 390.838928 -345.106919) (xy 390.888539 -345.12958)
			(xy 390.93442 -345.159071) (xy 390.975638 -345.19479) (xy 391.011353 -345.236012) (xy 391.040839 -345.281896)
			(xy 391.063495 -345.33151) (xy 391.07886 -345.383843) (xy 391.086622 -345.437829) (xy 391.086622 -345.492366)
			(xy 392.56947 -345.492366) (xy 392.56947 -345.437834) (xy 392.577231 -345.383857) (xy 392.592595 -345.331534)
			(xy 392.615248 -345.281929) (xy 392.64473 -345.236054) (xy 392.680441 -345.194841) (xy 392.721654 -345.15913)
			(xy 392.767529 -345.129648) (xy 392.817134 -345.106995) (xy 392.869457 -345.091631) (xy 392.923434 -345.08387)
			(xy 392.9507 -345.083384) (xy 393.8143 -345.083384) (xy 393.841573 -345.083779) (xy 393.895563 -345.091541)
			(xy 393.947899 -345.106908) (xy 393.997515 -345.129567) (xy 394.043401 -345.159057) (xy 394.084624 -345.194776)
			(xy 394.120343 -345.235999) (xy 394.149833 -345.281885) (xy 394.172492 -345.331501) (xy 394.187859 -345.383837)
			(xy 394.195621 -345.437827) (xy 394.195621 -345.492364) (xy 395.67847 -345.492364) (xy 395.67847 -345.437836)
			(xy 395.68623 -345.383862) (xy 395.701591 -345.331542) (xy 395.724242 -345.281941) (xy 395.753721 -345.236067)
			(xy 395.789427 -345.194855) (xy 395.830635 -345.159145) (xy 395.876505 -345.129661) (xy 395.926105 -345.107005)
			(xy 395.978423 -345.091638) (xy 396.032396 -345.083873) (xy 396.05966 -345.083384) (xy 396.92326 -345.083384)
			(xy 396.950536 -345.083753) (xy 397.004534 -345.091511) (xy 397.056878 -345.106876) (xy 397.106502 -345.129534)
			(xy 397.152396 -345.159024) (xy 397.193626 -345.194746) (xy 397.229352 -345.235972) (xy 397.258847 -345.281863)
			(xy 397.28151 -345.331485) (xy 397.29688 -345.383827) (xy 397.304644 -345.437824) (xy 397.304644 -345.492376)
			(xy 397.29688 -345.546373) (xy 397.28151 -345.598715) (xy 397.258847 -345.648337) (xy 397.229352 -345.694228)
			(xy 397.193626 -345.735454) (xy 397.152396 -345.771176) (xy 397.106502 -345.800666) (xy 397.056878 -345.823324)
			(xy 397.004534 -345.838689) (xy 396.950536 -345.846447) (xy 396.92326 -345.846908) (xy 396.05966 -345.846908)
			(xy 396.032396 -345.846327) (xy 395.978423 -345.838562) (xy 395.926105 -345.823195) (xy 395.876505 -345.800539)
			(xy 395.830635 -345.771055) (xy 395.789427 -345.735345) (xy 395.753721 -345.694133) (xy 395.724242 -345.648259)
			(xy 395.701591 -345.598658) (xy 395.68623 -345.546338) (xy 395.67847 -345.492364) (xy 394.195621 -345.492364)
			(xy 394.195621 -345.492373) (xy 394.187859 -345.546363) (xy 394.172492 -345.598699) (xy 394.149833 -345.648315)
			(xy 394.120343 -345.694201) (xy 394.084624 -345.735424) (xy 394.043401 -345.771143) (xy 393.997515 -345.800633)
			(xy 393.947899 -345.823292) (xy 393.895563 -345.838659) (xy 393.841573 -345.846421) (xy 393.8143 -345.846908)
			(xy 392.9507 -345.846908) (xy 392.923434 -345.84633) (xy 392.869457 -345.838569) (xy 392.817134 -345.823205)
			(xy 392.767529 -345.800552) (xy 392.721654 -345.77107) (xy 392.680441 -345.735359) (xy 392.64473 -345.694146)
			(xy 392.615248 -345.648271) (xy 392.592595 -345.598666) (xy 392.577231 -345.546343) (xy 392.56947 -345.492366)
			(xy 391.086622 -345.492366) (xy 391.086622 -345.492371) (xy 391.07886 -345.546357) (xy 391.063495 -345.59869)
			(xy 391.040839 -345.648304) (xy 391.011353 -345.694188) (xy 390.975638 -345.73541) (xy 390.93442 -345.771129)
			(xy 390.888539 -345.80062) (xy 390.838928 -345.823281) (xy 390.786597 -345.838651) (xy 390.732611 -345.846419)
			(xy 390.70534 -345.846908) (xy 389.84174 -345.846908) (xy 389.81447 -345.846355) (xy 389.760486 -345.838599)
			(xy 389.708155 -345.823238) (xy 389.658542 -345.800585) (xy 389.612659 -345.771102) (xy 389.571439 -345.735389)
			(xy 389.535722 -345.694173) (xy 389.506234 -345.648293) (xy 389.483576 -345.598683) (xy 389.46821 -345.546353)
			(xy 389.460447 -345.49237) (xy 387.977744 -345.49237) (xy 387.977744 -345.492375) (xy 387.969981 -345.54637)
			(xy 387.954612 -345.598711) (xy 387.93195 -345.648331) (xy 387.902457 -345.694221) (xy 387.866733 -345.735447)
			(xy 387.825505 -345.771169) (xy 387.779614 -345.800659) (xy 387.729992 -345.823319) (xy 387.677651 -345.838685)
			(xy 387.623655 -345.846446) (xy 387.59638 -345.846908) (xy 386.73278 -345.846908) (xy 386.705515 -345.846328)
			(xy 386.65154 -345.838565) (xy 386.599219 -345.8232) (xy 386.549617 -345.800545) (xy 386.503745 -345.771063)
			(xy 386.462534 -345.735352) (xy 386.426825 -345.694139) (xy 386.397345 -345.648265) (xy 386.374693 -345.598662)
			(xy 386.35933 -345.546341) (xy 386.35157 -345.492365) (xy 385.458208 -345.492365) (xy 385.458208 -346.3544)
			(xy 385.458665 -346.364278) (xy 385.466105 -346.382581) (xy 385.472686 -346.38996) (xy 385.47294 -346.390214)
			(xy 386.750052 -347.667326) (xy 386.754624 -347.67139) (xy 386.775521 -347.68837) (xy 386.812446 -347.727558)
			(xy 386.843052 -347.771856) (xy 386.866642 -347.820257) (xy 386.882679 -347.871657) (xy 386.890797 -347.924884)
			(xy 386.891276 -347.951806) (xy 386.891078 -347.969061) (xy 386.887771 -348.003411) (xy 386.884672 -348.020386)
			(xy 386.883656 -348.025212) (xy 386.883656 -348.153228) (xy 386.884148 -348.163235) (xy 386.891811 -348.181725)
			(xy 386.905962 -348.19588) (xy 386.924449 -348.203549) (xy 386.934456 -348.204028) (xy 387.282436 -348.204028)
			(xy 388.154926 -348.204028) (xy 388.182195 -348.204516) (xy 388.236177 -348.212281) (xy 388.288505 -348.227649)
			(xy 388.338113 -348.250307) (xy 388.383992 -348.279795) (xy 388.425207 -348.315511) (xy 388.460921 -348.356729)
			(xy 388.490405 -348.40261) (xy 388.51306 -348.45222) (xy 388.528424 -348.504548) (xy 388.536186 -348.558531)
			(xy 388.536186 -348.613069) (xy 388.536185 -348.613074) (xy 389.460392 -348.613074) (xy 389.460392 -348.558526)
			(xy 389.468155 -348.504535) (xy 389.483524 -348.452197) (xy 389.506185 -348.40258) (xy 389.535677 -348.356694)
			(xy 389.5714 -348.315471) (xy 389.612626 -348.279753) (xy 389.658515 -348.250266) (xy 389.708135 -348.22761)
			(xy 389.760474 -348.212246) (xy 389.814466 -348.204489) (xy 389.84174 -348.204028) (xy 390.70534 -348.204028)
			(xy 390.732607 -348.204537) (xy 390.786585 -348.212303) (xy 390.838908 -348.227672) (xy 390.888512 -348.25033)
			(xy 390.934387 -348.279816) (xy 390.975598 -348.31553) (xy 391.011308 -348.356746) (xy 391.04079 -348.402623)
			(xy 391.063442 -348.45223) (xy 391.078805 -348.504554) (xy 391.086566 -348.558533) (xy 391.086566 -348.613067)
			(xy 391.086566 -348.61307) (xy 392.569414 -348.61307) (xy 392.569414 -348.55853) (xy 392.577176 -348.504545)
			(xy 392.592542 -348.452214) (xy 392.615199 -348.402603) (xy 392.644686 -348.35672) (xy 392.680402 -348.315502)
			(xy 392.72162 -348.279786) (xy 392.767503 -348.250299) (xy 392.817114 -348.227642) (xy 392.869445 -348.212276)
			(xy 392.92343 -348.204514) (xy 392.9507 -348.204028) (xy 393.8143 -348.204028) (xy 393.841569 -348.204534)
			(xy 393.895551 -348.212296) (xy 393.947879 -348.227661) (xy 393.997488 -348.250316) (xy 394.043368 -348.279802)
			(xy 394.084584 -348.315516) (xy 394.120298 -348.356732) (xy 394.149784 -348.402612) (xy 394.172439 -348.452221)
			(xy 394.187804 -348.504549) (xy 394.195566 -348.558531) (xy 394.195566 -348.613068) (xy 395.678414 -348.613068)
			(xy 395.678414 -348.558532) (xy 395.686175 -348.50455) (xy 395.701539 -348.452223) (xy 395.724193 -348.402614)
			(xy 395.753676 -348.356734) (xy 395.789388 -348.315516) (xy 395.830601 -348.2798) (xy 395.876479 -348.250312)
			(xy 395.926085 -348.227653) (xy 395.978411 -348.212284) (xy 396.032392 -348.204517) (xy 396.05966 -348.204028)
			(xy 396.92326 -348.204028) (xy 396.950532 -348.204509) (xy 397.004522 -348.212266) (xy 397.056858 -348.227628)
			(xy 397.106475 -348.250283) (xy 397.152362 -348.279769) (xy 397.193586 -348.315485) (xy 397.229307 -348.356706)
			(xy 397.258798 -348.40259) (xy 397.281458 -348.452204) (xy 397.296825 -348.504539) (xy 397.304588 -348.558528)
			(xy 397.304588 -348.613072) (xy 397.296825 -348.667061) (xy 397.281458 -348.719396) (xy 397.258798 -348.76901)
			(xy 397.229307 -348.814894) (xy 397.193586 -348.856115) (xy 397.152362 -348.891831) (xy 397.106475 -348.921317)
			(xy 397.056858 -348.943972) (xy 397.004522 -348.959334) (xy 396.950532 -348.967091) (xy 396.92326 -348.967552)
			(xy 396.05966 -348.967552) (xy 396.032392 -348.967083) (xy 395.978411 -348.959316) (xy 395.926085 -348.943947)
			(xy 395.876479 -348.921288) (xy 395.830601 -348.8918) (xy 395.789388 -348.856084) (xy 395.753676 -348.814866)
			(xy 395.724193 -348.768986) (xy 395.701539 -348.719377) (xy 395.686175 -348.66705) (xy 395.678414 -348.613068)
			(xy 394.195566 -348.613068) (xy 394.195566 -348.613069) (xy 394.187804 -348.667051) (xy 394.172439 -348.719379)
			(xy 394.149784 -348.768988) (xy 394.120298 -348.814868) (xy 394.084584 -348.856084) (xy 394.043368 -348.891798)
			(xy 393.997488 -348.921284) (xy 393.947879 -348.943939) (xy 393.895551 -348.959304) (xy 393.841569 -348.967066)
			(xy 393.8143 -348.967552) (xy 392.9507 -348.967552) (xy 392.92343 -348.967086) (xy 392.869445 -348.959324)
			(xy 392.817114 -348.943958) (xy 392.767503 -348.921301) (xy 392.72162 -348.891814) (xy 392.680402 -348.856098)
			(xy 392.644686 -348.81488) (xy 392.615199 -348.768997) (xy 392.592542 -348.719386) (xy 392.577176 -348.667055)
			(xy 392.569414 -348.61307) (xy 391.086566 -348.61307) (xy 391.078805 -348.667046) (xy 391.063442 -348.71937)
			(xy 391.04079 -348.768977) (xy 391.011308 -348.814854) (xy 390.975598 -348.85607) (xy 390.934387 -348.891784)
			(xy 390.888512 -348.92127) (xy 390.838908 -348.943928) (xy 390.786585 -348.959297) (xy 390.732607 -348.967063)
			(xy 390.70534 -348.967552) (xy 389.84174 -348.967552) (xy 389.814466 -348.967111) (xy 389.760474 -348.959354)
			(xy 389.708135 -348.94399) (xy 389.658515 -348.921334) (xy 389.612626 -348.891847) (xy 389.5714 -348.856129)
			(xy 389.535677 -348.814906) (xy 389.506185 -348.76902) (xy 389.483524 -348.719403) (xy 389.468155 -348.667065)
			(xy 389.460392 -348.613074) (xy 388.536185 -348.613074) (xy 388.528424 -348.667052) (xy 388.51306 -348.71938)
			(xy 388.490405 -348.76899) (xy 388.460921 -348.814871) (xy 388.425207 -348.856089) (xy 388.383992 -348.891805)
			(xy 388.338113 -348.921293) (xy 388.288505 -348.943951) (xy 388.236177 -348.959319) (xy 388.182195 -348.967084)
			(xy 388.154926 -348.967552) (xy 387.291326 -348.967552) (xy 386.934456 -348.967552) (xy 386.924451 -348.968047)
			(xy 386.905966 -348.975713) (xy 386.891815 -348.989862) (xy 386.884148 -349.008347) (xy 386.883656 -349.018352)
			(xy 386.883656 -349.146368) (xy 386.884672 -349.151194) (xy 386.887781 -349.168168) (xy 386.891084 -349.202519)
			(xy 386.891276 -349.219774) (xy 386.891079 -349.237029) (xy 386.887776 -349.27138) (xy 386.884672 -349.288354)
			(xy 386.883656 -349.29318) (xy 386.883656 -350.904048) (xy 386.884672 -350.908874) (xy 386.887782 -350.925848)
			(xy 386.891087 -350.960199) (xy 386.891276 -350.977454) (xy 386.891076 -350.994708) (xy 386.887764 -351.029058)
			(xy 386.884672 -351.046034) (xy 386.883656 -351.05086) (xy 386.883656 -351.178876) (xy 386.884139 -351.18889)
			(xy 386.891793 -351.207398) (xy 386.905945 -351.221569) (xy 386.924443 -351.229247) (xy 386.934456 -351.229676)
			(xy 387.282436 -351.229676) (xy 388.154926 -351.229676) (xy 388.182191 -351.230164) (xy 388.236167 -351.237928)
			(xy 388.288488 -351.253294) (xy 388.33809 -351.27595) (xy 388.383963 -351.305433) (xy 388.425174 -351.341145)
			(xy 388.460882 -351.382358) (xy 388.490363 -351.428233) (xy 388.513015 -351.477836) (xy 388.528378 -351.530159)
			(xy 388.536138 -351.584135) (xy 388.536138 -351.638665) (xy 388.536137 -351.63867) (xy 389.46044 -351.63867)
			(xy 389.46044 -351.58413) (xy 389.468202 -351.530145) (xy 389.483569 -351.477814) (xy 389.506227 -351.428203)
			(xy 389.535715 -351.382322) (xy 389.571434 -351.341105) (xy 389.612654 -351.305391) (xy 389.658538 -351.275908)
			(xy 389.708152 -351.253255) (xy 389.760484 -351.237893) (xy 389.81447 -351.230137) (xy 389.84174 -351.229676)
			(xy 390.70534 -351.229676) (xy 390.73261 -351.230089) (xy 390.786595 -351.237856) (xy 390.838925 -351.253227)
			(xy 390.888535 -351.275887) (xy 390.934415 -351.305377) (xy 390.975632 -351.341096) (xy 391.011347 -351.382317)
			(xy 391.040832 -351.4282) (xy 391.063487 -351.477813) (xy 391.078852 -351.530144) (xy 391.086614 -351.58413)
			(xy 391.086614 -351.638667) (xy 392.569462 -351.638667) (xy 392.569462 -351.584133) (xy 392.577223 -351.530155)
			(xy 392.592587 -351.477831) (xy 392.615241 -351.428226) (xy 392.644724 -351.382349) (xy 392.680436 -351.341136)
			(xy 392.721649 -351.305424) (xy 392.767526 -351.275941) (xy 392.817131 -351.253287) (xy 392.869455 -351.237923)
			(xy 392.923433 -351.230162) (xy 392.9507 -351.229676) (xy 393.8143 -351.229676) (xy 393.841572 -351.230087)
			(xy 393.895561 -351.237849) (xy 393.947896 -351.253216) (xy 393.997511 -351.275874) (xy 394.043396 -351.305363)
			(xy 394.084618 -351.341082) (xy 394.120337 -351.382304) (xy 394.149826 -351.428189) (xy 394.172484 -351.477804)
			(xy 394.187851 -351.530139) (xy 394.195613 -351.584128) (xy 394.195613 -351.638665) (xy 395.678462 -351.638665)
			(xy 395.678462 -351.584135) (xy 395.686222 -351.53016) (xy 395.701584 -351.477839) (xy 395.724235 -351.428237)
			(xy 395.753714 -351.382362) (xy 395.789421 -351.34115) (xy 395.83063 -351.305438) (xy 395.876502 -351.275954)
			(xy 395.926102 -351.253298) (xy 395.978421 -351.237931) (xy 396.032395 -351.230165) (xy 396.05966 -351.229676)
			(xy 396.92326 -351.229676) (xy 396.950536 -351.230061) (xy 397.004532 -351.237819) (xy 397.056875 -351.253183)
			(xy 397.106498 -351.275841) (xy 397.152391 -351.30533) (xy 397.19362 -351.341051) (xy 397.229346 -351.382277)
			(xy 397.25884 -351.428167) (xy 397.281503 -351.477788) (xy 397.296872 -351.530129) (xy 397.304636 -351.584124)
			(xy 397.304636 -351.638676) (xy 397.296872 -351.692671) (xy 397.281503 -351.745012) (xy 397.25884 -351.794633)
			(xy 397.229346 -351.840523) (xy 397.19362 -351.881749) (xy 397.152391 -351.91747) (xy 397.106498 -351.946959)
			(xy 397.056875 -351.969617) (xy 397.004532 -351.984981) (xy 396.950536 -351.992739) (xy 396.92326 -351.9932)
			(xy 396.05966 -351.9932) (xy 396.032395 -351.992635) (xy 395.978421 -351.984869) (xy 395.926102 -351.969502)
			(xy 395.876502 -351.946846) (xy 395.83063 -351.917362) (xy 395.789421 -351.88165) (xy 395.753714 -351.840438)
			(xy 395.724235 -351.794563) (xy 395.701584 -351.744961) (xy 395.686222 -351.69264) (xy 395.678462 -351.638665)
			(xy 394.195613 -351.638665) (xy 394.195613 -351.638672) (xy 394.187851 -351.692661) (xy 394.172484 -351.744996)
			(xy 394.149826 -351.794611) (xy 394.120337 -351.840496) (xy 394.084618 -351.881718) (xy 394.043396 -351.917437)
			(xy 393.997511 -351.946926) (xy 393.947896 -351.969584) (xy 393.895561 -351.984951) (xy 393.841572 -351.992713)
			(xy 393.8143 -351.9932) (xy 392.9507 -351.9932) (xy 392.923433 -351.992638) (xy 392.869455 -351.984877)
			(xy 392.817131 -351.969513) (xy 392.767526 -351.946859) (xy 392.721649 -351.917376) (xy 392.680436 -351.881664)
			(xy 392.644724 -351.840451) (xy 392.615241 -351.794574) (xy 392.592587 -351.744969) (xy 392.577223 -351.692645)
			(xy 392.569462 -351.638667) (xy 391.086614 -351.638667) (xy 391.086614 -351.63867) (xy 391.078852 -351.692656)
			(xy 391.063487 -351.744987) (xy 391.040832 -351.7946) (xy 391.011347 -351.840483) (xy 390.975632 -351.881704)
			(xy 390.934415 -351.917423) (xy 390.888535 -351.946913) (xy 390.838925 -351.969573) (xy 390.786595 -351.984944)
			(xy 390.73261 -351.992711) (xy 390.70534 -351.9932) (xy 389.84174 -351.9932) (xy 389.81447 -351.992663)
			(xy 389.760484 -351.984907) (xy 389.708152 -351.969545) (xy 389.658538 -351.946892) (xy 389.612654 -351.917409)
			(xy 389.571434 -351.881695) (xy 389.535715 -351.840478) (xy 389.506227 -351.794597) (xy 389.483569 -351.744986)
			(xy 389.468202 -351.692655) (xy 389.46044 -351.63867) (xy 388.536137 -351.63867) (xy 388.528378 -351.692641)
			(xy 388.513015 -351.744964) (xy 388.490363 -351.794567) (xy 388.460882 -351.840442) (xy 388.425174 -351.881655)
			(xy 388.383963 -351.917367) (xy 388.33809 -351.94685) (xy 388.288488 -351.969506) (xy 388.236167 -351.984872)
			(xy 388.182191 -351.992636) (xy 388.154926 -351.9932) (xy 387.291326 -351.9932) (xy 386.934456 -351.9932)
			(xy 386.924454 -351.993696) (xy 386.905978 -352.001363) (xy 386.891838 -352.015514) (xy 386.884187 -352.033998)
			(xy 386.883656 -352.044) (xy 386.883656 -352.172016) (xy 386.884672 -352.176842) (xy 386.887784 -352.193815)
			(xy 386.891092 -352.228167) (xy 386.891276 -352.245422) (xy 386.891077 -352.262677) (xy 386.887769 -352.297026)
			(xy 386.884672 -352.314002) (xy 386.883656 -352.318828) (xy 386.883656 -354.024692) (xy 386.884672 -354.029518)
			(xy 386.887785 -354.046491) (xy 386.891095 -354.080843) (xy 386.891276 -354.098098) (xy 386.891078 -354.115353)
			(xy 386.887772 -354.149703) (xy 386.884672 -354.166678) (xy 386.883656 -354.171504) (xy 386.883656 -354.29952)
			(xy 386.884147 -354.309528) (xy 386.891808 -354.328021) (xy 386.905959 -354.342178) (xy 386.924448 -354.349848)
			(xy 386.934456 -354.35032) (xy 387.59638 -354.35032) (xy 387.623653 -354.350782) (xy 387.677645 -354.358542)
			(xy 387.729982 -354.373908) (xy 387.7796 -354.396565) (xy 387.825489 -354.426054) (xy 387.866713 -354.461773)
			(xy 387.902434 -354.502995) (xy 387.931925 -354.548882) (xy 387.954585 -354.598499) (xy 387.969953 -354.650836)
			(xy 387.977716 -354.704827) (xy 387.977716 -354.759373) (xy 387.977716 -354.759374) (xy 389.460384 -354.759374)
			(xy 389.460384 -354.704826) (xy 389.468147 -354.650833) (xy 389.483516 -354.598495) (xy 389.506178 -354.548876)
			(xy 389.535671 -354.502989) (xy 389.571394 -354.461766) (xy 389.612621 -354.426047) (xy 389.658512 -354.396559)
			(xy 389.708132 -354.373902) (xy 389.760472 -354.358539) (xy 389.814466 -354.350781) (xy 389.84174 -354.35032)
			(xy 390.70534 -354.35032) (xy 390.732606 -354.350845) (xy 390.786583 -354.358611) (xy 390.838905 -354.373979)
			(xy 390.888508 -354.396637) (xy 390.934382 -354.426122) (xy 390.975593 -354.461836) (xy 391.011302 -354.50305)
			(xy 391.040783 -354.548927) (xy 391.063435 -354.598532) (xy 391.078797 -354.650856) (xy 391.086558 -354.704834)
			(xy 391.086558 -354.759366) (xy 391.086557 -354.759371) (xy 392.569406 -354.759371) (xy 392.569406 -354.704829)
			(xy 392.577169 -354.650843) (xy 392.592535 -354.598511) (xy 392.615192 -354.548899) (xy 392.644679 -354.503016)
			(xy 392.680396 -354.461796) (xy 392.721616 -354.426079) (xy 392.767499 -354.396592) (xy 392.817111 -354.373935)
			(xy 392.869443 -354.358569) (xy 392.923429 -354.350806) (xy 392.9507 -354.35032) (xy 393.8143 -354.35032)
			(xy 393.841568 -354.350842) (xy 393.895549 -354.358604) (xy 393.947876 -354.373968) (xy 393.997484 -354.396623)
			(xy 394.043363 -354.426108) (xy 394.084578 -354.461822) (xy 394.120292 -354.503037) (xy 394.149777 -354.548916)
			(xy 394.172432 -354.598524) (xy 394.187796 -354.650851) (xy 394.195558 -354.704832) (xy 394.195558 -354.759368)
			(xy 394.195558 -354.759369) (xy 395.678406 -354.759369) (xy 395.678406 -354.704831) (xy 395.686167 -354.650849)
			(xy 395.701531 -354.59852) (xy 395.724186 -354.54891) (xy 395.753669 -354.503029) (xy 395.789382 -354.46181)
			(xy 395.830597 -354.426093) (xy 395.876475 -354.396605) (xy 395.926082 -354.373945) (xy 395.978409 -354.358576)
			(xy 396.032391 -354.350809) (xy 396.05966 -354.35032) (xy 396.92326 -354.35032) (xy 396.950532 -354.350817)
			(xy 397.00452 -354.358574) (xy 397.056855 -354.373936) (xy 397.106471 -354.39659) (xy 397.152358 -354.426075)
			(xy 397.193581 -354.461791) (xy 397.229301 -354.50301) (xy 397.258791 -354.548894) (xy 397.28145 -354.598507)
			(xy 397.296818 -354.650841) (xy 397.30458 -354.704828) (xy 397.30458 -354.759372) (xy 397.30458 -354.759373)
			(xy 398.787284 -354.759373) (xy 398.787284 -354.704827) (xy 398.795047 -354.650836) (xy 398.810415 -354.598499)
			(xy 398.833075 -354.548882) (xy 398.862566 -354.502995) (xy 398.898287 -354.461773) (xy 398.939511 -354.426054)
			(xy 398.9854 -354.396565) (xy 399.035018 -354.373908) (xy 399.087355 -354.358542) (xy 399.141347 -354.350782)
			(xy 399.16862 -354.35032) (xy 400.03222 -354.35032) (xy 400.059487 -354.350844) (xy 400.113466 -354.358607)
			(xy 400.165791 -354.373974) (xy 400.215396 -354.39663) (xy 400.261272 -354.426115) (xy 400.302486 -354.461829)
			(xy 400.338197 -354.503044) (xy 400.36768 -354.548922) (xy 400.390333 -354.598528) (xy 400.405697 -354.650854)
			(xy 400.413458 -354.704833) (xy 400.413458 -354.759367) (xy 400.405697 -354.813346) (xy 400.390333 -354.865672)
			(xy 400.36768 -354.915278) (xy 400.338197 -354.961156) (xy 400.302486 -355.002371) (xy 400.261272 -355.038085)
			(xy 400.215396 -355.06757) (xy 400.165791 -355.090226) (xy 400.113466 -355.105593) (xy 400.059487 -355.113356)
			(xy 400.03222 -355.113844) (xy 399.16862 -355.113844) (xy 399.141347 -355.113418) (xy 399.087355 -355.105658)
			(xy 399.035018 -355.090292) (xy 398.9854 -355.067635) (xy 398.939511 -355.038146) (xy 398.898287 -355.002427)
			(xy 398.862566 -354.961205) (xy 398.833075 -354.915318) (xy 398.810415 -354.865701) (xy 398.795047 -354.813364)
			(xy 398.787284 -354.759373) (xy 397.30458 -354.759373) (xy 397.296818 -354.813359) (xy 397.28145 -354.865693)
			(xy 397.258791 -354.915306) (xy 397.229301 -354.96119) (xy 397.193581 -355.002409) (xy 397.152358 -355.038125)
			(xy 397.106471 -355.06761) (xy 397.056855 -355.090264) (xy 397.00452 -355.105626) (xy 396.950532 -355.113383)
			(xy 396.92326 -355.113844) (xy 396.05966 -355.113844) (xy 396.032391 -355.113391) (xy 395.978409 -355.105624)
			(xy 395.926082 -355.090255) (xy 395.876475 -355.067595) (xy 395.830597 -355.038107) (xy 395.789382 -355.00239)
			(xy 395.753669 -354.961171) (xy 395.724186 -354.91529) (xy 395.701531 -354.86568) (xy 395.686167 -354.813351)
			(xy 395.678406 -354.759369) (xy 394.195558 -354.759369) (xy 394.187796 -354.813349) (xy 394.172432 -354.865676)
			(xy 394.149777 -354.915284) (xy 394.120292 -354.961163) (xy 394.084578 -355.002378) (xy 394.043363 -355.038092)
			(xy 393.997484 -355.067577) (xy 393.947876 -355.090232) (xy 393.895549 -355.105596) (xy 393.841568 -355.113358)
			(xy 393.8143 -355.113844) (xy 392.9507 -355.113844) (xy 392.923429 -355.113394) (xy 392.869443 -355.105631)
			(xy 392.817111 -355.090265) (xy 392.767499 -355.067608) (xy 392.721616 -355.038121) (xy 392.680396 -355.002404)
			(xy 392.644679 -354.961184) (xy 392.615192 -354.915301) (xy 392.592535 -354.865689) (xy 392.577169 -354.813357)
			(xy 392.569406 -354.759371) (xy 391.086557 -354.759371) (xy 391.078797 -354.813344) (xy 391.063435 -354.865668)
			(xy 391.040783 -354.915273) (xy 391.011302 -354.96115) (xy 390.975593 -355.002364) (xy 390.934382 -355.038078)
			(xy 390.888508 -355.067563) (xy 390.838905 -355.090221) (xy 390.786583 -355.105589) (xy 390.732606 -355.113355)
			(xy 390.70534 -355.113844) (xy 389.84174 -355.113844) (xy 389.814466 -355.113419) (xy 389.760472 -355.105661)
			(xy 389.708132 -355.090298) (xy 389.658512 -355.067641) (xy 389.612621 -355.038153) (xy 389.571394 -355.002434)
			(xy 389.535671 -354.961211) (xy 389.506178 -354.915324) (xy 389.483516 -354.865705) (xy 389.468147 -354.813367)
			(xy 389.460384 -354.759374) (xy 387.977716 -354.759374) (xy 387.969953 -354.813364) (xy 387.954585 -354.865701)
			(xy 387.931925 -354.915318) (xy 387.902434 -354.961205) (xy 387.866713 -355.002427) (xy 387.825489 -355.038146)
			(xy 387.7796 -355.067635) (xy 387.729982 -355.090292) (xy 387.677645 -355.105658) (xy 387.623653 -355.113418)
			(xy 387.59638 -355.113844) (xy 386.934456 -355.113844) (xy 386.924457 -355.11434) (xy 386.905988 -355.122009)
			(xy 386.89186 -355.136162) (xy 386.884223 -355.154645) (xy 386.883656 -355.164644) (xy 386.883656 -355.29266)
			(xy 386.884672 -355.297486) (xy 386.887781 -355.31446) (xy 386.891085 -355.348811) (xy 386.891276 -355.366066)
			(xy 386.891075 -355.38332) (xy 386.887763 -355.417669) (xy 386.884672 -355.434646) (xy 386.883656 -355.439472)
			(xy 386.883656 -355.678232) (xy 386.884117 -355.688109) (xy 386.891559 -355.706408) (xy 386.898134 -355.713792)
			(xy 386.898388 -355.714046) (xy 388.969313 -357.784971) (xy 389.460432 -357.784971) (xy 389.460432 -357.730429)
			(xy 389.468194 -357.676443) (xy 389.483561 -357.624111) (xy 389.50622 -357.574499) (xy 389.535709 -357.528617)
			(xy 389.571428 -357.4874) (xy 389.61265 -357.451685) (xy 389.658535 -357.422201) (xy 389.708149 -357.399547)
			(xy 389.760482 -357.384186) (xy 389.814469 -357.376429) (xy 389.84174 -357.375968) (xy 390.70534 -357.375968)
			(xy 390.73261 -357.376397) (xy 390.786593 -357.384164) (xy 390.838922 -357.399534) (xy 390.888531 -357.422194)
			(xy 390.934411 -357.451684) (xy 390.975627 -357.487402) (xy 391.01134 -357.528622) (xy 391.040825 -357.574504)
			(xy 391.06348 -357.624116) (xy 391.078844 -357.676446) (xy 391.086606 -357.73043) (xy 391.086606 -357.784967)
			(xy 392.569454 -357.784967) (xy 392.569454 -357.730433) (xy 392.577215 -357.676453) (xy 392.59258 -357.624128)
			(xy 392.615234 -357.574522) (xy 392.644718 -357.528644) (xy 392.68043 -357.48743) (xy 392.721644 -357.451718)
			(xy 392.767522 -357.422234) (xy 392.817128 -357.39958) (xy 392.869453 -357.384215) (xy 392.923433 -357.376454)
			(xy 392.9507 -357.375968) (xy 393.8143 -357.375968) (xy 393.841572 -357.376395) (xy 393.895559 -357.384157)
			(xy 393.947893 -357.399523) (xy 393.997507 -357.422181) (xy 394.043392 -357.451669) (xy 394.084612 -357.487388)
			(xy 394.120331 -357.528608) (xy 394.149819 -357.574493) (xy 394.172477 -357.624107) (xy 394.187843 -357.676441)
			(xy 394.195605 -357.730428) (xy 394.195605 -357.784965) (xy 395.678454 -357.784965) (xy 395.678454 -357.730435)
			(xy 395.686214 -357.676459) (xy 395.701576 -357.624137) (xy 395.724228 -357.574533) (xy 395.753708 -357.528658)
			(xy 395.789416 -357.487444) (xy 395.830625 -357.451732) (xy 395.876498 -357.422247) (xy 395.926099 -357.39959)
			(xy 395.97842 -357.384223) (xy 396.032395 -357.376457) (xy 396.05966 -357.375968) (xy 396.92326 -357.375968)
			(xy 396.950535 -357.376369) (xy 397.00453 -357.384127) (xy 397.056872 -357.399491) (xy 397.106494 -357.422148)
			(xy 397.152386 -357.451637) (xy 397.193615 -357.487357) (xy 397.229339 -357.528582) (xy 397.258833 -357.574471)
			(xy 397.281495 -357.62409) (xy 397.296865 -357.67643) (xy 397.304628 -357.730425) (xy 397.304628 -357.78497)
			(xy 398.787331 -357.78497) (xy 398.787331 -357.73043) (xy 398.795094 -357.676446) (xy 398.81046 -357.624116)
			(xy 398.833117 -357.574505) (xy 398.862604 -357.528624) (xy 398.898321 -357.487407) (xy 398.93954 -357.451692)
			(xy 398.985423 -357.422207) (xy 399.035034 -357.399553) (xy 399.087365 -357.384189) (xy 399.14135 -357.37643)
			(xy 399.16862 -357.375968) (xy 400.03222 -357.375968) (xy 400.059491 -357.376396) (xy 400.113476 -357.38416)
			(xy 400.165807 -357.399529) (xy 400.215419 -357.422188) (xy 400.261301 -357.451677) (xy 400.30252 -357.487395)
			(xy 400.338235 -357.528615) (xy 400.367722 -357.574499) (xy 400.390378 -357.624111) (xy 400.405744 -357.676443)
			(xy 400.413506 -357.730429) (xy 400.413506 -357.784971) (xy 400.405744 -357.838957) (xy 400.390378 -357.891289)
			(xy 400.367722 -357.940901) (xy 400.338235 -357.986785) (xy 400.30252 -358.028005) (xy 400.261301 -358.063723)
			(xy 400.215419 -358.093212) (xy 400.165807 -358.115871) (xy 400.113476 -358.13124) (xy 400.059491 -358.139004)
			(xy 400.03222 -358.139492) (xy 399.16862 -358.139492) (xy 399.14135 -358.13897) (xy 399.087365 -358.131211)
			(xy 399.035034 -358.115847) (xy 398.985423 -358.093193) (xy 398.93954 -358.063708) (xy 398.898321 -358.027993)
			(xy 398.862604 -357.986776) (xy 398.833117 -357.940895) (xy 398.81046 -357.891284) (xy 398.795094 -357.838954)
			(xy 398.787331 -357.78497) (xy 397.304628 -357.78497) (xy 397.304628 -357.784975) (xy 397.296865 -357.83897)
			(xy 397.281495 -357.89131) (xy 397.258833 -357.940929) (xy 397.229339 -357.986818) (xy 397.193615 -358.028043)
			(xy 397.152386 -358.063763) (xy 397.106494 -358.093252) (xy 397.056872 -358.115909) (xy 397.00453 -358.131273)
			(xy 396.950535 -358.139031) (xy 396.92326 -358.139492) (xy 396.05966 -358.139492) (xy 396.032395 -358.138943)
			(xy 395.97842 -358.131177) (xy 395.926099 -358.11581) (xy 395.876498 -358.093153) (xy 395.830625 -358.063668)
			(xy 395.789416 -358.027956) (xy 395.753708 -357.986742) (xy 395.724228 -357.940867) (xy 395.701576 -357.891263)
			(xy 395.686214 -357.838941) (xy 395.678454 -357.784965) (xy 394.195605 -357.784965) (xy 394.195605 -357.784972)
			(xy 394.187843 -357.838959) (xy 394.172477 -357.891293) (xy 394.149819 -357.940907) (xy 394.120331 -357.986792)
			(xy 394.084612 -358.028012) (xy 394.043392 -358.063731) (xy 393.997507 -358.093219) (xy 393.947893 -358.115877)
			(xy 393.895559 -358.131243) (xy 393.841572 -358.139005) (xy 393.8143 -358.139492) (xy 392.9507 -358.139492)
			(xy 392.923433 -358.138946) (xy 392.869453 -358.131185) (xy 392.817128 -358.11582) (xy 392.767522 -358.093166)
			(xy 392.721644 -358.063682) (xy 392.68043 -358.02797) (xy 392.644718 -357.986756) (xy 392.615234 -357.940878)
			(xy 392.59258 -357.891272) (xy 392.577215 -357.838947) (xy 392.569454 -357.784967) (xy 391.086606 -357.784967)
			(xy 391.086606 -357.78497) (xy 391.078844 -357.838954) (xy 391.06348 -357.891284) (xy 391.040825 -357.940896)
			(xy 391.01134 -357.986778) (xy 390.975627 -358.027998) (xy 390.934411 -358.063716) (xy 390.888531 -358.093206)
			(xy 390.838922 -358.115866) (xy 390.786593 -358.131236) (xy 390.73261 -358.139003) (xy 390.70534 -358.139492)
			(xy 389.84174 -358.139492) (xy 389.814469 -358.138971) (xy 389.760482 -358.131214) (xy 389.708149 -358.115853)
			(xy 389.658535 -358.093199) (xy 389.61265 -358.063715) (xy 389.571428 -358.028) (xy 389.535709 -357.986783)
			(xy 389.50622 -357.940901) (xy 389.483561 -357.891289) (xy 389.468194 -357.838957) (xy 389.460432 -357.784971)
			(xy 388.969313 -357.784971) (xy 391.780014 -360.595672) (xy 391.787438 -360.60245) (xy 391.806035 -360.610043)
			(xy 391.816082 -360.610404) (xy 391.90041 -360.610404) (xy 391.926497 -360.610891) (xy 391.978029 -360.619058)
			(xy 392.027647 -360.63519) (xy 392.074129 -360.658889) (xy 392.116328 -360.68957) (xy 392.135106 -360.707686)
			(xy 400.761962 -369.334542) (xy 400.769361 -369.341385) (xy 400.78796 -369.349106) (xy 400.79803 -369.349528)
		)
		(stroke
			(width 0)
			(type solid)
		)
		(fill yes)
		(layer "In9.Cu")
		(net "GND")
	)
	(gr_poly
		(pts
			(xy 125.456188 -309.07609) (xy 125.481729 -309.064601) (xy 125.53534 -309.048405) (xy 125.590746 -309.040237)
			(xy 125.618748 -309.039768) (xy 125.646749 -309.040261) (xy 125.70215 -309.048437) (xy 125.755766 -309.064607)
			(xy 125.781308 -309.07609) (xy 125.791468 -309.080916) (xy 126.462028 -309.080916) (xy 126.472188 -309.07609)
			(xy 126.497729 -309.064601) (xy 126.55134 -309.048405) (xy 126.606746 -309.040237) (xy 126.634748 -309.039768)
			(xy 126.662749 -309.040261) (xy 126.71815 -309.048437) (xy 126.771766 -309.064607) (xy 126.797308 -309.07609)
			(xy 126.807468 -309.080916) (xy 127.478028 -309.080916) (xy 127.488188 -309.07609) (xy 127.513729 -309.064601)
			(xy 127.56734 -309.048405) (xy 127.622746 -309.040237) (xy 127.650748 -309.039768) (xy 127.678749 -309.040261)
			(xy 127.73415 -309.048437) (xy 127.787766 -309.064607) (xy 127.813308 -309.07609) (xy 127.823468 -309.080916)
			(xy 128.494028 -309.080916) (xy 128.504188 -309.07609) (xy 128.529729 -309.064601) (xy 128.58334 -309.048405)
			(xy 128.638746 -309.040237) (xy 128.666748 -309.039768) (xy 128.694749 -309.040261) (xy 128.75015 -309.048437)
			(xy 128.803766 -309.064607) (xy 128.829308 -309.07609) (xy 128.839468 -309.080916) (xy 129.510028 -309.080916)
			(xy 129.520188 -309.07609) (xy 129.545729 -309.064601) (xy 129.59934 -309.048405) (xy 129.654746 -309.040237)
			(xy 129.682748 -309.039768) (xy 129.710749 -309.040261) (xy 129.76615 -309.048437) (xy 129.819766 -309.064607)
			(xy 129.845308 -309.07609) (xy 129.855468 -309.080916) (xy 130.526028 -309.080916) (xy 130.536188 -309.07609)
			(xy 130.561729 -309.064601) (xy 130.61534 -309.048405) (xy 130.670746 -309.040237) (xy 130.698748 -309.039768)
			(xy 130.726749 -309.040261) (xy 130.78215 -309.048437) (xy 130.835766 -309.064607) (xy 130.861308 -309.07609)
			(xy 130.871468 -309.080916) (xy 131.542028 -309.080916) (xy 131.552188 -309.07609) (xy 131.577729 -309.064601)
			(xy 131.63134 -309.048405) (xy 131.686746 -309.040237) (xy 131.714748 -309.039768) (xy 131.742749 -309.040261)
			(xy 131.79815 -309.048437) (xy 131.851766 -309.064607) (xy 131.877308 -309.07609) (xy 131.887468 -309.080916)
			(xy 132.558028 -309.080916) (xy 132.568188 -309.07609) (xy 132.593729 -309.064601) (xy 132.64734 -309.048405)
			(xy 132.702746 -309.040237) (xy 132.730748 -309.039768) (xy 132.758749 -309.040261) (xy 132.81415 -309.048437)
			(xy 132.867766 -309.064607) (xy 132.893308 -309.07609) (xy 132.903468 -309.080916) (xy 133.574028 -309.080916)
			(xy 133.584188 -309.07609) (xy 133.609729 -309.064601) (xy 133.66334 -309.048405) (xy 133.718746 -309.040237)
			(xy 133.746748 -309.039768) (xy 133.774749 -309.040261) (xy 133.83015 -309.048437) (xy 133.883766 -309.064607)
			(xy 133.909308 -309.07609) (xy 133.919468 -309.080916) (xy 134.772654 -309.080916) (xy 134.782529 -309.08045)
			(xy 134.800819 -309.072999) (xy 134.808214 -309.066438) (xy 134.808468 -309.066184) (xy 137.376916 -306.497736)
			(xy 137.3802 -306.494325) (xy 137.385568 -306.486526) (xy 137.387584 -306.482242) (xy 137.739374 -305.689254)
			(xy 137.758459 -305.647542) (xy 137.803221 -305.567469) (xy 137.855151 -305.491848) (xy 137.91381 -305.421319)
			(xy 137.945876 -305.388518) (xy 141.39164 -301.942754) (xy 141.42025 -301.914698) (xy 141.481271 -301.86275)
			(xy 141.546266 -301.815869) (xy 141.614814 -301.774356) (xy 141.650466 -301.756064) (xy 141.658709 -301.751515)
			(xy 141.671345 -301.737574) (xy 141.678082 -301.720007) (xy 141.678406 -301.710598) (xy 141.678406 -284.487112)
			(xy 141.678058 -284.478381) (xy 141.672182 -284.461938) (xy 141.661084 -284.448457) (xy 141.653768 -284.443678)
			(xy 141.567408 -284.391862) (xy 141.540992 -284.391354) (xy 141.529054 -284.397704) (xy 141.50121 -284.411848)
			(xy 141.442063 -284.431882) (xy 141.380446 -284.442036) (xy 141.349222 -284.442662) (xy 141.343634 -284.442662)
			(xy 141.316643 -284.4418) (xy 141.263299 -284.433406) (xy 141.211672 -284.417574) (xy 141.162793 -284.39462)
			(xy 141.117639 -284.365002) (xy 141.077113 -284.329314) (xy 141.042024 -284.288267) (xy 141.013074 -284.242682)
			(xy 140.990841 -284.193471) (xy 140.97577 -284.141616) (xy 140.968162 -284.088154) (xy 140.967714 -284.061154)
			(xy 140.968203 -284.033906) (xy 140.975965 -283.979964) (xy 140.991325 -283.927676) (xy 141.013969 -283.878106)
			(xy 141.043437 -283.832263) (xy 141.079128 -283.79108) (xy 141.120318 -283.755396) (xy 141.166166 -283.725936)
			(xy 141.21574 -283.703301) (xy 141.268031 -283.687951) (xy 141.321973 -283.680199) (xy 141.349222 -283.679646)
			(xy 141.38045 -283.680243) (xy 141.442077 -283.690374) (xy 141.501224 -283.710427) (xy 141.529054 -283.724604)
			(xy 141.536943 -283.72841) (xy 141.554257 -283.730978) (xy 141.571424 -283.727564) (xy 141.579092 -283.723334)
			(xy 141.653768 -283.67863) (xy 141.661048 -283.673816) (xy 141.6721 -283.660323) (xy 141.678016 -283.643915)
			(xy 141.678406 -283.635196) (xy 141.678406 -273.41068) (xy 141.678173 -273.403727) (xy 141.67445 -273.390327)
			(xy 141.67104 -273.384264) (xy 141.628163 -273.313214) (xy 141.546775 -273.168571) (xy 141.470461 -273.021188)
			(xy 141.434566 -272.946368) (xy 141.394179 -272.860107) (xy 141.319481 -272.684871) (xy 141.251828 -272.506796)
			(xy 141.191327 -272.326165) (xy 141.138076 -272.143267) (xy 141.092159 -271.958391) (xy 141.053649 -271.771831)
			(xy 141.022606 -271.583884) (xy 141.010386 -271.489424) (xy 141.00937 -271.480788) (xy 141.002004 -271.465802)
			(xy 137.89025 -268.354048) (xy 137.883406 -268.346649) (xy 137.875683 -268.32805) (xy 137.875264 -268.31798)
			(xy 137.875264 -262.197342) (xy 137.87483 -262.187277) (xy 137.867096 -262.168691) (xy 137.860278 -262.161274)
			(xy 135.84682 -260.147816) (xy 135.8392 -260.129274) (xy 135.8392 -260.124956) (xy 135.591042 -259.876798)
			(xy 135.584191 -259.869401) (xy 135.576451 -259.850803) (xy 135.576056 -259.84073) (xy 135.576056 -253.587504)
			(xy 135.575632 -253.577434) (xy 135.567914 -253.558833) (xy 135.56107 -253.551436) (xy 132.234686 -250.225052)
			(xy 132.227289 -250.218202) (xy 132.208691 -250.210464) (xy 132.198618 -250.210066) (xy 130.518154 -250.210066)
			(xy 130.488944 -250.237498) (xy 130.487674 -250.257564) (xy 130.48535 -250.286259) (xy 130.473158 -250.342522)
			(xy 130.452651 -250.396314) (xy 130.424295 -250.446415) (xy 130.388734 -250.491686) (xy 130.346774 -250.531101)
			(xy 130.299369 -250.563765) (xy 130.247595 -250.588935) (xy 130.192627 -250.606041) (xy 130.135712 -250.614695)
			(xy 130.106928 -250.615196) (xy 130.080462 -250.614752) (xy 130.028038 -250.607448) (xy 129.977127 -250.592964)
			(xy 129.928709 -250.571577) (xy 129.883715 -250.543698) (xy 129.843009 -250.509864) (xy 129.807374 -250.470725)
			(xy 129.777496 -250.427033) (xy 129.753947 -250.379629) (xy 129.737182 -250.329423) (xy 129.727523 -250.277381)
			(xy 129.725928 -250.25096) (xy 129.724912 -250.230386) (xy 129.695702 -250.202446) (xy 129.160778 -250.202446)
			(xy 129.131568 -250.230386) (xy 129.130552 -250.25096) (xy 129.128878 -250.277355) (xy 129.119157 -250.329343)
			(xy 129.102349 -250.379491) (xy 129.078776 -250.426836) (xy 129.04889 -250.470472) (xy 129.013263 -250.509562)
			(xy 128.97258 -250.543357) (xy 128.927619 -250.571209) (xy 128.879241 -250.592585) (xy 128.828376 -250.607075)
			(xy 128.775996 -250.6144) (xy 128.749552 -250.614942) (xy 128.748282 -250.614942) (xy 128.717893 -250.614247)
			(xy 128.657912 -250.604403) (xy 128.60025 -250.585173) (xy 128.546367 -250.557045) (xy 128.497625 -250.52073)
			(xy 128.475994 -250.499372) (xy 128.47574 -250.499118) (xy 128.468628 -250.492006) (xy 128.441196 -250.479814)
			(xy 128.436247 -250.477709) (xy 128.425744 -250.475411) (xy 128.420368 -250.475242) (xy 128.367536 -250.475242)
			(xy 128.362238 -250.475379) (xy 128.351867 -250.477552) (xy 128.346962 -250.47956) (xy 128.31953 -250.491752)
			(xy 128.312164 -250.499118) (xy 128.31191 -250.499372) (xy 128.293884 -250.517313) (xy 128.253903 -250.548746)
			(xy 128.2101 -250.574587) (xy 128.163252 -250.594379) (xy 128.114188 -250.60777) (xy 128.063781 -250.614521)
			(xy 128.038352 -250.614942) (xy 128.033272 -250.614942) (xy 128.0287 -250.614942) (xy 128.000098 -250.613715)
			(xy 127.943727 -250.603746) (xy 127.889479 -250.585459) (xy 127.838577 -250.559264) (xy 127.792165 -250.525752)
			(xy 127.751286 -250.485676) (xy 127.71686 -250.439938) (xy 127.689661 -250.389565) (xy 127.670301 -250.335692)
			(xy 127.659215 -250.279529) (xy 127.657352 -250.25096) (xy 127.656336 -250.230386) (xy 127.627126 -250.202446)
			(xy 126.677928 -250.202446) (xy 126.677166 -250.201684) (xy 123.59132 -250.201684) (xy 123.590558 -250.202446)
			(xy 105.25125 -250.202446) (xy 105.242893 -250.202828) (xy 105.227084 -250.208271) (xy 105.220262 -250.213114)
			(xy 105.217214 -250.2154) (xy 105.215182 -250.217432) (xy 105.211791 -250.220551) (xy 105.204123 -250.225655)
			(xy 105.199942 -250.227592) (xy 105.199688 -250.227592) (xy 105.19029 -250.231656) (xy 95.705422 -250.231656)
			(xy 95.686626 -250.239276) (xy 95.679514 -250.246642) (xy 94.580456 -251.3457) (xy 123.339096 -251.3457)
			(xy 123.343167 -251.290078) (xy 123.355293 -251.235641) (xy 123.375216 -251.18355) (xy 123.402512 -251.134915)
			(xy 123.436598 -251.090772) (xy 123.476747 -251.052063) (xy 123.522105 -251.019612) (xy 123.571705 -250.994111)
			(xy 123.624489 -250.976104) (xy 123.679332 -250.965974) (xy 123.735066 -250.963937) (xy 123.790503 -250.970037)
			(xy 123.84446 -250.984143) (xy 123.895789 -251.005955) (xy 123.943395 -251.035009) (xy 123.986263 -251.070684)
			(xy 124.02348 -251.112221) (xy 124.054253 -251.158734) (xy 124.077925 -251.209231) (xy 124.093993 -251.262638)
			(xy 124.102113 -251.317814) (xy 124.102622 -251.3457) (xy 124.863096 -251.3457) (xy 124.867167 -251.290078)
			(xy 124.879293 -251.235641) (xy 124.899216 -251.18355) (xy 124.926512 -251.134915) (xy 124.960598 -251.090772)
			(xy 125.000747 -251.052063) (xy 125.046105 -251.019612) (xy 125.095705 -250.994111) (xy 125.148489 -250.976104)
			(xy 125.203332 -250.965974) (xy 125.259066 -250.963937) (xy 125.314503 -250.970037) (xy 125.36846 -250.984143)
			(xy 125.419789 -251.005955) (xy 125.467395 -251.035009) (xy 125.510263 -251.070684) (xy 125.54748 -251.112221)
			(xy 125.578253 -251.158734) (xy 125.601925 -251.209231) (xy 125.617993 -251.262638) (xy 125.626113 -251.317814)
			(xy 125.626622 -251.3457) (xy 125.626113 -251.373586) (xy 125.617993 -251.428762) (xy 125.601925 -251.482169)
			(xy 125.578253 -251.532666) (xy 125.54748 -251.579179) (xy 125.510263 -251.620716) (xy 125.467395 -251.656391)
			(xy 125.419789 -251.685445) (xy 125.36846 -251.707257) (xy 125.314503 -251.721363) (xy 125.259066 -251.727463)
			(xy 125.203332 -251.725426) (xy 125.148489 -251.715296) (xy 125.095705 -251.697289) (xy 125.046105 -251.671788)
			(xy 125.000747 -251.639337) (xy 124.960598 -251.600628) (xy 124.926512 -251.556485) (xy 124.899216 -251.50785)
			(xy 124.879293 -251.455759) (xy 124.867167 -251.401322) (xy 124.863096 -251.3457) (xy 124.102622 -251.3457)
			(xy 124.102113 -251.373586) (xy 124.093993 -251.428762) (xy 124.077925 -251.482169) (xy 124.054253 -251.532666)
			(xy 124.02348 -251.579179) (xy 123.986263 -251.620716) (xy 123.943395 -251.656391) (xy 123.895789 -251.685445)
			(xy 123.84446 -251.707257) (xy 123.790503 -251.721363) (xy 123.735066 -251.727463) (xy 123.679332 -251.725426)
			(xy 123.624489 -251.715296) (xy 123.571705 -251.697289) (xy 123.522105 -251.671788) (xy 123.476747 -251.639337)
			(xy 123.436598 -251.600628) (xy 123.402512 -251.556485) (xy 123.375216 -251.50785) (xy 123.355293 -251.455759)
			(xy 123.343167 -251.401322) (xy 123.339096 -251.3457) (xy 94.580456 -251.3457) (xy 93.813884 -252.112272)
			(xy 120.272554 -252.112272) (xy 120.276625 -252.05665) (xy 120.288751 -252.002213) (xy 120.308674 -251.950122)
			(xy 120.33597 -251.901487) (xy 120.370056 -251.857344) (xy 120.410205 -251.818635) (xy 120.455563 -251.786184)
			(xy 120.505163 -251.760683) (xy 120.557947 -251.742676) (xy 120.61279 -251.732546) (xy 120.668524 -251.730509)
			(xy 120.723961 -251.736609) (xy 120.777918 -251.750715) (xy 120.829247 -251.772527) (xy 120.876853 -251.801581)
			(xy 120.919721 -251.837256) (xy 120.956938 -251.878793) (xy 120.987711 -251.925306) (xy 121.011383 -251.975803)
			(xy 121.027451 -252.02921) (xy 121.035571 -252.084386) (xy 121.03608 -252.112272) (xy 121.035571 -252.140158)
			(xy 121.028984 -252.184916) (xy 132.344158 -252.184916) (xy 132.348229 -252.129294) (xy 132.360355 -252.074857)
			(xy 132.380278 -252.022766) (xy 132.407574 -251.974131) (xy 132.44166 -251.929988) (xy 132.481809 -251.891279)
			(xy 132.527167 -251.858828) (xy 132.576767 -251.833327) (xy 132.629551 -251.81532) (xy 132.684394 -251.80519)
			(xy 132.740128 -251.803153) (xy 132.795565 -251.809253) (xy 132.849522 -251.823359) (xy 132.900851 -251.845171)
			(xy 132.948457 -251.874225) (xy 132.991325 -251.9099) (xy 133.028542 -251.951437) (xy 133.059315 -251.99795)
			(xy 133.082987 -252.048447) (xy 133.099055 -252.101854) (xy 133.107175 -252.15703) (xy 133.107684 -252.184916)
			(xy 133.107175 -252.212802) (xy 133.099055 -252.267978) (xy 133.082987 -252.321385) (xy 133.059315 -252.371882)
			(xy 133.028542 -252.418395) (xy 132.991325 -252.459932) (xy 132.948457 -252.495607) (xy 132.900851 -252.524661)
			(xy 132.849522 -252.546473) (xy 132.795565 -252.560579) (xy 132.740128 -252.566679) (xy 132.684394 -252.564642)
			(xy 132.629551 -252.554512) (xy 132.576767 -252.536505) (xy 132.527167 -252.511004) (xy 132.481809 -252.478553)
			(xy 132.44166 -252.439844) (xy 132.407574 -252.395701) (xy 132.380278 -252.347066) (xy 132.360355 -252.294975)
			(xy 132.348229 -252.240538) (xy 132.344158 -252.184916) (xy 121.028984 -252.184916) (xy 121.027451 -252.195334)
			(xy 121.011383 -252.248741) (xy 120.987711 -252.299238) (xy 120.956938 -252.345751) (xy 120.919721 -252.387288)
			(xy 120.876853 -252.422963) (xy 120.829247 -252.452017) (xy 120.777918 -252.473829) (xy 120.723961 -252.487935)
			(xy 120.668524 -252.494035) (xy 120.61279 -252.491998) (xy 120.557947 -252.481868) (xy 120.505163 -252.463861)
			(xy 120.455563 -252.43836) (xy 120.410205 -252.405909) (xy 120.370056 -252.3672) (xy 120.33597 -252.323057)
			(xy 120.308674 -252.274422) (xy 120.288751 -252.222331) (xy 120.276625 -252.167894) (xy 120.272554 -252.112272)
			(xy 93.813884 -252.112272) (xy 93.432122 -252.494034) (xy 93.425278 -252.501433) (xy 93.417553 -252.520032)
			(xy 93.417136 -252.530102) (xy 93.417136 -253.10592) (xy 118.323612 -253.10592) (xy 118.327683 -253.050298)
			(xy 118.339809 -252.995861) (xy 118.359732 -252.94377) (xy 118.387028 -252.895135) (xy 118.421114 -252.850992)
			(xy 118.461263 -252.812283) (xy 118.506621 -252.779832) (xy 118.556221 -252.754331) (xy 118.609005 -252.736324)
			(xy 118.663848 -252.726194) (xy 118.719582 -252.724157) (xy 118.775019 -252.730257) (xy 118.828976 -252.744363)
			(xy 118.880305 -252.766175) (xy 118.927911 -252.795229) (xy 118.970779 -252.830904) (xy 119.007996 -252.872441)
			(xy 119.038769 -252.918954) (xy 119.062441 -252.969451) (xy 119.078509 -253.022858) (xy 119.086629 -253.078034)
			(xy 119.087138 -253.10592) (xy 119.086629 -253.133806) (xy 119.078509 -253.188982) (xy 119.062441 -253.242389)
			(xy 119.038769 -253.292886) (xy 119.007996 -253.339399) (xy 118.970779 -253.380936) (xy 118.962459 -253.38786)
			(xy 126.243078 -253.38786) (xy 126.247149 -253.332238) (xy 126.259275 -253.277801) (xy 126.279198 -253.22571)
			(xy 126.306494 -253.177075) (xy 126.34058 -253.132932) (xy 126.380729 -253.094223) (xy 126.426087 -253.061772)
			(xy 126.475687 -253.036271) (xy 126.528471 -253.018264) (xy 126.583314 -253.008134) (xy 126.639048 -253.006097)
			(xy 126.694485 -253.012197) (xy 126.748442 -253.026303) (xy 126.799771 -253.048115) (xy 126.847377 -253.077169)
			(xy 126.890245 -253.112844) (xy 126.927462 -253.154381) (xy 126.943461 -253.178564) (xy 128.285746 -253.178564)
			(xy 128.289817 -253.122942) (xy 128.301943 -253.068505) (xy 128.321866 -253.016414) (xy 128.349162 -252.967779)
			(xy 128.383248 -252.923636) (xy 128.423397 -252.884927) (xy 128.468755 -252.852476) (xy 128.518355 -252.826975)
			(xy 128.571139 -252.808968) (xy 128.625982 -252.798838) (xy 128.681716 -252.796801) (xy 128.737153 -252.802901)
			(xy 128.79111 -252.817007) (xy 128.842439 -252.838819) (xy 128.890045 -252.867873) (xy 128.932913 -252.903548)
			(xy 128.97013 -252.945085) (xy 129.000903 -252.991598) (xy 129.024575 -253.042095) (xy 129.040643 -253.095502)
			(xy 129.048763 -253.150678) (xy 129.049272 -253.178564) (xy 130.349242 -253.178564) (xy 130.353313 -253.122942)
			(xy 130.365439 -253.068505) (xy 130.385362 -253.016414) (xy 130.412658 -252.967779) (xy 130.446744 -252.923636)
			(xy 130.486893 -252.884927) (xy 130.532251 -252.852476) (xy 130.581851 -252.826975) (xy 130.634635 -252.808968)
			(xy 130.689478 -252.798838) (xy 130.745212 -252.796801) (xy 130.800649 -252.802901) (xy 130.854606 -252.817007)
			(xy 130.905935 -252.838819) (xy 130.953541 -252.867873) (xy 130.996409 -252.903548) (xy 131.033626 -252.945085)
			(xy 131.064399 -252.991598) (xy 131.088071 -253.042095) (xy 131.104139 -253.095502) (xy 131.112259 -253.150678)
			(xy 131.112768 -253.178564) (xy 131.112259 -253.20645) (xy 131.104139 -253.261626) (xy 131.088071 -253.315033)
			(xy 131.064399 -253.36553) (xy 131.033626 -253.412043) (xy 130.996409 -253.45358) (xy 130.953541 -253.489255)
			(xy 130.905935 -253.518309) (xy 130.854606 -253.540121) (xy 130.800649 -253.554227) (xy 130.745212 -253.560327)
			(xy 130.689478 -253.55829) (xy 130.634635 -253.54816) (xy 130.581851 -253.530153) (xy 130.532251 -253.504652)
			(xy 130.486893 -253.472201) (xy 130.446744 -253.433492) (xy 130.412658 -253.389349) (xy 130.385362 -253.340714)
			(xy 130.365439 -253.288623) (xy 130.353313 -253.234186) (xy 130.349242 -253.178564) (xy 129.049272 -253.178564)
			(xy 129.048763 -253.20645) (xy 129.040643 -253.261626) (xy 129.024575 -253.315033) (xy 129.000903 -253.36553)
			(xy 128.97013 -253.412043) (xy 128.932913 -253.45358) (xy 128.890045 -253.489255) (xy 128.842439 -253.518309)
			(xy 128.79111 -253.540121) (xy 128.737153 -253.554227) (xy 128.681716 -253.560327) (xy 128.625982 -253.55829)
			(xy 128.571139 -253.54816) (xy 128.518355 -253.530153) (xy 128.468755 -253.504652) (xy 128.423397 -253.472201)
			(xy 128.383248 -253.433492) (xy 128.349162 -253.389349) (xy 128.321866 -253.340714) (xy 128.301943 -253.288623)
			(xy 128.289817 -253.234186) (xy 128.285746 -253.178564) (xy 126.943461 -253.178564) (xy 126.958235 -253.200894)
			(xy 126.981907 -253.251391) (xy 126.997975 -253.304798) (xy 127.006095 -253.359974) (xy 127.006604 -253.38786)
			(xy 127.006095 -253.415746) (xy 126.997975 -253.470922) (xy 126.981907 -253.524329) (xy 126.958235 -253.574826)
			(xy 126.927462 -253.621339) (xy 126.890245 -253.662876) (xy 126.847377 -253.698551) (xy 126.799771 -253.727605)
			(xy 126.748442 -253.749417) (xy 126.694485 -253.763523) (xy 126.639048 -253.769623) (xy 126.583314 -253.767586)
			(xy 126.528471 -253.757456) (xy 126.475687 -253.739449) (xy 126.426087 -253.713948) (xy 126.380729 -253.681497)
			(xy 126.34058 -253.642788) (xy 126.306494 -253.598645) (xy 126.279198 -253.55001) (xy 126.259275 -253.497919)
			(xy 126.247149 -253.443482) (xy 126.243078 -253.38786) (xy 118.962459 -253.38786) (xy 118.927911 -253.416611)
			(xy 118.880305 -253.445665) (xy 118.828976 -253.467477) (xy 118.775019 -253.481583) (xy 118.719582 -253.487683)
			(xy 118.663848 -253.485646) (xy 118.609005 -253.475516) (xy 118.556221 -253.457509) (xy 118.506621 -253.432008)
			(xy 118.461263 -253.399557) (xy 118.421114 -253.360848) (xy 118.387028 -253.316705) (xy 118.359732 -253.26807)
			(xy 118.339809 -253.215979) (xy 118.327683 -253.161542) (xy 118.323612 -253.10592) (xy 93.417136 -253.10592)
			(xy 93.417136 -253.971298) (xy 93.417413 -253.978853) (xy 93.421797 -253.993315) (xy 93.425772 -253.999746)
			(xy 93.609768 -254.275082) (xy 95.830642 -254.275082) (xy 95.834713 -254.21946) (xy 95.846839 -254.165023)
			(xy 95.866762 -254.112932) (xy 95.894058 -254.064297) (xy 95.928144 -254.020154) (xy 95.968293 -253.981445)
			(xy 96.013651 -253.948994) (xy 96.063251 -253.923493) (xy 96.116035 -253.905486) (xy 96.170878 -253.895356)
			(xy 96.226612 -253.893319) (xy 96.282049 -253.899419) (xy 96.336006 -253.913525) (xy 96.387335 -253.935337)
			(xy 96.434941 -253.964391) (xy 96.477809 -254.000066) (xy 96.515026 -254.041603) (xy 96.545799 -254.088116)
			(xy 96.569471 -254.138613) (xy 96.577211 -254.164338) (xy 117.675912 -254.164338) (xy 117.679983 -254.108716)
			(xy 117.692109 -254.054279) (xy 117.712032 -254.002188) (xy 117.739328 -253.953553) (xy 117.773414 -253.90941)
			(xy 117.813563 -253.870701) (xy 117.858921 -253.83825) (xy 117.908521 -253.812749) (xy 117.961305 -253.794742)
			(xy 118.016148 -253.784612) (xy 118.071882 -253.782575) (xy 118.127319 -253.788675) (xy 118.181276 -253.802781)
			(xy 118.232605 -253.824593) (xy 118.280211 -253.853647) (xy 118.323079 -253.889322) (xy 118.360296 -253.930859)
			(xy 118.391069 -253.977372) (xy 118.394651 -253.985014) (xy 121.718576 -253.985014) (xy 121.722647 -253.929392)
			(xy 121.734773 -253.874955) (xy 121.754696 -253.822864) (xy 121.781992 -253.774229) (xy 121.816078 -253.730086)
			(xy 121.856227 -253.691377) (xy 121.901585 -253.658926) (xy 121.951185 -253.633425) (xy 122.003969 -253.615418)
			(xy 122.058812 -253.605288) (xy 122.114546 -253.603251) (xy 122.169983 -253.609351) (xy 122.22394 -253.623457)
			(xy 122.275269 -253.645269) (xy 122.322875 -253.674323) (xy 122.365743 -253.709998) (xy 122.40296 -253.751535)
			(xy 122.433733 -253.798048) (xy 122.457405 -253.848545) (xy 122.473473 -253.901952) (xy 122.481593 -253.957128)
			(xy 122.482102 -253.985014) (xy 122.481593 -254.0129) (xy 122.473473 -254.068076) (xy 122.457405 -254.121483)
			(xy 122.433733 -254.17198) (xy 122.418791 -254.194564) (xy 130.317746 -254.194564) (xy 130.321817 -254.138942)
			(xy 130.333943 -254.084505) (xy 130.353866 -254.032414) (xy 130.381162 -253.983779) (xy 130.415248 -253.939636)
			(xy 130.455397 -253.900927) (xy 130.500755 -253.868476) (xy 130.550355 -253.842975) (xy 130.603139 -253.824968)
			(xy 130.657982 -253.814838) (xy 130.713716 -253.812801) (xy 130.769153 -253.818901) (xy 130.82311 -253.833007)
			(xy 130.874439 -253.854819) (xy 130.922045 -253.883873) (xy 130.964913 -253.919548) (xy 131.00213 -253.961085)
			(xy 131.032903 -254.007598) (xy 131.056575 -254.058095) (xy 131.072643 -254.111502) (xy 131.080763 -254.166678)
			(xy 131.081272 -254.194564) (xy 131.080763 -254.22245) (xy 131.072643 -254.277626) (xy 131.056575 -254.331033)
			(xy 131.032903 -254.38153) (xy 131.00213 -254.428043) (xy 130.964913 -254.46958) (xy 130.922045 -254.505255)
			(xy 130.874439 -254.534309) (xy 130.82311 -254.556121) (xy 130.769153 -254.570227) (xy 130.713716 -254.576327)
			(xy 130.657982 -254.57429) (xy 130.603139 -254.56416) (xy 130.550355 -254.546153) (xy 130.500755 -254.520652)
			(xy 130.455397 -254.488201) (xy 130.415248 -254.449492) (xy 130.381162 -254.405349) (xy 130.353866 -254.356714)
			(xy 130.333943 -254.304623) (xy 130.321817 -254.250186) (xy 130.317746 -254.194564) (xy 122.418791 -254.194564)
			(xy 122.40296 -254.218493) (xy 122.365743 -254.26003) (xy 122.322875 -254.295705) (xy 122.275269 -254.324759)
			(xy 122.22394 -254.346571) (xy 122.169983 -254.360677) (xy 122.114546 -254.366777) (xy 122.058812 -254.36474)
			(xy 122.003969 -254.35461) (xy 121.951185 -254.336603) (xy 121.901585 -254.311102) (xy 121.856227 -254.278651)
			(xy 121.816078 -254.239942) (xy 121.781992 -254.195799) (xy 121.754696 -254.147164) (xy 121.734773 -254.095073)
			(xy 121.722647 -254.040636) (xy 121.718576 -253.985014) (xy 118.394651 -253.985014) (xy 118.414741 -254.027869)
			(xy 118.430809 -254.081276) (xy 118.438929 -254.136452) (xy 118.439438 -254.164338) (xy 118.438929 -254.192224)
			(xy 118.430809 -254.2474) (xy 118.414741 -254.300807) (xy 118.391069 -254.351304) (xy 118.360296 -254.397817)
			(xy 118.323079 -254.439354) (xy 118.280211 -254.475029) (xy 118.232605 -254.504083) (xy 118.181276 -254.525895)
			(xy 118.127319 -254.540001) (xy 118.071882 -254.546101) (xy 118.016148 -254.544064) (xy 117.961305 -254.533934)
			(xy 117.908521 -254.515927) (xy 117.858921 -254.490426) (xy 117.813563 -254.457975) (xy 117.773414 -254.419266)
			(xy 117.739328 -254.375123) (xy 117.712032 -254.326488) (xy 117.692109 -254.274397) (xy 117.679983 -254.21996)
			(xy 117.675912 -254.164338) (xy 96.577211 -254.164338) (xy 96.585539 -254.19202) (xy 96.593659 -254.247196)
			(xy 96.594168 -254.275082) (xy 96.593659 -254.302968) (xy 96.585539 -254.358144) (xy 96.569471 -254.411551)
			(xy 96.545799 -254.462048) (xy 96.515026 -254.508561) (xy 96.477809 -254.550098) (xy 96.434941 -254.585773)
			(xy 96.387335 -254.614827) (xy 96.336006 -254.636639) (xy 96.282049 -254.650745) (xy 96.226612 -254.656845)
			(xy 96.170878 -254.654808) (xy 96.116035 -254.644678) (xy 96.063251 -254.626671) (xy 96.013651 -254.60117)
			(xy 95.968293 -254.568719) (xy 95.928144 -254.53001) (xy 95.894058 -254.485867) (xy 95.866762 -254.437232)
			(xy 95.846839 -254.385141) (xy 95.834713 -254.330704) (xy 95.830642 -254.275082) (xy 93.609768 -254.275082)
			(xy 94.45642 -255.542034) (xy 96.209102 -255.542034) (xy 96.213173 -255.486412) (xy 96.225299 -255.431975)
			(xy 96.245222 -255.379884) (xy 96.272518 -255.331249) (xy 96.306604 -255.287106) (xy 96.346753 -255.248397)
			(xy 96.392111 -255.215946) (xy 96.441711 -255.190445) (xy 96.494495 -255.172438) (xy 96.549338 -255.162308)
			(xy 96.605072 -255.160271) (xy 96.660509 -255.166371) (xy 96.714466 -255.180477) (xy 96.765795 -255.202289)
			(xy 96.813401 -255.231343) (xy 96.821227 -255.237856) (xy 114.069019 -255.237856) (xy 114.069019 -255.183344)
			(xy 114.076777 -255.129387) (xy 114.092135 -255.077083) (xy 114.114781 -255.027497) (xy 114.144253 -254.981639)
			(xy 114.179952 -254.940442) (xy 114.22115 -254.904745) (xy 114.267009 -254.875274) (xy 114.316596 -254.85263)
			(xy 114.3689 -254.837274) (xy 114.422858 -254.829518) (xy 114.450114 -254.829056) (xy 114.481487 -254.829688)
			(xy 114.543386 -254.839967) (xy 114.602771 -254.860231) (xy 114.630708 -254.874522) (xy 114.64036 -254.879602)
			(xy 114.662204 -254.881126) (xy 114.754406 -254.846582) (xy 114.7699 -254.831342) (xy 114.77371 -254.820928)
			(xy 114.784422 -254.794132) (xy 114.812718 -254.743841) (xy 114.848266 -254.698384) (xy 114.890253 -254.6588)
			(xy 114.937724 -254.62599) (xy 114.989594 -254.600704) (xy 115.044681 -254.583519) (xy 115.101727 -254.574825)
			(xy 115.13058 -254.574294) (xy 115.157834 -254.574752) (xy 115.211787 -254.582507) (xy 115.264088 -254.597861)
			(xy 115.313671 -254.620503) (xy 115.359527 -254.64997) (xy 115.400722 -254.685664) (xy 115.436418 -254.726857)
			(xy 115.465888 -254.772712) (xy 115.488532 -254.822293) (xy 115.503889 -254.874593) (xy 115.511647 -254.928546)
			(xy 115.511647 -254.983054) (xy 115.503889 -255.037007) (xy 115.488532 -255.089307) (xy 115.465888 -255.138888)
			(xy 115.436418 -255.184743) (xy 115.432972 -255.18872) (xy 116.295422 -255.18872) (xy 116.299493 -255.133098)
			(xy 116.311619 -255.078661) (xy 116.331542 -255.02657) (xy 116.358838 -254.977935) (xy 116.392924 -254.933792)
			(xy 116.433073 -254.895083) (xy 116.478431 -254.862632) (xy 116.528031 -254.837131) (xy 116.580815 -254.819124)
			(xy 116.635658 -254.808994) (xy 116.691392 -254.806957) (xy 116.746829 -254.813057) (xy 116.800786 -254.827163)
			(xy 116.852115 -254.848975) (xy 116.899721 -254.878029) (xy 116.942589 -254.913704) (xy 116.979806 -254.955241)
			(xy 117.010579 -255.001754) (xy 117.034251 -255.052251) (xy 117.050319 -255.105658) (xy 117.051142 -255.11125)
			(xy 120.99366 -255.11125) (xy 120.997731 -255.055628) (xy 121.009857 -255.001191) (xy 121.02978 -254.9491)
			(xy 121.057076 -254.900465) (xy 121.091162 -254.856322) (xy 121.131311 -254.817613) (xy 121.176669 -254.785162)
			(xy 121.226269 -254.759661) (xy 121.279053 -254.741654) (xy 121.333896 -254.731524) (xy 121.38963 -254.729487)
			(xy 121.445067 -254.735587) (xy 121.499024 -254.749693) (xy 121.550353 -254.771505) (xy 121.597959 -254.800559)
			(xy 121.640827 -254.836234) (xy 121.678044 -254.877771) (xy 121.708817 -254.924284) (xy 121.732489 -254.974781)
			(xy 121.748557 -255.028188) (xy 121.756677 -255.083364) (xy 121.757186 -255.11125) (xy 121.756677 -255.139136)
			(xy 121.748557 -255.194312) (xy 121.743667 -255.210564) (xy 130.349242 -255.210564) (xy 130.353313 -255.154942)
			(xy 130.365439 -255.100505) (xy 130.385362 -255.048414) (xy 130.412658 -254.999779) (xy 130.446744 -254.955636)
			(xy 130.486893 -254.916927) (xy 130.532251 -254.884476) (xy 130.581851 -254.858975) (xy 130.634635 -254.840968)
			(xy 130.689478 -254.830838) (xy 130.745212 -254.828801) (xy 130.800649 -254.834901) (xy 130.854606 -254.849007)
			(xy 130.905935 -254.870819) (xy 130.953541 -254.899873) (xy 130.996409 -254.935548) (xy 131.033626 -254.977085)
			(xy 131.064399 -255.023598) (xy 131.088071 -255.074095) (xy 131.104139 -255.127502) (xy 131.112259 -255.182678)
			(xy 131.112768 -255.210564) (xy 131.112259 -255.23845) (xy 131.104139 -255.293626) (xy 131.088071 -255.347033)
			(xy 131.064399 -255.39753) (xy 131.033626 -255.444043) (xy 130.996409 -255.48558) (xy 130.953541 -255.521255)
			(xy 130.905935 -255.550309) (xy 130.854606 -255.572121) (xy 130.800649 -255.586227) (xy 130.745212 -255.592327)
			(xy 130.689478 -255.59029) (xy 130.634635 -255.58016) (xy 130.581851 -255.562153) (xy 130.532251 -255.536652)
			(xy 130.486893 -255.504201) (xy 130.446744 -255.465492) (xy 130.412658 -255.421349) (xy 130.385362 -255.372714)
			(xy 130.365439 -255.320623) (xy 130.353313 -255.266186) (xy 130.349242 -255.210564) (xy 121.743667 -255.210564)
			(xy 121.732489 -255.247719) (xy 121.708817 -255.298216) (xy 121.678044 -255.344729) (xy 121.640827 -255.386266)
			(xy 121.597959 -255.421941) (xy 121.550353 -255.450995) (xy 121.499024 -255.472807) (xy 121.445067 -255.486913)
			(xy 121.38963 -255.493013) (xy 121.333896 -255.490976) (xy 121.279053 -255.480846) (xy 121.226269 -255.462839)
			(xy 121.176669 -255.437338) (xy 121.131311 -255.404887) (xy 121.091162 -255.366178) (xy 121.057076 -255.322035)
			(xy 121.02978 -255.2734) (xy 121.009857 -255.221309) (xy 120.997731 -255.166872) (xy 120.99366 -255.11125)
			(xy 117.051142 -255.11125) (xy 117.058439 -255.160834) (xy 117.058948 -255.18872) (xy 117.058439 -255.216606)
			(xy 117.050319 -255.271782) (xy 117.034251 -255.325189) (xy 117.010579 -255.375686) (xy 116.979806 -255.422199)
			(xy 116.942589 -255.463736) (xy 116.899721 -255.499411) (xy 116.852115 -255.528465) (xy 116.800786 -255.550277)
			(xy 116.746829 -255.564383) (xy 116.691392 -255.570483) (xy 116.635658 -255.568446) (xy 116.580815 -255.558316)
			(xy 116.528031 -255.540309) (xy 116.478431 -255.514808) (xy 116.433073 -255.482357) (xy 116.392924 -255.443648)
			(xy 116.358838 -255.399505) (xy 116.331542 -255.35087) (xy 116.311619 -255.298779) (xy 116.299493 -255.244342)
			(xy 116.295422 -255.18872) (xy 115.432972 -255.18872) (xy 115.400722 -255.225936) (xy 115.359527 -255.26163)
			(xy 115.313671 -255.291097) (xy 115.264088 -255.313739) (xy 115.211787 -255.329093) (xy 115.157834 -255.336848)
			(xy 115.13058 -255.33731) (xy 115.099206 -255.336685) (xy 115.037307 -255.326403) (xy 114.977922 -255.306137)
			(xy 114.949986 -255.291844) (xy 114.940334 -255.286764) (xy 114.91849 -255.28524) (xy 114.826288 -255.319784)
			(xy 114.810794 -255.335024) (xy 114.806984 -255.345438) (xy 114.796259 -255.372229) (xy 114.767966 -255.422521)
			(xy 114.732422 -255.467979) (xy 114.690436 -255.507565) (xy 114.642967 -255.540375) (xy 114.591098 -255.565662)
			(xy 114.536012 -255.582848) (xy 114.478966 -255.591541) (xy 114.450114 -255.592072) (xy 114.422858 -255.591682)
			(xy 114.3689 -255.583926) (xy 114.316596 -255.56857) (xy 114.267009 -255.545926) (xy 114.22115 -255.516455)
			(xy 114.179952 -255.480758) (xy 114.144253 -255.439561) (xy 114.114781 -255.393703) (xy 114.092135 -255.344117)
			(xy 114.076777 -255.291813) (xy 114.069019 -255.237856) (xy 96.821227 -255.237856) (xy 96.856269 -255.267018)
			(xy 96.893486 -255.308555) (xy 96.924259 -255.355068) (xy 96.947931 -255.405565) (xy 96.963999 -255.458972)
			(xy 96.972119 -255.514148) (xy 96.972628 -255.542034) (xy 96.972119 -255.56992) (xy 96.963999 -255.625096)
			(xy 96.947931 -255.678503) (xy 96.924259 -255.729) (xy 96.893486 -255.775513) (xy 96.856269 -255.81705)
			(xy 96.816817 -255.849882) (xy 97.080322 -255.849882) (xy 97.084393 -255.79426) (xy 97.096519 -255.739823)
			(xy 97.116442 -255.687732) (xy 97.143738 -255.639097) (xy 97.177824 -255.594954) (xy 97.217973 -255.556245)
			(xy 97.263331 -255.523794) (xy 97.312931 -255.498293) (xy 97.365715 -255.480286) (xy 97.420558 -255.470156)
			(xy 97.476292 -255.468119) (xy 97.531729 -255.474219) (xy 97.585686 -255.488325) (xy 97.637015 -255.510137)
			(xy 97.684621 -255.539191) (xy 97.727489 -255.574866) (xy 97.764706 -255.616403) (xy 97.795479 -255.662916)
			(xy 97.819151 -255.713413) (xy 97.835219 -255.76682) (xy 97.843339 -255.821996) (xy 97.843848 -255.849882)
			(xy 97.843339 -255.877768) (xy 97.835219 -255.932944) (xy 97.819151 -255.986351) (xy 97.795479 -256.036848)
			(xy 97.764706 -256.083361) (xy 97.727489 -256.124898) (xy 97.684621 -256.160573) (xy 97.637015 -256.189627)
			(xy 97.585686 -256.211439) (xy 97.531729 -256.225545) (xy 97.522468 -256.226564) (xy 126.220472 -256.226564)
			(xy 126.224543 -256.170942) (xy 126.236669 -256.116505) (xy 126.256592 -256.064414) (xy 126.283888 -256.015779)
			(xy 126.317974 -255.971636) (xy 126.358123 -255.932927) (xy 126.403481 -255.900476) (xy 126.453081 -255.874975)
			(xy 126.505865 -255.856968) (xy 126.560708 -255.846838) (xy 126.616442 -255.844801) (xy 126.671879 -255.850901)
			(xy 126.725836 -255.865007) (xy 126.777165 -255.886819) (xy 126.824771 -255.915873) (xy 126.867639 -255.951548)
			(xy 126.904856 -255.993085) (xy 126.935629 -256.039598) (xy 126.959301 -256.090095) (xy 126.975369 -256.143502)
			(xy 126.983489 -256.198678) (xy 126.983998 -256.226564) (xy 128.285746 -256.226564) (xy 128.289817 -256.170942)
			(xy 128.301943 -256.116505) (xy 128.321866 -256.064414) (xy 128.349162 -256.015779) (xy 128.383248 -255.971636)
			(xy 128.423397 -255.932927) (xy 128.468755 -255.900476) (xy 128.518355 -255.874975) (xy 128.571139 -255.856968)
			(xy 128.625982 -255.846838) (xy 128.681716 -255.844801) (xy 128.737153 -255.850901) (xy 128.79111 -255.865007)
			(xy 128.842439 -255.886819) (xy 128.890045 -255.915873) (xy 128.932913 -255.951548) (xy 128.97013 -255.993085)
			(xy 129.000903 -256.039598) (xy 129.024575 -256.090095) (xy 129.040643 -256.143502) (xy 129.048763 -256.198678)
			(xy 129.049272 -256.226564) (xy 129.048763 -256.25445) (xy 129.040643 -256.309626) (xy 129.024575 -256.363033)
			(xy 129.000903 -256.41353) (xy 128.97013 -256.460043) (xy 128.932913 -256.50158) (xy 128.890045 -256.537255)
			(xy 128.842439 -256.566309) (xy 128.79111 -256.588121) (xy 128.737153 -256.602227) (xy 128.681716 -256.608327)
			(xy 128.625982 -256.60629) (xy 128.571139 -256.59616) (xy 128.518355 -256.578153) (xy 128.468755 -256.552652)
			(xy 128.423397 -256.520201) (xy 128.383248 -256.481492) (xy 128.349162 -256.437349) (xy 128.321866 -256.388714)
			(xy 128.301943 -256.336623) (xy 128.289817 -256.282186) (xy 128.285746 -256.226564) (xy 126.983998 -256.226564)
			(xy 126.983489 -256.25445) (xy 126.975369 -256.309626) (xy 126.959301 -256.363033) (xy 126.935629 -256.41353)
			(xy 126.904856 -256.460043) (xy 126.867639 -256.50158) (xy 126.824771 -256.537255) (xy 126.777165 -256.566309)
			(xy 126.725836 -256.588121) (xy 126.671879 -256.602227) (xy 126.616442 -256.608327) (xy 126.560708 -256.60629)
			(xy 126.505865 -256.59616) (xy 126.453081 -256.578153) (xy 126.403481 -256.552652) (xy 126.358123 -256.520201)
			(xy 126.317974 -256.481492) (xy 126.283888 -256.437349) (xy 126.256592 -256.388714) (xy 126.236669 -256.336623)
			(xy 126.224543 -256.282186) (xy 126.220472 -256.226564) (xy 97.522468 -256.226564) (xy 97.476292 -256.231645)
			(xy 97.420558 -256.229608) (xy 97.365715 -256.219478) (xy 97.312931 -256.201471) (xy 97.263331 -256.17597)
			(xy 97.217973 -256.143519) (xy 97.177824 -256.10481) (xy 97.143738 -256.060667) (xy 97.116442 -256.012032)
			(xy 97.096519 -255.959941) (xy 97.084393 -255.905504) (xy 97.080322 -255.849882) (xy 96.816817 -255.849882)
			(xy 96.813401 -255.852725) (xy 96.765795 -255.881779) (xy 96.714466 -255.903591) (xy 96.660509 -255.917697)
			(xy 96.605072 -255.923797) (xy 96.549338 -255.92176) (xy 96.494495 -255.91163) (xy 96.441711 -255.893623)
			(xy 96.392111 -255.868122) (xy 96.346753 -255.835671) (xy 96.306604 -255.796962) (xy 96.272518 -255.752819)
			(xy 96.245222 -255.704184) (xy 96.225299 -255.652093) (xy 96.213173 -255.597656) (xy 96.209102 -255.542034)
			(xy 94.45642 -255.542034) (xy 95.535783 -257.15722) (xy 96.764092 -257.15722) (xy 96.768163 -257.101598)
			(xy 96.780289 -257.047161) (xy 96.800212 -256.99507) (xy 96.827508 -256.946435) (xy 96.861594 -256.902292)
			(xy 96.901743 -256.863583) (xy 96.947101 -256.831132) (xy 96.996701 -256.805631) (xy 97.049485 -256.787624)
			(xy 97.104328 -256.777494) (xy 97.160062 -256.775457) (xy 97.215499 -256.781557) (xy 97.269456 -256.795663)
			(xy 97.320785 -256.817475) (xy 97.368391 -256.846529) (xy 97.411259 -256.882204) (xy 97.448476 -256.923741)
			(xy 97.479249 -256.970254) (xy 97.502921 -257.020751) (xy 97.518989 -257.074158) (xy 97.527109 -257.129334)
			(xy 97.527131 -257.13055) (xy 116.295422 -257.13055) (xy 116.299493 -257.074928) (xy 116.311619 -257.020491)
			(xy 116.331542 -256.9684) (xy 116.358838 -256.919765) (xy 116.392924 -256.875622) (xy 116.433073 -256.836913)
			(xy 116.478431 -256.804462) (xy 116.528031 -256.778961) (xy 116.580815 -256.760954) (xy 116.635658 -256.750824)
			(xy 116.691392 -256.748787) (xy 116.746829 -256.754887) (xy 116.800786 -256.768993) (xy 116.852115 -256.790805)
			(xy 116.899721 -256.819859) (xy 116.942589 -256.855534) (xy 116.979806 -256.897071) (xy 117.010579 -256.943584)
			(xy 117.034251 -256.994081) (xy 117.050319 -257.047488) (xy 117.058439 -257.102664) (xy 117.058674 -257.115564)
			(xy 128.285746 -257.115564) (xy 128.289817 -257.059942) (xy 128.301943 -257.005505) (xy 128.321866 -256.953414)
			(xy 128.349162 -256.904779) (xy 128.383248 -256.860636) (xy 128.423397 -256.821927) (xy 128.468755 -256.789476)
			(xy 128.518355 -256.763975) (xy 128.571139 -256.745968) (xy 128.625982 -256.735838) (xy 128.681716 -256.733801)
			(xy 128.737153 -256.739901) (xy 128.79111 -256.754007) (xy 128.842439 -256.775819) (xy 128.890045 -256.804873)
			(xy 128.932913 -256.840548) (xy 128.97013 -256.882085) (xy 129.000903 -256.928598) (xy 129.024575 -256.979095)
			(xy 129.040643 -257.032502) (xy 129.048763 -257.087678) (xy 129.049272 -257.115564) (xy 129.048763 -257.14345)
			(xy 129.040643 -257.198626) (xy 129.024575 -257.252033) (xy 129.000903 -257.30253) (xy 128.97013 -257.349043)
			(xy 128.932913 -257.39058) (xy 128.890045 -257.426255) (xy 128.842439 -257.455309) (xy 128.79111 -257.477121)
			(xy 128.737153 -257.491227) (xy 128.681716 -257.497327) (xy 128.625982 -257.49529) (xy 128.571139 -257.48516)
			(xy 128.518355 -257.467153) (xy 128.468755 -257.441652) (xy 128.423397 -257.409201) (xy 128.383248 -257.370492)
			(xy 128.349162 -257.326349) (xy 128.321866 -257.277714) (xy 128.301943 -257.225623) (xy 128.289817 -257.171186)
			(xy 128.285746 -257.115564) (xy 117.058674 -257.115564) (xy 117.058948 -257.13055) (xy 117.058439 -257.158436)
			(xy 117.050319 -257.213612) (xy 117.034251 -257.267019) (xy 117.010579 -257.317516) (xy 116.979806 -257.364029)
			(xy 116.942589 -257.405566) (xy 116.899721 -257.441241) (xy 116.852115 -257.470295) (xy 116.800786 -257.492107)
			(xy 116.746829 -257.506213) (xy 116.691392 -257.512313) (xy 116.635658 -257.510276) (xy 116.580815 -257.500146)
			(xy 116.528031 -257.482139) (xy 116.478431 -257.456638) (xy 116.433073 -257.424187) (xy 116.392924 -257.385478)
			(xy 116.358838 -257.341335) (xy 116.331542 -257.2927) (xy 116.311619 -257.240609) (xy 116.299493 -257.186172)
			(xy 116.295422 -257.13055) (xy 97.527131 -257.13055) (xy 97.527618 -257.15722) (xy 97.527109 -257.185106)
			(xy 97.518989 -257.240282) (xy 97.502921 -257.293689) (xy 97.479249 -257.344186) (xy 97.448476 -257.390699)
			(xy 97.411259 -257.432236) (xy 97.368391 -257.467911) (xy 97.320785 -257.496965) (xy 97.269456 -257.518777)
			(xy 97.215499 -257.532883) (xy 97.160062 -257.538983) (xy 97.104328 -257.536946) (xy 97.049485 -257.526816)
			(xy 96.996701 -257.508809) (xy 96.947101 -257.483308) (xy 96.901743 -257.450857) (xy 96.861594 -257.412148)
			(xy 96.827508 -257.368005) (xy 96.800212 -257.31937) (xy 96.780289 -257.267279) (xy 96.768163 -257.212842)
			(xy 96.764092 -257.15722) (xy 95.535783 -257.15722) (xy 96.71614 -258.923536) (xy 108.0897 -258.923536)
			(xy 108.090164 -258.896092) (xy 108.098019 -258.841769) (xy 108.113586 -258.789134) (xy 108.136543 -258.739277)
			(xy 108.166414 -258.693229) (xy 108.202583 -258.651943) (xy 108.2443 -258.616273) (xy 108.267246 -258.60121)
			(xy 108.278168 -258.594098) (xy 108.290868 -258.571492) (xy 108.29163 -258.46024) (xy 108.279438 -258.43738)
			(xy 108.26877 -258.430268) (xy 108.24645 -258.415055) (xy 108.205883 -258.379395) (xy 108.170755 -258.338366)
			(xy 108.141768 -258.292791) (xy 108.119503 -258.243581) (xy 108.104405 -258.191721) (xy 108.096776 -258.13825)
			(xy 108.096304 -258.111244) (xy 108.096796 -258.083992) (xy 108.104548 -258.030041) (xy 108.119899 -257.977743)
			(xy 108.142537 -257.928162) (xy 108.172001 -257.882308) (xy 108.207692 -257.841115) (xy 108.248883 -257.805421)
			(xy 108.294734 -257.775952) (xy 108.344313 -257.75331) (xy 108.39661 -257.737954) (xy 108.45056 -257.730199)
			(xy 108.477812 -257.729736) (xy 108.504128 -257.73019) (xy 108.556263 -257.737408) (xy 108.606911 -257.75172)
			(xy 108.655113 -257.772855) (xy 108.699955 -257.80041) (xy 108.740587 -257.833865) (xy 108.758736 -257.852926)
			(xy 108.766252 -257.860335) (xy 108.785536 -257.868858) (xy 108.796074 -257.869436) (xy 108.87075 -257.869436)
			(xy 108.881297 -257.868883) (xy 108.900591 -257.860363) (xy 108.908088 -257.852926) (xy 108.926234 -257.833857)
			(xy 108.966851 -257.800377) (xy 109.011689 -257.772805) (xy 109.059895 -257.751664) (xy 109.11055 -257.737358)
			(xy 109.162693 -257.730158) (xy 109.189012 -257.729736) (xy 109.215328 -257.73019) (xy 109.267463 -257.737408)
			(xy 109.318111 -257.75172) (xy 109.366313 -257.772855) (xy 109.411155 -257.80041) (xy 109.451787 -257.833865)
			(xy 109.469936 -257.852926) (xy 109.477452 -257.860335) (xy 109.496736 -257.868858) (xy 109.507274 -257.869436)
			(xy 109.58195 -257.869436) (xy 109.592497 -257.868883) (xy 109.611791 -257.860363) (xy 109.619288 -257.852926)
			(xy 109.637434 -257.833857) (xy 109.678051 -257.800377) (xy 109.722889 -257.772805) (xy 109.771095 -257.751664)
			(xy 109.82175 -257.737358) (xy 109.873893 -257.730158) (xy 109.900212 -257.729736) (xy 109.927467 -257.730144)
			(xy 109.981422 -257.737904) (xy 110.033724 -257.753263) (xy 110.083307 -257.775911) (xy 110.129162 -257.805384)
			(xy 110.170356 -257.841083) (xy 110.20605 -257.882282) (xy 110.235516 -257.928142) (xy 110.258156 -257.977728)
			(xy 110.270431 -258.01955) (xy 116.422932 -258.01955) (xy 116.423402 -257.992297) (xy 116.431153 -257.938344)
			(xy 116.446505 -257.886044) (xy 116.469144 -257.836461) (xy 116.498611 -257.790606) (xy 116.534304 -257.749411)
			(xy 116.575498 -257.713717) (xy 116.621352 -257.684249) (xy 116.670934 -257.661608) (xy 116.723234 -257.646255)
			(xy 116.777187 -257.638503) (xy 116.80444 -257.638042) (xy 116.831497 -257.638464) (xy 116.885066 -257.646128)
			(xy 116.937014 -257.661283) (xy 116.986301 -257.683624) (xy 117.031938 -257.712704) (xy 117.073009 -257.747939)
			(xy 117.108691 -257.788623) (xy 117.138267 -257.833939) (xy 117.150134 -257.85826) (xy 117.154198 -257.866642)
			(xy 117.167406 -257.879596) (xy 117.246908 -257.913886) (xy 117.26545 -257.914648) (xy 117.27434 -257.9116)
			(xy 117.30367 -257.902497) (xy 117.364286 -257.892662) (xy 117.39499 -257.892042) (xy 117.422247 -257.892404)
			(xy 117.476206 -257.900161) (xy 117.528512 -257.915518) (xy 117.5781 -257.938163) (xy 117.62396 -257.967635)
			(xy 117.66516 -258.003333) (xy 117.700859 -258.044532) (xy 117.730332 -258.090391) (xy 117.749135 -258.131564)
			(xy 126.258572 -258.131564) (xy 126.262643 -258.075942) (xy 126.274769 -258.021505) (xy 126.294692 -257.969414)
			(xy 126.321988 -257.920779) (xy 126.356074 -257.876636) (xy 126.396223 -257.837927) (xy 126.441581 -257.805476)
			(xy 126.491181 -257.779975) (xy 126.543965 -257.761968) (xy 126.598808 -257.751838) (xy 126.654542 -257.749801)
			(xy 126.709979 -257.755901) (xy 126.763936 -257.770007) (xy 126.815265 -257.791819) (xy 126.862871 -257.820873)
			(xy 126.905739 -257.856548) (xy 126.942956 -257.898085) (xy 126.973729 -257.944598) (xy 126.997401 -257.995095)
			(xy 127.013469 -258.048502) (xy 127.021589 -258.103678) (xy 127.022098 -258.131564) (xy 130.317746 -258.131564)
			(xy 130.321817 -258.075942) (xy 130.333943 -258.021505) (xy 130.353866 -257.969414) (xy 130.381162 -257.920779)
			(xy 130.415248 -257.876636) (xy 130.455397 -257.837927) (xy 130.500755 -257.805476) (xy 130.550355 -257.779975)
			(xy 130.603139 -257.761968) (xy 130.657982 -257.751838) (xy 130.713716 -257.749801) (xy 130.769153 -257.755901)
			(xy 130.82311 -257.770007) (xy 130.874439 -257.791819) (xy 130.922045 -257.820873) (xy 130.964913 -257.856548)
			(xy 131.00213 -257.898085) (xy 131.032903 -257.944598) (xy 131.056575 -257.995095) (xy 131.072643 -258.048502)
			(xy 131.080763 -258.103678) (xy 131.081272 -258.131564) (xy 131.080763 -258.15945) (xy 131.072643 -258.214626)
			(xy 131.056575 -258.268033) (xy 131.032903 -258.31853) (xy 131.00213 -258.365043) (xy 130.964913 -258.40658)
			(xy 130.922045 -258.442255) (xy 130.874439 -258.471309) (xy 130.82311 -258.493121) (xy 130.769153 -258.507227)
			(xy 130.713716 -258.513327) (xy 130.657982 -258.51129) (xy 130.603139 -258.50116) (xy 130.550355 -258.483153)
			(xy 130.500755 -258.457652) (xy 130.455397 -258.425201) (xy 130.415248 -258.386492) (xy 130.381162 -258.342349)
			(xy 130.353866 -258.293714) (xy 130.333943 -258.241623) (xy 130.321817 -258.187186) (xy 130.317746 -258.131564)
			(xy 127.022098 -258.131564) (xy 127.021589 -258.15945) (xy 127.013469 -258.214626) (xy 126.997401 -258.268033)
			(xy 126.973729 -258.31853) (xy 126.942956 -258.365043) (xy 126.905739 -258.40658) (xy 126.862871 -258.442255)
			(xy 126.815265 -258.471309) (xy 126.763936 -258.493121) (xy 126.709979 -258.507227) (xy 126.654542 -258.513327)
			(xy 126.598808 -258.51129) (xy 126.543965 -258.50116) (xy 126.491181 -258.483153) (xy 126.441581 -258.457652)
			(xy 126.396223 -258.425201) (xy 126.356074 -258.386492) (xy 126.321988 -258.342349) (xy 126.294692 -258.293714)
			(xy 126.274769 -258.241623) (xy 126.262643 -258.187186) (xy 126.258572 -258.131564) (xy 117.749135 -258.131564)
			(xy 117.752978 -258.139979) (xy 117.768337 -258.192284) (xy 117.776095 -258.246243) (xy 117.776095 -258.300757)
			(xy 117.768337 -258.354716) (xy 117.752978 -258.407021) (xy 117.730332 -258.456609) (xy 117.700859 -258.502468)
			(xy 117.66516 -258.543667) (xy 117.62396 -258.579365) (xy 117.5781 -258.608837) (xy 117.528512 -258.631482)
			(xy 117.476206 -258.646839) (xy 117.422247 -258.654596) (xy 117.39499 -258.655058) (xy 117.374442 -258.654758)
			(xy 117.333586 -258.650305) (xy 117.313456 -258.646168) (xy 117.301518 -258.643628) (xy 117.27815 -258.649724)
			(xy 117.198394 -258.720336) (xy 117.189504 -258.742688) (xy 117.19052 -258.75488) (xy 117.192298 -258.79044)
			(xy 117.191812 -258.817691) (xy 117.184056 -258.871639) (xy 117.168701 -258.923934) (xy 117.146059 -258.973511)
			(xy 117.116593 -259.019361) (xy 117.080902 -259.060552) (xy 117.039711 -259.096243) (xy 116.993861 -259.125709)
			(xy 116.944284 -259.148351) (xy 116.891989 -259.163706) (xy 116.838041 -259.171462) (xy 116.783539 -259.171462)
			(xy 116.729591 -259.163706) (xy 116.677296 -259.148351) (xy 116.627719 -259.125709) (xy 116.581869 -259.096243)
			(xy 116.540678 -259.060552) (xy 116.504987 -259.019361) (xy 116.475521 -258.973511) (xy 116.452879 -258.923934)
			(xy 116.437524 -258.871639) (xy 116.429768 -258.817691) (xy 116.429282 -258.79044) (xy 116.429857 -258.761315)
			(xy 116.438719 -258.703744) (xy 116.456227 -258.648188) (xy 116.481976 -258.595939) (xy 116.515366 -258.548209)
			(xy 116.555622 -258.506109) (xy 116.57838 -258.487926) (xy 116.587778 -258.48056) (xy 116.598192 -258.459224)
			(xy 116.59743 -258.354068) (xy 116.586762 -258.332986) (xy 116.576856 -258.325874) (xy 116.553429 -258.307703)
			(xy 116.511899 -258.265397) (xy 116.477407 -258.21718) (xy 116.450783 -258.16421) (xy 116.432668 -258.107762)
			(xy 116.423496 -258.049192) (xy 116.422932 -258.01955) (xy 110.270431 -258.01955) (xy 110.273508 -258.030032)
			(xy 110.28126 -258.083989) (xy 110.28172 -258.111244) (xy 110.281231 -258.138687) (xy 110.273379 -258.193009)
			(xy 110.257816 -258.245642) (xy 110.234863 -258.295499) (xy 110.204996 -258.341547) (xy 110.168831 -258.382834)
			(xy 110.127118 -258.418506) (xy 110.104174 -258.43357) (xy 110.093252 -258.440682) (xy 110.080552 -258.463288)
			(xy 110.07979 -258.57454) (xy 110.091982 -258.5974) (xy 110.10265 -258.604512) (xy 110.124965 -258.619731)
			(xy 110.165531 -258.655391) (xy 110.200659 -258.696419) (xy 110.229646 -258.741994) (xy 110.251912 -258.791202)
			(xy 110.267012 -258.84306) (xy 110.274642 -258.89653) (xy 110.275116 -258.923536) (xy 110.274656 -258.950788)
			(xy 110.266894 -259.004736) (xy 110.262245 -259.020564) (xy 112.290096 -259.020564) (xy 112.294167 -258.964942)
			(xy 112.306293 -258.910505) (xy 112.326216 -258.858414) (xy 112.353512 -258.809779) (xy 112.387598 -258.765636)
			(xy 112.427747 -258.726927) (xy 112.473105 -258.694476) (xy 112.522705 -258.668975) (xy 112.575489 -258.650968)
			(xy 112.630332 -258.640838) (xy 112.686066 -258.638801) (xy 112.741503 -258.644901) (xy 112.79546 -258.659007)
			(xy 112.846789 -258.680819) (xy 112.894395 -258.709873) (xy 112.937263 -258.745548) (xy 112.97448 -258.787085)
			(xy 113.005253 -258.833598) (xy 113.028925 -258.884095) (xy 113.044993 -258.937502) (xy 113.053113 -258.992678)
			(xy 113.053622 -259.020564) (xy 113.179096 -259.020564) (xy 113.183167 -258.964942) (xy 113.195293 -258.910505)
			(xy 113.215216 -258.858414) (xy 113.242512 -258.809779) (xy 113.276598 -258.765636) (xy 113.316747 -258.726927)
			(xy 113.362105 -258.694476) (xy 113.411705 -258.668975) (xy 113.464489 -258.650968) (xy 113.519332 -258.640838)
			(xy 113.575066 -258.638801) (xy 113.630503 -258.644901) (xy 113.68446 -258.659007) (xy 113.735789 -258.680819)
			(xy 113.783395 -258.709873) (xy 113.826263 -258.745548) (xy 113.86348 -258.787085) (xy 113.894253 -258.833598)
			(xy 113.917925 -258.884095) (xy 113.933993 -258.937502) (xy 113.942113 -258.992678) (xy 113.942622 -259.020564)
			(xy 113.942113 -259.04845) (xy 113.933993 -259.103626) (xy 113.917925 -259.157033) (xy 113.894253 -259.20753)
			(xy 113.86348 -259.254043) (xy 113.826263 -259.29558) (xy 113.783395 -259.331255) (xy 113.735789 -259.360309)
			(xy 113.68446 -259.382121) (xy 113.630503 -259.396227) (xy 113.575066 -259.402327) (xy 113.519332 -259.40029)
			(xy 113.464489 -259.39016) (xy 113.411705 -259.372153) (xy 113.362105 -259.346652) (xy 113.316747 -259.314201)
			(xy 113.276598 -259.275492) (xy 113.242512 -259.231349) (xy 113.215216 -259.182714) (xy 113.195293 -259.130623)
			(xy 113.183167 -259.076186) (xy 113.179096 -259.020564) (xy 113.053622 -259.020564) (xy 113.053113 -259.04845)
			(xy 113.044993 -259.103626) (xy 113.028925 -259.157033) (xy 113.005253 -259.20753) (xy 112.97448 -259.254043)
			(xy 112.937263 -259.29558) (xy 112.894395 -259.331255) (xy 112.846789 -259.360309) (xy 112.79546 -259.382121)
			(xy 112.741503 -259.396227) (xy 112.686066 -259.402327) (xy 112.630332 -259.40029) (xy 112.575489 -259.39016)
			(xy 112.522705 -259.372153) (xy 112.473105 -259.346652) (xy 112.427747 -259.314201) (xy 112.387598 -259.275492)
			(xy 112.353512 -259.231349) (xy 112.326216 -259.182714) (xy 112.306293 -259.130623) (xy 112.294167 -259.076186)
			(xy 112.290096 -259.020564) (xy 110.262245 -259.020564) (xy 110.251535 -259.057031) (xy 110.22889 -259.106608)
			(xy 110.199421 -259.152457) (xy 110.163727 -259.193647) (xy 110.122535 -259.229338) (xy 110.076683 -259.258804)
			(xy 110.027104 -259.281445) (xy 109.974809 -259.2968) (xy 109.92086 -259.304558) (xy 109.893608 -259.305044)
			(xy 109.867291 -259.304618) (xy 109.815157 -259.29739) (xy 109.764508 -259.283071) (xy 109.716307 -259.261931)
			(xy 109.671466 -259.234372) (xy 109.630834 -259.200915) (xy 109.612684 -259.181854) (xy 109.605163 -259.174451)
			(xy 109.585883 -259.165926) (xy 109.575346 -259.165344) (xy 109.50067 -259.165344) (xy 109.490121 -259.165884)
			(xy 109.470825 -259.17441) (xy 109.463332 -259.181854) (xy 109.445173 -259.200909) (xy 109.404559 -259.234391)
			(xy 109.359724 -259.261966) (xy 109.311521 -259.283109) (xy 109.260867 -259.297418) (xy 109.208726 -259.304621)
			(xy 109.182408 -259.305044) (xy 109.156091 -259.304618) (xy 109.103957 -259.29739) (xy 109.053308 -259.283071)
			(xy 109.005107 -259.261931) (xy 108.960266 -259.234372) (xy 108.919634 -259.200915) (xy 108.901484 -259.181854)
			(xy 108.893963 -259.174451) (xy 108.874683 -259.165926) (xy 108.864146 -259.165344) (xy 108.78947 -259.165344)
			(xy 108.778921 -259.165884) (xy 108.759625 -259.17441) (xy 108.752132 -259.181854) (xy 108.733973 -259.200909)
			(xy 108.693359 -259.234391) (xy 108.648524 -259.261966) (xy 108.600321 -259.283109) (xy 108.549667 -259.297418)
			(xy 108.497526 -259.304621) (xy 108.471208 -259.305044) (xy 108.443959 -259.304515) (xy 108.390014 -259.29676)
			(xy 108.337723 -259.281408) (xy 108.288148 -259.258771) (xy 108.242299 -259.229308) (xy 108.20111 -259.193622)
			(xy 108.165418 -259.152436) (xy 108.135951 -259.106591) (xy 108.113307 -259.057019) (xy 108.097949 -259.004729)
			(xy 108.090188 -258.950785) (xy 108.0897 -258.923536) (xy 96.71614 -258.923536) (xy 97.125039 -259.535422)
			(xy 114.207542 -259.535422) (xy 114.211613 -259.4798) (xy 114.223739 -259.425363) (xy 114.243662 -259.373272)
			(xy 114.270958 -259.324637) (xy 114.305044 -259.280494) (xy 114.345193 -259.241785) (xy 114.390551 -259.209334)
			(xy 114.440151 -259.183833) (xy 114.492935 -259.165826) (xy 114.547778 -259.155696) (xy 114.603512 -259.153659)
			(xy 114.658949 -259.159759) (xy 114.712906 -259.173865) (xy 114.755017 -259.19176) (xy 123.580396 -259.19176)
			(xy 123.584467 -259.136138) (xy 123.596593 -259.081701) (xy 123.616516 -259.02961) (xy 123.643812 -258.980975)
			(xy 123.677898 -258.936832) (xy 123.718047 -258.898123) (xy 123.763405 -258.865672) (xy 123.813005 -258.840171)
			(xy 123.865789 -258.822164) (xy 123.920632 -258.812034) (xy 123.976366 -258.809997) (xy 124.031803 -258.816097)
			(xy 124.08576 -258.830203) (xy 124.137089 -258.852015) (xy 124.184695 -258.881069) (xy 124.227563 -258.916744)
			(xy 124.26478 -258.958281) (xy 124.295553 -259.004794) (xy 124.319225 -259.055291) (xy 124.335293 -259.108698)
			(xy 124.341013 -259.147564) (xy 130.338828 -259.147564) (xy 130.342899 -259.091942) (xy 130.355025 -259.037505)
			(xy 130.374948 -258.985414) (xy 130.402244 -258.936779) (xy 130.43633 -258.892636) (xy 130.476479 -258.853927)
			(xy 130.521837 -258.821476) (xy 130.571437 -258.795975) (xy 130.624221 -258.777968) (xy 130.679064 -258.767838)
			(xy 130.734798 -258.765801) (xy 130.790235 -258.771901) (xy 130.844192 -258.786007) (xy 130.895521 -258.807819)
			(xy 130.943127 -258.836873) (xy 130.985995 -258.872548) (xy 131.023212 -258.914085) (xy 131.053985 -258.960598)
			(xy 131.077657 -259.011095) (xy 131.093725 -259.064502) (xy 131.101845 -259.119678) (xy 131.102354 -259.147564)
			(xy 131.101845 -259.17545) (xy 131.093725 -259.230626) (xy 131.077657 -259.284033) (xy 131.053985 -259.33453)
			(xy 131.023212 -259.381043) (xy 130.985995 -259.42258) (xy 130.943127 -259.458255) (xy 130.895521 -259.487309)
			(xy 130.844192 -259.509121) (xy 130.790235 -259.523227) (xy 130.734798 -259.529327) (xy 130.679064 -259.52729)
			(xy 130.624221 -259.51716) (xy 130.571437 -259.499153) (xy 130.521837 -259.473652) (xy 130.476479 -259.441201)
			(xy 130.43633 -259.402492) (xy 130.402244 -259.358349) (xy 130.374948 -259.309714) (xy 130.355025 -259.257623)
			(xy 130.342899 -259.203186) (xy 130.338828 -259.147564) (xy 124.341013 -259.147564) (xy 124.343413 -259.163874)
			(xy 124.343922 -259.19176) (xy 124.343413 -259.219646) (xy 124.335293 -259.274822) (xy 124.319225 -259.328229)
			(xy 124.295553 -259.378726) (xy 124.26478 -259.425239) (xy 124.227563 -259.466776) (xy 124.184695 -259.502451)
			(xy 124.137089 -259.531505) (xy 124.08576 -259.553317) (xy 124.031803 -259.567423) (xy 123.976366 -259.573523)
			(xy 123.920632 -259.571486) (xy 123.865789 -259.561356) (xy 123.813005 -259.543349) (xy 123.763405 -259.517848)
			(xy 123.718047 -259.485397) (xy 123.677898 -259.446688) (xy 123.643812 -259.402545) (xy 123.616516 -259.35391)
			(xy 123.596593 -259.301819) (xy 123.584467 -259.247382) (xy 123.580396 -259.19176) (xy 114.755017 -259.19176)
			(xy 114.764235 -259.195677) (xy 114.811841 -259.224731) (xy 114.854709 -259.260406) (xy 114.891926 -259.301943)
			(xy 114.922699 -259.348456) (xy 114.946371 -259.398953) (xy 114.962439 -259.45236) (xy 114.970559 -259.507536)
			(xy 114.971068 -259.535422) (xy 114.970559 -259.563308) (xy 114.962439 -259.618484) (xy 114.946371 -259.671891)
			(xy 114.922699 -259.722388) (xy 114.891926 -259.768901) (xy 114.854709 -259.810438) (xy 114.811841 -259.846113)
			(xy 114.764235 -259.875167) (xy 114.712906 -259.896979) (xy 114.658949 -259.911085) (xy 114.603512 -259.917185)
			(xy 114.547778 -259.915148) (xy 114.492935 -259.905018) (xy 114.440151 -259.887011) (xy 114.390551 -259.86151)
			(xy 114.345193 -259.829059) (xy 114.305044 -259.79035) (xy 114.270958 -259.746207) (xy 114.243662 -259.697572)
			(xy 114.223739 -259.645481) (xy 114.211613 -259.591044) (xy 114.207542 -259.535422) (xy 97.125039 -259.535422)
			(xy 97.884276 -260.671564) (xy 112.163096 -260.671564) (xy 112.167167 -260.615942) (xy 112.179293 -260.561505)
			(xy 112.199216 -260.509414) (xy 112.226512 -260.460779) (xy 112.260598 -260.416636) (xy 112.300747 -260.377927)
			(xy 112.346105 -260.345476) (xy 112.395705 -260.319975) (xy 112.448489 -260.301968) (xy 112.503332 -260.291838)
			(xy 112.559066 -260.289801) (xy 112.614503 -260.295901) (xy 112.66846 -260.310007) (xy 112.719789 -260.331819)
			(xy 112.767395 -260.360873) (xy 112.810263 -260.396548) (xy 112.84748 -260.438085) (xy 112.878253 -260.484598)
			(xy 112.901925 -260.535095) (xy 112.917993 -260.588502) (xy 112.926113 -260.643678) (xy 112.926622 -260.671564)
			(xy 112.926113 -260.69945) (xy 112.917993 -260.754626) (xy 112.901925 -260.808033) (xy 112.878253 -260.85853)
			(xy 112.84748 -260.905043) (xy 112.810263 -260.94658) (xy 112.767395 -260.982255) (xy 112.719789 -261.011309)
			(xy 112.66846 -261.033121) (xy 112.614503 -261.047227) (xy 112.559066 -261.053327) (xy 112.503332 -261.05129)
			(xy 112.448489 -261.04116) (xy 112.395705 -261.023153) (xy 112.346105 -260.997652) (xy 112.300747 -260.965201)
			(xy 112.260598 -260.926492) (xy 112.226512 -260.882349) (xy 112.199216 -260.833714) (xy 112.179293 -260.781623)
			(xy 112.167167 -260.727186) (xy 112.163096 -260.671564) (xy 97.884276 -260.671564) (xy 98.249212 -261.217664)
			(xy 114.140232 -261.217664) (xy 114.144303 -261.162042) (xy 114.156429 -261.107605) (xy 114.176352 -261.055514)
			(xy 114.203648 -261.006879) (xy 114.237734 -260.962736) (xy 114.277883 -260.924027) (xy 114.323241 -260.891576)
			(xy 114.372841 -260.866075) (xy 114.425625 -260.848068) (xy 114.480468 -260.837938) (xy 114.536202 -260.835901)
			(xy 114.591639 -260.842001) (xy 114.645596 -260.856107) (xy 114.696925 -260.877919) (xy 114.744531 -260.906973)
			(xy 114.787399 -260.942648) (xy 114.824616 -260.984185) (xy 114.855389 -261.030698) (xy 114.879061 -261.081195)
			(xy 114.895129 -261.134602) (xy 114.903249 -261.189778) (xy 114.903758 -261.217664) (xy 114.903249 -261.24555)
			(xy 114.895129 -261.300726) (xy 114.879061 -261.354133) (xy 114.855389 -261.40463) (xy 114.824616 -261.451143)
			(xy 114.787399 -261.49268) (xy 114.744531 -261.528355) (xy 114.696925 -261.557409) (xy 114.645596 -261.579221)
			(xy 114.591639 -261.593327) (xy 114.536202 -261.599427) (xy 114.480468 -261.59739) (xy 114.425625 -261.58726)
			(xy 114.372841 -261.569253) (xy 114.323241 -261.543752) (xy 114.277883 -261.511301) (xy 114.237734 -261.472592)
			(xy 114.203648 -261.428449) (xy 114.176352 -261.379814) (xy 114.156429 -261.327723) (xy 114.144303 -261.273286)
			(xy 114.140232 -261.217664) (xy 98.249212 -261.217664) (xy 99.242178 -262.703564) (xy 112.163096 -262.703564)
			(xy 112.167167 -262.647942) (xy 112.179293 -262.593505) (xy 112.199216 -262.541414) (xy 112.226512 -262.492779)
			(xy 112.260598 -262.448636) (xy 112.300747 -262.409927) (xy 112.346105 -262.377476) (xy 112.395705 -262.351975)
			(xy 112.448489 -262.333968) (xy 112.503332 -262.323838) (xy 112.559066 -262.321801) (xy 112.614503 -262.327901)
			(xy 112.66846 -262.342007) (xy 112.719789 -262.363819) (xy 112.767395 -262.392873) (xy 112.810263 -262.428548)
			(xy 112.84748 -262.470085) (xy 112.878253 -262.516598) (xy 112.901925 -262.567095) (xy 112.917993 -262.620502)
			(xy 112.926113 -262.675678) (xy 112.926622 -262.703564) (xy 112.926113 -262.73145) (xy 112.917993 -262.786626)
			(xy 112.901925 -262.840033) (xy 112.878253 -262.89053) (xy 112.84748 -262.937043) (xy 112.810263 -262.97858)
			(xy 112.767395 -263.014255) (xy 112.719789 -263.043309) (xy 112.66846 -263.065121) (xy 112.642667 -263.071864)
			(xy 116.382292 -263.071864) (xy 116.38285 -263.041885) (xy 116.392247 -262.982668) (xy 116.410789 -262.925649)
			(xy 116.438019 -262.872231) (xy 116.473268 -262.823728) (xy 116.494052 -262.802116) (xy 116.62664 -262.669528)
			(xy 116.633334 -262.662116) (xy 116.640969 -262.643685) (xy 116.640973 -262.623735) (xy 116.633346 -262.605301)
			(xy 116.62664 -262.5979) (xy 116.494052 -262.465312) (xy 116.473245 -262.443719) (xy 116.43799 -262.395217)
			(xy 116.41076 -262.341795) (xy 116.392227 -262.284769) (xy 116.382848 -262.225545) (xy 116.382292 -262.195564)
			(xy 116.382744 -262.168312) (xy 116.390506 -262.114363) (xy 116.405865 -262.062068) (xy 116.428511 -262.01249)
			(xy 116.457981 -261.96664) (xy 116.493676 -261.92545) (xy 116.534869 -261.889759) (xy 116.580722 -261.860293)
			(xy 116.630301 -261.837653) (xy 116.682598 -261.822298) (xy 116.736548 -261.814542) (xy 116.7638 -261.814056)
			(xy 116.793777 -261.814647) (xy 116.852992 -261.824038) (xy 116.910011 -261.842572) (xy 116.963429 -261.869795)
			(xy 117.011934 -261.905035) (xy 117.033548 -261.925816) (xy 117.154452 -262.046974) (xy 117.161878 -262.053782)
			(xy 117.180457 -262.061521) (xy 117.19052 -262.06196) (xy 117.815614 -262.06196) (xy 117.825685 -262.061552)
			(xy 117.844284 -262.05382) (xy 117.851682 -262.046974) (xy 118.015258 -261.883398) (xy 118.022086 -261.875988)
			(xy 118.029814 -261.857397) (xy 118.030244 -261.84733) (xy 118.030244 -261.13613) (xy 118.030759 -261.106157)
			(xy 118.04008 -261.046941) (xy 118.05856 -260.989916) (xy 118.085743 -260.936488) (xy 118.120957 -260.887976)
			(xy 118.14175 -260.866382) (xy 118.763796 -260.244336) (xy 118.785382 -260.223522) (xy 118.833887 -260.188268)
			(xy 118.887311 -260.16104) (xy 118.944338 -260.142508) (xy 119.003563 -260.133131) (xy 119.033544 -260.132576)
			(xy 123.254262 -260.132576) (xy 123.284239 -260.133185) (xy 123.343453 -260.14257) (xy 123.400472 -260.1611)
			(xy 123.453891 -260.188319) (xy 123.502396 -260.223557) (xy 123.52401 -260.244336) (xy 124.487361 -261.207758)
			(xy 131.570982 -261.207758) (xy 131.575053 -261.152136) (xy 131.587179 -261.097699) (xy 131.607102 -261.045608)
			(xy 131.634398 -260.996973) (xy 131.668484 -260.95283) (xy 131.708633 -260.914121) (xy 131.753991 -260.88167)
			(xy 131.803591 -260.856169) (xy 131.856375 -260.838162) (xy 131.911218 -260.828032) (xy 131.966952 -260.825995)
			(xy 132.022389 -260.832095) (xy 132.076346 -260.846201) (xy 132.127675 -260.868013) (xy 132.175281 -260.897067)
			(xy 132.218149 -260.932742) (xy 132.255366 -260.974279) (xy 132.286139 -261.020792) (xy 132.309811 -261.071289)
			(xy 132.325879 -261.124696) (xy 132.333999 -261.179872) (xy 132.334508 -261.207758) (xy 132.333999 -261.235644)
			(xy 132.325879 -261.29082) (xy 132.309811 -261.344227) (xy 132.286139 -261.394724) (xy 132.255366 -261.441237)
			(xy 132.218149 -261.482774) (xy 132.175281 -261.518449) (xy 132.127675 -261.547503) (xy 132.076346 -261.569315)
			(xy 132.022389 -261.583421) (xy 131.966952 -261.589521) (xy 131.911218 -261.587484) (xy 131.856375 -261.577354)
			(xy 131.803591 -261.559347) (xy 131.753991 -261.533846) (xy 131.708633 -261.501395) (xy 131.668484 -261.462686)
			(xy 131.634398 -261.418543) (xy 131.607102 -261.369908) (xy 131.587179 -261.317817) (xy 131.575053 -261.26338)
			(xy 131.570982 -261.207758) (xy 124.487361 -261.207758) (xy 125.094122 -261.814564) (xy 130.388104 -261.814564)
			(xy 130.392175 -261.758942) (xy 130.404301 -261.704505) (xy 130.424224 -261.652414) (xy 130.45152 -261.603779)
			(xy 130.485606 -261.559636) (xy 130.525755 -261.520927) (xy 130.571113 -261.488476) (xy 130.620713 -261.462975)
			(xy 130.673497 -261.444968) (xy 130.72834 -261.434838) (xy 130.784074 -261.432801) (xy 130.839511 -261.438901)
			(xy 130.893468 -261.453007) (xy 130.944797 -261.474819) (xy 130.992403 -261.503873) (xy 131.035271 -261.539548)
			(xy 131.072488 -261.581085) (xy 131.103261 -261.627598) (xy 131.126933 -261.678095) (xy 131.143001 -261.731502)
			(xy 131.151121 -261.786678) (xy 131.15163 -261.814564) (xy 131.151121 -261.84245) (xy 131.143001 -261.897626)
			(xy 131.126933 -261.951033) (xy 131.103261 -262.00153) (xy 131.072488 -262.048043) (xy 131.035271 -262.08958)
			(xy 130.992403 -262.125255) (xy 130.944797 -262.154309) (xy 130.893468 -262.176121) (xy 130.839511 -262.190227)
			(xy 130.784074 -262.196327) (xy 130.72834 -262.19429) (xy 130.673497 -262.18416) (xy 130.620713 -262.166153)
			(xy 130.571113 -262.140652) (xy 130.525755 -262.108201) (xy 130.485606 -262.069492) (xy 130.45152 -262.025349)
			(xy 130.424224 -261.976714) (xy 130.404301 -261.924623) (xy 130.392175 -261.870186) (xy 130.388104 -261.814564)
			(xy 125.094122 -261.814564) (xy 126.9492 -263.66978) (xy 126.956686 -263.676467) (xy 126.975242 -263.68406)
			(xy 126.985268 -263.684512) (xy 131.244594 -263.684512) (xy 131.274571 -263.68512) (xy 131.333784 -263.694508)
			(xy 131.390802 -263.71304) (xy 131.444221 -263.740258) (xy 131.492727 -263.775494) (xy 131.514342 -263.796272)
			(xy 141.19352 -273.47545) (xy 141.214322 -273.497047) (xy 141.249575 -273.54555) (xy 141.276804 -273.598971)
			(xy 141.295339 -273.655996) (xy 141.304722 -273.715218) (xy 141.30528 -273.745198) (xy 141.30528 -278.003)
			(xy 141.304679 -278.032977) (xy 141.295289 -278.092191) (xy 141.276756 -278.149209) (xy 141.249536 -278.202627)
			(xy 141.214299 -278.251133) (xy 141.19352 -278.272748) (xy 137.039096 -282.426918) (xy 137.032398 -282.434395)
			(xy 137.024812 -282.452958) (xy 137.024364 -282.462986) (xy 137.024364 -302.422052) (xy 137.023737 -302.452028)
			(xy 137.014354 -302.511241) (xy 136.995828 -302.568259) (xy 136.968614 -302.621678) (xy 136.933381 -302.670185)
			(xy 136.912604 -302.6918) (xy 135.494522 -304.109882) (xy 135.472916 -304.130657) (xy 135.424393 -304.165841)
			(xy 135.370965 -304.193006) (xy 135.313948 -304.211483) (xy 135.254743 -304.220819) (xy 135.224774 -304.221388)
			(xy 118.80596 -304.221388) (xy 118.795885 -304.221769) (xy 118.777286 -304.229518) (xy 118.769892 -304.236374)
			(xy 118.579138 -304.427382) (xy 118.557525 -304.448149) (xy 118.509004 -304.483334) (xy 118.455578 -304.5105)
			(xy 118.398562 -304.52898) (xy 118.339358 -304.538318) (xy 118.30939 -304.538888) (xy 118.282158 -304.538378)
			(xy 118.228249 -304.530626) (xy 118.175992 -304.515281) (xy 118.12645 -304.492657) (xy 118.080632 -304.463212)
			(xy 118.03947 -304.427547) (xy 118.003802 -304.386388) (xy 117.974355 -304.340571) (xy 117.951727 -304.291031)
			(xy 117.936379 -304.238774) (xy 117.928624 -304.184866) (xy 117.928136 -304.157634) (xy 117.928656 -304.127661)
			(xy 117.937976 -304.068446) (xy 117.956455 -304.01142) (xy 117.983637 -303.957992) (xy 118.01885 -303.909481)
			(xy 118.039642 -303.887886) (xy 118.24208 -303.685448) (xy 118.248819 -303.678061) (xy 118.256476 -303.659612)
			(xy 118.256486 -303.639636) (xy 118.248846 -303.621179) (xy 118.24208 -303.61382) (xy 118.039642 -303.411382)
			(xy 118.0189 -303.389746) (xy 117.983711 -303.341231) (xy 117.956539 -303.287811) (xy 117.938054 -303.230801)
			(xy 117.92871 -303.171601) (xy 117.928136 -303.141634) (xy 117.92864 -303.114401) (xy 117.936387 -303.060488)
			(xy 117.951728 -303.008226) (xy 117.974351 -302.958679) (xy 118.003795 -302.912857) (xy 118.039461 -302.871692)
			(xy 118.080622 -302.836021) (xy 118.126441 -302.806572) (xy 118.175985 -302.783944) (xy 118.228244 -302.768597)
			(xy 118.282157 -302.760843) (xy 118.30939 -302.76038) (xy 118.339363 -302.760901) (xy 118.398578 -302.770223)
			(xy 118.455602 -302.788703) (xy 118.50903 -302.815883) (xy 118.557543 -302.851095) (xy 118.579138 -302.871886)
			(xy 118.769892 -303.062894) (xy 118.777301 -303.069722) (xy 118.795893 -303.077449) (xy 118.80596 -303.07788)
			(xy 120.729756 -303.07788) (xy 120.74048 -303.077299) (xy 120.76004 -303.068489) (xy 120.767602 -303.060862)
			(xy 120.825514 -302.996854) (xy 120.832118 -302.976534) (xy 120.830848 -302.965612) (xy 120.829885 -302.955671)
			(xy 120.828869 -302.935722) (xy 120.828816 -302.925734) (xy 120.829298 -302.898364) (xy 120.837111 -302.844186)
			(xy 120.852597 -302.791683) (xy 120.875435 -302.741936) (xy 120.905156 -302.695968) (xy 120.922796 -302.675036)
			(xy 120.928892 -302.667924) (xy 120.935242 -302.650906) (xy 120.935242 -302.565562) (xy 120.928892 -302.548544)
			(xy 120.922796 -302.541432) (xy 120.905158 -302.520499) (xy 120.875446 -302.474527) (xy 120.85261 -302.424779)
			(xy 120.837119 -302.372279) (xy 120.82929 -302.318103) (xy 120.828816 -302.290734) (xy 120.829302 -302.263483)
			(xy 120.837058 -302.209535) (xy 120.852413 -302.15724) (xy 120.875055 -302.107663) (xy 120.904521 -302.061813)
			(xy 120.940212 -302.020622) (xy 120.981403 -301.984931) (xy 121.027253 -301.955465) (xy 121.07683 -301.932823)
			(xy 121.129125 -301.917468) (xy 121.183073 -301.909712) (xy 121.237575 -301.909712) (xy 121.291523 -301.917468)
			(xy 121.343818 -301.932823) (xy 121.393395 -301.955465) (xy 121.439245 -301.984931) (xy 121.480436 -302.020622)
			(xy 121.516127 -302.061813) (xy 121.545593 -302.107663) (xy 121.568235 -302.15724) (xy 121.58359 -302.209535)
			(xy 121.591346 -302.263483) (xy 121.591832 -302.290734) (xy 121.591402 -302.318106) (xy 121.583578 -302.372287)
			(xy 121.568082 -302.424791) (xy 121.545231 -302.474538) (xy 121.515498 -302.520502) (xy 121.497852 -302.541432)
			(xy 121.491756 -302.548544) (xy 121.485406 -302.565562) (xy 121.485406 -302.650906) (xy 121.491756 -302.667924)
			(xy 121.497852 -302.675036) (xy 121.515467 -302.695988) (xy 121.545184 -302.741954) (xy 121.568026 -302.791697)
			(xy 121.583522 -302.844193) (xy 121.591355 -302.898366) (xy 121.591832 -302.925734) (xy 121.59178 -302.935722)
			(xy 121.590766 -302.955671) (xy 121.5898 -302.965612) (xy 121.58853 -302.976534) (xy 121.595134 -302.996854)
			(xy 121.653046 -303.060862) (xy 121.660537 -303.068586) (xy 121.680143 -303.077403) (xy 121.690892 -303.07788)
			(xy 124.149866 -303.07788) (xy 124.16059 -303.077304) (xy 124.18015 -303.068491) (xy 124.187712 -303.060862)
			(xy 124.245624 -302.996854) (xy 124.252228 -302.976534) (xy 124.250958 -302.965612) (xy 124.249995 -302.955671)
			(xy 124.248979 -302.935722) (xy 124.248926 -302.925734) (xy 124.249406 -302.898364) (xy 124.257219 -302.844185)
			(xy 124.272705 -302.791682) (xy 124.295544 -302.741935) (xy 124.325266 -302.695968) (xy 124.342906 -302.675036)
			(xy 124.349002 -302.667924) (xy 124.355352 -302.650906) (xy 124.355352 -302.565562) (xy 124.349002 -302.548544)
			(xy 124.342906 -302.541432) (xy 124.325269 -302.520498) (xy 124.295557 -302.474526) (xy 124.27272 -302.424779)
			(xy 124.257229 -302.372279) (xy 124.2494 -302.318103) (xy 124.248926 -302.290734) (xy 124.249412 -302.263483)
			(xy 124.257168 -302.209535) (xy 124.272523 -302.15724) (xy 124.295165 -302.107663) (xy 124.324631 -302.061813)
			(xy 124.360322 -302.020622) (xy 124.401513 -301.984931) (xy 124.447363 -301.955465) (xy 124.49694 -301.932823)
			(xy 124.549235 -301.917468) (xy 124.603183 -301.909712) (xy 124.657685 -301.909712) (xy 124.711633 -301.917468)
			(xy 124.763928 -301.932823) (xy 124.813505 -301.955465) (xy 124.859355 -301.984931) (xy 124.900546 -302.020622)
			(xy 124.936237 -302.061813) (xy 124.965703 -302.107663) (xy 124.988345 -302.15724) (xy 125.0037 -302.209535)
			(xy 125.011456 -302.263483) (xy 125.011942 -302.290734) (xy 125.01151 -302.318106) (xy 125.003686 -302.372287)
			(xy 124.98819 -302.424791) (xy 124.96534 -302.474537) (xy 124.935607 -302.520502) (xy 124.917962 -302.541432)
			(xy 124.911866 -302.548544) (xy 124.905516 -302.565562) (xy 124.905516 -302.650906) (xy 124.911866 -302.667924)
			(xy 124.917962 -302.675036) (xy 124.935579 -302.695986) (xy 124.965295 -302.741953) (xy 124.988136 -302.791696)
			(xy 125.003632 -302.844193) (xy 125.011465 -302.898366) (xy 125.011942 -302.925734) (xy 125.01189 -302.935722)
			(xy 125.010876 -302.955671) (xy 125.00991 -302.965612) (xy 125.00864 -302.976534) (xy 125.015244 -302.996854)
			(xy 125.073156 -303.060862) (xy 125.080643 -303.06859) (xy 125.100252 -303.077405) (xy 125.111002 -303.07788)
			(xy 125.537976 -303.07788) (xy 125.548701 -303.077309) (xy 125.568261 -303.068492) (xy 125.575822 -303.060862)
			(xy 125.633734 -302.996854) (xy 125.640338 -302.976534) (xy 125.639068 -302.965612) (xy 125.638105 -302.955671)
			(xy 125.637089 -302.935722) (xy 125.637036 -302.925734) (xy 125.637513 -302.898364) (xy 125.645327 -302.844185)
			(xy 125.660813 -302.791682) (xy 125.683652 -302.741935) (xy 125.713375 -302.695968) (xy 125.731016 -302.675036)
			(xy 125.737112 -302.667924) (xy 125.743462 -302.650906) (xy 125.743462 -302.565562) (xy 125.737112 -302.548544)
			(xy 125.731016 -302.541432) (xy 125.713381 -302.520497) (xy 125.683668 -302.474525) (xy 125.660831 -302.424778)
			(xy 125.645339 -302.372278) (xy 125.63751 -302.318103) (xy 125.637036 -302.290734) (xy 125.637522 -302.263483)
			(xy 125.645278 -302.209535) (xy 125.660633 -302.15724) (xy 125.683275 -302.107663) (xy 125.712741 -302.061813)
			(xy 125.748432 -302.020622) (xy 125.789623 -301.984931) (xy 125.835473 -301.955465) (xy 125.88505 -301.932823)
			(xy 125.937345 -301.917468) (xy 125.991293 -301.909712) (xy 126.045795 -301.909712) (xy 126.099743 -301.917468)
			(xy 126.152038 -301.932823) (xy 126.201615 -301.955465) (xy 126.247465 -301.984931) (xy 126.288656 -302.020622)
			(xy 126.324347 -302.061813) (xy 126.353813 -302.107663) (xy 126.376455 -302.15724) (xy 126.39181 -302.209535)
			(xy 126.399566 -302.263483) (xy 126.400052 -302.290734) (xy 126.399618 -302.318106) (xy 126.391794 -302.372286)
			(xy 126.376298 -302.42479) (xy 126.353449 -302.474537) (xy 126.323717 -302.520502) (xy 126.306072 -302.541432)
			(xy 126.299976 -302.548544) (xy 126.293626 -302.565562) (xy 126.293626 -302.650906) (xy 126.299976 -302.667924)
			(xy 126.306072 -302.675036) (xy 126.32369 -302.695985) (xy 126.353406 -302.741953) (xy 126.376247 -302.791696)
			(xy 126.391742 -302.844193) (xy 126.399576 -302.898366) (xy 126.400052 -302.925734) (xy 126.4 -302.935722)
			(xy 126.398986 -302.955671) (xy 126.39802 -302.965612) (xy 126.39675 -302.976534) (xy 126.403354 -302.996854)
			(xy 126.461266 -303.060862) (xy 126.46875 -303.068595) (xy 126.488361 -303.077407) (xy 126.499112 -303.07788)
			(xy 127.569976 -303.07788) (xy 127.580701 -303.077309) (xy 127.600261 -303.068492) (xy 127.607822 -303.060862)
			(xy 127.665734 -302.996854) (xy 127.672338 -302.976534) (xy 127.671068 -302.965612) (xy 127.670105 -302.955671)
			(xy 127.669089 -302.935722) (xy 127.669036 -302.925734) (xy 127.669513 -302.898364) (xy 127.677327 -302.844185)
			(xy 127.692813 -302.791682) (xy 127.715652 -302.741935) (xy 127.745375 -302.695968) (xy 127.763016 -302.675036)
			(xy 127.769112 -302.667924) (xy 127.775462 -302.650906) (xy 127.775462 -302.565562) (xy 127.769112 -302.548544)
			(xy 127.763016 -302.541432) (xy 127.745381 -302.520497) (xy 127.715668 -302.474525) (xy 127.692831 -302.424778)
			(xy 127.677339 -302.372278) (xy 127.66951 -302.318103) (xy 127.669036 -302.290734) (xy 127.669522 -302.263483)
			(xy 127.677278 -302.209535) (xy 127.692633 -302.15724) (xy 127.715275 -302.107663) (xy 127.744741 -302.061813)
			(xy 127.780432 -302.020622) (xy 127.821623 -301.984931) (xy 127.867473 -301.955465) (xy 127.91705 -301.932823)
			(xy 127.969345 -301.917468) (xy 128.023293 -301.909712) (xy 128.077795 -301.909712) (xy 128.131743 -301.917468)
			(xy 128.184038 -301.932823) (xy 128.233615 -301.955465) (xy 128.279465 -301.984931) (xy 128.320656 -302.020622)
			(xy 128.356347 -302.061813) (xy 128.385813 -302.107663) (xy 128.408455 -302.15724) (xy 128.42381 -302.209535)
			(xy 128.431566 -302.263483) (xy 128.432052 -302.290734) (xy 128.431618 -302.318106) (xy 128.423794 -302.372286)
			(xy 128.408298 -302.42479) (xy 128.385449 -302.474537) (xy 128.355717 -302.520502) (xy 128.338072 -302.541432)
			(xy 128.331976 -302.548544) (xy 128.325626 -302.565562) (xy 128.325626 -302.650906) (xy 128.331976 -302.667924)
			(xy 128.338072 -302.675036) (xy 128.35569 -302.695985) (xy 128.385406 -302.741953) (xy 128.408247 -302.791696)
			(xy 128.423742 -302.844193) (xy 128.431576 -302.898366) (xy 128.432052 -302.925734) (xy 128.432 -302.935722)
			(xy 128.430986 -302.955671) (xy 128.43002 -302.965612) (xy 128.42875 -302.976534) (xy 128.435354 -302.996854)
			(xy 128.493266 -303.060862) (xy 128.50075 -303.068595) (xy 128.520361 -303.077407) (xy 128.531112 -303.07788)
			(xy 132.378196 -303.07788) (xy 132.388916 -303.077266) (xy 132.408476 -303.06848) (xy 132.416042 -303.060862)
			(xy 132.473954 -302.996854) (xy 132.480558 -302.976534) (xy 132.479288 -302.965612) (xy 132.478325 -302.955671)
			(xy 132.477309 -302.935722) (xy 132.477256 -302.925734) (xy 132.477728 -302.898364) (xy 132.485543 -302.844184)
			(xy 132.501029 -302.791681) (xy 132.52387 -302.741934) (xy 132.553595 -302.695967) (xy 132.571236 -302.675036)
			(xy 132.577332 -302.667924) (xy 132.583682 -302.650906) (xy 132.583682 -302.565562) (xy 132.577332 -302.548544)
			(xy 132.571236 -302.541432) (xy 132.553604 -302.520494) (xy 132.52389 -302.474523) (xy 132.501052 -302.424777)
			(xy 132.485559 -302.372278) (xy 132.47773 -302.318103) (xy 132.477256 -302.290734) (xy 132.477742 -302.263483)
			(xy 132.485498 -302.209535) (xy 132.500853 -302.15724) (xy 132.523495 -302.107663) (xy 132.552961 -302.061813)
			(xy 132.588652 -302.020622) (xy 132.629843 -301.984931) (xy 132.675693 -301.955465) (xy 132.72527 -301.932823)
			(xy 132.777565 -301.917468) (xy 132.831513 -301.909712) (xy 132.886015 -301.909712) (xy 132.939963 -301.917468)
			(xy 132.992258 -301.932823) (xy 133.041835 -301.955465) (xy 133.087685 -301.984931) (xy 133.128876 -302.020622)
			(xy 133.164567 -302.061813) (xy 133.194033 -302.107663) (xy 133.216675 -302.15724) (xy 133.23203 -302.209535)
			(xy 133.239786 -302.263483) (xy 133.240272 -302.290734) (xy 133.239833 -302.318105) (xy 133.232009 -302.372286)
			(xy 133.216514 -302.424789) (xy 133.193667 -302.474536) (xy 133.163936 -302.520501) (xy 133.146292 -302.541432)
			(xy 133.140196 -302.548544) (xy 133.133846 -302.565562) (xy 133.133846 -302.650906) (xy 133.140196 -302.667924)
			(xy 133.146292 -302.675036) (xy 133.163913 -302.695982) (xy 133.193628 -302.741951) (xy 133.216468 -302.791695)
			(xy 133.231963 -302.844193) (xy 133.239796 -302.898366) (xy 133.240272 -302.925734) (xy 133.24022 -302.935722)
			(xy 133.239206 -302.955671) (xy 133.23824 -302.965612) (xy 133.23697 -302.976534) (xy 133.243574 -302.996854)
			(xy 133.301486 -303.060862) (xy 133.308962 -303.068604) (xy 133.328579 -303.077411) (xy 133.339332 -303.07788)
			(xy 134.887716 -303.07788) (xy 134.897787 -303.077468) (xy 134.916385 -303.069738) (xy 134.923784 -303.062894)
			(xy 135.865616 -302.121062) (xy 135.872311 -302.113582) (xy 135.879901 -302.095022) (xy 135.880348 -302.084994)
			(xy 135.880348 -282.125928) (xy 135.880959 -282.095951) (xy 135.890345 -282.036737) (xy 135.908875 -281.979719)
			(xy 135.936093 -281.9263) (xy 135.971329 -281.877795) (xy 135.992108 -281.85618) (xy 140.146532 -277.70201)
			(xy 140.153252 -277.694549) (xy 140.160827 -277.675974) (xy 140.161264 -277.665942) (xy 140.161264 -274.082256)
			(xy 140.160901 -274.07221) (xy 140.153308 -274.053613) (xy 140.146532 -274.046188) (xy 130.943604 -264.84326)
			(xy 130.936146 -264.836536) (xy 130.917569 -264.828963) (xy 130.907536 -264.828528) (xy 126.64821 -264.828528)
			(xy 126.618233 -264.827935) (xy 126.559017 -264.818546) (xy 126.501999 -264.800012) (xy 126.44858 -264.77279)
			(xy 126.400076 -264.737549) (xy 126.378462 -264.716768) (xy 122.953272 -261.291324) (xy 122.945795 -261.284626)
			(xy 122.927232 -261.277039) (xy 122.917204 -261.276592) (xy 120.24614 -261.276592) (xy 120.234634 -261.277071)
			(xy 120.213876 -261.287) (xy 120.206262 -261.295642) (xy 120.149366 -261.367524) (xy 120.14454 -261.389622)
			(xy 120.14708 -261.401306) (xy 120.147842 -261.404354) (xy 120.150128 -261.413752) (xy 120.160288 -261.429246)
			(xy 120.231662 -261.479538) (xy 120.249442 -261.48411) (xy 120.259094 -261.483094) (xy 120.270352 -261.481798)
			(xy 120.292974 -261.480402) (xy 120.304306 -261.4803) (xy 120.331558 -261.48077) (xy 120.385506 -261.488528)
			(xy 120.437801 -261.503884) (xy 120.487378 -261.526526) (xy 120.533229 -261.555993) (xy 120.574419 -261.591685)
			(xy 120.610111 -261.632876) (xy 120.639577 -261.678727) (xy 120.662219 -261.728305) (xy 120.677574 -261.7806)
			(xy 120.68533 -261.834548) (xy 120.68533 -261.889052) (xy 120.677574 -261.943) (xy 120.662219 -261.995295)
			(xy 120.639577 -262.044873) (xy 120.610111 -262.090724) (xy 120.574419 -262.131915) (xy 120.533229 -262.167607)
			(xy 120.487378 -262.197074) (xy 120.437801 -262.219716) (xy 120.385506 -262.235072) (xy 120.331558 -262.24283)
			(xy 120.304306 -262.243316) (xy 120.275709 -262.242776) (xy 120.219157 -262.234239) (xy 120.164512 -262.217355)
			(xy 120.113001 -262.192503) (xy 120.065776 -262.16024) (xy 120.023897 -262.121288) (xy 119.988302 -262.076522)
			(xy 119.959789 -262.026943) (xy 119.938997 -261.973663) (xy 119.932196 -261.945882) (xy 119.92991 -261.936484)
			(xy 119.91975 -261.92099) (xy 119.848376 -261.870698) (xy 119.830596 -261.866126) (xy 119.820944 -261.867142)
			(xy 119.809685 -261.868435) (xy 119.787064 -261.869833) (xy 119.775732 -261.869936) (xy 119.748481 -261.869415)
			(xy 119.694534 -261.861663) (xy 119.642239 -261.846313) (xy 119.592661 -261.823676) (xy 119.546809 -261.794214)
			(xy 119.505616 -261.758526) (xy 119.469922 -261.717339) (xy 119.440453 -261.671492) (xy 119.417808 -261.621918)
			(xy 119.40245 -261.569625) (xy 119.394689 -261.515679) (xy 119.394224 -261.488428) (xy 119.394589 -261.464129)
			(xy 119.400747 -261.415921) (xy 119.412966 -261.368884) (xy 119.421656 -261.346188) (xy 119.425466 -261.337044)
			(xy 119.425466 -261.327392) (xy 119.425086 -261.317366) (xy 119.417407 -261.298842) (xy 119.403222 -261.284669)
			(xy 119.384692 -261.277006) (xy 119.374666 -261.276592) (xy 119.370602 -261.276592) (xy 119.360556 -261.276964)
			(xy 119.341959 -261.284549) (xy 119.334534 -261.291324) (xy 119.188738 -261.43712) (xy 119.181902 -261.444524)
			(xy 119.174179 -261.46312) (xy 119.173752 -261.473188) (xy 119.173752 -262.184388) (xy 119.173389 -262.209183)
			(xy 119.167013 -262.258361) (xy 119.161052 -262.282432) (xy 119.158973 -262.291976) (xy 119.161323 -262.311347)
			(xy 119.170743 -262.328436) (xy 119.185868 -262.340766) (xy 119.204504 -262.346549) (xy 119.223952 -262.344948)
			(xy 119.241392 -262.336195) (xy 119.248174 -262.329168) (xy 119.266372 -262.309149) (xy 119.307456 -262.27395)
			(xy 119.353099 -262.244906) (xy 119.402387 -262.222599) (xy 119.454331 -262.207477) (xy 119.50789 -262.199842)
			(xy 119.53494 -262.199374) (xy 119.562188 -262.199921) (xy 119.616129 -262.207682) (xy 119.668416 -262.223041)
			(xy 119.717985 -262.245684) (xy 119.763827 -262.275151) (xy 119.805009 -262.310843) (xy 119.840692 -262.352031)
			(xy 119.870151 -262.397879) (xy 119.892785 -262.447453) (xy 119.908133 -262.499743) (xy 119.915884 -262.553685)
			(xy 119.91588 -262.608181) (xy 119.908119 -262.662121) (xy 119.892762 -262.714409) (xy 119.870119 -262.763978)
			(xy 119.840653 -262.809821) (xy 119.804962 -262.851004) (xy 119.763774 -262.886688) (xy 119.717927 -262.916147)
			(xy 119.668354 -262.938782) (xy 119.616065 -262.954132) (xy 119.562123 -262.961884) (xy 119.507627 -262.96188)
			(xy 119.453686 -262.954121) (xy 119.401398 -262.938764) (xy 119.351828 -262.916123) (xy 119.305985 -262.886657)
			(xy 119.264802 -262.850968) (xy 119.229117 -262.80978) (xy 119.199656 -262.763934) (xy 119.17702 -262.714361)
			(xy 119.16167 -262.662072) (xy 119.153917 -262.60813) (xy 119.153432 -262.580882) (xy 119.153854 -262.556016)
			(xy 119.160351 -262.50671) (xy 119.166386 -262.482584) (xy 119.168413 -262.473003) (xy 119.16604 -262.453591)
			(xy 119.156567 -262.436481) (xy 119.141374 -262.424167) (xy 119.122673 -262.418442) (xy 119.10319 -262.420141)
			(xy 119.085762 -262.429015) (xy 119.07901 -262.436102) (xy 119.062246 -262.454136) (xy 118.42242 -263.093962)
			(xy 118.400812 -263.114734) (xy 118.352289 -263.149919) (xy 118.298863 -263.177085) (xy 118.241846 -263.195563)
			(xy 118.182641 -263.204899) (xy 118.152672 -263.205468) (xy 117.19052 -263.205468) (xy 117.18045 -263.205886)
			(xy 117.161851 -263.21361) (xy 117.154452 -263.220454) (xy 117.033548 -263.341612) (xy 117.01195 -263.362413)
			(xy 116.963448 -263.397667) (xy 116.910027 -263.424897) (xy 116.853002 -263.443431) (xy 116.79378 -263.452814)
			(xy 116.7638 -263.453372) (xy 116.736546 -263.452945) (xy 116.682591 -263.445187) (xy 116.630291 -263.429829)
			(xy 116.580708 -263.407184) (xy 116.534853 -263.377712) (xy 116.49366 -263.342015) (xy 116.457966 -263.300818)
			(xy 116.428499 -263.25496) (xy 116.405859 -263.205376) (xy 116.390506 -263.153073) (xy 116.382753 -263.099119)
			(xy 116.382292 -263.071864) (xy 112.642667 -263.071864) (xy 112.614503 -263.079227) (xy 112.559066 -263.085327)
			(xy 112.503332 -263.08329) (xy 112.448489 -263.07316) (xy 112.395705 -263.055153) (xy 112.346105 -263.029652)
			(xy 112.300747 -262.997201) (xy 112.260598 -262.958492) (xy 112.226512 -262.914349) (xy 112.199216 -262.865714)
			(xy 112.179293 -262.813623) (xy 112.167167 -262.759186) (xy 112.163096 -262.703564) (xy 99.242178 -262.703564)
			(xy 99.678744 -263.356852) (xy 99.705461 -263.397908) (xy 99.751648 -263.484296) (xy 99.770946 -263.529318)
			(xy 99.88169 -263.79678) (xy 99.886262 -263.805416) (xy 100.099922 -264.12952) (xy 114.449096 -264.12952)
			(xy 114.453167 -264.073898) (xy 114.465293 -264.019461) (xy 114.485216 -263.96737) (xy 114.512512 -263.918735)
			(xy 114.546598 -263.874592) (xy 114.586747 -263.835883) (xy 114.632105 -263.803432) (xy 114.681705 -263.777931)
			(xy 114.734489 -263.759924) (xy 114.789332 -263.749794) (xy 114.845066 -263.747757) (xy 114.900503 -263.753857)
			(xy 114.95446 -263.767963) (xy 115.000755 -263.787636) (xy 117.571772 -263.787636) (xy 117.575843 -263.732014)
			(xy 117.587969 -263.677577) (xy 117.607892 -263.625486) (xy 117.635188 -263.576851) (xy 117.669274 -263.532708)
			(xy 117.709423 -263.493999) (xy 117.754781 -263.461548) (xy 117.804381 -263.436047) (xy 117.857165 -263.41804)
			(xy 117.912008 -263.40791) (xy 117.967742 -263.405873) (xy 118.023179 -263.411973) (xy 118.077136 -263.426079)
			(xy 118.128465 -263.447891) (xy 118.176071 -263.476945) (xy 118.218939 -263.51262) (xy 118.256156 -263.554157)
			(xy 118.286929 -263.60067) (xy 118.310601 -263.651167) (xy 118.326669 -263.704574) (xy 118.334789 -263.75975)
			(xy 118.335298 -263.787636) (xy 118.334789 -263.815522) (xy 118.333996 -263.82091) (xy 119.443752 -263.82091)
			(xy 119.447823 -263.765288) (xy 119.459949 -263.710851) (xy 119.479872 -263.65876) (xy 119.507168 -263.610125)
			(xy 119.541254 -263.565982) (xy 119.581403 -263.527273) (xy 119.626761 -263.494822) (xy 119.676361 -263.469321)
			(xy 119.729145 -263.451314) (xy 119.783988 -263.441184) (xy 119.839722 -263.439147) (xy 119.895159 -263.445247)
			(xy 119.949116 -263.459353) (xy 120.000445 -263.481165) (xy 120.048051 -263.510219) (xy 120.090919 -263.545894)
			(xy 120.128136 -263.587431) (xy 120.158909 -263.633944) (xy 120.182581 -263.684441) (xy 120.198649 -263.737848)
			(xy 120.206769 -263.793024) (xy 120.207278 -263.82091) (xy 120.206769 -263.848796) (xy 120.198649 -263.903972)
			(xy 120.182581 -263.957379) (xy 120.158909 -264.007876) (xy 120.128136 -264.054389) (xy 120.090919 -264.095926)
			(xy 120.048051 -264.131601) (xy 120.000445 -264.160655) (xy 119.949116 -264.182467) (xy 119.895159 -264.196573)
			(xy 119.839722 -264.202673) (xy 119.783988 -264.200636) (xy 119.729145 -264.190506) (xy 119.676361 -264.172499)
			(xy 119.626761 -264.146998) (xy 119.581403 -264.114547) (xy 119.541254 -264.075838) (xy 119.507168 -264.031695)
			(xy 119.479872 -263.98306) (xy 119.459949 -263.930969) (xy 119.447823 -263.876532) (xy 119.443752 -263.82091)
			(xy 118.333996 -263.82091) (xy 118.326669 -263.870698) (xy 118.310601 -263.924105) (xy 118.286929 -263.974602)
			(xy 118.256156 -264.021115) (xy 118.218939 -264.062652) (xy 118.176071 -264.098327) (xy 118.128465 -264.127381)
			(xy 118.077136 -264.149193) (xy 118.023179 -264.163299) (xy 117.967742 -264.169399) (xy 117.912008 -264.167362)
			(xy 117.857165 -264.157232) (xy 117.804381 -264.139225) (xy 117.754781 -264.113724) (xy 117.709423 -264.081273)
			(xy 117.669274 -264.042564) (xy 117.635188 -263.998421) (xy 117.607892 -263.949786) (xy 117.587969 -263.897695)
			(xy 117.575843 -263.843258) (xy 117.571772 -263.787636) (xy 115.000755 -263.787636) (xy 115.005789 -263.789775)
			(xy 115.053395 -263.818829) (xy 115.096263 -263.854504) (xy 115.13348 -263.896041) (xy 115.164253 -263.942554)
			(xy 115.187925 -263.993051) (xy 115.203993 -264.046458) (xy 115.212113 -264.101634) (xy 115.212622 -264.12952)
			(xy 115.212113 -264.157406) (xy 115.203993 -264.212582) (xy 115.187925 -264.265989) (xy 115.164253 -264.316486)
			(xy 115.13348 -264.362999) (xy 115.096263 -264.404536) (xy 115.053395 -264.440211) (xy 115.005789 -264.469265)
			(xy 114.95446 -264.491077) (xy 114.900503 -264.505183) (xy 114.845066 -264.511283) (xy 114.789332 -264.509246)
			(xy 114.734489 -264.499116) (xy 114.681705 -264.481109) (xy 114.632105 -264.455608) (xy 114.586747 -264.423157)
			(xy 114.546598 -264.384448) (xy 114.512512 -264.340305) (xy 114.485216 -264.29167) (xy 114.465293 -264.239579)
			(xy 114.453167 -264.185142) (xy 114.449096 -264.12952) (xy 100.099922 -264.12952) (xy 100.28428 -264.409174)
			(xy 100.308017 -264.446008) (xy 100.349612 -264.523141) (xy 100.38421 -264.603656) (xy 100.398326 -264.64514)
			(xy 100.493686 -264.93597) (xy 120.417334 -264.93597) (xy 120.421405 -264.880348) (xy 120.433531 -264.825911)
			(xy 120.453454 -264.77382) (xy 120.48075 -264.725185) (xy 120.514836 -264.681042) (xy 120.554985 -264.642333)
			(xy 120.600343 -264.609882) (xy 120.649943 -264.584381) (xy 120.702727 -264.566374) (xy 120.75757 -264.556244)
			(xy 120.813304 -264.554207) (xy 120.868741 -264.560307) (xy 120.922698 -264.574413) (xy 120.974027 -264.596225)
			(xy 121.021633 -264.625279) (xy 121.064501 -264.660954) (xy 121.101718 -264.702491) (xy 121.132491 -264.749004)
			(xy 121.156163 -264.799501) (xy 121.172231 -264.852908) (xy 121.180351 -264.908084) (xy 121.18086 -264.93597)
			(xy 121.180351 -264.963856) (xy 121.172231 -265.019032) (xy 121.156163 -265.072439) (xy 121.132491 -265.122936)
			(xy 121.101718 -265.169449) (xy 121.064501 -265.210986) (xy 121.021633 -265.246661) (xy 120.974027 -265.275715)
			(xy 120.922698 -265.297527) (xy 120.868741 -265.311633) (xy 120.813304 -265.317733) (xy 120.75757 -265.315696)
			(xy 120.702727 -265.305566) (xy 120.649943 -265.287559) (xy 120.600343 -265.262058) (xy 120.554985 -265.229607)
			(xy 120.514836 -265.190898) (xy 120.48075 -265.146755) (xy 120.453454 -265.09812) (xy 120.433531 -265.046029)
			(xy 120.421405 -264.991592) (xy 120.417334 -264.93597) (xy 100.493686 -264.93597) (xy 100.678742 -265.500358)
			(xy 100.97897 -266.415774) (xy 100.979224 -266.416028) (xy 101.026468 -266.5603) (xy 101.027992 -266.563856)
			(xy 101.143308 -266.84224) (xy 101.161706 -266.888317) (xy 101.190344 -266.983316) (xy 101.209411 -267.080688)
			(xy 101.214682 -267.130022) (xy 101.21519 -267.13561) (xy 101.826822 -269.000732) (xy 101.842146 -269.049622)
			(xy 101.863782 -269.149774) (xy 101.870002 -269.20063) (xy 101.870002 -269.200884) (xy 101.870256 -269.203678)
			(xy 101.872288 -269.223744) (xy 101.873796 -269.242378) (xy 101.875574 -269.279727) (xy 101.875844 -269.29842)
			(xy 101.877117 -269.417038) (xy 102.50043 -269.417038) (xy 102.500935 -269.388299) (xy 102.509565 -269.331471)
			(xy 102.52662 -269.276581) (xy 102.551716 -269.22487) (xy 102.584283 -269.177507) (xy 102.603554 -269.15618)
			(xy 102.610158 -269.149068) (xy 102.61727 -269.131542) (xy 102.61727 -269.042134) (xy 102.610158 -269.024608)
			(xy 102.603554 -269.017496) (xy 102.584304 -268.996151) (xy 102.551734 -268.948794) (xy 102.526638 -268.897087)
			(xy 102.509582 -268.8422) (xy 102.500954 -268.785376) (xy 102.50043 -268.756638) (xy 102.500891 -268.729384)
			(xy 102.508644 -268.675431) (xy 102.523997 -268.623131) (xy 102.546638 -268.573549) (xy 102.576105 -268.527693)
			(xy 102.611799 -268.486499) (xy 102.652993 -268.450805) (xy 102.698849 -268.421338) (xy 102.748431 -268.398697)
			(xy 102.800731 -268.383344) (xy 102.854684 -268.375591) (xy 102.881938 -268.37513) (xy 102.909307 -268.375625)
			(xy 102.963485 -268.383435) (xy 103.015988 -268.398917) (xy 103.065736 -268.421752) (xy 103.111704 -268.451471)
			(xy 103.132636 -268.46911) (xy 103.139748 -268.475206) (xy 103.156766 -268.481556) (xy 103.24211 -268.481556)
			(xy 103.259128 -268.475206) (xy 103.26624 -268.46911) (xy 103.287173 -268.451469) (xy 103.333141 -268.421745)
			(xy 103.382887 -268.398899) (xy 103.435389 -268.383403) (xy 103.489567 -268.375574) (xy 103.544309 -268.375574)
			(xy 103.598487 -268.383403) (xy 103.650989 -268.398899) (xy 103.700735 -268.421745) (xy 103.746703 -268.451469)
			(xy 103.767636 -268.46911) (xy 103.774748 -268.475206) (xy 103.791766 -268.481556) (xy 103.87711 -268.481556)
			(xy 103.894128 -268.475206) (xy 103.90124 -268.46911) (xy 103.922173 -268.451469) (xy 103.968141 -268.421745)
			(xy 104.017887 -268.398899) (xy 104.070389 -268.383403) (xy 104.124567 -268.375574) (xy 104.179309 -268.375574)
			(xy 104.233487 -268.383403) (xy 104.285989 -268.398899) (xy 104.335735 -268.421745) (xy 104.381703 -268.451469)
			(xy 104.402636 -268.46911) (xy 104.409748 -268.475206) (xy 104.426766 -268.481556) (xy 104.51211 -268.481556)
			(xy 104.529128 -268.475206) (xy 104.53624 -268.46911) (xy 104.557173 -268.451469) (xy 104.603141 -268.421745)
			(xy 104.652887 -268.398899) (xy 104.705389 -268.383403) (xy 104.759567 -268.375574) (xy 104.814309 -268.375574)
			(xy 104.868487 -268.383403) (xy 104.920989 -268.398899) (xy 104.970735 -268.421745) (xy 105.016703 -268.451469)
			(xy 105.037636 -268.46911) (xy 105.044748 -268.475206) (xy 105.061766 -268.481556) (xy 105.14711 -268.481556)
			(xy 105.164128 -268.475206) (xy 105.17124 -268.46911) (xy 105.192185 -268.451487) (xy 105.238154 -268.421773)
			(xy 105.287898 -268.398933) (xy 105.340396 -268.383438) (xy 105.39457 -268.375606) (xy 105.421938 -268.37513)
			(xy 105.449192 -268.375543) (xy 105.503144 -268.383305) (xy 105.555443 -268.398667) (xy 105.605023 -268.421315)
			(xy 105.650875 -268.450789) (xy 105.692065 -268.486488) (xy 105.727756 -268.527686) (xy 105.757221 -268.573544)
			(xy 105.779859 -268.623129) (xy 105.795211 -268.67543) (xy 105.802963 -268.729384) (xy 105.803446 -268.756638)
			(xy 105.802933 -268.785377) (xy 105.794306 -268.842204) (xy 105.777253 -268.897095) (xy 105.752159 -268.948806)
			(xy 105.719593 -268.996169) (xy 105.700322 -269.017496) (xy 105.693718 -269.024608) (xy 105.686606 -269.042134)
			(xy 105.686606 -269.131542) (xy 105.693718 -269.149068) (xy 105.700322 -269.15618) (xy 105.719604 -269.177497)
			(xy 105.75217 -269.224861) (xy 105.777261 -269.276575) (xy 105.794309 -269.331468) (xy 105.802928 -269.388298)
			(xy 105.803446 -269.417038) (xy 105.802958 -269.444288) (xy 105.795197 -269.498234) (xy 105.779839 -269.550526)
			(xy 105.757196 -269.600101) (xy 105.727729 -269.64595) (xy 105.692038 -269.687138) (xy 105.65085 -269.722829)
			(xy 105.605001 -269.752296) (xy 105.555426 -269.774939) (xy 105.503134 -269.790297) (xy 105.449188 -269.798058)
			(xy 105.421938 -269.798546) (xy 105.394568 -269.798071) (xy 105.340389 -269.790257) (xy 105.287885 -269.774771)
			(xy 105.238138 -269.751931) (xy 105.192171 -269.722207) (xy 105.17124 -269.704566) (xy 105.164128 -269.69847)
			(xy 105.14711 -269.69212) (xy 105.061766 -269.69212) (xy 105.044748 -269.69847) (xy 105.037636 -269.704566)
			(xy 105.016703 -269.722207) (xy 104.970735 -269.751931) (xy 104.920989 -269.774777) (xy 104.868487 -269.790273)
			(xy 104.814309 -269.798102) (xy 104.759567 -269.798102) (xy 104.705389 -269.790273) (xy 104.652887 -269.774777)
			(xy 104.603141 -269.751931) (xy 104.557173 -269.722207) (xy 104.53624 -269.704566) (xy 104.529128 -269.69847)
			(xy 104.51211 -269.69212) (xy 104.426766 -269.69212) (xy 104.409748 -269.69847) (xy 104.402636 -269.704566)
			(xy 104.381703 -269.722207) (xy 104.335735 -269.751931) (xy 104.285989 -269.774777) (xy 104.233487 -269.790273)
			(xy 104.179309 -269.798102) (xy 104.124567 -269.798102) (xy 104.070389 -269.790273) (xy 104.017887 -269.774777)
			(xy 103.968141 -269.751931) (xy 103.922173 -269.722207) (xy 103.90124 -269.704566) (xy 103.894128 -269.69847)
			(xy 103.87711 -269.69212) (xy 103.791766 -269.69212) (xy 103.774748 -269.69847) (xy 103.767636 -269.704566)
			(xy 103.746703 -269.722207) (xy 103.700735 -269.751931) (xy 103.650989 -269.774777) (xy 103.598487 -269.790273)
			(xy 103.544309 -269.798102) (xy 103.489567 -269.798102) (xy 103.435389 -269.790273) (xy 103.382887 -269.774777)
			(xy 103.333141 -269.751931) (xy 103.287173 -269.722207) (xy 103.26624 -269.704566) (xy 103.259128 -269.69847)
			(xy 103.24211 -269.69212) (xy 103.156766 -269.69212) (xy 103.139748 -269.69847) (xy 103.132636 -269.704566)
			(xy 103.111697 -269.722196) (xy 103.065727 -269.751911) (xy 103.015981 -269.774749) (xy 102.963482 -269.790242)
			(xy 102.909307 -269.798071) (xy 102.881938 -269.798546) (xy 102.854689 -269.797987) (xy 102.800746 -269.790236)
			(xy 102.748455 -269.774888) (xy 102.698881 -269.752254) (xy 102.653032 -269.722795) (xy 102.611843 -269.687111)
			(xy 102.57615 -269.645929) (xy 102.546683 -269.600086) (xy 102.524039 -269.550516) (xy 102.50868 -269.498228)
			(xy 102.500919 -269.444286) (xy 102.50043 -269.417038) (xy 101.877117 -269.417038) (xy 101.919786 -273.391376)
			(xy 101.919786 -273.392138) (xy 101.920294 -273.403568) (xy 101.920294 -273.40941) (xy 101.920548 -273.422618)
			(xy 101.920548 -273.423634) (xy 101.920294 -273.457416) (xy 101.92004 -273.458178) (xy 101.92004 -273.494754)
			(xy 101.919476 -273.541639) (xy 101.91057 -273.634987) (xy 101.892861 -273.72707) (xy 101.866508 -273.817063)
			(xy 101.83175 -273.904154) (xy 101.81082 -273.946112) (xy 99.796017 -277.864824) (xy 103.46563 -277.864824)
			(xy 103.466154 -277.835907) (xy 103.47488 -277.778736) (xy 103.492136 -277.723537) (xy 103.517527 -277.671575)
			(xy 103.55047 -277.624041) (xy 103.590211 -277.582024) (xy 103.612696 -277.563834) (xy 103.621438 -277.556252)
			(xy 103.631632 -277.535509) (xy 103.632254 -277.523956) (xy 103.632254 -277.443692) (xy 103.631704 -277.432121)
			(xy 103.621497 -277.411349) (xy 103.612696 -277.403814) (xy 103.590218 -277.385616) (xy 103.550483 -277.343598)
			(xy 103.517543 -277.296064) (xy 103.492154 -277.244104) (xy 103.474896 -277.188908) (xy 103.466166 -277.13174)
			(xy 103.46563 -277.102824) (xy 103.466211 -277.073416) (xy 103.475241 -277.015298) (xy 103.493076 -276.959253)
			(xy 103.519295 -276.906604) (xy 103.553276 -276.858599) (xy 103.594217 -276.816372) (xy 103.641148 -276.780922)
			(xy 103.666798 -276.766528) (xy 103.678736 -276.760178) (xy 103.69296 -276.737826) (xy 103.698802 -276.624288)
			(xy 103.686864 -276.600412) (xy 103.675942 -276.593046) (xy 103.654185 -276.577733) (xy 103.614705 -276.54207)
			(xy 103.580561 -276.50127) (xy 103.552414 -276.456123) (xy 103.530809 -276.407504) (xy 103.516166 -276.356357)
			(xy 103.508768 -276.303671) (xy 103.508302 -276.27707) (xy 103.50875 -276.249699) (xy 103.516572 -276.195519)
			(xy 103.532065 -276.143016) (xy 103.554911 -276.093269) (xy 103.584639 -276.047303) (xy 103.602282 -276.026372)
			(xy 103.608378 -276.01926) (xy 103.614728 -276.002242) (xy 103.614728 -275.916898) (xy 103.608378 -275.89988)
			(xy 103.602282 -275.892768) (xy 103.584659 -275.871823) (xy 103.554945 -275.825854) (xy 103.532106 -275.776109)
			(xy 103.516611 -275.723612) (xy 103.508779 -275.669438) (xy 103.508302 -275.64207) (xy 103.508854 -275.612246)
			(xy 103.518108 -275.55332) (xy 103.536418 -275.496551) (xy 103.563338 -275.443323) (xy 103.598212 -275.394931)
			(xy 103.618792 -275.373338) (xy 103.626158 -275.366226) (xy 103.633778 -275.34743) (xy 103.632762 -275.25472)
			(xy 103.624888 -275.236178) (xy 103.617522 -275.229066) (xy 103.599566 -275.211014) (xy 103.568068 -275.171012)
			(xy 103.542169 -275.127176) (xy 103.522329 -275.080286) (xy 103.508902 -275.031173) (xy 103.502124 -274.980711)
			(xy 103.501698 -274.955254) (xy 103.502135 -274.928001) (xy 103.509898 -274.874052) (xy 103.525259 -274.821756)
			(xy 103.547906 -274.772178) (xy 103.577378 -274.726327) (xy 103.613074 -274.685137) (xy 103.654269 -274.649447)
			(xy 103.700123 -274.619981) (xy 103.749704 -274.597341) (xy 103.802002 -274.581987) (xy 103.855953 -274.574231)
			(xy 103.883206 -274.573746) (xy 103.912124 -274.574243) (xy 103.969297 -274.582974) (xy 104.024497 -274.600235)
			(xy 104.076459 -274.62563) (xy 104.123992 -274.658579) (xy 104.166007 -274.698324) (xy 104.184196 -274.720812)
			(xy 104.191762 -274.72957) (xy 104.212518 -274.739755) (xy 104.224074 -274.74037) (xy 104.304338 -274.74037)
			(xy 104.315903 -274.739775) (xy 104.336675 -274.729599) (xy 104.344216 -274.720812) (xy 104.360969 -274.700029)
			(xy 104.399323 -274.662899) (xy 104.442477 -274.631477) (xy 104.489591 -274.606378) (xy 104.539743 -274.588092)
			(xy 104.591954 -274.576975) (xy 104.645206 -274.573245) (xy 104.698458 -274.576975) (xy 104.750669 -274.588092)
			(xy 104.800821 -274.606378) (xy 104.847935 -274.631477) (xy 104.891089 -274.662899) (xy 104.929443 -274.700029)
			(xy 104.946196 -274.720812) (xy 104.953762 -274.72957) (xy 104.974518 -274.739755) (xy 104.986074 -274.74037)
			(xy 105.066338 -274.74037) (xy 105.077903 -274.739775) (xy 105.098675 -274.729599) (xy 105.106216 -274.720812)
			(xy 105.124401 -274.698323) (xy 105.166422 -274.658588) (xy 105.213958 -274.625649) (xy 105.26592 -274.600262)
			(xy 105.321119 -274.583007) (xy 105.37829 -274.57428) (xy 105.407206 -274.573746) (xy 105.434455 -274.574272)
			(xy 105.488399 -274.582028) (xy 105.54069 -274.597382) (xy 105.590265 -274.62002) (xy 105.636113 -274.649483)
			(xy 105.677302 -274.68517) (xy 105.712993 -274.726355) (xy 105.742461 -274.7722) (xy 105.765104 -274.821772)
			(xy 105.780463 -274.874062) (xy 105.788225 -274.928005) (xy 105.788714 -274.955254) (xy 105.788173 -274.985079)
			(xy 105.778915 -275.044005) (xy 105.760602 -275.100774) (xy 105.73368 -275.154002) (xy 105.698805 -275.202393)
			(xy 105.678224 -275.223986) (xy 105.670858 -275.231098) (xy 105.663238 -275.249894) (xy 105.664254 -275.342604)
			(xy 105.672128 -275.361146) (xy 105.679494 -275.368258) (xy 105.697465 -275.386296) (xy 105.728961 -275.426301)
			(xy 105.754857 -275.47014) (xy 105.774694 -275.517034) (xy 105.788119 -275.566148) (xy 105.794894 -275.616612)
			(xy 105.795318 -275.64207) (xy 105.794809 -275.670988) (xy 105.786083 -275.728161) (xy 105.768825 -275.783361)
			(xy 105.743432 -275.835324) (xy 105.710485 -275.882857) (xy 105.67074 -275.924872) (xy 105.648252 -275.94306)
			(xy 105.639504 -275.950635) (xy 105.629315 -275.971384) (xy 105.628694 -275.982938) (xy 105.628694 -276.063202)
			(xy 105.629265 -276.07477) (xy 105.63946 -276.09554) (xy 105.648252 -276.10308) (xy 105.670737 -276.121269)
			(xy 105.710469 -276.163291) (xy 105.743407 -276.210827) (xy 105.768794 -276.262788) (xy 105.786051 -276.317985)
			(xy 105.794782 -276.375154) (xy 105.795318 -276.40407) (xy 105.794817 -276.431322) (xy 105.787064 -276.485271)
			(xy 105.771712 -276.537567) (xy 105.749074 -276.587147) (xy 105.71961 -276.632999) (xy 105.68392 -276.674192)
			(xy 105.642731 -276.709886) (xy 105.596882 -276.739355) (xy 105.547305 -276.761998) (xy 105.49501 -276.777356)
			(xy 105.441062 -276.785114) (xy 105.41381 -276.785578) (xy 105.384893 -276.785061) (xy 105.327721 -276.776333)
			(xy 105.272522 -276.759075) (xy 105.22056 -276.733683) (xy 105.173026 -276.700739) (xy 105.13101 -276.660998)
			(xy 105.11282 -276.638512) (xy 105.105243 -276.629765) (xy 105.084496 -276.619573) (xy 105.072942 -276.618954)
			(xy 104.992678 -276.618954) (xy 104.981113 -276.61955) (xy 104.96034 -276.629725) (xy 104.9528 -276.638512)
			(xy 104.942769 -276.651117) (xy 104.920893 -276.674769) (xy 104.909112 -276.685756) (xy 104.900222 -276.693884)
			(xy 104.891586 -276.715982) (xy 104.901492 -276.82063) (xy 104.913938 -276.84095) (xy 104.924098 -276.8473)
			(xy 104.947407 -276.862306) (xy 104.989845 -276.897971) (xy 105.026673 -276.939405) (xy 105.057113 -276.985734)
			(xy 105.080524 -277.035983) (xy 105.096413 -277.089091) (xy 105.104446 -277.143941) (xy 105.104946 -277.171658)
			(xy 105.10446 -277.198909) (xy 105.096704 -277.252857) (xy 105.081349 -277.305152) (xy 105.058707 -277.354729)
			(xy 105.029241 -277.400579) (xy 104.99355 -277.44177) (xy 104.952359 -277.477461) (xy 104.906509 -277.506927)
			(xy 104.856932 -277.529569) (xy 104.804637 -277.544924) (xy 104.750689 -277.55268) (xy 104.696187 -277.55268)
			(xy 104.642239 -277.544924) (xy 104.589944 -277.529569) (xy 104.540367 -277.506927) (xy 104.494517 -277.477461)
			(xy 104.453326 -277.44177) (xy 104.417635 -277.400579) (xy 104.388169 -277.354729) (xy 104.365527 -277.305152)
			(xy 104.350172 -277.252857) (xy 104.342416 -277.198909) (xy 104.34193 -277.171658) (xy 104.342402 -277.14524)
			(xy 104.349686 -277.09291) (xy 104.364122 -277.042085) (xy 104.385435 -276.99374) (xy 104.413216 -276.948798)
			(xy 104.446934 -276.908121) (xy 104.466136 -276.889972) (xy 104.475026 -276.881844) (xy 104.483662 -276.859746)
			(xy 104.473756 -276.755098) (xy 104.46131 -276.734778) (xy 104.45115 -276.728428) (xy 104.429535 -276.714589)
			(xy 104.389877 -276.68201) (xy 104.354959 -276.644394) (xy 104.325417 -276.602424) (xy 104.313228 -276.579838)
			(xy 104.30764 -276.56917) (xy 104.28859 -276.5552) (xy 104.18445 -276.537928) (xy 104.161844 -276.544786)
			(xy 104.152954 -276.553168) (xy 104.1341 -276.57061) (xy 104.09256 -276.600817) (xy 104.07015 -276.613366)
			(xy 104.058212 -276.619716) (xy 104.043988 -276.642068) (xy 104.038146 -276.755606) (xy 104.050084 -276.779482)
			(xy 104.061006 -276.786848) (xy 104.082749 -276.802181) (xy 104.122231 -276.837839) (xy 104.156378 -276.878635)
			(xy 104.184528 -276.923778) (xy 104.206135 -276.972394) (xy 104.22078 -277.02354) (xy 104.22818 -277.076224)
			(xy 104.228646 -277.102824) (xy 104.228093 -277.13174) (xy 104.219374 -277.18891) (xy 104.202124 -277.244109)
			(xy 104.176739 -277.296072) (xy 104.143801 -277.343606) (xy 104.104064 -277.385623) (xy 104.08158 -277.403814)
			(xy 104.072813 -277.411371) (xy 104.062633 -277.432133) (xy 104.062022 -277.443692) (xy 104.062022 -277.523956)
			(xy 104.06261 -277.535522) (xy 104.072792 -277.556293) (xy 104.08158 -277.563834) (xy 104.104076 -277.582011)
			(xy 104.143811 -277.624033) (xy 104.176749 -277.671571) (xy 104.202136 -277.723535) (xy 104.219389 -277.778735)
			(xy 104.228114 -277.835907) (xy 104.228646 -277.864824) (xy 104.22816 -277.892075) (xy 104.220404 -277.946023)
			(xy 104.205049 -277.998318) (xy 104.182407 -278.047895) (xy 104.152941 -278.093745) (xy 104.11725 -278.134936)
			(xy 104.076059 -278.170627) (xy 104.030209 -278.200093) (xy 103.980632 -278.222735) (xy 103.928337 -278.23809)
			(xy 103.874389 -278.245846) (xy 103.819887 -278.245846) (xy 103.765939 -278.23809) (xy 103.713644 -278.222735)
			(xy 103.664067 -278.200093) (xy 103.618217 -278.170627) (xy 103.577026 -278.134936) (xy 103.541335 -278.093745)
			(xy 103.511869 -278.047895) (xy 103.489227 -277.998318) (xy 103.473872 -277.946023) (xy 103.466116 -277.892075)
			(xy 103.46563 -277.864824) (xy 99.796017 -277.864824) (xy 99.651058 -278.146764) (xy 99.638804 -278.170238)
			(xy 99.612119 -278.215982) (xy 99.597718 -278.238204) (xy 99.597464 -278.238458) (xy 99.5934 -278.244808)
			(xy 99.591368 -278.251412) (xy 99.590318 -278.25507) (xy 99.589178 -278.262594) (xy 99.589082 -278.266398)
			(xy 99.589082 -278.389334) (xy 99.588652 -278.399401) (xy 99.580927 -278.417995) (xy 99.574096 -278.425402)
			(xy 93.65996 -284.339538) (xy 93.653113 -284.346936) (xy 93.645383 -284.365535) (xy 93.644974 -284.375606)
			(xy 93.644974 -285.41853) (xy 94.233746 -285.41853) (xy 94.234306 -285.391282) (xy 94.242057 -285.337339)
			(xy 94.257406 -285.285048) (xy 94.280041 -285.235474) (xy 94.309499 -285.189626) (xy 94.345183 -285.148437)
			(xy 94.386365 -285.112745) (xy 94.432208 -285.083277) (xy 94.481777 -285.060633) (xy 94.534065 -285.045273)
			(xy 94.588006 -285.037511) (xy 94.615254 -285.037022) (xy 94.640871 -285.037414) (xy 94.691643 -285.044282)
			(xy 94.741038 -285.057886) (xy 94.788166 -285.077983) (xy 94.832179 -285.104209) (xy 94.85249 -285.119826)
			(xy 94.862142 -285.127446) (xy 94.885256 -285.132272) (xy 94.975426 -285.108904) (xy 94.986732 -285.105371)
			(xy 95.00461 -285.089875) (xy 95.009716 -285.079186) (xy 95.1738 -284.682946) (xy 95.183721 -284.660046)
			(xy 95.208659 -284.616815) (xy 95.239011 -284.577198) (xy 95.25635 -284.559248) (xy 100.386642 -279.428956)
			(xy 100.408256 -279.408172) (xy 100.456752 -279.372913) (xy 100.510169 -279.345679) (xy 100.567191 -279.327141)
			(xy 100.62641 -279.317755) (xy 100.65639 -279.317196) (xy 103.650542 -279.317196) (xy 103.66059 -279.31685)
			(xy 103.679188 -279.309247) (xy 103.68661 -279.302464) (xy 106.693208 -276.295866) (xy 106.6999 -276.288383)
			(xy 106.707492 -276.269825) (xy 106.70794 -276.259798) (xy 106.70794 -268.269974) (xy 106.708519 -268.239996)
			(xy 106.717914 -268.180781) (xy 106.736451 -268.123763) (xy 106.763676 -268.070344) (xy 106.798919 -268.02184)
			(xy 106.8197 -268.000226) (xy 108.399072 -266.420854) (xy 108.420687 -266.400088) (xy 108.469207 -266.364902)
			(xy 108.522632 -266.337735) (xy 108.579648 -266.319255) (xy 108.638852 -266.309918) (xy 108.66882 -266.309348)
			(xy 119.322088 -266.309348) (xy 119.332531 -266.308889) (xy 119.351678 -266.300547) (xy 119.365897 -266.285249)
			(xy 119.36984 -266.275566) (xy 119.407432 -266.170156) (xy 119.39905 -266.139422) (xy 119.38635 -266.129008)
			(xy 119.364942 -266.110797) (xy 119.327206 -266.069144) (xy 119.295988 -266.022408) (xy 119.271963 -265.971597)
			(xy 119.255651 -265.917812) (xy 119.247405 -265.862216) (xy 119.246904 -265.834114) (xy 119.24739 -265.806863)
			(xy 119.255146 -265.752915) (xy 119.270501 -265.70062) (xy 119.293143 -265.651043) (xy 119.322609 -265.605193)
			(xy 119.3583 -265.564002) (xy 119.399491 -265.528311) (xy 119.445341 -265.498845) (xy 119.494918 -265.476203)
			(xy 119.547213 -265.460848) (xy 119.601161 -265.453092) (xy 119.655663 -265.453092) (xy 119.709611 -265.460848)
			(xy 119.761906 -265.476203) (xy 119.811483 -265.498845) (xy 119.857333 -265.528311) (xy 119.898524 -265.564002)
			(xy 119.934215 -265.605193) (xy 119.963681 -265.651043) (xy 119.986323 -265.70062) (xy 120.001678 -265.752915)
			(xy 120.009434 -265.806863) (xy 120.00992 -265.834114) (xy 120.009472 -265.862218) (xy 120.001222 -265.917818)
			(xy 119.984902 -265.971606) (xy 119.960867 -266.022416) (xy 119.929635 -266.06915) (xy 119.891884 -266.110794)
			(xy 119.870474 -266.129008) (xy 119.857774 -266.139422) (xy 119.849392 -266.170156) (xy 119.886984 -266.275566)
			(xy 119.890987 -266.285201) (xy 119.905227 -266.300421) (xy 119.924318 -266.308785) (xy 119.934736 -266.309348)
			(xy 120.994424 -266.309348) (xy 121.004496 -266.308949) (xy 121.023095 -266.301211) (xy 121.030492 -266.294362)
			(xy 121.62155 -265.703304) (xy 121.628374 -265.695891) (xy 121.636105 -265.677302) (xy 121.636536 -265.667236)
			(xy 121.636536 -263.925304) (xy 121.637037 -263.89533) (xy 121.646362 -263.836114) (xy 121.664845 -263.779088)
			(xy 121.692031 -263.725661) (xy 121.727248 -263.67715) (xy 121.748042 -263.655556) (xy 122.191526 -263.212072)
			(xy 122.213105 -263.191251) (xy 122.261611 -263.155996) (xy 122.315037 -263.128769) (xy 122.372066 -263.110239)
			(xy 122.431292 -263.100865) (xy 122.461274 -263.100312) (xy 122.712734 -263.100312) (xy 122.879866 -263.09828)
			(xy 122.889892 -263.097746) (xy 122.908357 -263.089907) (xy 122.91568 -263.08304) (xy 123.077986 -262.916924)
			(xy 123.096007 -262.899107) (xy 123.135916 -262.867877) (xy 123.179609 -262.842206) (xy 123.226316 -262.822546)
			(xy 123.275215 -262.809243) (xy 123.325444 -262.802532) (xy 123.350782 -262.802116) (xy 123.378013 -262.802648)
			(xy 123.431922 -262.810396) (xy 123.484179 -262.825737) (xy 123.533721 -262.848359) (xy 123.57954 -262.877801)
			(xy 123.620702 -262.913464) (xy 123.65637 -262.954622) (xy 123.685818 -263.000437) (xy 123.708446 -263.049976)
			(xy 123.723793 -263.102231) (xy 123.731548 -263.156139) (xy 123.732036 -263.18337) (xy 123.73146 -263.212882)
			(xy 123.722374 -263.271202) (xy 123.704415 -263.327427) (xy 123.678011 -263.380215) (xy 123.643792 -263.428307)
			(xy 123.623578 -263.449816) (xy 123.45797 -263.619488) (xy 123.451341 -263.627003) (xy 123.44397 -263.645617)
			(xy 123.444258 -263.665636) (xy 123.452162 -263.68403) (xy 123.458986 -263.69137) (xy 123.628404 -263.85647)
			(xy 123.646278 -263.874489) (xy 123.67762 -263.914408) (xy 123.703394 -263.958131) (xy 123.723143 -264.004884)
			(xy 123.736518 -264.053843) (xy 123.743284 -264.104144) (xy 123.74372 -264.12952) (xy 123.743241 -264.156771)
			(xy 123.735482 -264.210719) (xy 123.720125 -264.263013) (xy 123.697482 -264.312589) (xy 123.668015 -264.358439)
			(xy 123.632323 -264.399629) (xy 123.591132 -264.43532) (xy 123.545282 -264.464786) (xy 123.495705 -264.487428)
			(xy 123.443411 -264.502784) (xy 123.389463 -264.510541) (xy 123.362212 -264.511028) (xy 123.332724 -264.510476)
			(xy 123.274457 -264.501357) (xy 123.218287 -264.483381) (xy 123.165552 -264.456977) (xy 123.117508 -264.422772)
			(xy 123.09602 -264.40257) (xy 122.945906 -264.256266) (xy 122.93839 -264.249686) (xy 122.919822 -264.24237)
			(xy 122.909838 -264.242042) (xy 122.830336 -264.242804) (xy 122.820399 -264.243413) (xy 122.802081 -264.251149)
			(xy 122.788086 -264.265274) (xy 122.78052 -264.283662) (xy 122.780044 -264.293604) (xy 122.780044 -266.004294)
			(xy 122.779547 -266.034268) (xy 122.770222 -266.093485) (xy 122.751738 -266.150511) (xy 122.724551 -266.203938)
			(xy 122.689333 -266.252448) (xy 122.668538 -266.274042) (xy 121.60123 -267.34135) (xy 121.579615 -267.362115)
			(xy 121.531095 -267.397302) (xy 121.47767 -267.424469) (xy 121.420654 -267.442949) (xy 121.36145 -267.452286)
			(xy 121.331482 -267.452856) (xy 109.005878 -267.452856) (xy 108.995805 -267.453255) (xy 108.977207 -267.460993)
			(xy 108.96981 -267.467842) (xy 107.866688 -268.570964) (xy 107.859982 -268.578436) (xy 107.852398 -268.597002)
			(xy 107.851956 -268.607032) (xy 107.851956 -269.417038) (xy 124.88545 -269.417038) (xy 124.885949 -269.388298)
			(xy 124.89458 -269.33147) (xy 124.911636 -269.27658) (xy 124.936733 -269.224869) (xy 124.969302 -269.177507)
			(xy 124.988574 -269.15618) (xy 124.995178 -269.149068) (xy 125.00229 -269.131542) (xy 125.00229 -269.042134)
			(xy 124.995178 -269.024608) (xy 124.988574 -269.017496) (xy 124.969327 -268.996148) (xy 124.936756 -268.948792)
			(xy 124.911659 -268.897086) (xy 124.894602 -268.8422) (xy 124.885974 -268.785376) (xy 124.88545 -268.756638)
			(xy 124.886013 -268.72939) (xy 124.893764 -268.675447) (xy 124.909112 -268.623156) (xy 124.931746 -268.573582)
			(xy 124.961204 -268.527733) (xy 124.996887 -268.486544) (xy 125.038069 -268.450852) (xy 125.083912 -268.421384)
			(xy 125.133481 -268.39874) (xy 125.185769 -268.383381) (xy 125.23971 -268.375619) (xy 125.266958 -268.37513)
			(xy 125.294328 -268.375613) (xy 125.348506 -268.383426) (xy 125.40101 -268.398911) (xy 125.450757 -268.421749)
			(xy 125.496724 -268.45147) (xy 125.517656 -268.46911) (xy 125.524768 -268.475206) (xy 125.541786 -268.481556)
			(xy 125.62713 -268.481556) (xy 125.644148 -268.475206) (xy 125.65126 -268.46911) (xy 125.672193 -268.451469)
			(xy 125.718161 -268.421745) (xy 125.767907 -268.398899) (xy 125.820409 -268.383403) (xy 125.874587 -268.375574)
			(xy 125.929329 -268.375574) (xy 125.983507 -268.383403) (xy 126.036009 -268.398899) (xy 126.085755 -268.421745)
			(xy 126.131723 -268.451469) (xy 126.152656 -268.46911) (xy 126.159768 -268.475206) (xy 126.176786 -268.481556)
			(xy 126.26213 -268.481556) (xy 126.279148 -268.475206) (xy 126.28626 -268.46911) (xy 126.307193 -268.451469)
			(xy 126.353161 -268.421745) (xy 126.402907 -268.398899) (xy 126.455409 -268.383403) (xy 126.509587 -268.375574)
			(xy 126.564329 -268.375574) (xy 126.618507 -268.383403) (xy 126.671009 -268.398899) (xy 126.720755 -268.421745)
			(xy 126.766723 -268.451469) (xy 126.787656 -268.46911) (xy 126.794768 -268.475206) (xy 126.811786 -268.481556)
			(xy 126.89713 -268.481556) (xy 126.914148 -268.475206) (xy 126.92126 -268.46911) (xy 126.942193 -268.451469)
			(xy 126.988161 -268.421745) (xy 127.037907 -268.398899) (xy 127.090409 -268.383403) (xy 127.144587 -268.375574)
			(xy 127.199329 -268.375574) (xy 127.253507 -268.383403) (xy 127.306009 -268.398899) (xy 127.355755 -268.421745)
			(xy 127.401723 -268.451469) (xy 127.422656 -268.46911) (xy 127.429768 -268.475206) (xy 127.446786 -268.481556)
			(xy 127.53213 -268.481556) (xy 127.549148 -268.475206) (xy 127.55626 -268.46911) (xy 127.577198 -268.451478)
			(xy 127.623169 -268.421765) (xy 127.672915 -268.398927) (xy 127.725414 -268.383434) (xy 127.779589 -268.375605)
			(xy 127.806958 -268.37513) (xy 127.834212 -268.375594) (xy 127.888164 -268.383347) (xy 127.940465 -268.398699)
			(xy 127.990047 -268.42134) (xy 128.035902 -268.450807) (xy 128.077096 -268.486501) (xy 128.112791 -268.527695)
			(xy 128.142258 -268.573549) (xy 128.164899 -268.623132) (xy 128.180252 -268.675432) (xy 128.188005 -268.729384)
			(xy 128.188466 -268.756638) (xy 128.187948 -268.785377) (xy 128.179321 -268.842204) (xy 128.162269 -268.897094)
			(xy 128.137177 -268.948805) (xy 128.104612 -268.996168) (xy 128.085342 -269.017496) (xy 128.078738 -269.024608)
			(xy 128.071626 -269.042134) (xy 128.071626 -269.131542) (xy 128.078738 -269.149068) (xy 128.085342 -269.15618)
			(xy 128.104627 -269.177494) (xy 128.137192 -269.224859) (xy 128.162282 -269.276574) (xy 128.17933 -269.331468)
			(xy 128.187948 -269.388298) (xy 128.188466 -269.417038) (xy 128.18808 -269.444294) (xy 128.180317 -269.49825)
			(xy 128.164954 -269.550552) (xy 128.142304 -269.600135) (xy 128.112828 -269.64599) (xy 128.077126 -269.687183)
			(xy 128.035926 -269.722876) (xy 127.990064 -269.752343) (xy 127.940477 -269.774982) (xy 127.888171 -269.790334)
			(xy 127.834214 -269.798086) (xy 127.806958 -269.798546) (xy 127.779588 -269.798059) (xy 127.72541 -269.790248)
			(xy 127.672906 -269.774765) (xy 127.623159 -269.751927) (xy 127.577192 -269.722206) (xy 127.55626 -269.704566)
			(xy 127.549148 -269.69847) (xy 127.53213 -269.69212) (xy 127.446786 -269.69212) (xy 127.429768 -269.69847)
			(xy 127.422656 -269.704566) (xy 127.401723 -269.722207) (xy 127.355755 -269.751931) (xy 127.306009 -269.774777)
			(xy 127.253507 -269.790273) (xy 127.199329 -269.798102) (xy 127.144587 -269.798102) (xy 127.090409 -269.790273)
			(xy 127.037907 -269.774777) (xy 126.988161 -269.751931) (xy 126.942193 -269.722207) (xy 126.92126 -269.704566)
			(xy 126.914148 -269.69847) (xy 126.89713 -269.69212) (xy 126.811786 -269.69212) (xy 126.794768 -269.69847)
			(xy 126.787656 -269.704566) (xy 126.766723 -269.722207) (xy 126.720755 -269.751931) (xy 126.671009 -269.774777)
			(xy 126.618507 -269.790273) (xy 126.564329 -269.798102) (xy 126.509587 -269.798102) (xy 126.455409 -269.790273)
			(xy 126.402907 -269.774777) (xy 126.353161 -269.751931) (xy 126.307193 -269.722207) (xy 126.28626 -269.704566)
			(xy 126.279148 -269.69847) (xy 126.26213 -269.69212) (xy 126.176786 -269.69212) (xy 126.159768 -269.69847)
			(xy 126.152656 -269.704566) (xy 126.131723 -269.722207) (xy 126.085755 -269.751931) (xy 126.036009 -269.774777)
			(xy 125.983507 -269.790273) (xy 125.929329 -269.798102) (xy 125.874587 -269.798102) (xy 125.820409 -269.790273)
			(xy 125.767907 -269.774777) (xy 125.718161 -269.751931) (xy 125.672193 -269.722207) (xy 125.65126 -269.704566)
			(xy 125.644148 -269.69847) (xy 125.62713 -269.69212) (xy 125.541786 -269.69212) (xy 125.524768 -269.69847)
			(xy 125.517656 -269.704566) (xy 125.496709 -269.722187) (xy 125.450741 -269.751903) (xy 125.400997 -269.774743)
			(xy 125.3485 -269.790238) (xy 125.294326 -269.79807) (xy 125.266958 -269.798546) (xy 125.239707 -269.798061)
			(xy 125.185762 -269.7903) (xy 125.133469 -269.774942) (xy 125.083894 -269.752298) (xy 125.038046 -269.722831)
			(xy 124.996857 -269.68714) (xy 124.961166 -269.645951) (xy 124.9317 -269.600102) (xy 124.909057 -269.550527)
			(xy 124.893699 -269.498234) (xy 124.885938 -269.444289) (xy 124.88545 -269.417038) (xy 107.851956 -269.417038)
			(xy 107.851956 -276.051264) (xy 109.061504 -276.051264) (xy 109.061948 -276.023893) (xy 109.069771 -275.969713)
			(xy 109.085265 -275.917209) (xy 109.108112 -275.867463) (xy 109.137841 -275.821497) (xy 109.155484 -275.800566)
			(xy 109.16158 -275.793454) (xy 109.16793 -275.776436) (xy 109.16793 -275.691092) (xy 109.16158 -275.674074)
			(xy 109.155484 -275.666962) (xy 109.13781 -275.646057) (xy 109.10809 -275.600083) (xy 109.085249 -275.550332)
			(xy 109.069757 -275.497826) (xy 109.061933 -275.443645) (xy 109.061937 -275.388901) (xy 109.069769 -275.334721)
			(xy 109.085268 -275.282217) (xy 109.108116 -275.232469) (xy 109.137843 -275.1865) (xy 109.155484 -275.165566)
			(xy 109.16158 -275.158454) (xy 109.16793 -275.141436) (xy 109.16793 -275.056092) (xy 109.16158 -275.039074)
			(xy 109.155484 -275.031962) (xy 109.137858 -275.011019) (xy 109.108145 -274.965049) (xy 109.085307 -274.915304)
			(xy 109.069812 -274.862806) (xy 109.06198 -274.808632) (xy 109.061504 -274.781264) (xy 109.061944 -274.754011)
			(xy 109.069706 -274.700061) (xy 109.085066 -274.647765) (xy 109.107713 -274.598187) (xy 109.137184 -274.552336)
			(xy 109.17288 -274.511146) (xy 109.214075 -274.475455) (xy 109.259929 -274.44599) (xy 109.30951 -274.42335)
			(xy 109.361808 -274.407996) (xy 109.415759 -274.400241) (xy 109.443012 -274.399756) (xy 109.470383 -274.400201)
			(xy 109.524564 -274.408022) (xy 109.577068 -274.423515) (xy 109.626814 -274.446362) (xy 109.67278 -274.476092)
			(xy 109.69371 -274.493736) (xy 109.700822 -274.499832) (xy 109.71784 -274.506182) (xy 109.803184 -274.506182)
			(xy 109.820202 -274.499832) (xy 109.827314 -274.493736) (xy 109.848272 -274.476129) (xy 109.894237 -274.446411)
			(xy 109.943978 -274.423569) (xy 109.996473 -274.40807) (xy 110.050645 -274.400234) (xy 110.078012 -274.399756)
			(xy 110.105262 -274.400267) (xy 110.159207 -274.408024) (xy 110.211499 -274.423379) (xy 110.261074 -274.446018)
			(xy 110.306922 -274.475483) (xy 110.348112 -274.511171) (xy 110.383803 -274.552358) (xy 110.41327 -274.598205)
			(xy 110.435913 -274.647779) (xy 110.451271 -274.70007) (xy 110.459032 -274.754014) (xy 110.45952 -274.781264)
			(xy 110.459052 -274.808634) (xy 110.451238 -274.862814) (xy 110.43575 -274.915318) (xy 110.412908 -274.965065)
			(xy 110.383182 -275.011031) (xy 110.36554 -275.031962) (xy 110.359444 -275.039074) (xy 110.353094 -275.056092)
			(xy 110.353094 -275.141436) (xy 110.359444 -275.158454) (xy 110.36554 -275.165566) (xy 110.383147 -275.186527)
			(xy 110.412876 -275.232489) (xy 110.435725 -275.28223) (xy 110.451226 -275.334728) (xy 110.459058 -275.388904)
			(xy 110.459062 -275.443642) (xy 110.451237 -275.497819) (xy 110.435744 -275.550319) (xy 110.412902 -275.600064)
			(xy 110.38318 -275.64603) (xy 110.36554 -275.666962) (xy 110.359444 -275.674074) (xy 110.353094 -275.691092)
			(xy 110.353094 -275.776436) (xy 110.359444 -275.793454) (xy 110.36554 -275.800566) (xy 110.383147 -275.821527)
			(xy 110.412876 -275.867489) (xy 110.435725 -275.91723) (xy 110.451226 -275.969728) (xy 110.459058 -276.023904)
			(xy 110.459062 -276.078642) (xy 110.451237 -276.132819) (xy 110.435744 -276.185319) (xy 110.412902 -276.235064)
			(xy 110.38318 -276.28103) (xy 110.36554 -276.301962) (xy 110.359444 -276.309074) (xy 110.353094 -276.326092)
			(xy 110.353094 -276.411436) (xy 110.359444 -276.428454) (xy 110.36554 -276.435566) (xy 110.381698 -276.454665)
			(xy 110.409391 -276.496327) (xy 110.431379 -276.541263) (xy 110.439708 -276.564852) (xy 110.443518 -276.576282)
			(xy 110.460282 -276.593046) (xy 110.559342 -276.626574) (xy 110.582964 -276.623526) (xy 110.59287 -276.616668)
			(xy 110.616626 -276.601325) (xy 110.667684 -276.577015) (xy 110.721771 -276.560506) (xy 110.777701 -276.552158)
			(xy 110.805976 -276.551644) (xy 110.833224 -276.5522) (xy 110.887167 -276.559952) (xy 110.939458 -276.575302)
			(xy 110.989031 -276.597937) (xy 111.03488 -276.627396) (xy 111.076069 -276.66308) (xy 111.111761 -276.704263)
			(xy 111.141229 -276.750105) (xy 111.163873 -276.799675) (xy 111.179232 -276.851962) (xy 111.186994 -276.905904)
			(xy 111.187484 -276.933152) (xy 111.18705 -276.959469) (xy 111.179827 -277.011604) (xy 111.165511 -277.062253)
			(xy 111.144372 -277.110455) (xy 111.116813 -277.155296) (xy 111.083356 -277.195927) (xy 111.064294 -277.214076)
			(xy 111.0569 -277.221604) (xy 111.048372 -277.240879) (xy 111.047784 -277.251414) (xy 111.047784 -277.32609)
			(xy 111.04831 -277.33664) (xy 111.056848 -277.355935) (xy 111.064294 -277.363428) (xy 111.083386 -277.38155)
			(xy 111.116863 -277.422173) (xy 111.144432 -277.467016) (xy 111.165568 -277.515226) (xy 111.17987 -277.565886)
			(xy 111.187065 -277.618032) (xy 111.187322 -277.634192) (xy 120.08485 -277.634192) (xy 120.085348 -277.606122)
			(xy 120.093588 -277.550589) (xy 120.109875 -277.496862) (xy 120.133856 -277.446101) (xy 120.165015 -277.3994)
			(xy 120.202679 -277.357769) (xy 120.224042 -277.339552) (xy 120.232678 -277.33244) (xy 120.24233 -277.312882)
			(xy 120.24487 -277.213314) (xy 120.236234 -277.193502) (xy 120.227852 -277.185882) (xy 120.208519 -277.167737)
			(xy 120.174597 -277.126988) (xy 120.146643 -277.081936) (xy 120.125194 -277.033447) (xy 120.110665 -276.982456)
			(xy 120.103334 -276.929944) (xy 120.102884 -276.903434) (xy 120.103387 -276.876182) (xy 120.111139 -276.822233)
			(xy 120.12649 -276.769937) (xy 120.149128 -276.720357) (xy 120.178592 -276.674504) (xy 120.214282 -276.633311)
			(xy 120.255471 -276.597617) (xy 120.30132 -276.568148) (xy 120.350897 -276.545505) (xy 120.403192 -276.530148)
			(xy 120.45714 -276.52239) (xy 120.484392 -276.521926) (xy 120.510644 -276.52235) (xy 120.562654 -276.529537)
			(xy 120.613186 -276.543791) (xy 120.661285 -276.564842) (xy 120.706042 -276.592292) (xy 120.74661 -276.625622)
			(xy 120.782223 -276.664202) (xy 120.797574 -276.685502) (xy 120.805448 -276.696678) (xy 120.829324 -276.708108)
			(xy 120.94337 -276.700234) (xy 120.965468 -276.685502) (xy 120.971564 -276.67331) (xy 120.983825 -276.650017)
			(xy 121.013792 -276.606742) (xy 121.049423 -276.567996) (xy 121.09004 -276.534514) (xy 121.134873 -276.506933)
			(xy 121.183072 -276.485774) (xy 121.233721 -276.47144) (xy 121.285859 -276.464203) (xy 121.312178 -276.46376)
			(xy 121.345706 -276.465284) (xy 121.355779 -276.465774) (xy 121.374985 -276.459662) (xy 121.390363 -276.446633)
			(xy 121.399547 -276.428692) (xy 121.401125 -276.408599) (xy 121.394855 -276.389444) (xy 121.381699 -276.374175)
			(xy 121.372884 -276.369272) (xy 121.351374 -276.358095) (xy 121.311121 -276.331087) (xy 121.29262 -276.315424)
			(xy 121.285508 -276.309328) (xy 121.26849 -276.302978) (xy 121.183146 -276.302978) (xy 121.166128 -276.309328)
			(xy 121.159016 -276.315424) (xy 121.138092 -276.333073) (xy 121.092116 -276.362782) (xy 121.042367 -276.385616)
			(xy 120.989865 -276.401105) (xy 120.935688 -276.408931) (xy 120.908318 -276.409404) (xy 120.881065 -276.408928)
			(xy 120.827115 -276.401173) (xy 120.774817 -276.385819) (xy 120.725237 -276.363179) (xy 120.679383 -276.333712)
			(xy 120.63819 -276.29802) (xy 120.602496 -276.256828) (xy 120.573028 -276.210976) (xy 120.550386 -276.161396)
			(xy 120.53503 -276.109099) (xy 120.527273 -276.055149) (xy 120.52681 -276.027896) (xy 120.527271 -276.000526)
			(xy 120.53509 -275.946346) (xy 120.55058 -275.893843) (xy 120.573423 -275.844096) (xy 120.603148 -275.79813)
			(xy 120.62079 -275.777198) (xy 120.626886 -275.770086) (xy 120.633236 -275.753068) (xy 120.633236 -275.667724)
			(xy 120.626886 -275.650706) (xy 120.62079 -275.643594) (xy 120.603147 -275.622664) (xy 120.573425 -275.576695)
			(xy 120.550582 -275.526948) (xy 120.535088 -275.474446) (xy 120.52726 -275.420267) (xy 120.527261 -275.365527)
			(xy 120.535089 -275.311349) (xy 120.550584 -275.258847) (xy 120.573428 -275.2091) (xy 120.603151 -275.163131)
			(xy 120.62079 -275.142198) (xy 120.626886 -275.135086) (xy 120.633236 -275.118068) (xy 120.633236 -275.032724)
			(xy 120.626886 -275.015706) (xy 120.62079 -275.008594) (xy 120.603133 -274.987676) (xy 120.573424 -274.941699)
			(xy 120.550592 -274.891948) (xy 120.535105 -274.839444) (xy 120.527282 -274.785266) (xy 120.52681 -274.757896)
			(xy 120.527252 -274.730642) (xy 120.53501 -274.67669) (xy 120.550367 -274.62439) (xy 120.573011 -274.574809)
			(xy 120.602481 -274.528955) (xy 120.638177 -274.487762) (xy 120.679373 -274.452068) (xy 120.725228 -274.422601)
			(xy 120.774811 -274.399959) (xy 120.827111 -274.384605) (xy 120.881064 -274.37685) (xy 120.908318 -274.376388)
			(xy 120.935688 -274.376846) (xy 120.989868 -274.384667) (xy 121.042371 -274.400158) (xy 121.092118 -274.423001)
			(xy 121.138084 -274.452726) (xy 121.159016 -274.470368) (xy 121.166128 -274.476464) (xy 121.183146 -274.482814)
			(xy 121.26849 -274.482814) (xy 121.285508 -274.476464) (xy 121.29262 -274.470368) (xy 121.313567 -274.452748)
			(xy 121.359536 -274.423034) (xy 121.40928 -274.400195) (xy 121.461777 -274.3847) (xy 121.51595 -274.376865)
			(xy 121.543318 -274.376388) (xy 121.57057 -274.376861) (xy 121.624517 -274.38462) (xy 121.676812 -274.399977)
			(xy 121.726389 -274.42262) (xy 121.772239 -274.452088) (xy 121.813429 -274.487781) (xy 121.849121 -274.528972)
			(xy 121.878587 -274.574823) (xy 121.901228 -274.624401) (xy 121.916583 -274.676696) (xy 121.92434 -274.730644)
			(xy 121.924826 -274.757896) (xy 121.924376 -274.785267) (xy 121.916557 -274.839447) (xy 121.901065 -274.891951)
			(xy 121.878219 -274.941698) (xy 121.84849 -274.987664) (xy 121.830846 -275.008594) (xy 121.82475 -275.015706)
			(xy 121.8184 -275.032724) (xy 121.8184 -275.118068) (xy 121.82475 -275.135086) (xy 121.830846 -275.142198)
			(xy 121.848484 -275.163133) (xy 121.878211 -275.2091) (xy 121.901058 -275.258846) (xy 121.916556 -275.311348)
			(xy 121.924385 -275.365526) (xy 121.924386 -275.420268) (xy 121.916557 -275.474447) (xy 121.90106 -275.526949)
			(xy 121.878214 -275.576695) (xy 121.848488 -275.622662) (xy 121.830846 -275.643594) (xy 121.82475 -275.650706)
			(xy 121.8184 -275.667724) (xy 121.8184 -275.753068) (xy 121.82475 -275.770086) (xy 121.830846 -275.777198)
			(xy 121.848489 -275.798127) (xy 121.878202 -275.8441) (xy 121.901038 -275.893848) (xy 121.916528 -275.94635)
			(xy 121.924354 -276.000526) (xy 121.924826 -276.027896) (xy 121.924546 -276.046184) (xy 124.460254 -276.046184)
			(xy 124.460698 -276.018813) (xy 124.468519 -275.964632) (xy 124.484012 -275.912128) (xy 124.506859 -275.862382)
			(xy 124.53659 -275.816416) (xy 124.554234 -275.795486) (xy 124.56033 -275.788374) (xy 124.56668 -275.771356)
			(xy 124.56668 -275.686012) (xy 124.56033 -275.668994) (xy 124.554234 -275.661882) (xy 124.536625 -275.640925)
			(xy 124.506908 -275.59496) (xy 124.484065 -275.545219) (xy 124.468567 -275.492723) (xy 124.460732 -275.438552)
			(xy 124.460254 -275.411184) (xy 124.460763 -275.383934) (xy 124.46852 -275.329989) (xy 124.483876 -275.277697)
			(xy 124.506516 -275.228122) (xy 124.53598 -275.182274) (xy 124.571669 -275.141085) (xy 124.612856 -275.105394)
			(xy 124.658703 -275.075927) (xy 124.708277 -275.053283) (xy 124.760568 -275.037925) (xy 124.814512 -275.030164)
			(xy 124.841762 -275.029676) (xy 124.869132 -275.030146) (xy 124.923312 -275.03796) (xy 124.975816 -275.053447)
			(xy 125.025563 -275.076288) (xy 125.071529 -275.106014) (xy 125.09246 -275.123656) (xy 125.099572 -275.129752)
			(xy 125.11659 -275.136102) (xy 125.201934 -275.136102) (xy 125.218952 -275.129752) (xy 125.226064 -275.123656)
			(xy 125.246997 -275.106015) (xy 125.292965 -275.076291) (xy 125.342711 -275.053445) (xy 125.395213 -275.037949)
			(xy 125.449391 -275.03012) (xy 125.504133 -275.03012) (xy 125.558311 -275.037949) (xy 125.610813 -275.053445)
			(xy 125.660559 -275.076291) (xy 125.706527 -275.106015) (xy 125.72746 -275.123656) (xy 125.734572 -275.129752)
			(xy 125.75159 -275.136102) (xy 125.836934 -275.136102) (xy 125.853952 -275.129752) (xy 125.861064 -275.123656)
			(xy 125.881997 -275.106015) (xy 125.927965 -275.076291) (xy 125.977711 -275.053445) (xy 126.030213 -275.037949)
			(xy 126.084391 -275.03012) (xy 126.139133 -275.03012) (xy 126.193311 -275.037949) (xy 126.245813 -275.053445)
			(xy 126.295559 -275.076291) (xy 126.341527 -275.106015) (xy 126.36246 -275.123656) (xy 126.369572 -275.129752)
			(xy 126.38659 -275.136102) (xy 126.471934 -275.136102) (xy 126.488952 -275.129752) (xy 126.496064 -275.123656)
			(xy 126.516997 -275.106015) (xy 126.562965 -275.076291) (xy 126.612711 -275.053445) (xy 126.665213 -275.037949)
			(xy 126.719391 -275.03012) (xy 126.774133 -275.03012) (xy 126.828311 -275.037949) (xy 126.880813 -275.053445)
			(xy 126.930559 -275.076291) (xy 126.976527 -275.106015) (xy 126.99746 -275.123656) (xy 127.004572 -275.129752)
			(xy 127.02159 -275.136102) (xy 127.106934 -275.136102) (xy 127.123952 -275.129752) (xy 127.131064 -275.123656)
			(xy 127.151993 -275.106013) (xy 127.197967 -275.076303) (xy 127.247716 -275.053469) (xy 127.300217 -275.037978)
			(xy 127.354393 -275.03015) (xy 127.381762 -275.029676) (xy 127.409013 -275.030191) (xy 127.462961 -275.037942)
			(xy 127.515257 -275.053292) (xy 127.564836 -275.075929) (xy 127.610689 -275.105392) (xy 127.651882 -275.14108)
			(xy 127.687576 -275.182268) (xy 127.717045 -275.228116) (xy 127.739689 -275.277692) (xy 127.755047 -275.329986)
			(xy 127.762806 -275.383933) (xy 127.76327 -275.411184) (xy 127.762802 -275.438554) (xy 127.754986 -275.492734)
			(xy 127.739497 -275.545237) (xy 127.716656 -275.594984) (xy 127.686931 -275.640951) (xy 127.66929 -275.661882)
			(xy 127.663194 -275.668994) (xy 127.656844 -275.686012) (xy 127.656844 -275.771356) (xy 127.663194 -275.788374)
			(xy 127.66929 -275.795486) (xy 127.686934 -275.816414) (xy 127.716646 -275.862388) (xy 127.739481 -275.912136)
			(xy 127.754971 -275.964638) (xy 127.762797 -276.018815) (xy 127.76327 -276.046184) (xy 127.76283 -276.073438)
			(xy 127.755074 -276.127392) (xy 127.739718 -276.179693) (xy 127.717075 -276.229275) (xy 127.687605 -276.27513)
			(xy 127.651908 -276.316324) (xy 127.610713 -276.352018) (xy 127.564856 -276.381485) (xy 127.515272 -276.404126)
			(xy 127.46297 -276.419479) (xy 127.409016 -276.427231) (xy 127.381762 -276.427692) (xy 127.354393 -276.427192)
			(xy 127.300215 -276.419382) (xy 127.247712 -276.403901) (xy 127.197965 -276.381067) (xy 127.151997 -276.35135)
			(xy 127.131064 -276.333712) (xy 127.123952 -276.327616) (xy 127.106934 -276.321266) (xy 127.02159 -276.321266)
			(xy 127.004572 -276.327616) (xy 126.99746 -276.333712) (xy 126.976527 -276.351353) (xy 126.930559 -276.381077)
			(xy 126.880813 -276.403923) (xy 126.828311 -276.419419) (xy 126.774133 -276.427248) (xy 126.719391 -276.427248)
			(xy 126.665213 -276.419419) (xy 126.612711 -276.403923) (xy 126.562965 -276.381077) (xy 126.516997 -276.351353)
			(xy 126.496064 -276.333712) (xy 126.488952 -276.327616) (xy 126.471934 -276.321266) (xy 126.38659 -276.321266)
			(xy 126.369572 -276.327616) (xy 126.36246 -276.333712) (xy 126.341527 -276.351353) (xy 126.295559 -276.381077)
			(xy 126.245813 -276.403923) (xy 126.193311 -276.419419) (xy 126.139133 -276.427248) (xy 126.084391 -276.427248)
			(xy 126.030213 -276.419419) (xy 125.977711 -276.403923) (xy 125.927965 -276.381077) (xy 125.881997 -276.351353)
			(xy 125.861064 -276.333712) (xy 125.853952 -276.327616) (xy 125.836934 -276.321266) (xy 125.75159 -276.321266)
			(xy 125.734572 -276.327616) (xy 125.72746 -276.333712) (xy 125.706527 -276.351353) (xy 125.660559 -276.381077)
			(xy 125.610813 -276.403923) (xy 125.558311 -276.419419) (xy 125.504133 -276.427248) (xy 125.449391 -276.427248)
			(xy 125.395213 -276.419419) (xy 125.342711 -276.403923) (xy 125.292965 -276.381077) (xy 125.246997 -276.351353)
			(xy 125.226064 -276.333712) (xy 125.218952 -276.327616) (xy 125.201934 -276.321266) (xy 125.11659 -276.321266)
			(xy 125.099572 -276.327616) (xy 125.09246 -276.333712) (xy 125.071518 -276.351338) (xy 125.025547 -276.381052)
			(xy 124.975803 -276.40389) (xy 124.923304 -276.419384) (xy 124.86913 -276.427216) (xy 124.841762 -276.427692)
			(xy 124.814509 -276.427257) (xy 124.760559 -276.419495) (xy 124.708262 -276.404135) (xy 124.658684 -276.381488)
			(xy 124.612833 -276.352016) (xy 124.571642 -276.316319) (xy 124.535951 -276.275124) (xy 124.506486 -276.229269)
			(xy 124.483846 -276.179687) (xy 124.468493 -276.127388) (xy 124.460739 -276.073437) (xy 124.460254 -276.046184)
			(xy 121.924546 -276.046184) (xy 121.924387 -276.056524) (xy 121.915839 -276.113137) (xy 121.898921 -276.167835)
			(xy 121.874013 -276.219388) (xy 121.841674 -276.266636) (xy 121.802633 -276.308517) (xy 121.757768 -276.344087)
			(xy 121.708088 -276.372547) (xy 121.654709 -276.393257) (xy 121.626884 -276.400006) (xy 121.613422 -276.403054)
			(xy 121.593102 -276.422358) (xy 121.561098 -276.535134) (xy 121.568464 -276.562312) (xy 121.57837 -276.571964)
			(xy 121.596267 -276.58999) (xy 121.627628 -276.629949) (xy 121.653411 -276.673716) (xy 121.673158 -276.720517)
			(xy 121.686522 -276.769523) (xy 121.693266 -276.81987) (xy 121.693686 -276.845268) (xy 121.693215 -276.872521)
			(xy 121.685462 -276.926473) (xy 121.670109 -276.978772) (xy 121.647468 -277.028353) (xy 121.618001 -277.074208)
			(xy 121.582308 -277.115401) (xy 121.541116 -277.151095) (xy 121.495262 -277.180563) (xy 121.445681 -277.203205)
			(xy 121.393383 -277.21856) (xy 121.339431 -277.226314) (xy 121.312178 -277.226776) (xy 121.285925 -277.226374)
			(xy 121.233915 -277.219182) (xy 121.183382 -277.204925) (xy 121.135283 -277.18387) (xy 121.090527 -277.156417)
			(xy 121.049959 -277.123084) (xy 121.014347 -277.084501) (xy 120.998996 -277.0632) (xy 120.991122 -277.052024)
			(xy 120.967246 -277.040594) (xy 120.8532 -277.048468) (xy 120.831102 -277.0632) (xy 120.825006 -277.075392)
			(xy 120.812694 -277.098751) (xy 120.782606 -277.142141) (xy 120.746822 -277.180968) (xy 120.726708 -277.198074)
			(xy 120.718072 -277.205186) (xy 120.70842 -277.224744) (xy 120.70588 -277.324312) (xy 120.714516 -277.344124)
			(xy 120.722898 -277.351744) (xy 120.742185 -277.369935) (xy 120.776113 -277.410673) (xy 120.804075 -277.455716)
			(xy 120.825531 -277.504195) (xy 120.84007 -277.555179) (xy 120.847411 -277.607684) (xy 120.847866 -277.634192)
			(xy 120.84738 -277.661443) (xy 120.839624 -277.715391) (xy 120.834827 -277.731728) (xy 120.970292 -277.731728)
			(xy 120.974363 -277.676106) (xy 120.986489 -277.621669) (xy 121.006412 -277.569578) (xy 121.033708 -277.520943)
			(xy 121.067794 -277.4768) (xy 121.107943 -277.438091) (xy 121.153301 -277.40564) (xy 121.202901 -277.380139)
			(xy 121.255685 -277.362132) (xy 121.310528 -277.352002) (xy 121.366262 -277.349965) (xy 121.421699 -277.356065)
			(xy 121.475656 -277.370171) (xy 121.526985 -277.391983) (xy 121.574591 -277.421037) (xy 121.617459 -277.456712)
			(xy 121.654676 -277.498249) (xy 121.685449 -277.544762) (xy 121.709121 -277.595259) (xy 121.723891 -277.644352)
			(xy 127.083566 -277.644352) (xy 127.084018 -277.618036) (xy 127.09124 -277.565902) (xy 127.105554 -277.515255)
			(xy 127.126689 -277.467053) (xy 127.154244 -277.422211) (xy 127.187696 -277.381579) (xy 127.206756 -277.363428)
			(xy 127.214141 -277.355892) (xy 127.222676 -277.336623) (xy 127.223266 -277.32609) (xy 127.223266 -277.251414)
			(xy 127.222753 -277.240862) (xy 127.214208 -277.221566) (xy 127.206756 -277.214076) (xy 127.187676 -277.195942)
			(xy 127.154196 -277.155323) (xy 127.126624 -277.110482) (xy 127.105485 -277.062275) (xy 127.091181 -277.011616)
			(xy 127.083985 -276.959472) (xy 127.083566 -276.933152) (xy 127.084052 -276.905901) (xy 127.091808 -276.851953)
			(xy 127.107163 -276.799658) (xy 127.129805 -276.750081) (xy 127.159271 -276.704231) (xy 127.194962 -276.66304)
			(xy 127.236153 -276.627349) (xy 127.282003 -276.597883) (xy 127.33158 -276.575241) (xy 127.383875 -276.559886)
			(xy 127.437823 -276.55213) (xy 127.492325 -276.55213) (xy 127.546273 -276.559886) (xy 127.598568 -276.575241)
			(xy 127.648145 -276.597883) (xy 127.693995 -276.627349) (xy 127.735186 -276.66304) (xy 127.770877 -276.704231)
			(xy 127.800343 -276.750081) (xy 127.822985 -276.799658) (xy 127.83834 -276.851953) (xy 127.846096 -276.905901)
			(xy 127.846582 -276.933152) (xy 127.846149 -276.959469) (xy 127.838926 -277.011604) (xy 127.824609 -277.062253)
			(xy 127.803471 -277.110455) (xy 127.775912 -277.155296) (xy 127.742454 -277.195927) (xy 127.723392 -277.214076)
			(xy 127.715998 -277.221604) (xy 127.70747 -277.240879) (xy 127.706882 -277.251414) (xy 127.706882 -277.32609)
			(xy 127.707408 -277.33664) (xy 127.715946 -277.355935) (xy 127.723392 -277.363428) (xy 127.742483 -277.381551)
			(xy 127.775961 -277.422173) (xy 127.80353 -277.467016) (xy 127.824666 -277.515226) (xy 127.838968 -277.565886)
			(xy 127.846163 -277.618032) (xy 127.846582 -277.644352) (xy 127.846096 -277.671603) (xy 127.83834 -277.725551)
			(xy 127.822985 -277.777846) (xy 127.800343 -277.827423) (xy 127.770877 -277.873273) (xy 127.735186 -277.914464)
			(xy 127.693995 -277.950155) (xy 127.648145 -277.979621) (xy 127.598568 -278.002263) (xy 127.546273 -278.017618)
			(xy 127.492325 -278.025374) (xy 127.437823 -278.025374) (xy 127.383875 -278.017618) (xy 127.33158 -278.002263)
			(xy 127.282003 -277.979621) (xy 127.236153 -277.950155) (xy 127.194962 -277.914464) (xy 127.159271 -277.873273)
			(xy 127.129805 -277.827423) (xy 127.107163 -277.777846) (xy 127.091808 -277.725551) (xy 127.084052 -277.671603)
			(xy 127.083566 -277.644352) (xy 121.723891 -277.644352) (xy 121.725189 -277.648666) (xy 121.733309 -277.703842)
			(xy 121.733818 -277.731728) (xy 121.733309 -277.759614) (xy 121.725189 -277.81479) (xy 121.709121 -277.868197)
			(xy 121.685449 -277.918694) (xy 121.654676 -277.965207) (xy 121.617459 -278.006744) (xy 121.574591 -278.042419)
			(xy 121.526985 -278.071473) (xy 121.475656 -278.093285) (xy 121.421699 -278.107391) (xy 121.366262 -278.113491)
			(xy 121.310528 -278.111454) (xy 121.255685 -278.101324) (xy 121.202901 -278.083317) (xy 121.153301 -278.057816)
			(xy 121.107943 -278.025365) (xy 121.067794 -277.986656) (xy 121.033708 -277.942513) (xy 121.006412 -277.893878)
			(xy 120.986489 -277.841787) (xy 120.974363 -277.78735) (xy 120.970292 -277.731728) (xy 120.834827 -277.731728)
			(xy 120.824269 -277.767686) (xy 120.801627 -277.817263) (xy 120.772161 -277.863113) (xy 120.73647 -277.904304)
			(xy 120.695279 -277.939995) (xy 120.649429 -277.969461) (xy 120.599852 -277.992103) (xy 120.547557 -278.007458)
			(xy 120.493609 -278.015214) (xy 120.439107 -278.015214) (xy 120.385159 -278.007458) (xy 120.332864 -277.992103)
			(xy 120.283287 -277.969461) (xy 120.237437 -277.939995) (xy 120.196246 -277.904304) (xy 120.160555 -277.863113)
			(xy 120.131089 -277.817263) (xy 120.108447 -277.767686) (xy 120.093092 -277.715391) (xy 120.085336 -277.661443)
			(xy 120.08485 -277.634192) (xy 111.187322 -277.634192) (xy 111.187484 -277.644352) (xy 111.187 -277.671605)
			(xy 111.179249 -277.725556) (xy 111.163898 -277.777855) (xy 111.141259 -277.827437) (xy 111.111794 -277.873291)
			(xy 111.076102 -277.914485) (xy 111.03491 -277.950179) (xy 110.989058 -277.979648) (xy 110.939478 -278.002289)
			(xy 110.88718 -278.017644) (xy 110.833229 -278.025398) (xy 110.805976 -278.02586) (xy 110.779505 -278.025464)
			(xy 110.72707 -278.018167) (xy 110.676147 -278.003687) (xy 110.627717 -277.982304) (xy 110.582709 -277.954428)
			(xy 110.541989 -277.920596) (xy 110.506339 -277.881457) (xy 110.476445 -277.837763) (xy 110.452882 -277.790355)
			(xy 110.436101 -277.740144) (xy 110.430818 -277.714202) (xy 110.428532 -277.701756) (xy 110.413292 -277.682198)
			(xy 110.31347 -277.638002) (xy 110.288832 -277.639526) (xy 110.27791 -277.646384) (xy 110.255255 -277.659759)
			(xy 110.207064 -277.680861) (xy 110.156431 -277.695147) (xy 110.104317 -277.702345) (xy 110.078012 -277.702772)
			(xy 110.050758 -277.702333) (xy 109.996804 -277.694577) (xy 109.944504 -277.679221) (xy 109.894921 -277.656577)
			(xy 109.849066 -277.627107) (xy 109.807872 -277.591411) (xy 109.772179 -277.550215) (xy 109.742711 -277.504358)
			(xy 109.720071 -277.454774) (xy 109.704718 -277.402472) (xy 109.696965 -277.348518) (xy 109.696504 -277.321264)
			(xy 109.696948 -277.293893) (xy 109.704771 -277.239713) (xy 109.720265 -277.187209) (xy 109.743112 -277.137463)
			(xy 109.772841 -277.091497) (xy 109.790484 -277.070566) (xy 109.79658 -277.063454) (xy 109.80293 -277.046436)
			(xy 109.80293 -276.961092) (xy 109.79658 -276.944074) (xy 109.790484 -276.936962) (xy 109.772858 -276.916019)
			(xy 109.743145 -276.870049) (xy 109.720307 -276.820304) (xy 109.704812 -276.767806) (xy 109.69698 -276.713632)
			(xy 109.696504 -276.686264) (xy 109.697083 -276.656788) (xy 109.706142 -276.598536) (xy 109.724056 -276.542372)
			(xy 109.750396 -276.489632) (xy 109.784537 -276.441572) (xy 109.804708 -276.420072) (xy 109.811249 -276.412742)
			(xy 109.81869 -276.394578) (xy 109.819186 -276.384766) (xy 109.819186 -276.331426) (xy 109.81182 -276.324568)
			(xy 109.804477 -276.318045) (xy 109.786323 -276.310594) (xy 109.776514 -276.31009) (xy 109.74451 -276.31009)
			(xy 109.734698 -276.310593) (xy 109.716533 -276.318027) (xy 109.709204 -276.324568) (xy 109.687705 -276.344742)
			(xy 109.639645 -276.378886) (xy 109.586906 -276.405232) (xy 109.530741 -276.423153) (xy 109.472489 -276.432223)
			(xy 109.443012 -276.432772) (xy 109.415758 -276.432333) (xy 109.361804 -276.424577) (xy 109.309504 -276.409221)
			(xy 109.259921 -276.386577) (xy 109.214066 -276.357107) (xy 109.172872 -276.321411) (xy 109.137179 -276.280215)
			(xy 109.107711 -276.234358) (xy 109.085071 -276.184774) (xy 109.069718 -276.132472) (xy 109.061965 -276.078518)
			(xy 109.061504 -276.051264) (xy 107.851956 -276.051264) (xy 107.851956 -276.596856) (xy 107.851334 -276.626832)
			(xy 107.84195 -276.686046) (xy 107.823423 -276.743063) (xy 107.796207 -276.796483) (xy 107.760973 -276.844989)
			(xy 107.740196 -276.866604) (xy 104.257348 -280.349452) (xy 104.23574 -280.370242) (xy 104.187242 -280.4055)
			(xy 104.133823 -280.432733) (xy 104.076801 -280.451269) (xy 104.01758 -280.460654) (xy 103.9876 -280.461212)
			(xy 100.993448 -280.461212) (xy 100.983402 -280.461577) (xy 100.964806 -280.469169) (xy 100.95738 -280.475944)
			(xy 100.816156 -280.617168) (xy 105.533444 -280.617168) (xy 105.53393 -280.589917) (xy 105.541686 -280.535969)
			(xy 105.557041 -280.483674) (xy 105.579683 -280.434097) (xy 105.609149 -280.388247) (xy 105.64484 -280.347056)
			(xy 105.686031 -280.311365) (xy 105.731881 -280.281899) (xy 105.781458 -280.259257) (xy 105.833753 -280.243902)
			(xy 105.887701 -280.236146) (xy 105.942203 -280.236146) (xy 105.996151 -280.243902) (xy 106.048446 -280.259257)
			(xy 106.098023 -280.281899) (xy 106.143873 -280.311365) (xy 106.185064 -280.347056) (xy 106.220755 -280.388247)
			(xy 106.250221 -280.434097) (xy 106.272863 -280.483674) (xy 106.288218 -280.535969) (xy 106.295974 -280.589917)
			(xy 106.29646 -280.617168) (xy 106.296402 -280.627794) (xy 106.295259 -280.649015) (xy 106.294174 -280.659586)
			(xy 106.292904 -280.669238) (xy 106.29773 -280.687526) (xy 106.349292 -280.758392) (xy 106.365294 -280.768552)
			(xy 106.374692 -280.770584) (xy 106.390186 -280.77414) (xy 106.399838 -280.776426) (xy 106.418888 -280.773886)
			(xy 106.497628 -280.728674) (xy 106.509566 -280.713434) (xy 106.51236 -280.703782) (xy 106.520447 -280.677692)
			(xy 106.542991 -280.627942) (xy 106.572402 -280.581917) (xy 106.60808 -280.54056) (xy 106.649294 -280.504717)
			(xy 106.6952 -280.475122) (xy 106.74486 -280.452379) (xy 106.797257 -280.436956) (xy 106.851318 -280.429166)
			(xy 106.878628 -280.4287) (xy 106.9038 -280.429089) (xy 106.953707 -280.435711) (xy 107.002311 -280.448836)
			(xy 107.025694 -280.458164) (xy 107.035854 -280.462482) (xy 107.05719 -280.461974) (xy 107.145328 -280.420064)
			(xy 107.159298 -280.403808) (xy 107.162346 -280.39314) (xy 107.171111 -280.365228) (xy 107.196048 -280.312306)
			(xy 107.228773 -280.263812) (xy 107.26852 -280.220885) (xy 107.314357 -280.184531) (xy 107.365207 -280.155603)
			(xy 107.419879 -280.13478) (xy 107.477089 -280.12255) (xy 107.506262 -280.120344) (xy 107.517946 -280.119582)
			(xy 107.538012 -280.108406) (xy 107.597448 -280.02484) (xy 107.601512 -280.002234) (xy 107.59821 -279.991058)
			(xy 107.591446 -279.965556) (xy 107.584179 -279.913298) (xy 107.583732 -279.886918) (xy 107.584218 -279.859667)
			(xy 107.591974 -279.805719) (xy 107.607329 -279.753424) (xy 107.629971 -279.703847) (xy 107.659437 -279.657997)
			(xy 107.695128 -279.616806) (xy 107.736319 -279.581115) (xy 107.782169 -279.551649) (xy 107.831746 -279.529007)
			(xy 107.884041 -279.513652) (xy 107.937989 -279.505896) (xy 107.992491 -279.505896) (xy 108.046439 -279.513652)
			(xy 108.098734 -279.529007) (xy 108.148311 -279.551649) (xy 108.194161 -279.581115) (xy 108.235352 -279.616806)
			(xy 108.271043 -279.657997) (xy 108.300509 -279.703847) (xy 108.323151 -279.753424) (xy 108.338506 -279.805719)
			(xy 108.346262 -279.859667) (xy 108.346748 -279.886918) (xy 108.346265 -279.915793) (xy 108.337582 -279.972885)
			(xy 108.320385 -280.028015) (xy 108.295069 -280.07992) (xy 108.262214 -280.127412) (xy 108.222571 -280.169404)
			(xy 108.177046 -280.204936) (xy 108.126683 -280.233195) (xy 108.072634 -280.253533) (xy 108.016135 -280.265486)
			(xy 107.987338 -280.267664) (xy 107.975654 -280.268426) (xy 107.955588 -280.279602) (xy 107.896152 -280.363168)
			(xy 107.892088 -280.385774) (xy 107.89539 -280.39695) (xy 107.902155 -280.422452) (xy 107.909422 -280.47471)
			(xy 107.909868 -280.50109) (xy 107.9091 -280.535173) (xy 107.896969 -280.602251) (xy 107.891764 -280.617168)
			(xy 113.693956 -280.617168) (xy 113.694442 -280.589917) (xy 113.702198 -280.535969) (xy 113.717553 -280.483674)
			(xy 113.740195 -280.434097) (xy 113.769661 -280.388247) (xy 113.805352 -280.347056) (xy 113.846543 -280.311365)
			(xy 113.892393 -280.281899) (xy 113.94197 -280.259257) (xy 113.994265 -280.243902) (xy 114.048213 -280.236146)
			(xy 114.102715 -280.236146) (xy 114.156663 -280.243902) (xy 114.208958 -280.259257) (xy 114.258535 -280.281899)
			(xy 114.304385 -280.311365) (xy 114.345576 -280.347056) (xy 114.381267 -280.388247) (xy 114.410733 -280.434097)
			(xy 114.433375 -280.483674) (xy 114.44873 -280.535969) (xy 114.456486 -280.589917) (xy 114.456972 -280.617168)
			(xy 114.456914 -280.627794) (xy 114.455771 -280.649015) (xy 114.454686 -280.659586) (xy 114.453416 -280.669238)
			(xy 114.458242 -280.687526) (xy 114.509804 -280.758392) (xy 114.525806 -280.768552) (xy 114.535204 -280.770584)
			(xy 114.550698 -280.77414) (xy 114.56035 -280.776426) (xy 114.5794 -280.773886) (xy 114.65814 -280.728674)
			(xy 114.670078 -280.713434) (xy 114.672872 -280.703782) (xy 114.680948 -280.677689) (xy 114.703493 -280.627938)
			(xy 114.732906 -280.581913) (xy 114.768585 -280.540556) (xy 114.8098 -280.504713) (xy 114.855708 -280.475118)
			(xy 114.905369 -280.452376) (xy 114.957767 -280.436953) (xy 115.01183 -280.429165) (xy 115.03914 -280.4287)
			(xy 115.064312 -280.429085) (xy 115.114219 -280.435709) (xy 115.162823 -280.448835) (xy 115.186206 -280.458164)
			(xy 115.196366 -280.462482) (xy 115.217702 -280.461974) (xy 115.30584 -280.420064) (xy 115.31981 -280.403808)
			(xy 115.322858 -280.39314) (xy 115.331613 -280.365225) (xy 115.356551 -280.312302) (xy 115.389277 -280.263808)
			(xy 115.429026 -280.220881) (xy 115.474864 -280.184527) (xy 115.525716 -280.1556) (xy 115.580389 -280.134778)
			(xy 115.6376 -280.122549) (xy 115.666774 -280.120344) (xy 115.678458 -280.119582) (xy 115.698524 -280.108406)
			(xy 115.75796 -280.02484) (xy 115.762024 -280.002234) (xy 115.758722 -279.991058) (xy 115.751959 -279.965556)
			(xy 115.744691 -279.913298) (xy 115.744244 -279.886918) (xy 115.74473 -279.859667) (xy 115.752486 -279.805719)
			(xy 115.767841 -279.753424) (xy 115.790483 -279.703847) (xy 115.819949 -279.657997) (xy 115.85564 -279.616806)
			(xy 115.896831 -279.581115) (xy 115.942681 -279.551649) (xy 115.992258 -279.529007) (xy 116.044553 -279.513652)
			(xy 116.098501 -279.505896) (xy 116.153003 -279.505896) (xy 116.206951 -279.513652) (xy 116.259246 -279.529007)
			(xy 116.308823 -279.551649) (xy 116.354673 -279.581115) (xy 116.395864 -279.616806) (xy 116.431555 -279.657997)
			(xy 116.461021 -279.703847) (xy 116.483663 -279.753424) (xy 116.499018 -279.805719) (xy 116.506774 -279.859667)
			(xy 116.50726 -279.886918) (xy 116.506766 -279.915792) (xy 116.498083 -279.972884) (xy 116.480887 -280.028012)
			(xy 116.455572 -280.079916) (xy 116.422718 -280.127408) (xy 116.383076 -280.1694) (xy 116.337553 -280.204933)
			(xy 116.287192 -280.233192) (xy 116.233144 -280.253531) (xy 116.176647 -280.265485) (xy 116.14785 -280.267664)
			(xy 116.136166 -280.268426) (xy 116.1161 -280.279602) (xy 116.056664 -280.363168) (xy 116.0526 -280.385774)
			(xy 116.055902 -280.39695) (xy 116.062667 -280.422452) (xy 116.069934 -280.47471) (xy 116.07038 -280.50109)
			(xy 116.069612 -280.535173) (xy 116.05748 -280.602251) (xy 116.052276 -280.617168) (xy 122.192542 -280.617168)
			(xy 122.193028 -280.589917) (xy 122.200784 -280.535969) (xy 122.216139 -280.483674) (xy 122.238781 -280.434097)
			(xy 122.268247 -280.388247) (xy 122.303938 -280.347056) (xy 122.345129 -280.311365) (xy 122.390979 -280.281899)
			(xy 122.440556 -280.259257) (xy 122.492851 -280.243902) (xy 122.546799 -280.236146) (xy 122.601301 -280.236146)
			(xy 122.655249 -280.243902) (xy 122.707544 -280.259257) (xy 122.757121 -280.281899) (xy 122.802971 -280.311365)
			(xy 122.844162 -280.347056) (xy 122.879853 -280.388247) (xy 122.909319 -280.434097) (xy 122.931961 -280.483674)
			(xy 122.947316 -280.535969) (xy 122.955072 -280.589917) (xy 122.955558 -280.617168) (xy 122.9555 -280.627794)
			(xy 122.954357 -280.649015) (xy 122.953272 -280.659586) (xy 122.952002 -280.669238) (xy 122.956828 -280.687526)
			(xy 123.00839 -280.758392) (xy 123.024392 -280.768552) (xy 123.03379 -280.770584) (xy 123.049284 -280.77414)
			(xy 123.058936 -280.776426) (xy 123.077986 -280.773886) (xy 123.156726 -280.728674) (xy 123.168664 -280.713434)
			(xy 123.171458 -280.703782) (xy 123.179458 -280.677663) (xy 123.202009 -280.627907) (xy 123.23143 -280.58188)
			(xy 123.267119 -280.540521) (xy 123.308344 -280.50468) (xy 123.354262 -280.475088) (xy 123.403934 -280.452352)
			(xy 123.456341 -280.436937) (xy 123.510412 -280.429159) (xy 123.537726 -280.4287) (xy 123.562898 -280.42909)
			(xy 123.612805 -280.435711) (xy 123.661409 -280.448836) (xy 123.684792 -280.458164) (xy 123.694952 -280.462482)
			(xy 123.716288 -280.461974) (xy 123.804426 -280.420064) (xy 123.818396 -280.403808) (xy 123.821444 -280.39314)
			(xy 123.830211 -280.365229) (xy 123.855147 -280.312307) (xy 123.887872 -280.263813) (xy 123.927619 -280.220886)
			(xy 123.973456 -280.184532) (xy 124.024306 -280.155604) (xy 124.078977 -280.134781) (xy 124.136187 -280.12255)
			(xy 124.16536 -280.120344) (xy 124.177044 -280.119582) (xy 124.19711 -280.108406) (xy 124.256546 -280.02484)
			(xy 124.26061 -280.002234) (xy 124.257308 -279.991058) (xy 124.250544 -279.965556) (xy 124.243277 -279.913298)
			(xy 124.24283 -279.886918) (xy 124.243316 -279.859667) (xy 124.251072 -279.805719) (xy 124.266427 -279.753424)
			(xy 124.289069 -279.703847) (xy 124.318535 -279.657997) (xy 124.354226 -279.616806) (xy 124.395417 -279.581115)
			(xy 124.441267 -279.551649) (xy 124.490844 -279.529007) (xy 124.543139 -279.513652) (xy 124.597087 -279.505896)
			(xy 124.651589 -279.505896) (xy 124.705537 -279.513652) (xy 124.757832 -279.529007) (xy 124.807409 -279.551649)
			(xy 124.853259 -279.581115) (xy 124.89445 -279.616806) (xy 124.930141 -279.657997) (xy 124.959607 -279.703847)
			(xy 124.982249 -279.753424) (xy 124.997604 -279.805719) (xy 125.00536 -279.859667) (xy 125.005846 -279.886918)
			(xy 125.005365 -279.915793) (xy 124.996681 -279.972886) (xy 124.979485 -280.028015) (xy 124.954169 -280.07992)
			(xy 124.921313 -280.127412) (xy 124.88167 -280.169405) (xy 124.836145 -280.204937) (xy 124.785782 -280.233195)
			(xy 124.731732 -280.253533) (xy 124.675233 -280.265486) (xy 124.646436 -280.267664) (xy 124.634752 -280.268426)
			(xy 124.614686 -280.279602) (xy 124.55525 -280.363168) (xy 124.551186 -280.385774) (xy 124.554488 -280.39695)
			(xy 124.561253 -280.422452) (xy 124.56852 -280.47471) (xy 124.568966 -280.50109) (xy 124.568199 -280.535173)
			(xy 124.556067 -280.602251) (xy 124.550862 -280.617168) (xy 130.353054 -280.617168) (xy 130.35354 -280.589917)
			(xy 130.361296 -280.535969) (xy 130.376651 -280.483674) (xy 130.399293 -280.434097) (xy 130.428759 -280.388247)
			(xy 130.46445 -280.347056) (xy 130.505641 -280.311365) (xy 130.551491 -280.281899) (xy 130.601068 -280.259257)
			(xy 130.653363 -280.243902) (xy 130.707311 -280.236146) (xy 130.761813 -280.236146) (xy 130.815761 -280.243902)
			(xy 130.868056 -280.259257) (xy 130.917633 -280.281899) (xy 130.963483 -280.311365) (xy 131.004674 -280.347056)
			(xy 131.040365 -280.388247) (xy 131.069831 -280.434097) (xy 131.092473 -280.483674) (xy 131.107828 -280.535969)
			(xy 131.115584 -280.589917) (xy 131.11607 -280.617168) (xy 131.116012 -280.627794) (xy 131.114869 -280.649015)
			(xy 131.113784 -280.659586) (xy 131.112514 -280.669238) (xy 131.11734 -280.687526) (xy 131.168902 -280.758392)
			(xy 131.184904 -280.768552) (xy 131.194302 -280.770584) (xy 131.209796 -280.77414) (xy 131.219448 -280.776426)
			(xy 131.238498 -280.773886) (xy 131.317238 -280.728674) (xy 131.329176 -280.713434) (xy 131.33197 -280.703782)
			(xy 131.340048 -280.677689) (xy 131.362592 -280.627938) (xy 131.392005 -280.581913) (xy 131.427684 -280.540556)
			(xy 131.468899 -280.504713) (xy 131.514807 -280.475118) (xy 131.564468 -280.452377) (xy 131.616865 -280.436954)
			(xy 131.670928 -280.429165) (xy 131.698238 -280.4287) (xy 131.72341 -280.429086) (xy 131.773317 -280.435709)
			(xy 131.821921 -280.448835) (xy 131.845304 -280.458164) (xy 131.855464 -280.462482) (xy 131.8768 -280.461974)
			(xy 131.964938 -280.420064) (xy 131.978908 -280.403808) (xy 131.981956 -280.39314) (xy 131.990713 -280.365225)
			(xy 132.01565 -280.312303) (xy 132.048377 -280.263809) (xy 132.088125 -280.220881) (xy 132.133963 -280.184528)
			(xy 132.184814 -280.155601) (xy 132.239487 -280.134778) (xy 132.296699 -280.12255) (xy 132.325872 -280.120344)
			(xy 132.337556 -280.119582) (xy 132.357622 -280.108406) (xy 132.417058 -280.02484) (xy 132.421122 -280.002234)
			(xy 132.41782 -279.991058) (xy 132.411057 -279.965556) (xy 132.403789 -279.913298) (xy 132.403342 -279.886918)
			(xy 132.403828 -279.859667) (xy 132.411584 -279.805719) (xy 132.426939 -279.753424) (xy 132.449581 -279.703847)
			(xy 132.479047 -279.657997) (xy 132.514738 -279.616806) (xy 132.555929 -279.581115) (xy 132.601779 -279.551649)
			(xy 132.651356 -279.529007) (xy 132.703651 -279.513652) (xy 132.757599 -279.505896) (xy 132.812101 -279.505896)
			(xy 132.866049 -279.513652) (xy 132.918344 -279.529007) (xy 132.967921 -279.551649) (xy 133.013771 -279.581115)
			(xy 133.054962 -279.616806) (xy 133.090653 -279.657997) (xy 133.120119 -279.703847) (xy 133.142761 -279.753424)
			(xy 133.158116 -279.805719) (xy 133.165872 -279.859667) (xy 133.166358 -279.886918) (xy 133.165866 -279.915792)
			(xy 133.157183 -279.972884) (xy 133.139987 -280.028013) (xy 133.114672 -280.079917) (xy 133.081817 -280.127408)
			(xy 133.042175 -280.169401) (xy 132.996652 -280.204933) (xy 132.94629 -280.233192) (xy 132.892242 -280.253531)
			(xy 132.835745 -280.265485) (xy 132.806948 -280.267664) (xy 132.795264 -280.268426) (xy 132.775198 -280.279602)
			(xy 132.715762 -280.363168) (xy 132.711698 -280.385774) (xy 132.715 -280.39695) (xy 132.721765 -280.422452)
			(xy 132.729032 -280.47471) (xy 132.729478 -280.50109) (xy 132.72871 -280.535173) (xy 132.716578 -280.602251)
			(xy 132.705348 -280.63444) (xy 132.701284 -280.645616) (xy 132.703824 -280.669492) (xy 132.761228 -280.758138)
			(xy 132.781802 -280.77033) (xy 132.79374 -280.771092) (xy 132.822349 -280.773546) (xy 132.878415 -280.785926)
			(xy 132.931995 -280.806566) (xy 132.981878 -280.835) (xy 133.026939 -280.870584) (xy 133.06616 -280.912518)
			(xy 133.098658 -280.959854) (xy 133.123698 -281.011523) (xy 133.125308 -281.01671) (xy 133.856982 -281.01671)
			(xy 133.861053 -280.961088) (xy 133.873179 -280.906651) (xy 133.893102 -280.85456) (xy 133.920398 -280.805925)
			(xy 133.954484 -280.761782) (xy 133.994633 -280.723073) (xy 134.039991 -280.690622) (xy 134.089591 -280.665121)
			(xy 134.142375 -280.647114) (xy 134.197218 -280.636984) (xy 134.252952 -280.634947) (xy 134.308389 -280.641047)
			(xy 134.362346 -280.655153) (xy 134.413675 -280.676965) (xy 134.461281 -280.706019) (xy 134.504149 -280.741694)
			(xy 134.541366 -280.783231) (xy 134.572139 -280.829744) (xy 134.595811 -280.880241) (xy 134.611879 -280.933648)
			(xy 134.619999 -280.988824) (xy 134.620508 -281.01671) (xy 134.619999 -281.044596) (xy 134.611879 -281.099772)
			(xy 134.595811 -281.153179) (xy 134.572139 -281.203676) (xy 134.541366 -281.250189) (xy 134.504149 -281.291726)
			(xy 134.461281 -281.327401) (xy 134.413675 -281.356455) (xy 134.362346 -281.378267) (xy 134.308389 -281.392373)
			(xy 134.252952 -281.398473) (xy 134.197218 -281.396436) (xy 134.142375 -281.386306) (xy 134.089591 -281.368299)
			(xy 134.039991 -281.342798) (xy 133.994633 -281.310347) (xy 133.954484 -281.271638) (xy 133.920398 -281.227495)
			(xy 133.893102 -281.17886) (xy 133.873179 -281.126769) (xy 133.861053 -281.072332) (xy 133.856982 -281.01671)
			(xy 133.125308 -281.01671) (xy 133.140715 -281.066361) (xy 133.149325 -281.123129) (xy 133.149848 -281.151838)
			(xy 133.149362 -281.179089) (xy 133.141606 -281.233037) (xy 133.126251 -281.285332) (xy 133.103609 -281.334909)
			(xy 133.074143 -281.380759) (xy 133.038452 -281.42195) (xy 132.997261 -281.457641) (xy 132.951411 -281.487107)
			(xy 132.901834 -281.509749) (xy 132.849539 -281.525104) (xy 132.795591 -281.53286) (xy 132.741089 -281.53286)
			(xy 132.687141 -281.525104) (xy 132.634846 -281.509749) (xy 132.585269 -281.487107) (xy 132.539419 -281.457641)
			(xy 132.498228 -281.42195) (xy 132.462537 -281.380759) (xy 132.433071 -281.334909) (xy 132.410429 -281.285332)
			(xy 132.395074 -281.233037) (xy 132.387318 -281.179089) (xy 132.386832 -281.151838) (xy 132.387581 -281.117754)
			(xy 132.399725 -281.050676) (xy 132.410962 -281.018488) (xy 132.415026 -281.007312) (xy 132.412486 -280.983436)
			(xy 132.355082 -280.89479) (xy 132.334508 -280.882598) (xy 132.32257 -280.881836) (xy 132.291272 -280.87909)
			(xy 132.230127 -280.86467) (xy 132.200904 -280.853134) (xy 132.190744 -280.848816) (xy 132.169408 -280.849324)
			(xy 132.08127 -280.891234) (xy 132.0673 -280.90749) (xy 132.064252 -280.918158) (xy 132.056057 -280.944129)
			(xy 132.033378 -280.993638) (xy 132.003889 -281.03942) (xy 131.968191 -281.080544) (xy 131.927007 -281.116173)
			(xy 131.881176 -281.145585) (xy 131.831628 -281.168181) (xy 131.779371 -281.183502) (xy 131.725466 -281.191236)
			(xy 131.698238 -281.191716) (xy 131.674882 -281.191348) (xy 131.628524 -281.185619) (xy 131.605782 -281.180286)
			(xy 131.59613 -281.178) (xy 131.57708 -281.18054) (xy 131.49834 -281.225752) (xy 131.486402 -281.240992)
			(xy 131.483608 -281.250644) (xy 131.475566 -281.276749) (xy 131.453016 -281.3265) (xy 131.423599 -281.372525)
			(xy 131.387915 -281.413882) (xy 131.346695 -281.449723) (xy 131.300783 -281.479317) (xy 131.251118 -281.502056)
			(xy 131.198717 -281.517477) (xy 131.144652 -281.525262) (xy 131.11734 -281.525726) (xy 131.090089 -281.525208)
			(xy 131.036141 -281.517456) (xy 130.983845 -281.502106) (xy 130.934266 -281.47947) (xy 130.888414 -281.450008)
			(xy 130.847221 -281.41432) (xy 130.811527 -281.373133) (xy 130.782058 -281.327285) (xy 130.759414 -281.277709)
			(xy 130.744056 -281.225416) (xy 130.736297 -281.171469) (xy 130.735832 -281.144218) (xy 130.735889 -281.133592)
			(xy 130.737032 -281.112371) (xy 130.738118 -281.1018) (xy 130.739388 -281.092148) (xy 130.734562 -281.07386)
			(xy 130.683 -281.002994) (xy 130.666998 -280.992834) (xy 130.6576 -280.990802) (xy 130.6293 -280.984437)
			(xy 130.574912 -280.964276) (xy 130.524204 -280.936113) (xy 130.478344 -280.900597) (xy 130.43839 -280.858547)
			(xy 130.405263 -280.810934) (xy 130.379727 -280.758853) (xy 130.36237 -280.703506) (xy 130.353593 -280.64617)
			(xy 130.353054 -280.617168) (xy 124.550862 -280.617168) (xy 124.544836 -280.63444) (xy 124.540772 -280.645616)
			(xy 124.543312 -280.669492) (xy 124.600716 -280.758138) (xy 124.62129 -280.77033) (xy 124.633228 -280.771092)
			(xy 124.661836 -280.773556) (xy 124.717902 -280.785935) (xy 124.771482 -280.806573) (xy 124.821365 -280.835005)
			(xy 124.866426 -280.870589) (xy 124.905648 -280.912521) (xy 124.938145 -280.959856) (xy 124.95745 -280.999692)
			(xy 125.69647 -280.999692) (xy 125.700541 -280.94407) (xy 125.712667 -280.889633) (xy 125.73259 -280.837542)
			(xy 125.759886 -280.788907) (xy 125.793972 -280.744764) (xy 125.834121 -280.706055) (xy 125.879479 -280.673604)
			(xy 125.929079 -280.648103) (xy 125.981863 -280.630096) (xy 126.036706 -280.619966) (xy 126.09244 -280.617929)
			(xy 126.147877 -280.624029) (xy 126.201834 -280.638135) (xy 126.253163 -280.659947) (xy 126.300769 -280.689001)
			(xy 126.343637 -280.724676) (xy 126.380854 -280.766213) (xy 126.411627 -280.812726) (xy 126.435299 -280.863223)
			(xy 126.451367 -280.91663) (xy 126.459487 -280.971806) (xy 126.459996 -280.999692) (xy 126.459487 -281.027578)
			(xy 126.451367 -281.082754) (xy 126.435299 -281.136161) (xy 126.411627 -281.186658) (xy 126.380854 -281.233171)
			(xy 126.343637 -281.274708) (xy 126.300769 -281.310383) (xy 126.253163 -281.339437) (xy 126.201834 -281.361249)
			(xy 126.147877 -281.375355) (xy 126.09244 -281.381455) (xy 126.036706 -281.379418) (xy 125.981863 -281.369288)
			(xy 125.929079 -281.351281) (xy 125.879479 -281.32578) (xy 125.834121 -281.293329) (xy 125.793972 -281.25462)
			(xy 125.759886 -281.210477) (xy 125.73259 -281.161842) (xy 125.712667 -281.109751) (xy 125.700541 -281.055314)
			(xy 125.69647 -280.999692) (xy 124.95745 -280.999692) (xy 124.963185 -281.011525) (xy 124.980203 -281.066362)
			(xy 124.988813 -281.12313) (xy 124.989336 -281.151838) (xy 124.98885 -281.179089) (xy 124.981094 -281.233037)
			(xy 124.965739 -281.285332) (xy 124.943097 -281.334909) (xy 124.913631 -281.380759) (xy 124.87794 -281.42195)
			(xy 124.836749 -281.457641) (xy 124.790899 -281.487107) (xy 124.741322 -281.509749) (xy 124.689027 -281.525104)
			(xy 124.635079 -281.53286) (xy 124.580577 -281.53286) (xy 124.526629 -281.525104) (xy 124.474334 -281.509749)
			(xy 124.424757 -281.487107) (xy 124.378907 -281.457641) (xy 124.337716 -281.42195) (xy 124.302025 -281.380759)
			(xy 124.272559 -281.334909) (xy 124.249917 -281.285332) (xy 124.234562 -281.233037) (xy 124.226806 -281.179089)
			(xy 124.22632 -281.151838) (xy 124.22707 -281.117754) (xy 124.239214 -281.050676) (xy 124.25045 -281.018488)
			(xy 124.254514 -281.007312) (xy 124.251974 -280.983436) (xy 124.19457 -280.89479) (xy 124.173996 -280.882598)
			(xy 124.162058 -280.881836) (xy 124.13076 -280.879093) (xy 124.069615 -280.864671) (xy 124.040392 -280.853134)
			(xy 124.030232 -280.848816) (xy 124.008896 -280.849324) (xy 123.920758 -280.891234) (xy 123.906788 -280.90749)
			(xy 123.90374 -280.918158) (xy 123.895555 -280.944132) (xy 123.872875 -280.993643) (xy 123.843386 -281.039425)
			(xy 123.807686 -281.080549) (xy 123.766501 -281.116178) (xy 123.720668 -281.145589) (xy 123.671119 -281.168184)
			(xy 123.618861 -281.183504) (xy 123.564955 -281.191237) (xy 123.537726 -281.191716) (xy 123.51437 -281.19135)
			(xy 123.468011 -281.18562) (xy 123.44527 -281.180286) (xy 123.435618 -281.178) (xy 123.416568 -281.18054)
			(xy 123.337828 -281.225752) (xy 123.32589 -281.240992) (xy 123.323096 -281.250644) (xy 123.315064 -281.276752)
			(xy 123.292514 -281.326504) (xy 123.263095 -281.37253) (xy 123.22741 -281.413886) (xy 123.186189 -281.449728)
			(xy 123.140276 -281.479321) (xy 123.090609 -281.50206) (xy 123.038207 -281.517479) (xy 122.98414 -281.525263)
			(xy 122.956828 -281.525726) (xy 122.929577 -281.525219) (xy 122.875628 -281.517466) (xy 122.823332 -281.502114)
			(xy 122.773753 -281.479477) (xy 122.727901 -281.450013) (xy 122.686709 -281.414324) (xy 122.651015 -281.373136)
			(xy 122.621546 -281.327287) (xy 122.598902 -281.277711) (xy 122.583544 -281.225417) (xy 122.575785 -281.171469)
			(xy 122.57532 -281.144218) (xy 122.575377 -281.133592) (xy 122.57652 -281.112371) (xy 122.577606 -281.1018)
			(xy 122.578876 -281.092148) (xy 122.57405 -281.07386) (xy 122.522488 -281.002994) (xy 122.506486 -280.992834)
			(xy 122.497088 -280.990802) (xy 122.468786 -280.984445) (xy 122.414398 -280.964282) (xy 122.36369 -280.936118)
			(xy 122.317831 -280.900601) (xy 122.277877 -280.85855) (xy 122.24475 -280.810936) (xy 122.219214 -280.758854)
			(xy 122.201858 -280.703507) (xy 122.193081 -280.64617) (xy 122.192542 -280.617168) (xy 116.052276 -280.617168)
			(xy 116.04625 -280.63444) (xy 116.042186 -280.645616) (xy 116.044726 -280.669492) (xy 116.10213 -280.758138)
			(xy 116.122704 -280.77033) (xy 116.134642 -280.771092) (xy 116.163251 -280.773544) (xy 116.219318 -280.785925)
			(xy 116.272897 -280.806565) (xy 116.32278 -280.834999) (xy 116.367841 -280.870584) (xy 116.407062 -280.912517)
			(xy 116.43956 -280.959853) (xy 116.4646 -281.011523) (xy 116.46621 -281.01671) (xy 117.197884 -281.01671)
			(xy 117.201955 -280.961088) (xy 117.214081 -280.906651) (xy 117.234004 -280.85456) (xy 117.2613 -280.805925)
			(xy 117.295386 -280.761782) (xy 117.335535 -280.723073) (xy 117.380893 -280.690622) (xy 117.430493 -280.665121)
			(xy 117.483277 -280.647114) (xy 117.53812 -280.636984) (xy 117.593854 -280.634947) (xy 117.649291 -280.641047)
			(xy 117.703248 -280.655153) (xy 117.754577 -280.676965) (xy 117.802183 -280.706019) (xy 117.845051 -280.741694)
			(xy 117.882268 -280.783231) (xy 117.913041 -280.829744) (xy 117.936713 -280.880241) (xy 117.952781 -280.933648)
			(xy 117.960901 -280.988824) (xy 117.96141 -281.01671) (xy 117.960901 -281.044596) (xy 117.952781 -281.099772)
			(xy 117.936713 -281.153179) (xy 117.913041 -281.203676) (xy 117.882268 -281.250189) (xy 117.845051 -281.291726)
			(xy 117.802183 -281.327401) (xy 117.754577 -281.356455) (xy 117.703248 -281.378267) (xy 117.649291 -281.392373)
			(xy 117.593854 -281.398473) (xy 117.53812 -281.396436) (xy 117.483277 -281.386306) (xy 117.430493 -281.368299)
			(xy 117.380893 -281.342798) (xy 117.335535 -281.310347) (xy 117.295386 -281.271638) (xy 117.2613 -281.227495)
			(xy 117.234004 -281.17886) (xy 117.214081 -281.126769) (xy 117.201955 -281.072332) (xy 117.197884 -281.01671)
			(xy 116.46621 -281.01671) (xy 116.481617 -281.066361) (xy 116.490227 -281.123129) (xy 116.49075 -281.151838)
			(xy 116.490264 -281.179089) (xy 116.482508 -281.233037) (xy 116.467153 -281.285332) (xy 116.444511 -281.334909)
			(xy 116.415045 -281.380759) (xy 116.379354 -281.42195) (xy 116.338163 -281.457641) (xy 116.292313 -281.487107)
			(xy 116.242736 -281.509749) (xy 116.190441 -281.525104) (xy 116.136493 -281.53286) (xy 116.081991 -281.53286)
			(xy 116.028043 -281.525104) (xy 115.975748 -281.509749) (xy 115.926171 -281.487107) (xy 115.880321 -281.457641)
			(xy 115.83913 -281.42195) (xy 115.803439 -281.380759) (xy 115.773973 -281.334909) (xy 115.751331 -281.285332)
			(xy 115.735976 -281.233037) (xy 115.72822 -281.179089) (xy 115.727734 -281.151838) (xy 115.728483 -281.117754)
			(xy 115.740627 -281.050676) (xy 115.751864 -281.018488) (xy 115.755928 -281.007312) (xy 115.753388 -280.983436)
			(xy 115.695984 -280.89479) (xy 115.67541 -280.882598) (xy 115.663472 -280.881836) (xy 115.632174 -280.879089)
			(xy 115.571029 -280.86467) (xy 115.541806 -280.853134) (xy 115.531646 -280.848816) (xy 115.51031 -280.849324)
			(xy 115.422172 -280.891234) (xy 115.408202 -280.90749) (xy 115.405154 -280.918158) (xy 115.396957 -280.944128)
			(xy 115.374278 -280.993638) (xy 115.34479 -281.039419) (xy 115.309091 -281.080543) (xy 115.267908 -281.116173)
			(xy 115.222077 -281.145584) (xy 115.17253 -281.16818) (xy 115.120273 -281.183501) (xy 115.066368 -281.191236)
			(xy 115.03914 -281.191716) (xy 115.015784 -281.191347) (xy 114.969426 -281.185619) (xy 114.946684 -281.180286)
			(xy 114.937032 -281.178) (xy 114.917982 -281.18054) (xy 114.839242 -281.225752) (xy 114.827304 -281.240992)
			(xy 114.82451 -281.250644) (xy 114.816466 -281.276748) (xy 114.793917 -281.326499) (xy 114.764499 -281.372524)
			(xy 114.728816 -281.413881) (xy 114.687596 -281.449723) (xy 114.641685 -281.479316) (xy 114.59202 -281.502056)
			(xy 114.539619 -281.517476) (xy 114.485554 -281.525262) (xy 114.458242 -281.525726) (xy 114.430991 -281.525206)
			(xy 114.377043 -281.517455) (xy 114.324747 -281.502105) (xy 114.275169 -281.479469) (xy 114.229316 -281.450007)
			(xy 114.188123 -281.414319) (xy 114.152429 -281.373132) (xy 114.12296 -281.327284) (xy 114.100316 -281.277709)
			(xy 114.084958 -281.225416) (xy 114.077199 -281.171469) (xy 114.076734 -281.144218) (xy 114.076791 -281.133592)
			(xy 114.077934 -281.112371) (xy 114.07902 -281.1018) (xy 114.08029 -281.092148) (xy 114.075464 -281.07386)
			(xy 114.023902 -281.002994) (xy 114.0079 -280.992834) (xy 113.998502 -280.990802) (xy 113.970202 -280.984435)
			(xy 113.915815 -280.964275) (xy 113.865106 -280.936112) (xy 113.819246 -280.900596) (xy 113.779292 -280.858547)
			(xy 113.746165 -280.810933) (xy 113.720629 -280.758853) (xy 113.703272 -280.703506) (xy 113.694495 -280.64617)
			(xy 113.693956 -280.617168) (xy 107.891764 -280.617168) (xy 107.885738 -280.63444) (xy 107.881674 -280.645616)
			(xy 107.884214 -280.669492) (xy 107.941618 -280.758138) (xy 107.962192 -280.77033) (xy 107.97413 -280.771092)
			(xy 108.002738 -280.773554) (xy 108.058804 -280.785934) (xy 108.112384 -280.806572) (xy 108.162267 -280.835004)
			(xy 108.207328 -280.870588) (xy 108.24655 -280.912521) (xy 108.279047 -280.959856) (xy 108.304087 -281.011525)
			(xy 108.321105 -281.066362) (xy 108.329715 -281.12313) (xy 108.330238 -281.151838) (xy 108.329975 -281.16657)
			(xy 108.75594 -281.16657) (xy 108.760011 -281.110948) (xy 108.772137 -281.056511) (xy 108.79206 -281.00442)
			(xy 108.819356 -280.955785) (xy 108.853442 -280.911642) (xy 108.893591 -280.872933) (xy 108.938949 -280.840482)
			(xy 108.988549 -280.814981) (xy 109.041333 -280.796974) (xy 109.096176 -280.786844) (xy 109.15191 -280.784807)
			(xy 109.207347 -280.790907) (xy 109.261304 -280.805013) (xy 109.312633 -280.826825) (xy 109.360239 -280.855879)
			(xy 109.403107 -280.891554) (xy 109.440324 -280.933091) (xy 109.471097 -280.979604) (xy 109.494769 -281.030101)
			(xy 109.510837 -281.083508) (xy 109.518957 -281.138684) (xy 109.519466 -281.16657) (xy 109.518957 -281.194456)
			(xy 109.510837 -281.249632) (xy 109.494769 -281.303039) (xy 109.471097 -281.353536) (xy 109.440324 -281.400049)
			(xy 109.403107 -281.441586) (xy 109.360239 -281.477261) (xy 109.312633 -281.506315) (xy 109.261304 -281.528127)
			(xy 109.207347 -281.542233) (xy 109.15191 -281.548333) (xy 109.096176 -281.546296) (xy 109.041333 -281.536166)
			(xy 108.988549 -281.518159) (xy 108.938949 -281.492658) (xy 108.893591 -281.460207) (xy 108.853442 -281.421498)
			(xy 108.819356 -281.377355) (xy 108.79206 -281.32872) (xy 108.772137 -281.276629) (xy 108.760011 -281.222192)
			(xy 108.75594 -281.16657) (xy 108.329975 -281.16657) (xy 108.329752 -281.179089) (xy 108.321996 -281.233037)
			(xy 108.306641 -281.285332) (xy 108.283999 -281.334909) (xy 108.254533 -281.380759) (xy 108.218842 -281.42195)
			(xy 108.177651 -281.457641) (xy 108.131801 -281.487107) (xy 108.082224 -281.509749) (xy 108.029929 -281.525104)
			(xy 107.975981 -281.53286) (xy 107.921479 -281.53286) (xy 107.867531 -281.525104) (xy 107.815236 -281.509749)
			(xy 107.765659 -281.487107) (xy 107.719809 -281.457641) (xy 107.678618 -281.42195) (xy 107.642927 -281.380759)
			(xy 107.613461 -281.334909) (xy 107.590819 -281.285332) (xy 107.575464 -281.233037) (xy 107.567708 -281.179089)
			(xy 107.567222 -281.151838) (xy 107.567971 -281.117754) (xy 107.580116 -281.050676) (xy 107.591352 -281.018488)
			(xy 107.595416 -281.007312) (xy 107.592876 -280.983436) (xy 107.535472 -280.89479) (xy 107.514898 -280.882598)
			(xy 107.50296 -280.881836) (xy 107.471662 -280.879092) (xy 107.410517 -280.864671) (xy 107.381294 -280.853134)
			(xy 107.371134 -280.848816) (xy 107.349798 -280.849324) (xy 107.26166 -280.891234) (xy 107.24769 -280.90749)
			(xy 107.244642 -280.918158) (xy 107.236455 -280.944132) (xy 107.213776 -280.993642) (xy 107.184286 -281.039424)
			(xy 107.148587 -281.080548) (xy 107.107402 -281.116177) (xy 107.06157 -281.145588) (xy 107.012021 -281.168184)
			(xy 106.959763 -281.183504) (xy 106.905857 -281.191237) (xy 106.878628 -281.191716) (xy 106.855272 -281.19135)
			(xy 106.808913 -281.185619) (xy 106.786172 -281.180286) (xy 106.77652 -281.178) (xy 106.75747 -281.18054)
			(xy 106.67873 -281.225752) (xy 106.666792 -281.240992) (xy 106.663998 -281.250644) (xy 106.655965 -281.276752)
			(xy 106.633414 -281.326504) (xy 106.603996 -281.372529) (xy 106.568311 -281.413886) (xy 106.52709 -281.449727)
			(xy 106.481177 -281.47932) (xy 106.431511 -281.502059) (xy 106.379109 -281.517479) (xy 106.325042 -281.525263)
			(xy 106.29773 -281.525726) (xy 106.270479 -281.525217) (xy 106.21653 -281.517464) (xy 106.164234 -281.502113)
			(xy 106.114656 -281.479475) (xy 106.068803 -281.450012) (xy 106.027611 -281.414323) (xy 105.991917 -281.373135)
			(xy 105.962448 -281.327287) (xy 105.939804 -281.277711) (xy 105.924446 -281.225417) (xy 105.916687 -281.171469)
			(xy 105.916222 -281.144218) (xy 105.916279 -281.133592) (xy 105.917422 -281.112371) (xy 105.918508 -281.1018)
			(xy 105.919778 -281.092148) (xy 105.914952 -281.07386) (xy 105.86339 -281.002994) (xy 105.847388 -280.992834)
			(xy 105.83799 -280.990802) (xy 105.809688 -280.984444) (xy 105.755301 -280.964281) (xy 105.704593 -280.936117)
			(xy 105.658733 -280.9006) (xy 105.618779 -280.85855) (xy 105.585652 -280.810935) (xy 105.560116 -280.758854)
			(xy 105.54276 -280.703507) (xy 105.533983 -280.64617) (xy 105.533444 -280.617168) (xy 100.816156 -280.617168)
			(xy 98.528886 -282.904438) (xy 101.903022 -282.904438) (xy 101.903506 -282.876864) (xy 101.911454 -282.822292)
			(xy 101.927175 -282.769432) (xy 101.950341 -282.719386) (xy 101.980471 -282.673196) (xy 102.016936 -282.631824)
			(xy 102.037642 -282.613608) (xy 102.045759 -282.606005) (xy 102.055112 -282.585853) (xy 102.055676 -282.574746)
			(xy 102.055676 -282.49753) (xy 102.055115 -282.486419) (xy 102.045772 -282.46626) (xy 102.037642 -282.458668)
			(xy 102.016973 -282.440412) (xy 101.980505 -282.399048) (xy 101.950375 -282.352863) (xy 101.927208 -282.302821)
			(xy 101.911489 -282.249965) (xy 101.903545 -282.195397) (xy 101.903542 -282.140253) (xy 101.911479 -282.085683)
			(xy 101.927191 -282.032825) (xy 101.950351 -281.98278) (xy 101.980476 -281.936592) (xy 102.016937 -281.895223)
			(xy 102.037642 -281.877008) (xy 102.045759 -281.869405) (xy 102.055112 -281.849253) (xy 102.055676 -281.838146)
			(xy 102.055676 -281.76093) (xy 102.055115 -281.749819) (xy 102.045772 -281.72966) (xy 102.037642 -281.722068)
			(xy 102.016921 -281.703868) (xy 101.980449 -281.662498) (xy 101.950317 -281.616306) (xy 101.927153 -281.566256)
			(xy 101.911439 -281.513391) (xy 101.903504 -281.458814) (xy 101.903022 -281.431238) (xy 101.903491 -281.403985)
			(xy 101.911243 -281.350032) (xy 101.926596 -281.297733) (xy 101.949236 -281.248151) (xy 101.978703 -281.202296)
			(xy 102.014397 -281.161102) (xy 102.05559 -281.125408) (xy 102.101444 -281.09594) (xy 102.151025 -281.073299)
			(xy 102.203325 -281.057945) (xy 102.257277 -281.050191) (xy 102.28453 -281.04973) (xy 102.312387 -281.050204)
			(xy 102.367506 -281.058332) (xy 102.420859 -281.074383) (xy 102.471313 -281.098016) (xy 102.517798 -281.128729)
			(xy 102.559327 -281.165871) (xy 102.595019 -281.208652) (xy 102.624116 -281.256165) (xy 102.646 -281.307402)
			(xy 102.653592 -281.33421) (xy 102.655878 -281.3431) (xy 102.666546 -281.35834) (xy 102.738428 -281.406092)
			(xy 102.756462 -281.410156) (xy 102.765606 -281.408886) (xy 102.778623 -281.407218) (xy 102.804807 -281.405437)
			(xy 102.81793 -281.40533) (xy 102.831053 -281.405425) (xy 102.857239 -281.407203) (xy 102.870254 -281.408886)
			(xy 102.879398 -281.410156) (xy 102.897432 -281.406092) (xy 102.969314 -281.35834) (xy 102.979982 -281.3431)
			(xy 102.982268 -281.33421) (xy 102.989866 -281.307402) (xy 103.011728 -281.256153) (xy 103.040812 -281.208628)
			(xy 103.076499 -281.165839) (xy 103.118029 -281.128694) (xy 103.16452 -281.097985) (xy 103.214983 -281.074364)
			(xy 103.268345 -281.058334) (xy 103.323471 -281.050234) (xy 103.35133 -281.04973) (xy 103.378585 -281.050127)
			(xy 103.432541 -281.057889) (xy 103.484842 -281.073251) (xy 103.534425 -281.0959) (xy 103.58028 -281.125374)
			(xy 103.621473 -281.161075) (xy 103.657166 -281.202275) (xy 103.686633 -281.248135) (xy 103.709273 -281.297722)
			(xy 103.724625 -281.350026) (xy 103.732378 -281.403983) (xy 103.732838 -281.431238) (xy 103.732367 -281.458537)
			(xy 103.724591 -281.512579) (xy 103.709189 -281.564959) (xy 103.686476 -281.614609) (xy 103.656915 -281.660512)
			(xy 103.639366 -281.681428) (xy 103.633016 -281.688794) (xy 103.626666 -281.706574) (xy 103.630222 -281.795982)
			(xy 103.637842 -281.813254) (xy 103.6447 -281.820112) (xy 103.665831 -281.841741) (xy 103.701631 -281.89047)
			(xy 103.729295 -281.944237) (xy 103.735566 -281.963368) (xy 108.281722 -281.963368) (xy 108.285793 -281.907746)
			(xy 108.297919 -281.853309) (xy 108.317842 -281.801218) (xy 108.345138 -281.752583) (xy 108.379224 -281.70844)
			(xy 108.419373 -281.669731) (xy 108.464731 -281.63728) (xy 108.514331 -281.611779) (xy 108.567115 -281.593772)
			(xy 108.621958 -281.583642) (xy 108.677692 -281.581605) (xy 108.733129 -281.587705) (xy 108.787086 -281.601811)
			(xy 108.838415 -281.623623) (xy 108.886021 -281.652677) (xy 108.928889 -281.688352) (xy 108.966106 -281.729889)
			(xy 108.996879 -281.776402) (xy 109.020551 -281.826899) (xy 109.036619 -281.880306) (xy 109.044739 -281.935482)
			(xy 109.045248 -281.963368) (xy 109.044739 -281.991254) (xy 109.036619 -282.04643) (xy 109.020551 -282.099837)
			(xy 108.996879 -282.150334) (xy 108.966106 -282.196847) (xy 108.928889 -282.238384) (xy 108.886021 -282.274059)
			(xy 108.838415 -282.303113) (xy 108.787086 -282.324925) (xy 108.733129 -282.339031) (xy 108.677692 -282.345131)
			(xy 108.621958 -282.343094) (xy 108.567115 -282.332964) (xy 108.514331 -282.314957) (xy 108.464731 -282.289456)
			(xy 108.419373 -282.257005) (xy 108.379224 -282.218296) (xy 108.345138 -282.174153) (xy 108.317842 -282.125518)
			(xy 108.297919 -282.073427) (xy 108.285793 -282.01899) (xy 108.281722 -281.963368) (xy 103.735566 -281.963368)
			(xy 103.74813 -282.001695) (xy 103.757663 -282.061405) (xy 103.758238 -282.091638) (xy 103.757742 -282.119276)
			(xy 103.74975 -282.173971) (xy 103.733952 -282.226942) (xy 103.710681 -282.277081) (xy 103.680421 -282.323338)
			(xy 103.66248 -282.344368) (xy 103.654098 -282.35402) (xy 103.648256 -282.378404) (xy 103.675434 -282.484576)
			(xy 103.692452 -282.503118) (xy 103.70439 -282.507436) (xy 103.731799 -282.517772) (xy 103.783314 -282.545654)
			(xy 103.829959 -282.581086) (xy 103.870637 -282.623235) (xy 103.904391 -282.671108) (xy 103.930427 -282.72358)
			(xy 103.948133 -282.779416) (xy 103.957092 -282.837304) (xy 103.957628 -282.866592) (xy 103.957115 -282.893842)
			(xy 103.957113 -282.893854) (xy 104.287247 -282.893854) (xy 104.287247 -282.839346) (xy 104.295005 -282.785392)
			(xy 104.310362 -282.733091) (xy 104.333007 -282.683509) (xy 104.362477 -282.637654) (xy 104.398174 -282.59646)
			(xy 104.43937 -282.560765) (xy 104.485226 -282.531297) (xy 104.53481 -282.508655) (xy 104.587111 -282.493301)
			(xy 104.641066 -282.485546) (xy 104.66832 -282.485084) (xy 104.695692 -282.485518) (xy 104.749873 -282.49334)
			(xy 104.802377 -282.508836) (xy 104.852124 -282.531685) (xy 104.898088 -282.561418) (xy 104.919018 -282.579064)
			(xy 104.92613 -282.58516) (xy 104.943148 -282.59151) (xy 105.028492 -282.59151) (xy 105.04551 -282.58516)
			(xy 105.052622 -282.579064) (xy 105.073568 -282.561442) (xy 105.119538 -282.531729) (xy 105.169282 -282.50889)
			(xy 105.221779 -282.493395) (xy 105.275952 -282.485561) (xy 105.30332 -282.485084) (xy 105.33057 -282.485587)
			(xy 105.384514 -282.493346) (xy 105.436805 -282.508702) (xy 105.486379 -282.531344) (xy 105.532226 -282.56081)
			(xy 105.573413 -282.596501) (xy 105.609102 -282.63769) (xy 105.638565 -282.683538) (xy 105.661205 -282.733113)
			(xy 105.676558 -282.785405) (xy 105.684314 -282.83935) (xy 105.684314 -282.89385) (xy 105.682792 -282.904438)
			(xy 110.063534 -282.904438) (xy 110.064014 -282.876864) (xy 110.071962 -282.822291) (xy 110.087683 -282.769431)
			(xy 110.110851 -282.719385) (xy 110.140981 -282.673195) (xy 110.177447 -282.631824) (xy 110.198154 -282.613608)
			(xy 110.206273 -282.606006) (xy 110.215625 -282.585854) (xy 110.216188 -282.574746) (xy 110.216188 -282.49753)
			(xy 110.215623 -282.48642) (xy 110.206283 -282.466261) (xy 110.198154 -282.458668) (xy 110.177484 -282.440412)
			(xy 110.141016 -282.399048) (xy 110.110884 -282.352864) (xy 110.087717 -282.302822) (xy 110.071997 -282.249966)
			(xy 110.064053 -282.195397) (xy 110.064049 -282.140252) (xy 110.071987 -282.085682) (xy 110.087699 -282.032824)
			(xy 110.11086 -281.982779) (xy 110.140986 -281.936591) (xy 110.177449 -281.895222) (xy 110.198154 -281.877008)
			(xy 110.206273 -281.869406) (xy 110.215625 -281.849254) (xy 110.216188 -281.838146) (xy 110.216188 -281.76093)
			(xy 110.215623 -281.74982) (xy 110.206283 -281.729661) (xy 110.198154 -281.722068) (xy 110.177415 -281.703887)
			(xy 110.140949 -281.662511) (xy 110.110821 -281.616314) (xy 110.087661 -281.566261) (xy 110.07195 -281.513393)
			(xy 110.064016 -281.458814) (xy 110.063534 -281.431238) (xy 110.063991 -281.403984) (xy 110.071744 -281.350031)
			(xy 110.087097 -281.29773) (xy 110.109738 -281.248147) (xy 110.139206 -281.202292) (xy 110.174901 -281.161098)
			(xy 110.216095 -281.125404) (xy 110.261951 -281.095936) (xy 110.311534 -281.073296) (xy 110.363835 -281.057943)
			(xy 110.417788 -281.050191) (xy 110.445042 -281.04973) (xy 110.4729 -281.050193) (xy 110.528019 -281.058323)
			(xy 110.581372 -281.074376) (xy 110.631826 -281.09801) (xy 110.678311 -281.128725) (xy 110.71984 -281.165867)
			(xy 110.755531 -281.20865) (xy 110.784628 -281.256164) (xy 110.806512 -281.307402) (xy 110.814104 -281.33421)
			(xy 110.81639 -281.3431) (xy 110.827058 -281.35834) (xy 110.89894 -281.406092) (xy 110.916974 -281.410156)
			(xy 110.926118 -281.408886) (xy 110.939135 -281.407217) (xy 110.965319 -281.405437) (xy 110.978442 -281.40533)
			(xy 110.991565 -281.405424) (xy 111.017751 -281.407203) (xy 111.030766 -281.408886) (xy 111.03991 -281.410156)
			(xy 111.057944 -281.406092) (xy 111.129826 -281.35834) (xy 111.140494 -281.3431) (xy 111.14278 -281.33421)
			(xy 111.150367 -281.307399) (xy 111.17223 -281.256149) (xy 111.201315 -281.208623) (xy 111.237003 -281.165834)
			(xy 111.278535 -281.12869) (xy 111.325028 -281.097981) (xy 111.375492 -281.074361) (xy 111.428855 -281.058331)
			(xy 111.483983 -281.050233) (xy 111.511842 -281.04973) (xy 111.539096 -281.050139) (xy 111.593048 -281.057902)
			(xy 111.645347 -281.073264) (xy 111.694927 -281.095913) (xy 111.740779 -281.125387) (xy 111.78197 -281.161087)
			(xy 111.817661 -281.202285) (xy 111.847125 -281.248143) (xy 111.869764 -281.297728) (xy 111.885115 -281.35003)
			(xy 111.892867 -281.403984) (xy 111.89335 -281.431238) (xy 111.892876 -281.458537) (xy 111.8851 -281.512578)
			(xy 111.869699 -281.564959) (xy 111.846986 -281.614608) (xy 111.817427 -281.660512) (xy 111.799878 -281.681428)
			(xy 111.793528 -281.688794) (xy 111.787178 -281.706574) (xy 111.790734 -281.795982) (xy 111.798354 -281.813254)
			(xy 111.805212 -281.820112) (xy 111.826328 -281.841756) (xy 111.862133 -281.890479) (xy 111.889802 -281.944242)
			(xy 111.896073 -281.963368) (xy 116.442234 -281.963368) (xy 116.446305 -281.907746) (xy 116.458431 -281.853309)
			(xy 116.478354 -281.801218) (xy 116.50565 -281.752583) (xy 116.539736 -281.70844) (xy 116.579885 -281.669731)
			(xy 116.625243 -281.63728) (xy 116.674843 -281.611779) (xy 116.727627 -281.593772) (xy 116.78247 -281.583642)
			(xy 116.838204 -281.581605) (xy 116.893641 -281.587705) (xy 116.947598 -281.601811) (xy 116.998927 -281.623623)
			(xy 117.046533 -281.652677) (xy 117.089401 -281.688352) (xy 117.126618 -281.729889) (xy 117.157391 -281.776402)
			(xy 117.181063 -281.826899) (xy 117.197131 -281.880306) (xy 117.205251 -281.935482) (xy 117.20576 -281.963368)
			(xy 117.205251 -281.991254) (xy 117.197131 -282.04643) (xy 117.181063 -282.099837) (xy 117.157391 -282.150334)
			(xy 117.126618 -282.196847) (xy 117.089401 -282.238384) (xy 117.046533 -282.274059) (xy 116.998927 -282.303113)
			(xy 116.947598 -282.324925) (xy 116.893641 -282.339031) (xy 116.838204 -282.345131) (xy 116.78247 -282.343094)
			(xy 116.727627 -282.332964) (xy 116.674843 -282.314957) (xy 116.625243 -282.289456) (xy 116.579885 -282.257005)
			(xy 116.539736 -282.218296) (xy 116.50565 -282.174153) (xy 116.478354 -282.125518) (xy 116.458431 -282.073427)
			(xy 116.446305 -282.01899) (xy 116.442234 -281.963368) (xy 111.896073 -281.963368) (xy 111.90864 -282.001697)
			(xy 111.918175 -282.061406) (xy 111.91875 -282.091638) (xy 111.918251 -282.119276) (xy 111.910259 -282.173971)
			(xy 111.894462 -282.226942) (xy 111.871191 -282.27708) (xy 111.840932 -282.323338) (xy 111.822992 -282.344368)
			(xy 111.81461 -282.35402) (xy 111.808768 -282.378404) (xy 111.835946 -282.484576) (xy 111.852964 -282.503118)
			(xy 111.864902 -282.507436) (xy 111.892314 -282.517765) (xy 111.943828 -282.545649) (xy 111.990473 -282.581082)
			(xy 112.03115 -282.623232) (xy 112.064904 -282.671106) (xy 112.09094 -282.723579) (xy 112.108645 -282.779416)
			(xy 112.117604 -282.837304) (xy 112.11814 -282.866592) (xy 112.117605 -282.893855) (xy 112.447747 -282.893855)
			(xy 112.447747 -282.839345) (xy 112.455505 -282.78539) (xy 112.470863 -282.733089) (xy 112.493509 -282.683505)
			(xy 112.52298 -282.63765) (xy 112.558678 -282.596455) (xy 112.599876 -282.560761) (xy 112.645734 -282.531293)
			(xy 112.695319 -282.508652) (xy 112.747622 -282.493299) (xy 112.801577 -282.485545) (xy 112.828832 -282.485084)
			(xy 112.856204 -282.485511) (xy 112.910385 -282.493335) (xy 112.96289 -282.508832) (xy 113.012636 -282.531683)
			(xy 113.0586 -282.561418) (xy 113.07953 -282.579064) (xy 113.086642 -282.58516) (xy 113.10366 -282.59151)
			(xy 113.189004 -282.59151) (xy 113.206022 -282.58516) (xy 113.213134 -282.579064) (xy 113.234076 -282.561437)
			(xy 113.280046 -282.531724) (xy 113.329791 -282.508887) (xy 113.38229 -282.493393) (xy 113.436464 -282.48556)
			(xy 113.463832 -282.485084) (xy 113.491081 -282.485588) (xy 113.545024 -282.493348) (xy 113.597314 -282.508706)
			(xy 113.646886 -282.531348) (xy 113.692732 -282.560815) (xy 113.733917 -282.596505) (xy 113.769605 -282.637694)
			(xy 113.799067 -282.683542) (xy 113.821706 -282.733116) (xy 113.837059 -282.785407) (xy 113.844814 -282.839351)
			(xy 113.844814 -282.893849) (xy 113.843292 -282.904438) (xy 118.56212 -282.904438) (xy 118.562605 -282.876864)
			(xy 118.570552 -282.822292) (xy 118.586273 -282.769432) (xy 118.60944 -282.719386) (xy 118.639569 -282.673196)
			(xy 118.676034 -282.631824) (xy 118.69674 -282.613608) (xy 118.704857 -282.606004) (xy 118.71421 -282.585853)
			(xy 118.714774 -282.574746) (xy 118.714774 -282.49753) (xy 118.714214 -282.486419) (xy 118.704871 -282.46626)
			(xy 118.69674 -282.458668) (xy 118.676071 -282.440412) (xy 118.639604 -282.399047) (xy 118.609473 -282.352863)
			(xy 118.586307 -282.302821) (xy 118.570588 -282.249965) (xy 118.562644 -282.195397) (xy 118.56264 -282.140253)
			(xy 118.570577 -282.085683) (xy 118.586289 -282.032825) (xy 118.609449 -281.98278) (xy 118.639574 -281.936592)
			(xy 118.676035 -281.895223) (xy 118.69674 -281.877008) (xy 118.704857 -281.869404) (xy 118.71421 -281.849253)
			(xy 118.714774 -281.838146) (xy 118.714774 -281.76093) (xy 118.714214 -281.749819) (xy 118.704871 -281.72966)
			(xy 118.69674 -281.722068) (xy 118.676018 -281.703868) (xy 118.639547 -281.662498) (xy 118.609415 -281.616306)
			(xy 118.586251 -281.566256) (xy 118.570537 -281.513391) (xy 118.562602 -281.458814) (xy 118.56212 -281.431238)
			(xy 118.562591 -281.403985) (xy 118.570343 -281.350033) (xy 118.585696 -281.297733) (xy 118.608336 -281.248151)
			(xy 118.637803 -281.202297) (xy 118.673496 -281.161103) (xy 118.714689 -281.125409) (xy 118.760543 -281.095941)
			(xy 118.810124 -281.073299) (xy 118.862423 -281.057945) (xy 118.916375 -281.050191) (xy 118.943628 -281.04973)
			(xy 118.971485 -281.050206) (xy 119.026604 -281.058334) (xy 119.079956 -281.074385) (xy 119.130411 -281.098017)
			(xy 119.176896 -281.12873) (xy 119.218425 -281.165871) (xy 119.254117 -281.208652) (xy 119.283214 -281.256166)
			(xy 119.305098 -281.307402) (xy 119.31269 -281.33421) (xy 119.314976 -281.3431) (xy 119.325644 -281.35834)
			(xy 119.397526 -281.406092) (xy 119.41556 -281.410156) (xy 119.424704 -281.408886) (xy 119.437721 -281.407218)
			(xy 119.463905 -281.405438) (xy 119.477028 -281.40533) (xy 119.490151 -281.405425) (xy 119.516337 -281.407203)
			(xy 119.529352 -281.408886) (xy 119.538496 -281.410156) (xy 119.55653 -281.406092) (xy 119.628412 -281.35834)
			(xy 119.63908 -281.3431) (xy 119.641366 -281.33421) (xy 119.648875 -281.307374) (xy 119.670745 -281.25612)
			(xy 119.699839 -281.208591) (xy 119.735536 -281.1658) (xy 119.777078 -281.128657) (xy 119.823581 -281.097951)
			(xy 119.874056 -281.074336) (xy 119.927429 -281.058315) (xy 119.982565 -281.050227) (xy 120.010428 -281.04973)
			(xy 120.037683 -281.050129) (xy 120.091639 -281.057891) (xy 120.14394 -281.073252) (xy 120.193523 -281.095901)
			(xy 120.239378 -281.125375) (xy 120.280571 -281.161076) (xy 120.316264 -281.202275) (xy 120.345731 -281.248135)
			(xy 120.368371 -281.297722) (xy 120.383723 -281.350026) (xy 120.391476 -281.403983) (xy 120.391936 -281.431238)
			(xy 120.391466 -281.458537) (xy 120.383689 -281.512579) (xy 120.368287 -281.564959) (xy 120.345574 -281.614609)
			(xy 120.316013 -281.660512) (xy 120.298464 -281.681428) (xy 120.292114 -281.688794) (xy 120.285764 -281.706574)
			(xy 120.28932 -281.795982) (xy 120.29694 -281.813254) (xy 120.303798 -281.820112) (xy 120.324929 -281.841741)
			(xy 120.360729 -281.89047) (xy 120.388393 -281.944237) (xy 120.394664 -281.963368) (xy 124.94082 -281.963368)
			(xy 124.944891 -281.907746) (xy 124.957017 -281.853309) (xy 124.97694 -281.801218) (xy 125.004236 -281.752583)
			(xy 125.038322 -281.70844) (xy 125.078471 -281.669731) (xy 125.123829 -281.63728) (xy 125.173429 -281.611779)
			(xy 125.226213 -281.593772) (xy 125.281056 -281.583642) (xy 125.33679 -281.581605) (xy 125.392227 -281.587705)
			(xy 125.446184 -281.601811) (xy 125.497513 -281.623623) (xy 125.545119 -281.652677) (xy 125.587987 -281.688352)
			(xy 125.625204 -281.729889) (xy 125.655977 -281.776402) (xy 125.679649 -281.826899) (xy 125.695717 -281.880306)
			(xy 125.703837 -281.935482) (xy 125.704346 -281.963368) (xy 125.703837 -281.991254) (xy 125.695717 -282.04643)
			(xy 125.679649 -282.099837) (xy 125.655977 -282.150334) (xy 125.625204 -282.196847) (xy 125.587987 -282.238384)
			(xy 125.545119 -282.274059) (xy 125.497513 -282.303113) (xy 125.446184 -282.324925) (xy 125.392227 -282.339031)
			(xy 125.33679 -282.345131) (xy 125.281056 -282.343094) (xy 125.226213 -282.332964) (xy 125.173429 -282.314957)
			(xy 125.123829 -282.289456) (xy 125.078471 -282.257005) (xy 125.038322 -282.218296) (xy 125.004236 -282.174153)
			(xy 124.97694 -282.125518) (xy 124.957017 -282.073427) (xy 124.944891 -282.01899) (xy 124.94082 -281.963368)
			(xy 120.394664 -281.963368) (xy 120.407228 -282.001695) (xy 120.416761 -282.061405) (xy 120.417336 -282.091638)
			(xy 120.41684 -282.119276) (xy 120.408848 -282.173971) (xy 120.393051 -282.226942) (xy 120.369779 -282.277081)
			(xy 120.339519 -282.323339) (xy 120.321578 -282.344368) (xy 120.313196 -282.35402) (xy 120.307354 -282.378404)
			(xy 120.334532 -282.484576) (xy 120.35155 -282.503118) (xy 120.363488 -282.507436) (xy 120.390896 -282.517773)
			(xy 120.442411 -282.545655) (xy 120.489057 -282.581087) (xy 120.529735 -282.623235) (xy 120.563489 -282.671108)
			(xy 120.589525 -282.72358) (xy 120.607231 -282.779417) (xy 120.61619 -282.837304) (xy 120.616726 -282.866592)
			(xy 120.616192 -282.893854) (xy 120.946347 -282.893854) (xy 120.946347 -282.839346) (xy 120.954105 -282.785392)
			(xy 120.969462 -282.733092) (xy 120.992107 -282.683509) (xy 121.021577 -282.637654) (xy 121.057273 -282.59646)
			(xy 121.098469 -282.560766) (xy 121.144325 -282.531298) (xy 121.193909 -282.508656) (xy 121.24621 -282.493301)
			(xy 121.300164 -282.485546) (xy 121.327418 -282.485084) (xy 121.35479 -282.485519) (xy 121.408971 -282.493341)
			(xy 121.461475 -282.508836) (xy 121.511222 -282.531686) (xy 121.557186 -282.561418) (xy 121.578116 -282.579064)
			(xy 121.585228 -282.58516) (xy 121.602246 -282.59151) (xy 121.68759 -282.59151) (xy 121.704608 -282.58516)
			(xy 121.71172 -282.579064) (xy 121.732667 -282.561443) (xy 121.778636 -282.53173) (xy 121.82838 -282.508891)
			(xy 121.880877 -282.493396) (xy 121.93505 -282.485561) (xy 121.962418 -282.485084) (xy 121.989668 -282.485587)
			(xy 122.043612 -282.493345) (xy 122.095904 -282.508702) (xy 122.145478 -282.531343) (xy 122.191325 -282.56081)
			(xy 122.232512 -282.5965) (xy 122.268201 -282.637689) (xy 122.297665 -282.683538) (xy 122.320305 -282.733113)
			(xy 122.335658 -282.785405) (xy 122.343414 -282.83935) (xy 122.343414 -282.89385) (xy 122.341892 -282.904438)
			(xy 126.722632 -282.904438) (xy 126.723113 -282.876864) (xy 126.731061 -282.822291) (xy 126.746782 -282.769431)
			(xy 126.769949 -282.719385) (xy 126.800079 -282.673195) (xy 126.836545 -282.631824) (xy 126.857252 -282.613608)
			(xy 126.86537 -282.606006) (xy 126.874723 -282.585854) (xy 126.875286 -282.574746) (xy 126.875286 -282.49753)
			(xy 126.874722 -282.48642) (xy 126.865381 -282.466261) (xy 126.857252 -282.458668) (xy 126.836582 -282.440412)
			(xy 126.800114 -282.399048) (xy 126.769982 -282.352864) (xy 126.746815 -282.302822) (xy 126.731096 -282.249966)
			(xy 126.723152 -282.195397) (xy 126.723148 -282.140252) (xy 126.731085 -282.085682) (xy 126.746798 -282.032824)
			(xy 126.769959 -281.982779) (xy 126.800084 -281.936591) (xy 126.836547 -281.895222) (xy 126.857252 -281.877008)
			(xy 126.86537 -281.869406) (xy 126.874723 -281.849254) (xy 126.875286 -281.838146) (xy 126.875286 -281.76093)
			(xy 126.874722 -281.74982) (xy 126.865381 -281.729661) (xy 126.857252 -281.722068) (xy 126.836513 -281.703888)
			(xy 126.800046 -281.662511) (xy 126.769919 -281.616315) (xy 126.746759 -281.566261) (xy 126.731048 -281.513393)
			(xy 126.723114 -281.458814) (xy 126.722632 -281.431238) (xy 126.723091 -281.403984) (xy 126.730844 -281.350031)
			(xy 126.746197 -281.297731) (xy 126.768838 -281.248148) (xy 126.798306 -281.202293) (xy 126.834 -281.161099)
			(xy 126.875194 -281.125404) (xy 126.92105 -281.095937) (xy 126.970633 -281.073296) (xy 127.022933 -281.057943)
			(xy 127.076886 -281.050191) (xy 127.10414 -281.04973) (xy 127.131997 -281.050195) (xy 127.187117 -281.058325)
			(xy 127.240469 -281.074377) (xy 127.290924 -281.098011) (xy 127.337409 -281.128725) (xy 127.378938 -281.165868)
			(xy 127.414629 -281.20865) (xy 127.443726 -281.256164) (xy 127.46561 -281.307402) (xy 127.473202 -281.33421)
			(xy 127.475488 -281.3431) (xy 127.486156 -281.35834) (xy 127.558038 -281.406092) (xy 127.576072 -281.410156)
			(xy 127.585216 -281.408886) (xy 127.598233 -281.407217) (xy 127.624417 -281.405437) (xy 127.63754 -281.40533)
			(xy 127.650663 -281.405424) (xy 127.676849 -281.407203) (xy 127.689864 -281.408886) (xy 127.699008 -281.410156)
			(xy 127.717042 -281.406092) (xy 127.788924 -281.35834) (xy 127.799592 -281.3431) (xy 127.801878 -281.33421)
			(xy 127.809467 -281.307399) (xy 127.83133 -281.256149) (xy 127.860415 -281.208624) (xy 127.896103 -281.165835)
			(xy 127.937634 -281.12869) (xy 127.984126 -281.097982) (xy 128.034591 -281.074361) (xy 128.087954 -281.058332)
			(xy 128.143081 -281.050234) (xy 128.17094 -281.04973) (xy 128.198194 -281.050141) (xy 128.252146 -281.057904)
			(xy 128.304445 -281.073266) (xy 128.354025 -281.095914) (xy 128.399877 -281.125388) (xy 128.441068 -281.161088)
			(xy 128.476758 -281.202286) (xy 128.506223 -281.248144) (xy 128.528862 -281.297728) (xy 128.544213 -281.35003)
			(xy 128.551965 -281.403984) (xy 128.552448 -281.431238) (xy 128.551975 -281.458537) (xy 128.544199 -281.512578)
			(xy 128.528797 -281.564959) (xy 128.506085 -281.614608) (xy 128.476525 -281.660512) (xy 128.458976 -281.681428)
			(xy 128.452626 -281.688794) (xy 128.446276 -281.706574) (xy 128.449832 -281.795982) (xy 128.457452 -281.813254)
			(xy 128.46431 -281.820112) (xy 128.485426 -281.841756) (xy 128.521231 -281.890479) (xy 128.5489 -281.944242)
			(xy 128.555171 -281.963368) (xy 133.101332 -281.963368) (xy 133.105403 -281.907746) (xy 133.117529 -281.853309)
			(xy 133.137452 -281.801218) (xy 133.164748 -281.752583) (xy 133.198834 -281.70844) (xy 133.238983 -281.669731)
			(xy 133.284341 -281.63728) (xy 133.333941 -281.611779) (xy 133.386725 -281.593772) (xy 133.441568 -281.583642)
			(xy 133.497302 -281.581605) (xy 133.552739 -281.587705) (xy 133.606696 -281.601811) (xy 133.658025 -281.623623)
			(xy 133.705631 -281.652677) (xy 133.748499 -281.688352) (xy 133.785716 -281.729889) (xy 133.816489 -281.776402)
			(xy 133.840161 -281.826899) (xy 133.856229 -281.880306) (xy 133.864349 -281.935482) (xy 133.864858 -281.963368)
			(xy 133.864349 -281.991254) (xy 133.856229 -282.04643) (xy 133.840161 -282.099837) (xy 133.816489 -282.150334)
			(xy 133.785716 -282.196847) (xy 133.748499 -282.238384) (xy 133.705631 -282.274059) (xy 133.658025 -282.303113)
			(xy 133.606696 -282.324925) (xy 133.552739 -282.339031) (xy 133.497302 -282.345131) (xy 133.441568 -282.343094)
			(xy 133.386725 -282.332964) (xy 133.333941 -282.314957) (xy 133.284341 -282.289456) (xy 133.238983 -282.257005)
			(xy 133.198834 -282.218296) (xy 133.164748 -282.174153) (xy 133.137452 -282.125518) (xy 133.117529 -282.073427)
			(xy 133.105403 -282.01899) (xy 133.101332 -281.963368) (xy 128.555171 -281.963368) (xy 128.567738 -282.001697)
			(xy 128.577273 -282.061406) (xy 128.577848 -282.091638) (xy 128.577349 -282.119276) (xy 128.569357 -282.173971)
			(xy 128.553561 -282.226942) (xy 128.530289 -282.27708) (xy 128.50003 -282.323338) (xy 128.48209 -282.344368)
			(xy 128.473708 -282.35402) (xy 128.467866 -282.378404) (xy 128.495044 -282.484576) (xy 128.512062 -282.503118)
			(xy 128.524 -282.507436) (xy 128.551411 -282.517766) (xy 128.602926 -282.54565) (xy 128.64957 -282.581083)
			(xy 128.690248 -282.623232) (xy 128.724002 -282.671106) (xy 128.750038 -282.723579) (xy 128.767743 -282.779416)
			(xy 128.776702 -282.837304) (xy 128.777238 -282.866592) (xy 128.776703 -282.893855) (xy 129.106847 -282.893855)
			(xy 129.106847 -282.839345) (xy 129.114605 -282.785391) (xy 129.129963 -282.733089) (xy 129.152608 -282.683506)
			(xy 129.18208 -282.637651) (xy 129.217777 -282.596456) (xy 129.258975 -282.560762) (xy 129.304832 -282.531294)
			(xy 129.354417 -282.508653) (xy 129.40672 -282.493299) (xy 129.460675 -282.485545) (xy 129.48793 -282.485084)
			(xy 129.515302 -282.485512) (xy 129.569483 -282.493336) (xy 129.621988 -282.508833) (xy 129.671734 -282.531683)
			(xy 129.717698 -282.561418) (xy 129.738628 -282.579064) (xy 129.74574 -282.58516) (xy 129.762758 -282.59151)
			(xy 129.848102 -282.59151) (xy 129.86512 -282.58516) (xy 129.872232 -282.579064) (xy 129.893174 -282.561438)
			(xy 129.939145 -282.531725) (xy 129.98889 -282.508887) (xy 130.041388 -282.493393) (xy 130.095562 -282.485561)
			(xy 130.12293 -282.485084) (xy 130.150179 -282.485588) (xy 130.204123 -282.493348) (xy 130.256413 -282.508705)
			(xy 130.305985 -282.531347) (xy 130.351831 -282.560814) (xy 130.393017 -282.596505) (xy 130.428704 -282.637693)
			(xy 130.458167 -282.683541) (xy 130.480805 -282.733115) (xy 130.496159 -282.785407) (xy 130.503914 -282.839351)
			(xy 130.503914 -282.893849) (xy 130.496159 -282.947793) (xy 130.480805 -283.000085) (xy 130.458167 -283.049659)
			(xy 130.428704 -283.095507) (xy 130.393017 -283.136695) (xy 130.351831 -283.172386) (xy 130.305985 -283.201853)
			(xy 130.256413 -283.224495) (xy 130.204123 -283.239852) (xy 130.150179 -283.247612) (xy 130.12293 -283.2481)
			(xy 130.09556 -283.247616) (xy 130.041382 -283.239803) (xy 129.988879 -283.224318) (xy 129.939132 -283.20148)
			(xy 129.893164 -283.171759) (xy 129.872232 -283.15412) (xy 129.86512 -283.148024) (xy 129.848102 -283.141674)
			(xy 129.762758 -283.141674) (xy 129.74574 -283.148024) (xy 129.738628 -283.15412) (xy 129.717699 -283.171763)
			(xy 129.671725 -283.201473) (xy 129.621977 -283.224308) (xy 129.569475 -283.239798) (xy 129.515299 -283.247626)
			(xy 129.48793 -283.2481) (xy 129.460675 -283.247655) (xy 129.40672 -283.239901) (xy 129.354417 -283.224547)
			(xy 129.304832 -283.201906) (xy 129.258975 -283.172438) (xy 129.217777 -283.136744) (xy 129.18208 -283.095549)
			(xy 129.152608 -283.049694) (xy 129.129963 -283.000111) (xy 129.114605 -282.947809) (xy 129.106847 -282.893855)
			(xy 128.776703 -282.893855) (xy 128.776652 -282.89643) (xy 128.767344 -282.955376) (xy 128.758696 -282.98394)
			(xy 128.755394 -282.994354) (xy 128.75768 -283.015944) (xy 128.807718 -283.100526) (xy 128.825498 -283.112972)
			(xy 128.836166 -283.115004) (xy 128.861983 -283.120344) (xy 128.911899 -283.137313) (xy 128.959003 -283.160993)
			(xy 129.002398 -283.190934) (xy 129.041256 -283.226565) (xy 129.074838 -283.267208) (xy 129.102503 -283.312087)
			(xy 129.123725 -283.360349) (xy 129.138099 -283.411073) (xy 129.145351 -283.463293) (xy 129.145792 -283.489654)
			(xy 129.145209 -283.519777) (xy 129.135733 -283.579274) (xy 129.117026 -283.636542) (xy 129.089553 -283.690159)
			(xy 129.053995 -283.738793) (xy 129.033016 -283.760418) (xy 129.02565 -283.76753) (xy 129.01803 -283.786326)
			(xy 129.01803 -283.878782) (xy 129.02565 -283.897578) (xy 129.033016 -283.90469) (xy 129.054019 -283.926293)
			(xy 129.089584 -283.974928) (xy 129.117059 -284.02855) (xy 129.131438 -284.072584) (xy 134.033006 -284.072584)
			(xy 134.033461 -284.045213) (xy 134.041281 -283.991034) (xy 134.056773 -283.93853) (xy 134.079617 -283.888784)
			(xy 134.109344 -283.842817) (xy 134.126986 -283.821886) (xy 134.133082 -283.814774) (xy 134.139432 -283.797756)
			(xy 134.139432 -283.712412) (xy 134.133082 -283.695394) (xy 134.126986 -283.688282) (xy 134.10937 -283.667332)
			(xy 134.079655 -283.621364) (xy 134.056815 -283.571621) (xy 134.041318 -283.519124) (xy 134.033484 -283.464952)
			(xy 134.033006 -283.437584) (xy 134.033492 -283.410333) (xy 134.041248 -283.356385) (xy 134.056603 -283.30409)
			(xy 134.079245 -283.254513) (xy 134.108711 -283.208663) (xy 134.144402 -283.167472) (xy 134.185593 -283.131781)
			(xy 134.231443 -283.102315) (xy 134.28102 -283.079673) (xy 134.333315 -283.064318) (xy 134.387263 -283.056562)
			(xy 134.441765 -283.056562) (xy 134.495713 -283.064318) (xy 134.548008 -283.079673) (xy 134.597585 -283.102315)
			(xy 134.643435 -283.131781) (xy 134.684626 -283.167472) (xy 134.720317 -283.208663) (xy 134.749783 -283.254513)
			(xy 134.772425 -283.30409) (xy 134.78778 -283.356385) (xy 134.795536 -283.410333) (xy 134.796022 -283.437584)
			(xy 134.795566 -283.464955) (xy 134.787748 -283.519135) (xy 134.772258 -283.571639) (xy 134.749414 -283.621386)
			(xy 134.719685 -283.667351) (xy 134.702042 -283.688282) (xy 134.695946 -283.695394) (xy 134.689596 -283.712412)
			(xy 134.689596 -283.797756) (xy 134.695946 -283.814774) (xy 134.702042 -283.821886) (xy 134.719695 -283.842807)
			(xy 134.749403 -283.888783) (xy 134.772236 -283.938534) (xy 134.787724 -283.991037) (xy 134.79555 -284.045214)
			(xy 134.796022 -284.072584) (xy 134.795536 -284.099835) (xy 134.78778 -284.153783) (xy 134.772425 -284.206078)
			(xy 134.749783 -284.255655) (xy 134.720317 -284.301505) (xy 134.684626 -284.342696) (xy 134.643435 -284.378387)
			(xy 134.597585 -284.407853) (xy 134.548008 -284.430495) (xy 134.495713 -284.44585) (xy 134.441765 -284.453606)
			(xy 134.387263 -284.453606) (xy 134.333315 -284.44585) (xy 134.28102 -284.430495) (xy 134.231443 -284.407853)
			(xy 134.185593 -284.378387) (xy 134.144402 -284.342696) (xy 134.108711 -284.301505) (xy 134.079245 -284.255655)
			(xy 134.056603 -284.206078) (xy 134.041248 -284.153783) (xy 134.033492 -284.099835) (xy 134.033006 -284.072584)
			(xy 129.131438 -284.072584) (xy 129.135762 -284.085825) (xy 129.145227 -284.145328) (xy 129.145792 -284.175454)
			(xy 129.145306 -284.202705) (xy 129.13755 -284.256653) (xy 129.122195 -284.308948) (xy 129.099553 -284.358525)
			(xy 129.070087 -284.404375) (xy 129.034396 -284.445566) (xy 128.993205 -284.481257) (xy 128.947355 -284.510723)
			(xy 128.897778 -284.533365) (xy 128.845483 -284.54872) (xy 128.791535 -284.556476) (xy 128.737033 -284.556476)
			(xy 128.683085 -284.54872) (xy 128.63079 -284.533365) (xy 128.581213 -284.510723) (xy 128.535363 -284.481257)
			(xy 128.494172 -284.445566) (xy 128.458481 -284.404375) (xy 128.429015 -284.358525) (xy 128.406373 -284.308948)
			(xy 128.391018 -284.256653) (xy 128.383262 -284.202705) (xy 128.382776 -284.175454) (xy 128.383374 -284.145332)
			(xy 128.392847 -284.085836) (xy 128.411551 -284.028568) (xy 128.439021 -283.974951) (xy 128.474575 -283.926316)
			(xy 128.495552 -283.90469) (xy 128.502918 -283.897578) (xy 128.510538 -283.878782) (xy 128.510538 -283.786326)
			(xy 128.502918 -283.76753) (xy 128.495552 -283.760418) (xy 128.474564 -283.7388) (xy 128.438995 -283.69017)
			(xy 128.411515 -283.636552) (xy 128.392809 -283.57928) (xy 128.383342 -283.519779) (xy 128.382776 -283.489654)
			(xy 128.383349 -283.459815) (xy 128.392666 -283.400869) (xy 128.401318 -283.372306) (xy 128.40462 -283.361892)
			(xy 128.402334 -283.340302) (xy 128.352296 -283.25572) (xy 128.334516 -283.243274) (xy 128.323848 -283.241242)
			(xy 128.295998 -283.235391) (xy 128.242335 -283.216454) (xy 128.192078 -283.18976) (xy 128.146341 -283.155899)
			(xy 128.106139 -283.115622) (xy 128.072363 -283.069823) (xy 128.045761 -283.019516) (xy 128.026924 -282.965818)
			(xy 128.02108 -282.937966) (xy 128.01854 -282.925774) (xy 128.002792 -282.905962) (xy 127.902716 -282.862528)
			(xy 127.87757 -282.86456) (xy 127.866902 -282.871164) (xy 127.843932 -282.885202) (xy 127.794858 -282.907333)
			(xy 127.743156 -282.922329) (xy 127.689857 -282.929892) (xy 127.66294 -282.930346) (xy 127.644921 -282.930129)
			(xy 127.609046 -282.926692) (xy 127.591312 -282.923488) (xy 127.581914 -282.92171) (xy 127.562864 -282.92552)
			(xy 127.48768 -282.973272) (xy 127.47625 -282.98902) (xy 127.473964 -282.998418) (xy 127.466566 -283.025463)
			(xy 127.444939 -283.07719) (xy 127.415976 -283.125197) (xy 127.380301 -283.16845) (xy 127.338682 -283.206018)
			(xy 127.292014 -283.237092) (xy 127.241301 -283.261004) (xy 127.187636 -283.27724) (xy 127.132173 -283.285449)
			(xy 127.10414 -283.285946) (xy 127.07689 -283.285408) (xy 127.022944 -283.277657) (xy 126.970649 -283.262308)
			(xy 126.921072 -283.239673) (xy 126.875221 -283.210213) (xy 126.834028 -283.174527) (xy 126.798334 -283.133342)
			(xy 126.768864 -283.087497) (xy 126.746219 -283.037924) (xy 126.73086 -282.985633) (xy 126.723098 -282.931688)
			(xy 126.722632 -282.904438) (xy 122.341892 -282.904438) (xy 122.335658 -282.947795) (xy 122.320305 -283.000087)
			(xy 122.297665 -283.049662) (xy 122.268201 -283.095511) (xy 122.232512 -283.1367) (xy 122.191325 -283.17239)
			(xy 122.145478 -283.201857) (xy 122.095904 -283.224498) (xy 122.043612 -283.239855) (xy 121.989668 -283.247613)
			(xy 121.962418 -283.2481) (xy 121.935048 -283.247623) (xy 121.88087 -283.239808) (xy 121.828367 -283.224321)
			(xy 121.778619 -283.201482) (xy 121.732652 -283.17176) (xy 121.71172 -283.15412) (xy 121.704608 -283.148024)
			(xy 121.68759 -283.141674) (xy 121.602246 -283.141674) (xy 121.585228 -283.148024) (xy 121.578116 -283.15412)
			(xy 121.557191 -283.171768) (xy 121.511216 -283.201478) (xy 121.461467 -283.224312) (xy 121.408965 -283.239801)
			(xy 121.354788 -283.247627) (xy 121.327418 -283.2481) (xy 121.300164 -283.247654) (xy 121.24621 -283.239899)
			(xy 121.193909 -283.224544) (xy 121.144325 -283.201902) (xy 121.098469 -283.172434) (xy 121.057273 -283.13674)
			(xy 121.021577 -283.095546) (xy 120.992107 -283.049691) (xy 120.969462 -283.000108) (xy 120.954105 -282.947808)
			(xy 120.946347 -282.893854) (xy 120.616192 -282.893854) (xy 120.616141 -282.89643) (xy 120.606832 -282.955376)
			(xy 120.598184 -282.98394) (xy 120.594882 -282.994354) (xy 120.597168 -283.015944) (xy 120.647206 -283.100526)
			(xy 120.664986 -283.112972) (xy 120.675654 -283.115004) (xy 120.701469 -283.120353) (xy 120.751385 -283.13732)
			(xy 120.798489 -283.160999) (xy 120.841884 -283.190938) (xy 120.880743 -283.226569) (xy 120.914325 -283.26721)
			(xy 120.94199 -283.312089) (xy 120.963212 -283.36035) (xy 120.977587 -283.411074) (xy 120.984839 -283.463293)
			(xy 120.98528 -283.489654) (xy 120.984672 -283.519776) (xy 120.975198 -283.57927) (xy 120.956496 -283.636537)
			(xy 120.929029 -283.690155) (xy 120.893479 -283.738791) (xy 120.872504 -283.760418) (xy 120.865138 -283.76753)
			(xy 120.857518 -283.786326) (xy 120.857518 -283.878782) (xy 120.865138 -283.897578) (xy 120.872504 -283.90469)
			(xy 120.893505 -283.926295) (xy 120.929071 -283.97493) (xy 120.956547 -284.028551) (xy 120.970926 -284.072584)
			(xy 125.872494 -284.072584) (xy 125.872952 -284.045214) (xy 125.880772 -283.991034) (xy 125.896263 -283.938531)
			(xy 125.919107 -283.888784) (xy 125.948832 -283.842818) (xy 125.966474 -283.821886) (xy 125.97257 -283.814774)
			(xy 125.97892 -283.797756) (xy 125.97892 -283.712412) (xy 125.97257 -283.695394) (xy 125.966474 -283.688282)
			(xy 125.948856 -283.667333) (xy 125.919142 -283.621365) (xy 125.896302 -283.571621) (xy 125.880806 -283.519124)
			(xy 125.872972 -283.464952) (xy 125.872494 -283.437584) (xy 125.87298 -283.410333) (xy 125.880736 -283.356385)
			(xy 125.896091 -283.30409) (xy 125.918733 -283.254513) (xy 125.948199 -283.208663) (xy 125.98389 -283.167472)
			(xy 126.025081 -283.131781) (xy 126.070931 -283.102315) (xy 126.120508 -283.079673) (xy 126.172803 -283.064318)
			(xy 126.226751 -283.056562) (xy 126.281253 -283.056562) (xy 126.335201 -283.064318) (xy 126.387496 -283.079673)
			(xy 126.437073 -283.102315) (xy 126.482923 -283.131781) (xy 126.524114 -283.167472) (xy 126.559805 -283.208663)
			(xy 126.589271 -283.254513) (xy 126.611913 -283.30409) (xy 126.627268 -283.356385) (xy 126.635024 -283.410333)
			(xy 126.63551 -283.437584) (xy 126.635032 -283.464954) (xy 126.627217 -283.519132) (xy 126.61173 -283.571635)
			(xy 126.588891 -283.621382) (xy 126.55917 -283.66735) (xy 126.54153 -283.688282) (xy 126.535434 -283.695394)
			(xy 126.529084 -283.712412) (xy 126.529084 -283.797756) (xy 126.535434 -283.814774) (xy 126.54153 -283.821886)
			(xy 126.559181 -283.842809) (xy 126.58889 -283.888785) (xy 126.611723 -283.938534) (xy 126.627211 -283.991037)
			(xy 126.635037 -284.045214) (xy 126.63551 -284.072584) (xy 126.635024 -284.099835) (xy 126.627268 -284.153783)
			(xy 126.611913 -284.206078) (xy 126.589271 -284.255655) (xy 126.559805 -284.301505) (xy 126.524114 -284.342696)
			(xy 126.482923 -284.378387) (xy 126.437073 -284.407853) (xy 126.387496 -284.430495) (xy 126.335201 -284.44585)
			(xy 126.281253 -284.453606) (xy 126.226751 -284.453606) (xy 126.172803 -284.44585) (xy 126.120508 -284.430495)
			(xy 126.070931 -284.407853) (xy 126.025081 -284.378387) (xy 125.98389 -284.342696) (xy 125.948199 -284.301505)
			(xy 125.918733 -284.255655) (xy 125.896091 -284.206078) (xy 125.880736 -284.153783) (xy 125.87298 -284.099835)
			(xy 125.872494 -284.072584) (xy 120.970926 -284.072584) (xy 120.97525 -284.085825) (xy 120.984715 -284.145328)
			(xy 120.98528 -284.175454) (xy 120.984794 -284.202705) (xy 120.977038 -284.256653) (xy 120.961683 -284.308948)
			(xy 120.939041 -284.358525) (xy 120.909575 -284.404375) (xy 120.873884 -284.445566) (xy 120.832693 -284.481257)
			(xy 120.786843 -284.510723) (xy 120.737266 -284.533365) (xy 120.684971 -284.54872) (xy 120.631023 -284.556476)
			(xy 120.576521 -284.556476) (xy 120.522573 -284.54872) (xy 120.470278 -284.533365) (xy 120.420701 -284.510723)
			(xy 120.374851 -284.481257) (xy 120.33366 -284.445566) (xy 120.297969 -284.404375) (xy 120.268503 -284.358525)
			(xy 120.245861 -284.308948) (xy 120.230506 -284.256653) (xy 120.22275 -284.202705) (xy 120.222264 -284.175454)
			(xy 120.222865 -284.145332) (xy 120.232338 -284.085837) (xy 120.251042 -284.028569) (xy 120.278511 -283.974951)
			(xy 120.314064 -283.926316) (xy 120.33504 -283.90469) (xy 120.342406 -283.897578) (xy 120.350026 -283.878782)
			(xy 120.350026 -283.786326) (xy 120.342406 -283.76753) (xy 120.33504 -283.760418) (xy 120.31405 -283.738802)
			(xy 120.278482 -283.690171) (xy 120.251003 -283.636553) (xy 120.232297 -283.57928) (xy 120.22283 -283.519779)
			(xy 120.222264 -283.489654) (xy 120.222837 -283.459815) (xy 120.232154 -283.400869) (xy 120.240806 -283.372306)
			(xy 120.244108 -283.361892) (xy 120.241822 -283.340302) (xy 120.191784 -283.25572) (xy 120.174004 -283.243274)
			(xy 120.163336 -283.241242) (xy 120.135485 -283.2354) (xy 120.081821 -283.216461) (xy 120.031564 -283.189765)
			(xy 119.985828 -283.155903) (xy 119.945626 -283.115625) (xy 119.91185 -283.069825) (xy 119.885249 -283.019517)
			(xy 119.866412 -282.965818) (xy 119.860568 -282.937966) (xy 119.858028 -282.925774) (xy 119.84228 -282.905962)
			(xy 119.742204 -282.862528) (xy 119.717058 -282.86456) (xy 119.70639 -282.871164) (xy 119.683423 -282.885207)
			(xy 119.634348 -282.907337) (xy 119.582645 -282.922332) (xy 119.529345 -282.929892) (xy 119.502428 -282.930346)
			(xy 119.484408 -282.93013) (xy 119.448534 -282.926693) (xy 119.4308 -282.923488) (xy 119.421402 -282.92171)
			(xy 119.402352 -282.92552) (xy 119.327168 -282.973272) (xy 119.315738 -282.98902) (xy 119.313452 -282.998418)
			(xy 119.306065 -283.025466) (xy 119.284437 -283.077194) (xy 119.255473 -283.125202) (xy 119.219797 -283.168455)
			(xy 119.178176 -283.206023) (xy 119.131506 -283.237097) (xy 119.080793 -283.261008) (xy 119.027126 -283.277242)
			(xy 118.971662 -283.285449) (xy 118.943628 -283.285946) (xy 118.916379 -283.285396) (xy 118.862436 -283.277644)
			(xy 118.810145 -283.262294) (xy 118.76057 -283.239659) (xy 118.714721 -283.2102) (xy 118.673532 -283.174515)
			(xy 118.63784 -283.133331) (xy 118.608372 -283.087488) (xy 118.585729 -283.037917) (xy 118.57037 -282.985629)
			(xy 118.562609 -282.931687) (xy 118.56212 -282.904438) (xy 113.843292 -282.904438) (xy 113.837059 -282.947793)
			(xy 113.821706 -283.000084) (xy 113.799067 -283.049658) (xy 113.769605 -283.095506) (xy 113.733917 -283.136695)
			(xy 113.692732 -283.172385) (xy 113.646886 -283.201852) (xy 113.597314 -283.224494) (xy 113.545024 -283.239852)
			(xy 113.491081 -283.247612) (xy 113.463832 -283.2481) (xy 113.436462 -283.247615) (xy 113.382284 -283.239802)
			(xy 113.329781 -283.224317) (xy 113.280034 -283.20148) (xy 113.234066 -283.171759) (xy 113.213134 -283.15412)
			(xy 113.206022 -283.148024) (xy 113.189004 -283.141674) (xy 113.10366 -283.141674) (xy 113.086642 -283.148024)
			(xy 113.07953 -283.15412) (xy 113.0586 -283.171762) (xy 113.012626 -283.201472) (xy 112.962878 -283.224308)
			(xy 112.910377 -283.239798) (xy 112.856201 -283.247626) (xy 112.828832 -283.2481) (xy 112.801577 -283.247655)
			(xy 112.747622 -283.239901) (xy 112.695319 -283.224548) (xy 112.645734 -283.201907) (xy 112.599876 -283.172439)
			(xy 112.558678 -283.136745) (xy 112.52298 -283.09555) (xy 112.493509 -283.049695) (xy 112.470863 -283.000111)
			(xy 112.455505 -282.94781) (xy 112.447747 -282.893855) (xy 112.117605 -282.893855) (xy 112.117554 -282.89643)
			(xy 112.108246 -282.955376) (xy 112.099598 -282.98394) (xy 112.096296 -282.994354) (xy 112.098582 -283.015944)
			(xy 112.14862 -283.100526) (xy 112.1664 -283.112972) (xy 112.177068 -283.115004) (xy 112.202885 -283.120343)
			(xy 112.252801 -283.137311) (xy 112.299905 -283.160992) (xy 112.3433 -283.190933) (xy 112.382158 -283.226565)
			(xy 112.41574 -283.267207) (xy 112.443405 -283.312087) (xy 112.464627 -283.360349) (xy 112.479001 -283.411073)
			(xy 112.486253 -283.463293) (xy 112.486694 -283.489654) (xy 112.48611 -283.519777) (xy 112.476635 -283.579274)
			(xy 112.457928 -283.636542) (xy 112.430454 -283.690159) (xy 112.394897 -283.738793) (xy 112.373918 -283.760418)
			(xy 112.366552 -283.76753) (xy 112.358932 -283.786326) (xy 112.358932 -283.878782) (xy 112.366552 -283.897578)
			(xy 112.373918 -283.90469) (xy 112.394922 -283.926293) (xy 112.430486 -283.974928) (xy 112.457962 -284.02855)
			(xy 112.47234 -284.072584) (xy 117.373908 -284.072584) (xy 117.374363 -284.045213) (xy 117.382183 -283.991034)
			(xy 117.397675 -283.93853) (xy 117.420519 -283.888784) (xy 117.450246 -283.842817) (xy 117.467888 -283.821886)
			(xy 117.473984 -283.814774) (xy 117.480334 -283.797756) (xy 117.480334 -283.712412) (xy 117.473984 -283.695394)
			(xy 117.467888 -283.688282) (xy 117.450272 -283.667331) (xy 117.420557 -283.621363) (xy 117.397717 -283.571621)
			(xy 117.38222 -283.519124) (xy 117.374386 -283.464952) (xy 117.373908 -283.437584) (xy 117.374394 -283.410333)
			(xy 117.38215 -283.356385) (xy 117.397505 -283.30409) (xy 117.420147 -283.254513) (xy 117.449613 -283.208663)
			(xy 117.485304 -283.167472) (xy 117.526495 -283.131781) (xy 117.572345 -283.102315) (xy 117.621922 -283.079673)
			(xy 117.674217 -283.064318) (xy 117.728165 -283.056562) (xy 117.782667 -283.056562) (xy 117.836615 -283.064318)
			(xy 117.88891 -283.079673) (xy 117.938487 -283.102315) (xy 117.984337 -283.131781) (xy 118.025528 -283.167472)
			(xy 118.061219 -283.208663) (xy 118.090685 -283.254513) (xy 118.113327 -283.30409) (xy 118.128682 -283.356385)
			(xy 118.136438 -283.410333) (xy 118.136924 -283.437584) (xy 118.136467 -283.464955) (xy 118.12865 -283.519135)
			(xy 118.11316 -283.571639) (xy 118.090315 -283.621386) (xy 118.060587 -283.667351) (xy 118.042944 -283.688282)
			(xy 118.036848 -283.695394) (xy 118.030498 -283.712412) (xy 118.030498 -283.797756) (xy 118.036848 -283.814774)
			(xy 118.042944 -283.821886) (xy 118.060597 -283.842807) (xy 118.090306 -283.888783) (xy 118.113138 -283.938534)
			(xy 118.128626 -283.991037) (xy 118.136452 -284.045214) (xy 118.136924 -284.072584) (xy 118.136438 -284.099835)
			(xy 118.128682 -284.153783) (xy 118.113327 -284.206078) (xy 118.090685 -284.255655) (xy 118.061219 -284.301505)
			(xy 118.025528 -284.342696) (xy 117.984337 -284.378387) (xy 117.938487 -284.407853) (xy 117.88891 -284.430495)
			(xy 117.836615 -284.44585) (xy 117.782667 -284.453606) (xy 117.728165 -284.453606) (xy 117.674217 -284.44585)
			(xy 117.621922 -284.430495) (xy 117.572345 -284.407853) (xy 117.526495 -284.378387) (xy 117.485304 -284.342696)
			(xy 117.449613 -284.301505) (xy 117.420147 -284.255655) (xy 117.397505 -284.206078) (xy 117.38215 -284.153783)
			(xy 117.374394 -284.099835) (xy 117.373908 -284.072584) (xy 112.47234 -284.072584) (xy 112.476664 -284.085825)
			(xy 112.486129 -284.145328) (xy 112.486694 -284.175454) (xy 112.486208 -284.202705) (xy 112.478452 -284.256653)
			(xy 112.463097 -284.308948) (xy 112.440455 -284.358525) (xy 112.410989 -284.404375) (xy 112.375298 -284.445566)
			(xy 112.334107 -284.481257) (xy 112.288257 -284.510723) (xy 112.23868 -284.533365) (xy 112.186385 -284.54872)
			(xy 112.132437 -284.556476) (xy 112.077935 -284.556476) (xy 112.023987 -284.54872) (xy 111.971692 -284.533365)
			(xy 111.922115 -284.510723) (xy 111.876265 -284.481257) (xy 111.835074 -284.445566) (xy 111.799383 -284.404375)
			(xy 111.769917 -284.358525) (xy 111.747275 -284.308948) (xy 111.73192 -284.256653) (xy 111.724164 -284.202705)
			(xy 111.723678 -284.175454) (xy 111.724275 -284.145332) (xy 111.733748 -284.085836) (xy 111.752453 -284.028568)
			(xy 111.779923 -283.974951) (xy 111.815477 -283.926316) (xy 111.836454 -283.90469) (xy 111.84382 -283.897578)
			(xy 111.85144 -283.878782) (xy 111.85144 -283.786326) (xy 111.84382 -283.76753) (xy 111.836454 -283.760418)
			(xy 111.815467 -283.738799) (xy 111.779897 -283.69017) (xy 111.752417 -283.636552) (xy 111.733711 -283.57928)
			(xy 111.724244 -283.519779) (xy 111.723678 -283.489654) (xy 111.72425 -283.459815) (xy 111.733568 -283.400869)
			(xy 111.74222 -283.372306) (xy 111.745522 -283.361892) (xy 111.743236 -283.340302) (xy 111.693198 -283.25572)
			(xy 111.675418 -283.243274) (xy 111.66475 -283.241242) (xy 111.636901 -283.23539) (xy 111.583237 -283.216453)
			(xy 111.53298 -283.189759) (xy 111.487243 -283.155898) (xy 111.447041 -283.115622) (xy 111.413265 -283.069823)
			(xy 111.386664 -283.019516) (xy 111.367826 -282.965818) (xy 111.361982 -282.937966) (xy 111.359442 -282.925774)
			(xy 111.343694 -282.905962) (xy 111.243618 -282.862528) (xy 111.218472 -282.86456) (xy 111.207804 -282.871164)
			(xy 111.184833 -282.885201) (xy 111.13576 -282.907332) (xy 111.084058 -282.922329) (xy 111.030759 -282.929892)
			(xy 111.003842 -282.930346) (xy 110.985823 -282.930129) (xy 110.949948 -282.926692) (xy 110.932214 -282.923488)
			(xy 110.922816 -282.92171) (xy 110.903766 -282.92552) (xy 110.828582 -282.973272) (xy 110.817152 -282.98902)
			(xy 110.814866 -282.998418) (xy 110.807467 -283.025462) (xy 110.785839 -283.07719) (xy 110.756877 -283.125197)
			(xy 110.721202 -283.168449) (xy 110.679583 -283.206017) (xy 110.632915 -283.237092) (xy 110.582203 -283.261004)
			(xy 110.528538 -283.277239) (xy 110.473075 -283.285448) (xy 110.445042 -283.285946) (xy 110.417792 -283.285406)
			(xy 110.363846 -283.277655) (xy 110.311552 -283.262307) (xy 110.261974 -283.239672) (xy 110.216123 -283.210212)
			(xy 110.17493 -283.174526) (xy 110.139236 -283.133341) (xy 110.109767 -283.087496) (xy 110.087121 -283.037923)
			(xy 110.071762 -282.985633) (xy 110.064 -282.931688) (xy 110.063534 -282.904438) (xy 105.682792 -282.904438)
			(xy 105.676558 -282.947795) (xy 105.661205 -283.000087) (xy 105.638565 -283.049662) (xy 105.609102 -283.09551)
			(xy 105.573413 -283.136699) (xy 105.532226 -283.17239) (xy 105.486379 -283.201856) (xy 105.436805 -283.224498)
			(xy 105.384514 -283.239854) (xy 105.33057 -283.247613) (xy 105.30332 -283.2481) (xy 105.27595 -283.247622)
			(xy 105.221772 -283.239807) (xy 105.169269 -283.224321) (xy 105.119522 -283.201482) (xy 105.073554 -283.17176)
			(xy 105.052622 -283.15412) (xy 105.04551 -283.148024) (xy 105.028492 -283.141674) (xy 104.943148 -283.141674)
			(xy 104.92613 -283.148024) (xy 104.919018 -283.15412) (xy 104.898093 -283.171767) (xy 104.852118 -283.201477)
			(xy 104.802368 -283.224311) (xy 104.749866 -283.2398) (xy 104.69569 -283.247627) (xy 104.66832 -283.2481)
			(xy 104.641066 -283.247654) (xy 104.587111 -283.239899) (xy 104.53481 -283.224545) (xy 104.485226 -283.201903)
			(xy 104.43937 -283.172435) (xy 104.398174 -283.13674) (xy 104.362477 -283.095546) (xy 104.333007 -283.049691)
			(xy 104.310362 -283.000109) (xy 104.295005 -282.947808) (xy 104.287247 -282.893854) (xy 103.957113 -282.893854)
			(xy 103.94936 -282.947788) (xy 103.934007 -283.000081) (xy 103.911368 -283.049657) (xy 103.881904 -283.095506)
			(xy 103.846216 -283.136696) (xy 103.805029 -283.172388) (xy 103.759181 -283.201855) (xy 103.709607 -283.224497)
			(xy 103.657315 -283.239854) (xy 103.60337 -283.247613) (xy 103.57612 -283.2481) (xy 103.549739 -283.247582)
			(xy 103.497478 -283.240334) (xy 103.446716 -283.225947) (xy 103.398425 -283.204695) (xy 103.353526 -283.176985)
			(xy 103.312879 -283.143347) (xy 103.27726 -283.104423) (xy 103.247351 -283.060959) (xy 103.223723 -283.013784)
			(xy 103.206829 -282.9638) (xy 103.20147 -282.937966) (xy 103.19893 -282.925774) (xy 103.183182 -282.905962)
			(xy 103.083106 -282.862528) (xy 103.05796 -282.86456) (xy 103.047292 -282.871164) (xy 103.024324 -282.885206)
			(xy 102.97525 -282.907336) (xy 102.923547 -282.922331) (xy 102.870247 -282.929892) (xy 102.84333 -282.930346)
			(xy 102.825311 -282.93013) (xy 102.789436 -282.926693) (xy 102.771702 -282.923488) (xy 102.762304 -282.92171)
			(xy 102.743254 -282.92552) (xy 102.66807 -282.973272) (xy 102.65664 -282.98902) (xy 102.654354 -282.998418)
			(xy 102.646966 -283.025465) (xy 102.625337 -283.077194) (xy 102.596373 -283.125201) (xy 102.560697 -283.168454)
			(xy 102.519077 -283.206022) (xy 102.472407 -283.237096) (xy 102.421694 -283.261007) (xy 102.368028 -283.277242)
			(xy 102.312564 -283.285449) (xy 102.28453 -283.285946) (xy 102.257281 -283.285394) (xy 102.203338 -283.277643)
			(xy 102.151047 -283.262293) (xy 102.101472 -283.239658) (xy 102.055624 -283.210199) (xy 102.014434 -283.174514)
			(xy 101.978742 -283.133331) (xy 101.949274 -283.087487) (xy 101.926631 -283.037917) (xy 101.911272 -282.985629)
			(xy 101.903511 -282.931687) (xy 101.903022 -282.904438) (xy 98.528886 -282.904438) (xy 97.25787 -284.175454)
			(xy 103.562656 -284.175454) (xy 103.566727 -284.119832) (xy 103.578853 -284.065395) (xy 103.598776 -284.013304)
			(xy 103.626072 -283.964669) (xy 103.660158 -283.920526) (xy 103.700307 -283.881817) (xy 103.745665 -283.849366)
			(xy 103.795265 -283.823865) (xy 103.848049 -283.805858) (xy 103.902892 -283.795728) (xy 103.958626 -283.793691)
			(xy 104.014063 -283.799791) (xy 104.06802 -283.813897) (xy 104.119349 -283.835709) (xy 104.166955 -283.864763)
			(xy 104.209823 -283.900438) (xy 104.24704 -283.941975) (xy 104.277813 -283.988488) (xy 104.301485 -284.038985)
			(xy 104.311594 -284.072584) (xy 109.213396 -284.072584) (xy 109.213854 -284.045213) (xy 109.221674 -283.991034)
			(xy 109.237165 -283.938531) (xy 109.260008 -283.888784) (xy 109.289734 -283.842818) (xy 109.307376 -283.821886)
			(xy 109.313472 -283.814774) (xy 109.319822 -283.797756) (xy 109.319822 -283.712412) (xy 109.313472 -283.695394)
			(xy 109.307376 -283.688282) (xy 109.289758 -283.667333) (xy 109.260044 -283.621364) (xy 109.237204 -283.571621)
			(xy 109.221708 -283.519124) (xy 109.213874 -283.464952) (xy 109.213396 -283.437584) (xy 109.213882 -283.410333)
			(xy 109.221638 -283.356385) (xy 109.236993 -283.30409) (xy 109.259635 -283.254513) (xy 109.289101 -283.208663)
			(xy 109.324792 -283.167472) (xy 109.365983 -283.131781) (xy 109.411833 -283.102315) (xy 109.46141 -283.079673)
			(xy 109.513705 -283.064318) (xy 109.567653 -283.056562) (xy 109.622155 -283.056562) (xy 109.676103 -283.064318)
			(xy 109.728398 -283.079673) (xy 109.777975 -283.102315) (xy 109.823825 -283.131781) (xy 109.865016 -283.167472)
			(xy 109.900707 -283.208663) (xy 109.930173 -283.254513) (xy 109.952815 -283.30409) (xy 109.96817 -283.356385)
			(xy 109.975926 -283.410333) (xy 109.976412 -283.437584) (xy 109.975934 -283.464954) (xy 109.968118 -283.519132)
			(xy 109.952632 -283.571635) (xy 109.929793 -283.621382) (xy 109.900072 -283.66735) (xy 109.882432 -283.688282)
			(xy 109.876336 -283.695394) (xy 109.869986 -283.712412) (xy 109.869986 -283.797756) (xy 109.876336 -283.814774)
			(xy 109.882432 -283.821886) (xy 109.900083 -283.842808) (xy 109.929792 -283.888784) (xy 109.952625 -283.938534)
			(xy 109.968113 -283.991037) (xy 109.975939 -284.045214) (xy 109.976412 -284.072584) (xy 109.975926 -284.099835)
			(xy 109.96817 -284.153783) (xy 109.952815 -284.206078) (xy 109.930173 -284.255655) (xy 109.900707 -284.301505)
			(xy 109.865016 -284.342696) (xy 109.823825 -284.378387) (xy 109.777975 -284.407853) (xy 109.728398 -284.430495)
			(xy 109.676103 -284.44585) (xy 109.622155 -284.453606) (xy 109.567653 -284.453606) (xy 109.513705 -284.44585)
			(xy 109.46141 -284.430495) (xy 109.411833 -284.407853) (xy 109.365983 -284.378387) (xy 109.324792 -284.342696)
			(xy 109.289101 -284.301505) (xy 109.259635 -284.255655) (xy 109.236993 -284.206078) (xy 109.221638 -284.153783)
			(xy 109.213882 -284.099835) (xy 109.213396 -284.072584) (xy 104.311594 -284.072584) (xy 104.317553 -284.092392)
			(xy 104.325673 -284.147568) (xy 104.326182 -284.175454) (xy 104.325673 -284.20334) (xy 104.317553 -284.258516)
			(xy 104.301485 -284.311923) (xy 104.277813 -284.36242) (xy 104.24704 -284.408933) (xy 104.209823 -284.45047)
			(xy 104.166955 -284.486145) (xy 104.119349 -284.515199) (xy 104.06802 -284.537011) (xy 104.014063 -284.551117)
			(xy 103.958626 -284.557217) (xy 103.902892 -284.55518) (xy 103.848049 -284.54505) (xy 103.795265 -284.527043)
			(xy 103.745665 -284.501542) (xy 103.700307 -284.469091) (xy 103.660158 -284.430382) (xy 103.626072 -284.386239)
			(xy 103.598776 -284.337604) (xy 103.578853 -284.285513) (xy 103.566727 -284.231076) (xy 103.562656 -284.175454)
			(xy 97.25787 -284.175454) (xy 96.17964 -285.253684) (xy 96.176213 -285.257306) (xy 96.170722 -285.265628)
			(xy 96.168718 -285.270194) (xy 95.42145 -287.074102) (xy 95.419674 -287.078729) (xy 95.417758 -287.088451)
			(xy 95.41764 -287.093406) (xy 95.41764 -287.419542) (xy 95.734632 -287.419542) (xy 95.735115 -287.392759)
			(xy 95.742629 -287.339723) (xy 95.757487 -287.288259) (xy 95.779397 -287.239379) (xy 95.807929 -287.194044)
			(xy 95.842521 -287.153145) (xy 95.882493 -287.117487) (xy 95.92706 -287.08777) (xy 95.975345 -287.064578)
			(xy 96.026399 -287.048368) (xy 96.079219 -287.039458) (xy 96.10598 -287.038288) (xy 96.12158 -287.037342)
			(xy 96.151087 -287.027075) (xy 96.17612 -287.008383) (xy 96.194346 -286.983009) (xy 96.204066 -286.953318)
			(xy 96.204786 -286.937704) (xy 96.205545 -286.910643) (xy 96.213772 -286.857137) (xy 96.229479 -286.805332)
			(xy 96.252351 -286.756266) (xy 96.281928 -286.710926) (xy 96.317618 -286.670222) (xy 96.358702 -286.634971)
			(xy 96.404357 -286.605881) (xy 96.453664 -286.583536) (xy 96.505636 -286.568386) (xy 96.559227 -286.560733)
			(xy 96.586294 -286.56026) (xy 96.613544 -286.560783) (xy 96.667488 -286.568538) (xy 96.71978 -286.583891)
			(xy 96.769356 -286.606529) (xy 96.815204 -286.635992) (xy 96.856394 -286.671679) (xy 96.892086 -286.712865)
			(xy 96.921553 -286.758711) (xy 96.935556 -286.789368) (xy 108.672374 -286.789368) (xy 108.676445 -286.733746)
			(xy 108.688571 -286.679309) (xy 108.708494 -286.627218) (xy 108.73579 -286.578583) (xy 108.769876 -286.53444)
			(xy 108.810025 -286.495731) (xy 108.855383 -286.46328) (xy 108.904983 -286.437779) (xy 108.957767 -286.419772)
			(xy 109.01261 -286.409642) (xy 109.068344 -286.407605) (xy 109.123781 -286.413705) (xy 109.177738 -286.427811)
			(xy 109.229067 -286.449623) (xy 109.276673 -286.478677) (xy 109.319541 -286.514352) (xy 109.356758 -286.555889)
			(xy 109.387531 -286.602402) (xy 109.411203 -286.652899) (xy 109.427271 -286.706306) (xy 109.429365 -286.720534)
			(xy 109.558834 -286.720534) (xy 109.562905 -286.664912) (xy 109.575031 -286.610475) (xy 109.594954 -286.558384)
			(xy 109.62225 -286.509749) (xy 109.656336 -286.465606) (xy 109.696485 -286.426897) (xy 109.741843 -286.394446)
			(xy 109.791443 -286.368945) (xy 109.844227 -286.350938) (xy 109.89907 -286.340808) (xy 109.954804 -286.338771)
			(xy 110.010241 -286.344871) (xy 110.064198 -286.358977) (xy 110.115527 -286.380789) (xy 110.163133 -286.409843)
			(xy 110.206001 -286.445518) (xy 110.243218 -286.487055) (xy 110.273991 -286.533568) (xy 110.297663 -286.584065)
			(xy 110.313731 -286.637472) (xy 110.321851 -286.692648) (xy 110.32236 -286.720534) (xy 110.321851 -286.74842)
			(xy 110.31575 -286.789876) (xy 125.407926 -286.789876) (xy 125.411997 -286.734254) (xy 125.424123 -286.679817)
			(xy 125.444046 -286.627726) (xy 125.471342 -286.579091) (xy 125.505428 -286.534948) (xy 125.545577 -286.496239)
			(xy 125.590935 -286.463788) (xy 125.640535 -286.438287) (xy 125.693319 -286.42028) (xy 125.748162 -286.41015)
			(xy 125.803896 -286.408113) (xy 125.859333 -286.414213) (xy 125.91329 -286.428319) (xy 125.964619 -286.450131)
			(xy 126.012225 -286.479185) (xy 126.055093 -286.51486) (xy 126.09231 -286.556397) (xy 126.123083 -286.60291)
			(xy 126.146755 -286.653407) (xy 126.162213 -286.704786) (xy 126.29464 -286.704786) (xy 126.298711 -286.649164)
			(xy 126.310837 -286.594727) (xy 126.33076 -286.542636) (xy 126.358056 -286.494001) (xy 126.392142 -286.449858)
			(xy 126.432291 -286.411149) (xy 126.477649 -286.378698) (xy 126.527249 -286.353197) (xy 126.580033 -286.33519)
			(xy 126.634876 -286.32506) (xy 126.69061 -286.323023) (xy 126.746047 -286.329123) (xy 126.800004 -286.343229)
			(xy 126.851333 -286.365041) (xy 126.898939 -286.394095) (xy 126.941807 -286.42977) (xy 126.979024 -286.471307)
			(xy 127.009797 -286.51782) (xy 127.033469 -286.568317) (xy 127.049537 -286.621724) (xy 127.057657 -286.6769)
			(xy 127.058166 -286.704786) (xy 127.057657 -286.732672) (xy 127.049537 -286.787848) (xy 127.033469 -286.841255)
			(xy 127.009797 -286.891752) (xy 126.979024 -286.938265) (xy 126.941807 -286.979802) (xy 126.898939 -287.015477)
			(xy 126.851333 -287.044531) (xy 126.800004 -287.066343) (xy 126.746047 -287.080449) (xy 126.69061 -287.086549)
			(xy 126.634876 -287.084512) (xy 126.580033 -287.074382) (xy 126.527249 -287.056375) (xy 126.477649 -287.030874)
			(xy 126.432291 -286.998423) (xy 126.392142 -286.959714) (xy 126.358056 -286.915571) (xy 126.33076 -286.866936)
			(xy 126.310837 -286.814845) (xy 126.298711 -286.760408) (xy 126.29464 -286.704786) (xy 126.162213 -286.704786)
			(xy 126.162823 -286.706814) (xy 126.170943 -286.76199) (xy 126.171452 -286.789876) (xy 126.170943 -286.817762)
			(xy 126.162823 -286.872938) (xy 126.146755 -286.926345) (xy 126.123083 -286.976842) (xy 126.09231 -287.023355)
			(xy 126.055093 -287.064892) (xy 126.012225 -287.100567) (xy 125.964619 -287.129621) (xy 125.91329 -287.151433)
			(xy 125.859333 -287.165539) (xy 125.803896 -287.171639) (xy 125.748162 -287.169602) (xy 125.693319 -287.159472)
			(xy 125.640535 -287.141465) (xy 125.590935 -287.115964) (xy 125.545577 -287.083513) (xy 125.505428 -287.044804)
			(xy 125.471342 -287.000661) (xy 125.444046 -286.952026) (xy 125.424123 -286.899935) (xy 125.411997 -286.845498)
			(xy 125.407926 -286.789876) (xy 110.31575 -286.789876) (xy 110.313731 -286.803596) (xy 110.297663 -286.857003)
			(xy 110.273991 -286.9075) (xy 110.243218 -286.954013) (xy 110.206001 -286.99555) (xy 110.163133 -287.031225)
			(xy 110.115527 -287.060279) (xy 110.064198 -287.082091) (xy 110.010241 -287.096197) (xy 109.954804 -287.102297)
			(xy 109.89907 -287.10026) (xy 109.844227 -287.09013) (xy 109.791443 -287.072123) (xy 109.741843 -287.046622)
			(xy 109.696485 -287.014171) (xy 109.656336 -286.975462) (xy 109.62225 -286.931319) (xy 109.594954 -286.882684)
			(xy 109.575031 -286.830593) (xy 109.562905 -286.776156) (xy 109.558834 -286.720534) (xy 109.429365 -286.720534)
			(xy 109.435391 -286.761482) (xy 109.4359 -286.789368) (xy 109.435391 -286.817254) (xy 109.427271 -286.87243)
			(xy 109.411203 -286.925837) (xy 109.387531 -286.976334) (xy 109.356758 -287.022847) (xy 109.319541 -287.064384)
			(xy 109.276673 -287.100059) (xy 109.229067 -287.129113) (xy 109.177738 -287.150925) (xy 109.123781 -287.165031)
			(xy 109.068344 -287.171131) (xy 109.01261 -287.169094) (xy 108.957767 -287.158964) (xy 108.904983 -287.140957)
			(xy 108.855383 -287.115456) (xy 108.810025 -287.083005) (xy 108.769876 -287.044296) (xy 108.73579 -287.000153)
			(xy 108.708494 -286.951518) (xy 108.688571 -286.899427) (xy 108.676445 -286.84499) (xy 108.672374 -286.789368)
			(xy 96.935556 -286.789368) (xy 96.944196 -286.808284) (xy 96.959554 -286.860574) (xy 96.967314 -286.914518)
			(xy 96.967802 -286.941768) (xy 96.967296 -286.96855) (xy 96.959781 -287.021583) (xy 96.944923 -287.073045)
			(xy 96.923014 -287.121923) (xy 96.894485 -287.167256) (xy 96.859895 -287.208154) (xy 96.819926 -287.243812)
			(xy 96.775363 -287.27353) (xy 96.727081 -287.296723) (xy 96.67603 -287.312936) (xy 96.623214 -287.32185)
			(xy 96.596454 -287.323022) (xy 96.580855 -287.323986) (xy 96.551348 -287.334246) (xy 96.526313 -287.352932)
			(xy 96.508086 -287.378303) (xy 96.498367 -287.407992) (xy 96.497648 -287.423606) (xy 96.496864 -287.450665)
			(xy 96.488637 -287.504168) (xy 96.472931 -287.555972) (xy 96.45006 -287.605035) (xy 96.420485 -287.650374)
			(xy 96.384798 -287.691077) (xy 96.343717 -287.726328) (xy 96.298066 -287.755418) (xy 96.248762 -287.777765)
			(xy 96.196794 -287.792918) (xy 96.143206 -287.800575) (xy 96.11614 -287.80105) (xy 96.088892 -287.800485)
			(xy 96.034949 -287.792735) (xy 95.982658 -287.777387) (xy 95.933084 -287.754753) (xy 95.887236 -287.725295)
			(xy 95.846046 -287.689612) (xy 95.810354 -287.64843) (xy 95.780886 -287.602588) (xy 95.758242 -287.553019)
			(xy 95.742883 -287.500731) (xy 95.735121 -287.44679) (xy 95.734632 -287.419542) (xy 95.41764 -287.419542)
			(xy 95.41764 -291.079682) (xy 95.417982 -291.08973) (xy 95.42559 -291.108327) (xy 95.432372 -291.11575)
			(xy 98.516328 -294.199564) (xy 110.64951 -294.199564) (xy 110.653581 -294.143942) (xy 110.665707 -294.089505)
			(xy 110.68563 -294.037414) (xy 110.712926 -293.988779) (xy 110.747012 -293.944636) (xy 110.787161 -293.905927)
			(xy 110.832519 -293.873476) (xy 110.882119 -293.847975) (xy 110.934903 -293.829968) (xy 110.989746 -293.819838)
			(xy 111.04548 -293.817801) (xy 111.100917 -293.823901) (xy 111.154874 -293.838007) (xy 111.206203 -293.859819)
			(xy 111.253809 -293.888873) (xy 111.296677 -293.924548) (xy 111.333894 -293.966085) (xy 111.364667 -294.012598)
			(xy 111.388339 -294.063095) (xy 111.404407 -294.116502) (xy 111.412527 -294.171678) (xy 111.41273 -294.1828)
			(xy 127.26873 -294.1828) (xy 127.272801 -294.127178) (xy 127.284927 -294.072741) (xy 127.30485 -294.02065)
			(xy 127.332146 -293.972015) (xy 127.366232 -293.927872) (xy 127.406381 -293.889163) (xy 127.451739 -293.856712)
			(xy 127.501339 -293.831211) (xy 127.554123 -293.813204) (xy 127.608966 -293.803074) (xy 127.6647 -293.801037)
			(xy 127.720137 -293.807137) (xy 127.774094 -293.821243) (xy 127.825423 -293.843055) (xy 127.873029 -293.872109)
			(xy 127.915897 -293.907784) (xy 127.953114 -293.949321) (xy 127.983887 -293.995834) (xy 128.007559 -294.046331)
			(xy 128.023627 -294.099738) (xy 128.031747 -294.154914) (xy 128.032256 -294.1828) (xy 128.031747 -294.210686)
			(xy 128.023627 -294.265862) (xy 128.007559 -294.319269) (xy 127.983887 -294.369766) (xy 127.953114 -294.416279)
			(xy 127.915897 -294.457816) (xy 127.873029 -294.493491) (xy 127.825423 -294.522545) (xy 127.774094 -294.544357)
			(xy 127.720137 -294.558463) (xy 127.6647 -294.564563) (xy 127.608966 -294.562526) (xy 127.554123 -294.552396)
			(xy 127.501339 -294.534389) (xy 127.451739 -294.508888) (xy 127.406381 -294.476437) (xy 127.366232 -294.437728)
			(xy 127.332146 -294.393585) (xy 127.30485 -294.34495) (xy 127.284927 -294.292859) (xy 127.272801 -294.238422)
			(xy 127.26873 -294.1828) (xy 111.41273 -294.1828) (xy 111.413036 -294.199564) (xy 111.412527 -294.22745)
			(xy 111.404407 -294.282626) (xy 111.388339 -294.336033) (xy 111.364667 -294.38653) (xy 111.333894 -294.433043)
			(xy 111.296677 -294.47458) (xy 111.253809 -294.510255) (xy 111.206203 -294.539309) (xy 111.154874 -294.561121)
			(xy 111.100917 -294.575227) (xy 111.04548 -294.581327) (xy 110.989746 -294.57929) (xy 110.934903 -294.56916)
			(xy 110.882119 -294.551153) (xy 110.832519 -294.525652) (xy 110.787161 -294.493201) (xy 110.747012 -294.454492)
			(xy 110.712926 -294.410349) (xy 110.68563 -294.361714) (xy 110.665707 -294.309623) (xy 110.653581 -294.255186)
			(xy 110.64951 -294.199564) (xy 98.516328 -294.199564) (xy 99.16863 -294.851836) (xy 102.046784 -294.851836)
			(xy 102.050855 -294.796214) (xy 102.062981 -294.741777) (xy 102.082904 -294.689686) (xy 102.1102 -294.641051)
			(xy 102.144286 -294.596908) (xy 102.184435 -294.558199) (xy 102.229793 -294.525748) (xy 102.279393 -294.500247)
			(xy 102.332177 -294.48224) (xy 102.38702 -294.47211) (xy 102.442754 -294.470073) (xy 102.498191 -294.476173)
			(xy 102.552148 -294.490279) (xy 102.603477 -294.512091) (xy 102.651083 -294.541145) (xy 102.693951 -294.57682)
			(xy 102.731168 -294.618357) (xy 102.761941 -294.66487) (xy 102.785613 -294.715367) (xy 102.801681 -294.768774)
			(xy 102.809801 -294.82395) (xy 102.81031 -294.851836) (xy 117.14048 -294.851836) (xy 117.144551 -294.796214)
			(xy 117.156677 -294.741777) (xy 117.1766 -294.689686) (xy 117.203896 -294.641051) (xy 117.237982 -294.596908)
			(xy 117.278131 -294.558199) (xy 117.323489 -294.525748) (xy 117.373089 -294.500247) (xy 117.425873 -294.48224)
			(xy 117.480716 -294.47211) (xy 117.53645 -294.470073) (xy 117.591887 -294.476173) (xy 117.645844 -294.490279)
			(xy 117.697173 -294.512091) (xy 117.744779 -294.541145) (xy 117.787647 -294.57682) (xy 117.824864 -294.618357)
			(xy 117.855637 -294.66487) (xy 117.879309 -294.715367) (xy 117.895377 -294.768774) (xy 117.903497 -294.82395)
			(xy 117.904006 -294.851836) (xy 118.705882 -294.851836) (xy 118.709953 -294.796214) (xy 118.722079 -294.741777)
			(xy 118.742002 -294.689686) (xy 118.769298 -294.641051) (xy 118.803384 -294.596908) (xy 118.843533 -294.558199)
			(xy 118.888891 -294.525748) (xy 118.938491 -294.500247) (xy 118.991275 -294.48224) (xy 119.046118 -294.47211)
			(xy 119.101852 -294.470073) (xy 119.157289 -294.476173) (xy 119.211246 -294.490279) (xy 119.262575 -294.512091)
			(xy 119.310181 -294.541145) (xy 119.353049 -294.57682) (xy 119.390266 -294.618357) (xy 119.421039 -294.66487)
			(xy 119.444711 -294.715367) (xy 119.460779 -294.768774) (xy 119.468899 -294.82395) (xy 119.469408 -294.851836)
			(xy 133.799578 -294.851836) (xy 133.803649 -294.796214) (xy 133.815775 -294.741777) (xy 133.835698 -294.689686)
			(xy 133.862994 -294.641051) (xy 133.89708 -294.596908) (xy 133.937229 -294.558199) (xy 133.982587 -294.525748)
			(xy 134.032187 -294.500247) (xy 134.084971 -294.48224) (xy 134.139814 -294.47211) (xy 134.195548 -294.470073)
			(xy 134.250985 -294.476173) (xy 134.304942 -294.490279) (xy 134.356271 -294.512091) (xy 134.403877 -294.541145)
			(xy 134.446745 -294.57682) (xy 134.483962 -294.618357) (xy 134.514735 -294.66487) (xy 134.538407 -294.715367)
			(xy 134.554475 -294.768774) (xy 134.562595 -294.82395) (xy 134.563104 -294.851836) (xy 134.562595 -294.879722)
			(xy 134.554475 -294.934898) (xy 134.538407 -294.988305) (xy 134.514735 -295.038802) (xy 134.483962 -295.085315)
			(xy 134.446745 -295.126852) (xy 134.403877 -295.162527) (xy 134.356271 -295.191581) (xy 134.304942 -295.213393)
			(xy 134.250985 -295.227499) (xy 134.195548 -295.233599) (xy 134.139814 -295.231562) (xy 134.084971 -295.221432)
			(xy 134.032187 -295.203425) (xy 133.982587 -295.177924) (xy 133.937229 -295.145473) (xy 133.89708 -295.106764)
			(xy 133.862994 -295.062621) (xy 133.835698 -295.013986) (xy 133.815775 -294.961895) (xy 133.803649 -294.907458)
			(xy 133.799578 -294.851836) (xy 119.469408 -294.851836) (xy 119.468899 -294.879722) (xy 119.460779 -294.934898)
			(xy 119.444711 -294.988305) (xy 119.421039 -295.038802) (xy 119.390266 -295.085315) (xy 119.353049 -295.126852)
			(xy 119.310181 -295.162527) (xy 119.262575 -295.191581) (xy 119.211246 -295.213393) (xy 119.157289 -295.227499)
			(xy 119.101852 -295.233599) (xy 119.046118 -295.231562) (xy 118.991275 -295.221432) (xy 118.938491 -295.203425)
			(xy 118.888891 -295.177924) (xy 118.843533 -295.145473) (xy 118.803384 -295.106764) (xy 118.769298 -295.062621)
			(xy 118.742002 -295.013986) (xy 118.722079 -294.961895) (xy 118.709953 -294.907458) (xy 118.705882 -294.851836)
			(xy 117.904006 -294.851836) (xy 117.903497 -294.879722) (xy 117.895377 -294.934898) (xy 117.879309 -294.988305)
			(xy 117.855637 -295.038802) (xy 117.824864 -295.085315) (xy 117.787647 -295.126852) (xy 117.744779 -295.162527)
			(xy 117.697173 -295.191581) (xy 117.645844 -295.213393) (xy 117.591887 -295.227499) (xy 117.53645 -295.233599)
			(xy 117.480716 -295.231562) (xy 117.425873 -295.221432) (xy 117.373089 -295.203425) (xy 117.323489 -295.177924)
			(xy 117.278131 -295.145473) (xy 117.237982 -295.106764) (xy 117.203896 -295.062621) (xy 117.1766 -295.013986)
			(xy 117.156677 -294.961895) (xy 117.144551 -294.907458) (xy 117.14048 -294.851836) (xy 102.81031 -294.851836)
			(xy 102.809801 -294.879722) (xy 102.801681 -294.934898) (xy 102.785613 -294.988305) (xy 102.761941 -295.038802)
			(xy 102.731168 -295.085315) (xy 102.693951 -295.126852) (xy 102.651083 -295.162527) (xy 102.603477 -295.191581)
			(xy 102.552148 -295.213393) (xy 102.498191 -295.227499) (xy 102.442754 -295.233599) (xy 102.38702 -295.231562)
			(xy 102.332177 -295.221432) (xy 102.279393 -295.203425) (xy 102.229793 -295.177924) (xy 102.184435 -295.145473)
			(xy 102.144286 -295.106764) (xy 102.1102 -295.062621) (xy 102.082904 -295.013986) (xy 102.062981 -294.961895)
			(xy 102.050855 -294.907458) (xy 102.046784 -294.851836) (xy 99.16863 -294.851836) (xy 100.944172 -296.627296)
			(xy 100.964987 -296.648881) (xy 101.000241 -296.697386) (xy 101.027469 -296.75081) (xy 101.046 -296.807838)
			(xy 101.055377 -296.867063) (xy 101.055932 -296.897044) (xy 101.055932 -298.420536) (xy 103.494586 -298.420536)
			(xy 103.495077 -298.393167) (xy 103.502889 -298.338989) (xy 103.518373 -298.286486) (xy 103.541209 -298.236739)
			(xy 103.570928 -298.190771) (xy 103.588566 -298.169838) (xy 103.594662 -298.162726) (xy 103.601012 -298.145708)
			(xy 103.601012 -298.060364) (xy 103.594662 -298.043346) (xy 103.588566 -298.036234) (xy 103.570959 -298.015273)
			(xy 103.54123 -297.969311) (xy 103.51838 -297.91957) (xy 103.502879 -297.867072) (xy 103.495046 -297.812896)
			(xy 103.495042 -297.758158) (xy 103.502868 -297.703981) (xy 103.518361 -297.651481) (xy 103.541204 -297.601736)
			(xy 103.570926 -297.55577) (xy 103.588566 -297.534838) (xy 103.594662 -297.527726) (xy 103.601012 -297.510708)
			(xy 103.601012 -297.425364) (xy 103.594662 -297.408346) (xy 103.588566 -297.401234) (xy 103.570959 -297.380273)
			(xy 103.54123 -297.334311) (xy 103.51838 -297.28457) (xy 103.502879 -297.232072) (xy 103.495046 -297.177896)
			(xy 103.495042 -297.123158) (xy 103.502868 -297.068981) (xy 103.518361 -297.016481) (xy 103.541204 -296.966736)
			(xy 103.570926 -296.92077) (xy 103.588566 -296.899838) (xy 103.594662 -296.892726) (xy 103.601012 -296.875708)
			(xy 103.601012 -296.790364) (xy 103.594662 -296.773346) (xy 103.588566 -296.766234) (xy 103.570959 -296.745273)
			(xy 103.54123 -296.699311) (xy 103.51838 -296.64957) (xy 103.502879 -296.597072) (xy 103.495046 -296.542896)
			(xy 103.495042 -296.488158) (xy 103.502868 -296.433981) (xy 103.518361 -296.381481) (xy 103.541204 -296.331736)
			(xy 103.570926 -296.28577) (xy 103.588566 -296.264838) (xy 103.594662 -296.257726) (xy 103.601012 -296.240708)
			(xy 103.601012 -296.155364) (xy 103.594662 -296.138346) (xy 103.588566 -296.131234) (xy 103.570959 -296.110273)
			(xy 103.54123 -296.064311) (xy 103.51838 -296.01457) (xy 103.502879 -295.962072) (xy 103.495046 -295.907896)
			(xy 103.495042 -295.853158) (xy 103.502868 -295.798981) (xy 103.518361 -295.746481) (xy 103.541204 -295.696736)
			(xy 103.570926 -295.65077) (xy 103.588566 -295.629838) (xy 103.594662 -295.622726) (xy 103.601012 -295.605708)
			(xy 103.601012 -295.520364) (xy 103.594662 -295.503346) (xy 103.588566 -295.496234) (xy 103.570924 -295.475304)
			(xy 103.541214 -295.42933) (xy 103.518379 -295.379582) (xy 103.502888 -295.327081) (xy 103.49506 -295.272905)
			(xy 103.494586 -295.245536) (xy 103.495089 -295.218284) (xy 103.502841 -295.164335) (xy 103.518192 -295.112038)
			(xy 103.54083 -295.062459) (xy 103.570293 -295.016606) (xy 103.605983 -294.975413) (xy 103.647172 -294.939719)
			(xy 103.693022 -294.91025) (xy 103.742599 -294.887607) (xy 103.794894 -294.87225) (xy 103.848842 -294.864492)
			(xy 103.876094 -294.864028) (xy 103.903464 -294.864491) (xy 103.957644 -294.872308) (xy 104.010147 -294.887798)
			(xy 104.059894 -294.91064) (xy 104.105861 -294.940366) (xy 104.126792 -294.958008) (xy 104.133904 -294.964104)
			(xy 104.150922 -294.970454) (xy 104.236266 -294.970454) (xy 104.253284 -294.964104) (xy 104.260396 -294.958008)
			(xy 104.28132 -294.940359) (xy 104.327295 -294.910648) (xy 104.377044 -294.887814) (xy 104.429547 -294.872325)
			(xy 104.483724 -294.8645) (xy 104.511094 -294.864028) (xy 104.538348 -294.864461) (xy 104.592302 -294.872218)
			(xy 104.644603 -294.887575) (xy 104.694185 -294.91022) (xy 104.74004 -294.93969) (xy 104.781234 -294.975387)
			(xy 104.816928 -295.016584) (xy 104.846395 -295.062441) (xy 104.869035 -295.112025) (xy 104.884388 -295.164327)
			(xy 104.892141 -295.218282) (xy 104.892602 -295.245536) (xy 104.892157 -295.272907) (xy 104.884334 -295.327087)
			(xy 104.86884 -295.37959) (xy 104.845993 -295.429337) (xy 104.816265 -295.475303) (xy 104.798622 -295.496234)
			(xy 104.792526 -295.503346) (xy 104.786176 -295.520364) (xy 104.786176 -295.605708) (xy 104.792526 -295.622726)
			(xy 104.798622 -295.629838) (xy 104.816296 -295.650743) (xy 104.846016 -295.696717) (xy 104.868856 -295.746468)
			(xy 104.884347 -295.798974) (xy 104.892171 -295.853155) (xy 104.892167 -295.907899) (xy 104.884336 -295.962079)
			(xy 104.868837 -296.014583) (xy 104.845989 -296.064331) (xy 104.816263 -296.1103) (xy 104.798622 -296.131234)
			(xy 104.792526 -296.138346) (xy 104.786176 -296.155364) (xy 104.786176 -296.240708) (xy 104.792526 -296.257726)
			(xy 104.798622 -296.264838) (xy 104.816296 -296.285743) (xy 104.846016 -296.331717) (xy 104.868856 -296.381468)
			(xy 104.884347 -296.433974) (xy 104.892171 -296.488155) (xy 104.892167 -296.542899) (xy 104.884336 -296.597079)
			(xy 104.868837 -296.649583) (xy 104.845989 -296.699331) (xy 104.816263 -296.7453) (xy 104.798622 -296.766234)
			(xy 104.792526 -296.773346) (xy 104.786176 -296.790364) (xy 104.786176 -296.875708) (xy 104.792526 -296.892726)
			(xy 104.798622 -296.899838) (xy 104.816296 -296.920743) (xy 104.846016 -296.966717) (xy 104.868856 -297.016468)
			(xy 104.884347 -297.068974) (xy 104.892171 -297.123155) (xy 104.892167 -297.177899) (xy 104.884336 -297.232079)
			(xy 104.868837 -297.284583) (xy 104.845989 -297.334331) (xy 104.816263 -297.3803) (xy 104.798622 -297.401234)
			(xy 104.792526 -297.408346) (xy 104.786176 -297.425364) (xy 104.786176 -297.510708) (xy 104.792526 -297.527726)
			(xy 104.798622 -297.534838) (xy 104.816296 -297.555743) (xy 104.846016 -297.601717) (xy 104.868856 -297.651468)
			(xy 104.884347 -297.703974) (xy 104.892171 -297.758155) (xy 104.892167 -297.812899) (xy 104.884336 -297.867079)
			(xy 104.868837 -297.919583) (xy 104.845989 -297.969331) (xy 104.816263 -298.0153) (xy 104.798622 -298.036234)
			(xy 104.792526 -298.043346) (xy 104.786176 -298.060364) (xy 104.786176 -298.145708) (xy 104.792526 -298.162726)
			(xy 104.798622 -298.169838) (xy 104.816249 -298.19078) (xy 104.845962 -298.23675) (xy 104.8688 -298.286495)
			(xy 104.884294 -298.338994) (xy 104.892126 -298.393168) (xy 104.892602 -298.420536) (xy 108.135166 -298.420536)
			(xy 108.135637 -298.393166) (xy 108.143451 -298.338986) (xy 108.158938 -298.286483) (xy 108.181779 -298.236736)
			(xy 108.211504 -298.190769) (xy 108.229146 -298.169838) (xy 108.235242 -298.162726) (xy 108.241592 -298.145708)
			(xy 108.241592 -298.060364) (xy 108.235242 -298.043346) (xy 108.229146 -298.036234) (xy 108.21154 -298.015273)
			(xy 108.181812 -297.969311) (xy 108.158963 -297.919569) (xy 108.143464 -297.867071) (xy 108.135631 -297.812896)
			(xy 108.135627 -297.758158) (xy 108.143452 -297.703982) (xy 108.158944 -297.651482) (xy 108.181786 -297.601737)
			(xy 108.211507 -297.55577) (xy 108.229146 -297.534838) (xy 108.235242 -297.527726) (xy 108.241592 -297.510708)
			(xy 108.241592 -297.425364) (xy 108.235242 -297.408346) (xy 108.229146 -297.401234) (xy 108.21154 -297.380273)
			(xy 108.181812 -297.334311) (xy 108.158963 -297.284569) (xy 108.143464 -297.232071) (xy 108.135631 -297.177896)
			(xy 108.135627 -297.123158) (xy 108.143452 -297.068982) (xy 108.158944 -297.016482) (xy 108.181786 -296.966737)
			(xy 108.211507 -296.92077) (xy 108.229146 -296.899838) (xy 108.235242 -296.892726) (xy 108.241592 -296.875708)
			(xy 108.241592 -296.790364) (xy 108.235242 -296.773346) (xy 108.229146 -296.766234) (xy 108.21154 -296.745273)
			(xy 108.181812 -296.699311) (xy 108.158963 -296.649569) (xy 108.143464 -296.597071) (xy 108.135631 -296.542896)
			(xy 108.135627 -296.488158) (xy 108.143452 -296.433982) (xy 108.158944 -296.381482) (xy 108.181786 -296.331737)
			(xy 108.211507 -296.28577) (xy 108.229146 -296.264838) (xy 108.235242 -296.257726) (xy 108.241592 -296.240708)
			(xy 108.241592 -296.155364) (xy 108.235242 -296.138346) (xy 108.229146 -296.131234) (xy 108.21154 -296.110273)
			(xy 108.181812 -296.064311) (xy 108.158963 -296.014569) (xy 108.143464 -295.962071) (xy 108.135631 -295.907896)
			(xy 108.135627 -295.853158) (xy 108.143452 -295.798982) (xy 108.158944 -295.746482) (xy 108.181786 -295.696737)
			(xy 108.211507 -295.65077) (xy 108.229146 -295.629838) (xy 108.235242 -295.622726) (xy 108.241592 -295.605708)
			(xy 108.241592 -295.520364) (xy 108.235242 -295.503346) (xy 108.229146 -295.496234) (xy 108.211517 -295.475294)
			(xy 108.181802 -295.429324) (xy 108.158963 -295.379579) (xy 108.14347 -295.327079) (xy 108.13564 -295.272905)
			(xy 108.135166 -295.245536) (xy 108.135689 -295.218285) (xy 108.14344 -295.164338) (xy 108.15879 -295.112043)
			(xy 108.181427 -295.062464) (xy 108.210889 -295.016612) (xy 108.246576 -294.97542) (xy 108.287763 -294.939726)
			(xy 108.33361 -294.910256) (xy 108.383184 -294.887612) (xy 108.435477 -294.872253) (xy 108.489423 -294.864493)
			(xy 108.516674 -294.864028) (xy 108.544044 -294.864502) (xy 108.598223 -294.872317) (xy 108.650726 -294.887804)
			(xy 108.700473 -294.910644) (xy 108.74644 -294.940367) (xy 108.767372 -294.958008) (xy 108.774484 -294.964104)
			(xy 108.791502 -294.970454) (xy 108.876846 -294.970454) (xy 108.893864 -294.964104) (xy 108.900976 -294.958008)
			(xy 108.921907 -294.940368) (xy 108.96788 -294.910656) (xy 109.017628 -294.88782) (xy 109.070129 -294.872329)
			(xy 109.124305 -294.864502) (xy 109.151674 -294.864028) (xy 109.178928 -294.86448) (xy 109.232881 -294.872234)
			(xy 109.285181 -294.887589) (xy 109.334764 -294.910231) (xy 109.380619 -294.939699) (xy 109.421813 -294.975394)
			(xy 109.457507 -295.016589) (xy 109.486974 -295.062445) (xy 109.509615 -295.112028) (xy 109.524968 -295.164329)
			(xy 109.532721 -295.218282) (xy 109.533182 -295.245536) (xy 109.532741 -295.272907) (xy 109.524918 -295.327088)
			(xy 109.509423 -295.379591) (xy 109.486576 -295.429338) (xy 109.456846 -295.475303) (xy 109.439202 -295.496234)
			(xy 109.433106 -295.503346) (xy 109.426756 -295.520364) (xy 109.426756 -295.605708) (xy 109.433106 -295.622726)
			(xy 109.439202 -295.629838) (xy 109.456877 -295.650743) (xy 109.486598 -295.696716) (xy 109.509439 -295.746467)
			(xy 109.524932 -295.798973) (xy 109.532756 -295.853155) (xy 109.532752 -295.907899) (xy 109.52492 -295.96208)
			(xy 109.50942 -296.014584) (xy 109.486572 -296.064331) (xy 109.456844 -296.110301) (xy 109.439202 -296.131234)
			(xy 109.433106 -296.138346) (xy 109.426756 -296.155364) (xy 109.426756 -296.240708) (xy 109.433106 -296.257726)
			(xy 109.439202 -296.264838) (xy 109.456877 -296.285743) (xy 109.486598 -296.331716) (xy 109.509439 -296.381467)
			(xy 109.524932 -296.433973) (xy 109.532756 -296.488155) (xy 109.532752 -296.542899) (xy 109.52492 -296.59708)
			(xy 109.50942 -296.649584) (xy 109.486572 -296.699331) (xy 109.456844 -296.745301) (xy 109.439202 -296.766234)
			(xy 109.433106 -296.773346) (xy 109.426756 -296.790364) (xy 109.426756 -296.875708) (xy 109.433106 -296.892726)
			(xy 109.439202 -296.899838) (xy 109.456877 -296.920743) (xy 109.486598 -296.966716) (xy 109.509439 -297.016467)
			(xy 109.524932 -297.068973) (xy 109.532756 -297.123155) (xy 109.532752 -297.177899) (xy 109.52492 -297.23208)
			(xy 109.50942 -297.284584) (xy 109.486572 -297.334331) (xy 109.456844 -297.380301) (xy 109.439202 -297.401234)
			(xy 109.433106 -297.408346) (xy 109.426756 -297.425364) (xy 109.426756 -297.510708) (xy 109.433106 -297.527726)
			(xy 109.439202 -297.534838) (xy 109.456877 -297.555743) (xy 109.486598 -297.601716) (xy 109.509439 -297.651467)
			(xy 109.524932 -297.703973) (xy 109.532756 -297.758155) (xy 109.532752 -297.812899) (xy 109.52492 -297.86708)
			(xy 109.50942 -297.919584) (xy 109.486572 -297.969331) (xy 109.456844 -298.015301) (xy 109.439202 -298.036234)
			(xy 109.433106 -298.043346) (xy 109.426756 -298.060364) (xy 109.426756 -298.145708) (xy 109.433106 -298.162726)
			(xy 109.439202 -298.169838) (xy 109.456826 -298.190782) (xy 109.48654 -298.236752) (xy 109.509379 -298.286496)
			(xy 109.524873 -298.338994) (xy 109.532706 -298.393168) (xy 109.533182 -298.420536) (xy 110.562898 -298.420536)
			(xy 110.563386 -298.393167) (xy 110.571198 -298.338988) (xy 110.586682 -298.286486) (xy 110.609519 -298.236738)
			(xy 110.639239 -298.19077) (xy 110.656878 -298.169838) (xy 110.662974 -298.162726) (xy 110.669324 -298.145708)
			(xy 110.669324 -298.060364) (xy 110.662974 -298.043346) (xy 110.656878 -298.036234) (xy 110.639275 -298.015272)
			(xy 110.609552 -297.969308) (xy 110.586708 -297.919566) (xy 110.571211 -297.867069) (xy 110.56338 -297.812895)
			(xy 110.563376 -297.758159) (xy 110.571199 -297.703984) (xy 110.586689 -297.651485) (xy 110.609526 -297.60174)
			(xy 110.639242 -297.555772) (xy 110.656878 -297.534838) (xy 110.662974 -297.527726) (xy 110.669324 -297.510708)
			(xy 110.669324 -297.425364) (xy 110.662974 -297.408346) (xy 110.656878 -297.401234) (xy 110.639275 -297.380272)
			(xy 110.609552 -297.334308) (xy 110.586708 -297.284566) (xy 110.571211 -297.232069) (xy 110.56338 -297.177895)
			(xy 110.563376 -297.123159) (xy 110.571199 -297.068984) (xy 110.586689 -297.016485) (xy 110.609526 -296.96674)
			(xy 110.639242 -296.920772) (xy 110.656878 -296.899838) (xy 110.662974 -296.892726) (xy 110.669324 -296.875708)
			(xy 110.669324 -296.790364) (xy 110.662974 -296.773346) (xy 110.656878 -296.766234) (xy 110.639275 -296.745272)
			(xy 110.609552 -296.699308) (xy 110.586708 -296.649566) (xy 110.571211 -296.597069) (xy 110.56338 -296.542895)
			(xy 110.563376 -296.488159) (xy 110.571199 -296.433984) (xy 110.586689 -296.381485) (xy 110.609526 -296.33174)
			(xy 110.639242 -296.285772) (xy 110.656878 -296.264838) (xy 110.662974 -296.257726) (xy 110.669324 -296.240708)
			(xy 110.669324 -296.155364) (xy 110.662974 -296.138346) (xy 110.656878 -296.131234) (xy 110.639275 -296.110272)
			(xy 110.609552 -296.064308) (xy 110.586708 -296.014566) (xy 110.571211 -295.962069) (xy 110.56338 -295.907895)
			(xy 110.563376 -295.853159) (xy 110.571199 -295.798984) (xy 110.586689 -295.746485) (xy 110.609526 -295.69674)
			(xy 110.639242 -295.650772) (xy 110.656878 -295.629838) (xy 110.662974 -295.622726) (xy 110.669324 -295.605708)
			(xy 110.669324 -295.520364) (xy 110.662974 -295.503346) (xy 110.656878 -295.496234) (xy 110.639238 -295.475303)
			(xy 110.609527 -295.429329) (xy 110.586692 -295.379582) (xy 110.571201 -295.327081) (xy 110.563372 -295.272905)
			(xy 110.562898 -295.245536) (xy 110.563389 -295.218284) (xy 110.571141 -295.164334) (xy 110.586493 -295.112036)
			(xy 110.609132 -295.062455) (xy 110.638596 -295.016602) (xy 110.674287 -294.975409) (xy 110.715478 -294.939714)
			(xy 110.761329 -294.910246) (xy 110.810908 -294.887603) (xy 110.863204 -294.872247) (xy 110.917154 -294.864491)
			(xy 110.944406 -294.864028) (xy 110.971777 -294.864484) (xy 111.025956 -294.872303) (xy 111.07846 -294.887794)
			(xy 111.128207 -294.910638) (xy 111.174173 -294.940365) (xy 111.195104 -294.958008) (xy 111.202216 -294.964104)
			(xy 111.219234 -294.970454) (xy 111.304578 -294.970454) (xy 111.321596 -294.964104) (xy 111.328708 -294.958008)
			(xy 111.349627 -294.940353) (xy 111.395603 -294.910643) (xy 111.445354 -294.88781) (xy 111.497858 -294.872323)
			(xy 111.552036 -294.864499) (xy 111.579406 -294.864028) (xy 111.606661 -294.86445) (xy 111.660615 -294.872209)
			(xy 111.712916 -294.887567) (xy 111.762498 -294.910213) (xy 111.808353 -294.939685) (xy 111.849547 -294.975383)
			(xy 111.88524 -295.016581) (xy 111.914707 -295.062439) (xy 111.937347 -295.112024) (xy 111.9527 -295.164326)
			(xy 111.960453 -295.218281) (xy 111.960914 -295.245536) (xy 111.960466 -295.272907) (xy 111.952643 -295.327087)
			(xy 111.93715 -295.37959) (xy 111.914304 -295.429336) (xy 111.884576 -295.475303) (xy 111.866934 -295.496234)
			(xy 111.860838 -295.503346) (xy 111.854488 -295.520364) (xy 111.854488 -295.605708) (xy 111.860838 -295.622726)
			(xy 111.866934 -295.629838) (xy 111.884612 -295.650741) (xy 111.914338 -295.696713) (xy 111.937184 -295.746464)
			(xy 111.952679 -295.798971) (xy 111.960505 -295.853154) (xy 111.960501 -295.9079) (xy 111.952667 -295.962082)
			(xy 111.937164 -296.014587) (xy 111.914312 -296.064334) (xy 111.884579 -296.110302) (xy 111.866934 -296.131234)
			(xy 111.860838 -296.138346) (xy 111.854488 -296.155364) (xy 111.854488 -296.240708) (xy 111.860838 -296.257726)
			(xy 111.866934 -296.264838) (xy 111.884612 -296.285741) (xy 111.914338 -296.331713) (xy 111.937184 -296.381464)
			(xy 111.952679 -296.433971) (xy 111.960505 -296.488154) (xy 111.960501 -296.5429) (xy 111.952667 -296.597082)
			(xy 111.937164 -296.649587) (xy 111.914312 -296.699334) (xy 111.884579 -296.745302) (xy 111.866934 -296.766234)
			(xy 111.860838 -296.773346) (xy 111.854488 -296.790364) (xy 111.854488 -296.875708) (xy 111.860838 -296.892726)
			(xy 111.866934 -296.899838) (xy 111.884612 -296.920741) (xy 111.914338 -296.966713) (xy 111.937184 -297.016464)
			(xy 111.952679 -297.068971) (xy 111.960505 -297.123154) (xy 111.960501 -297.1779) (xy 111.952667 -297.232082)
			(xy 111.937164 -297.284587) (xy 111.914312 -297.334334) (xy 111.884579 -297.380302) (xy 111.866934 -297.401234)
			(xy 111.860838 -297.408346) (xy 111.854488 -297.425364) (xy 111.854488 -297.510708) (xy 111.860838 -297.527726)
			(xy 111.866934 -297.534838) (xy 111.884612 -297.555741) (xy 111.914338 -297.601713) (xy 111.937184 -297.651464)
			(xy 111.952679 -297.703971) (xy 111.960505 -297.758154) (xy 111.960501 -297.8129) (xy 111.952667 -297.867082)
			(xy 111.937164 -297.919587) (xy 111.914312 -297.969334) (xy 111.884579 -298.015302) (xy 111.866934 -298.036234)
			(xy 111.860838 -298.043346) (xy 111.854488 -298.060364) (xy 111.854488 -298.145708) (xy 111.860838 -298.162726)
			(xy 111.866934 -298.169838) (xy 111.884563 -298.190778) (xy 111.914275 -298.236749) (xy 111.937112 -298.286495)
			(xy 111.952606 -298.338993) (xy 111.960438 -298.393167) (xy 111.960914 -298.420536) (xy 115.203478 -298.420536)
			(xy 115.203946 -298.393166) (xy 115.211761 -298.338986) (xy 115.227248 -298.286482) (xy 115.25009 -298.236735)
			(xy 115.279816 -298.190769) (xy 115.297458 -298.169838) (xy 115.303554 -298.162726) (xy 115.309904 -298.145708)
			(xy 115.309904 -298.060364) (xy 115.303554 -298.043346) (xy 115.297458 -298.036234) (xy 115.279851 -298.015273)
			(xy 115.250123 -297.969311) (xy 115.227273 -297.91957) (xy 115.211773 -297.867072) (xy 115.20394 -297.812896)
			(xy 115.203936 -297.758158) (xy 115.211761 -297.703981) (xy 115.227254 -297.651481) (xy 115.250097 -297.601736)
			(xy 115.279819 -297.55577) (xy 115.297458 -297.534838) (xy 115.303554 -297.527726) (xy 115.309904 -297.510708)
			(xy 115.309904 -297.425364) (xy 115.303554 -297.408346) (xy 115.297458 -297.401234) (xy 115.279851 -297.380273)
			(xy 115.250123 -297.334311) (xy 115.227273 -297.28457) (xy 115.211773 -297.232072) (xy 115.20394 -297.177896)
			(xy 115.203936 -297.123158) (xy 115.211761 -297.068981) (xy 115.227254 -297.016481) (xy 115.250097 -296.966736)
			(xy 115.279819 -296.92077) (xy 115.297458 -296.899838) (xy 115.303554 -296.892726) (xy 115.309904 -296.875708)
			(xy 115.309904 -296.790364) (xy 115.303554 -296.773346) (xy 115.297458 -296.766234) (xy 115.279851 -296.745273)
			(xy 115.250123 -296.699311) (xy 115.227273 -296.64957) (xy 115.211773 -296.597072) (xy 115.20394 -296.542896)
			(xy 115.203936 -296.488158) (xy 115.211761 -296.433981) (xy 115.227254 -296.381481) (xy 115.250097 -296.331736)
			(xy 115.279819 -296.28577) (xy 115.297458 -296.264838) (xy 115.303554 -296.257726) (xy 115.309904 -296.240708)
			(xy 115.309904 -296.155364) (xy 115.303554 -296.138346) (xy 115.297458 -296.131234) (xy 115.279851 -296.110273)
			(xy 115.250123 -296.064311) (xy 115.227273 -296.01457) (xy 115.211773 -295.962072) (xy 115.20394 -295.907896)
			(xy 115.203936 -295.853158) (xy 115.211761 -295.798981) (xy 115.227254 -295.746481) (xy 115.250097 -295.696736)
			(xy 115.279819 -295.65077) (xy 115.297458 -295.629838) (xy 115.303554 -295.622726) (xy 115.309904 -295.605708)
			(xy 115.309904 -295.520364) (xy 115.303554 -295.503346) (xy 115.297458 -295.496234) (xy 115.279814 -295.475306)
			(xy 115.250105 -295.429331) (xy 115.22727 -295.379583) (xy 115.21178 -295.327081) (xy 115.203952 -295.272905)
			(xy 115.203478 -295.245536) (xy 115.203989 -295.218285) (xy 115.21174 -295.164336) (xy 115.227091 -295.11204)
			(xy 115.249729 -295.062461) (xy 115.279191 -295.016608) (xy 115.31488 -294.975416) (xy 115.356068 -294.939721)
			(xy 115.401917 -294.910253) (xy 115.451493 -294.887609) (xy 115.503787 -294.872251) (xy 115.557735 -294.864492)
			(xy 115.584986 -294.864028) (xy 115.612356 -294.864495) (xy 115.666536 -294.872312) (xy 115.719039 -294.8878)
			(xy 115.768786 -294.910642) (xy 115.814752 -294.940367) (xy 115.835684 -294.958008) (xy 115.842796 -294.964104)
			(xy 115.859814 -294.970454) (xy 115.945158 -294.970454) (xy 115.962176 -294.964104) (xy 115.969288 -294.958008)
			(xy 115.990215 -294.940362) (xy 116.036189 -294.910651) (xy 116.085938 -294.887816) (xy 116.13844 -294.872327)
			(xy 116.192616 -294.864501) (xy 116.219986 -294.864028) (xy 116.24724 -294.864468) (xy 116.301194 -294.872224)
			(xy 116.353494 -294.887581) (xy 116.403077 -294.910224) (xy 116.448932 -294.939694) (xy 116.490125 -294.97539)
			(xy 116.525819 -295.016586) (xy 116.555287 -295.062443) (xy 116.577927 -295.112026) (xy 116.59328 -295.164328)
			(xy 116.601033 -295.218282) (xy 116.601494 -295.245536) (xy 116.60105 -295.272907) (xy 116.593227 -295.327087)
			(xy 116.577733 -295.379591) (xy 116.554886 -295.429337) (xy 116.525157 -295.475303) (xy 116.507514 -295.496234)
			(xy 116.501418 -295.503346) (xy 116.495068 -295.520364) (xy 116.495068 -295.605708) (xy 116.501418 -295.622726)
			(xy 116.507514 -295.629838) (xy 116.525188 -295.650743) (xy 116.554908 -295.696717) (xy 116.577749 -295.746468)
			(xy 116.593241 -295.798974) (xy 116.601065 -295.853155) (xy 116.601061 -295.907899) (xy 116.593229 -295.962079)
			(xy 116.57773 -296.014583) (xy 116.554882 -296.064331) (xy 116.525156 -296.1103) (xy 116.507514 -296.131234)
			(xy 116.501418 -296.138346) (xy 116.495068 -296.155364) (xy 116.495068 -296.240708) (xy 116.501418 -296.257726)
			(xy 116.507514 -296.264838) (xy 116.525188 -296.285743) (xy 116.554908 -296.331717) (xy 116.577749 -296.381468)
			(xy 116.593241 -296.433974) (xy 116.601065 -296.488155) (xy 116.601061 -296.542899) (xy 116.593229 -296.597079)
			(xy 116.57773 -296.649583) (xy 116.554882 -296.699331) (xy 116.525156 -296.7453) (xy 116.507514 -296.766234)
			(xy 116.501418 -296.773346) (xy 116.495068 -296.790364) (xy 116.495068 -296.875708) (xy 116.501418 -296.892726)
			(xy 116.507514 -296.899838) (xy 116.525188 -296.920743) (xy 116.554908 -296.966717) (xy 116.577749 -297.016468)
			(xy 116.593241 -297.068974) (xy 116.601065 -297.123155) (xy 116.601061 -297.177899) (xy 116.593229 -297.232079)
			(xy 116.57773 -297.284583) (xy 116.554882 -297.334331) (xy 116.525156 -297.3803) (xy 116.507514 -297.401234)
			(xy 116.501418 -297.408346) (xy 116.495068 -297.425364) (xy 116.495068 -297.510708) (xy 116.501418 -297.527726)
			(xy 116.507514 -297.534838) (xy 116.525188 -297.555743) (xy 116.554908 -297.601717) (xy 116.577749 -297.651468)
			(xy 116.593241 -297.703974) (xy 116.601065 -297.758155) (xy 116.601061 -297.812899) (xy 116.593229 -297.867079)
			(xy 116.57773 -297.919583) (xy 116.554882 -297.969331) (xy 116.525156 -298.0153) (xy 116.507514 -298.036234)
			(xy 116.501418 -298.043346) (xy 116.495068 -298.060364) (xy 116.495068 -298.145708) (xy 116.501418 -298.162726)
			(xy 116.507514 -298.169838) (xy 116.52514 -298.190781) (xy 116.554853 -298.236751) (xy 116.577691 -298.286496)
			(xy 116.593186 -298.338994) (xy 116.601018 -298.393168) (xy 116.601494 -298.420536) (xy 120.153684 -298.420536)
			(xy 120.154151 -298.393166) (xy 120.161965 -298.338986) (xy 120.177453 -298.286482) (xy 120.200295 -298.236735)
			(xy 120.230021 -298.190769) (xy 120.247664 -298.169838) (xy 120.25376 -298.162726) (xy 120.26011 -298.145708)
			(xy 120.26011 -298.060364) (xy 120.25376 -298.043346) (xy 120.247664 -298.036234) (xy 120.230057 -298.015273)
			(xy 120.200328 -297.969311) (xy 120.177478 -297.91957) (xy 120.161978 -297.867072) (xy 120.154145 -297.812896)
			(xy 120.154141 -297.758158) (xy 120.161966 -297.703981) (xy 120.177459 -297.651481) (xy 120.200302 -297.601736)
			(xy 120.230024 -297.55577) (xy 120.247664 -297.534838) (xy 120.25376 -297.527726) (xy 120.26011 -297.510708)
			(xy 120.26011 -297.425364) (xy 120.25376 -297.408346) (xy 120.247664 -297.401234) (xy 120.230057 -297.380273)
			(xy 120.200328 -297.334311) (xy 120.177478 -297.28457) (xy 120.161978 -297.232072) (xy 120.154145 -297.177896)
			(xy 120.154141 -297.123158) (xy 120.161966 -297.068981) (xy 120.177459 -297.016481) (xy 120.200302 -296.966736)
			(xy 120.230024 -296.92077) (xy 120.247664 -296.899838) (xy 120.25376 -296.892726) (xy 120.26011 -296.875708)
			(xy 120.26011 -296.790364) (xy 120.25376 -296.773346) (xy 120.247664 -296.766234) (xy 120.230057 -296.745273)
			(xy 120.200328 -296.699311) (xy 120.177478 -296.64957) (xy 120.161978 -296.597072) (xy 120.154145 -296.542896)
			(xy 120.154141 -296.488158) (xy 120.161966 -296.433981) (xy 120.177459 -296.381481) (xy 120.200302 -296.331736)
			(xy 120.230024 -296.28577) (xy 120.247664 -296.264838) (xy 120.25376 -296.257726) (xy 120.26011 -296.240708)
			(xy 120.26011 -296.155364) (xy 120.25376 -296.138346) (xy 120.247664 -296.131234) (xy 120.230057 -296.110273)
			(xy 120.200328 -296.064311) (xy 120.177478 -296.01457) (xy 120.161978 -295.962072) (xy 120.154145 -295.907896)
			(xy 120.154141 -295.853158) (xy 120.161966 -295.798981) (xy 120.177459 -295.746481) (xy 120.200302 -295.696736)
			(xy 120.230024 -295.65077) (xy 120.247664 -295.629838) (xy 120.25376 -295.622726) (xy 120.26011 -295.605708)
			(xy 120.26011 -295.520364) (xy 120.25376 -295.503346) (xy 120.247664 -295.496234) (xy 120.230022 -295.475305)
			(xy 120.200312 -295.42933) (xy 120.177477 -295.379582) (xy 120.161986 -295.327081) (xy 120.154158 -295.272905)
			(xy 120.153684 -295.245536) (xy 120.154189 -295.218284) (xy 120.161941 -295.164335) (xy 120.177292 -295.112039)
			(xy 120.199929 -295.062459) (xy 120.229393 -295.016606) (xy 120.265082 -294.975414) (xy 120.306271 -294.939719)
			(xy 120.352121 -294.910251) (xy 120.401697 -294.887607) (xy 120.453992 -294.87225) (xy 120.50794 -294.864492)
			(xy 120.535192 -294.864028) (xy 120.562562 -294.864492) (xy 120.616742 -294.872309) (xy 120.669245 -294.887798)
			(xy 120.718992 -294.910641) (xy 120.764959 -294.940366) (xy 120.78589 -294.958008) (xy 120.793002 -294.964104)
			(xy 120.81002 -294.970454) (xy 120.895364 -294.970454) (xy 120.912382 -294.964104) (xy 120.919494 -294.958008)
			(xy 120.940419 -294.94036) (xy 120.986393 -294.910649) (xy 121.036143 -294.887815) (xy 121.088645 -294.872326)
			(xy 121.142822 -294.8645) (xy 121.170192 -294.864028) (xy 121.197446 -294.864463) (xy 121.2514 -294.87222)
			(xy 121.303701 -294.887577) (xy 121.353283 -294.910221) (xy 121.399138 -294.939691) (xy 121.440332 -294.975388)
			(xy 121.476026 -295.016584) (xy 121.505493 -295.062441) (xy 121.528133 -295.112026) (xy 121.543486 -295.164327)
			(xy 121.551239 -295.218282) (xy 121.5517 -295.245536) (xy 121.551255 -295.272907) (xy 121.543432 -295.327087)
			(xy 121.527938 -295.37959) (xy 121.505092 -295.429337) (xy 121.475363 -295.475303) (xy 121.45772 -295.496234)
			(xy 121.451624 -295.503346) (xy 121.445274 -295.520364) (xy 121.445274 -295.605708) (xy 121.451624 -295.622726)
			(xy 121.45772 -295.629838) (xy 121.475394 -295.650743) (xy 121.505114 -295.696717) (xy 121.527954 -295.746468)
			(xy 121.543446 -295.798974) (xy 121.55127 -295.853155) (xy 121.551266 -295.907899) (xy 121.543434 -295.962079)
			(xy 121.527935 -296.014583) (xy 121.505088 -296.064331) (xy 121.475361 -296.1103) (xy 121.45772 -296.131234)
			(xy 121.451624 -296.138346) (xy 121.445274 -296.155364) (xy 121.445274 -296.240708) (xy 121.451624 -296.257726)
			(xy 121.45772 -296.264838) (xy 121.475394 -296.285743) (xy 121.505114 -296.331717) (xy 121.527954 -296.381468)
			(xy 121.543446 -296.433974) (xy 121.55127 -296.488155) (xy 121.551266 -296.542899) (xy 121.543434 -296.597079)
			(xy 121.527935 -296.649583) (xy 121.505088 -296.699331) (xy 121.475361 -296.7453) (xy 121.45772 -296.766234)
			(xy 121.451624 -296.773346) (xy 121.445274 -296.790364) (xy 121.445274 -296.875708) (xy 121.451624 -296.892726)
			(xy 121.45772 -296.899838) (xy 121.475394 -296.920743) (xy 121.505114 -296.966717) (xy 121.527954 -297.016468)
			(xy 121.543446 -297.068974) (xy 121.55127 -297.123155) (xy 121.551266 -297.177899) (xy 121.543434 -297.232079)
			(xy 121.527935 -297.284583) (xy 121.505088 -297.334331) (xy 121.475361 -297.3803) (xy 121.45772 -297.401234)
			(xy 121.451624 -297.408346) (xy 121.445274 -297.425364) (xy 121.445274 -297.510708) (xy 121.451624 -297.527726)
			(xy 121.45772 -297.534838) (xy 121.475394 -297.555743) (xy 121.505114 -297.601717) (xy 121.527954 -297.651468)
			(xy 121.543446 -297.703974) (xy 121.55127 -297.758155) (xy 121.551266 -297.812899) (xy 121.543434 -297.867079)
			(xy 121.527935 -297.919583) (xy 121.505088 -297.969331) (xy 121.475361 -298.0153) (xy 121.45772 -298.036234)
			(xy 121.451624 -298.043346) (xy 121.445274 -298.060364) (xy 121.445274 -298.145708) (xy 121.451624 -298.162726)
			(xy 121.45772 -298.169838) (xy 121.475347 -298.19078) (xy 121.50506 -298.23675) (xy 121.527898 -298.286495)
			(xy 121.543392 -298.338994) (xy 121.551224 -298.393168) (xy 121.5517 -298.420536) (xy 124.794264 -298.420536)
			(xy 124.794736 -298.393166) (xy 124.80255 -298.338986) (xy 124.818037 -298.286483) (xy 124.840878 -298.236736)
			(xy 124.870602 -298.190769) (xy 124.888244 -298.169838) (xy 124.89434 -298.162726) (xy 124.90069 -298.145708)
			(xy 124.90069 -298.060364) (xy 124.89434 -298.043346) (xy 124.888244 -298.036234) (xy 124.870638 -298.015273)
			(xy 124.84091 -297.969311) (xy 124.818062 -297.919569) (xy 124.802562 -297.867071) (xy 124.79473 -297.812896)
			(xy 124.794726 -297.758158) (xy 124.80255 -297.703982) (xy 124.818043 -297.651482) (xy 124.840884 -297.601737)
			(xy 124.870605 -297.55577) (xy 124.888244 -297.534838) (xy 124.89434 -297.527726) (xy 124.90069 -297.510708)
			(xy 124.90069 -297.425364) (xy 124.89434 -297.408346) (xy 124.888244 -297.401234) (xy 124.870638 -297.380273)
			(xy 124.84091 -297.334311) (xy 124.818062 -297.284569) (xy 124.802562 -297.232071) (xy 124.79473 -297.177896)
			(xy 124.794726 -297.123158) (xy 124.80255 -297.068982) (xy 124.818043 -297.016482) (xy 124.840884 -296.966737)
			(xy 124.870605 -296.92077) (xy 124.888244 -296.899838) (xy 124.89434 -296.892726) (xy 124.90069 -296.875708)
			(xy 124.90069 -296.790364) (xy 124.89434 -296.773346) (xy 124.888244 -296.766234) (xy 124.870638 -296.745273)
			(xy 124.84091 -296.699311) (xy 124.818062 -296.649569) (xy 124.802562 -296.597071) (xy 124.79473 -296.542896)
			(xy 124.794726 -296.488158) (xy 124.80255 -296.433982) (xy 124.818043 -296.381482) (xy 124.840884 -296.331737)
			(xy 124.870605 -296.28577) (xy 124.888244 -296.264838) (xy 124.89434 -296.257726) (xy 124.90069 -296.240708)
			(xy 124.90069 -296.155364) (xy 124.89434 -296.138346) (xy 124.888244 -296.131234) (xy 124.870638 -296.110273)
			(xy 124.84091 -296.064311) (xy 124.818062 -296.014569) (xy 124.802562 -295.962071) (xy 124.79473 -295.907896)
			(xy 124.794726 -295.853158) (xy 124.80255 -295.798982) (xy 124.818043 -295.746482) (xy 124.840884 -295.696737)
			(xy 124.870605 -295.65077) (xy 124.888244 -295.629838) (xy 124.89434 -295.622726) (xy 124.90069 -295.605708)
			(xy 124.90069 -295.520364) (xy 124.89434 -295.503346) (xy 124.888244 -295.496234) (xy 124.870614 -295.475294)
			(xy 124.840899 -295.429324) (xy 124.818061 -295.379579) (xy 124.802568 -295.32708) (xy 124.794738 -295.272905)
			(xy 124.794264 -295.245536) (xy 124.794789 -295.218285) (xy 124.80254 -295.164338) (xy 124.81789 -295.112043)
			(xy 124.840526 -295.062465) (xy 124.869988 -295.016613) (xy 124.905675 -294.975421) (xy 124.946862 -294.939726)
			(xy 124.992709 -294.910257) (xy 125.042283 -294.887613) (xy 125.094575 -294.872254) (xy 125.148521 -294.864493)
			(xy 125.175772 -294.864028) (xy 125.203142 -294.864504) (xy 125.257321 -294.872318) (xy 125.309824 -294.887805)
			(xy 125.359571 -294.910644) (xy 125.405538 -294.940367) (xy 125.42647 -294.958008) (xy 125.433582 -294.964104)
			(xy 125.4506 -294.970454) (xy 125.535944 -294.970454) (xy 125.552962 -294.964104) (xy 125.560074 -294.958008)
			(xy 125.581006 -294.940369) (xy 125.626979 -294.910657) (xy 125.676726 -294.887821) (xy 125.729227 -294.87233)
			(xy 125.783403 -294.864502) (xy 125.810772 -294.864028) (xy 125.838026 -294.864481) (xy 125.891979 -294.872236)
			(xy 125.944279 -294.88759) (xy 125.993862 -294.910232) (xy 126.039717 -294.9397) (xy 126.080911 -294.975395)
			(xy 126.116605 -295.01659) (xy 126.146072 -295.062445) (xy 126.168713 -295.112028) (xy 126.184066 -295.164329)
			(xy 126.191819 -295.218282) (xy 126.19228 -295.245536) (xy 126.19184 -295.272907) (xy 126.184017 -295.327088)
			(xy 126.168522 -295.379591) (xy 126.145674 -295.429338) (xy 126.115944 -295.475303) (xy 126.0983 -295.496234)
			(xy 126.092204 -295.503346) (xy 126.085854 -295.520364) (xy 126.085854 -295.605708) (xy 126.092204 -295.622726)
			(xy 126.0983 -295.629838) (xy 126.115975 -295.650743) (xy 126.145696 -295.696716) (xy 126.168538 -295.746467)
			(xy 126.18403 -295.798973) (xy 126.191855 -295.853155) (xy 126.191851 -295.907899) (xy 126.184018 -295.96208)
			(xy 126.168519 -296.014584) (xy 126.14567 -296.064332) (xy 126.115942 -296.110301) (xy 126.0983 -296.131234)
			(xy 126.092204 -296.138346) (xy 126.085854 -296.155364) (xy 126.085854 -296.240708) (xy 126.092204 -296.257726)
			(xy 126.0983 -296.264838) (xy 126.115975 -296.285743) (xy 126.145696 -296.331716) (xy 126.168538 -296.381467)
			(xy 126.18403 -296.433973) (xy 126.191855 -296.488155) (xy 126.191851 -296.542899) (xy 126.184018 -296.59708)
			(xy 126.168519 -296.649584) (xy 126.14567 -296.699332) (xy 126.115942 -296.745301) (xy 126.0983 -296.766234)
			(xy 126.092204 -296.773346) (xy 126.085854 -296.790364) (xy 126.085854 -296.875708) (xy 126.092204 -296.892726)
			(xy 126.0983 -296.899838) (xy 126.115975 -296.920743) (xy 126.145696 -296.966716) (xy 126.168538 -297.016467)
			(xy 126.18403 -297.068973) (xy 126.191855 -297.123155) (xy 126.191851 -297.177899) (xy 126.184018 -297.23208)
			(xy 126.168519 -297.284584) (xy 126.14567 -297.334332) (xy 126.115942 -297.380301) (xy 126.0983 -297.401234)
			(xy 126.092204 -297.408346) (xy 126.085854 -297.425364) (xy 126.085854 -297.510708) (xy 126.092204 -297.527726)
			(xy 126.0983 -297.534838) (xy 126.115975 -297.555743) (xy 126.145696 -297.601716) (xy 126.168538 -297.651467)
			(xy 126.18403 -297.703973) (xy 126.191855 -297.758155) (xy 126.191851 -297.812899) (xy 126.184018 -297.86708)
			(xy 126.168519 -297.919584) (xy 126.14567 -297.969332) (xy 126.115942 -298.015301) (xy 126.0983 -298.036234)
			(xy 126.092204 -298.043346) (xy 126.085854 -298.060364) (xy 126.085854 -298.145708) (xy 126.092204 -298.162726)
			(xy 126.0983 -298.169838) (xy 126.115923 -298.190783) (xy 126.145638 -298.236752) (xy 126.168477 -298.286496)
			(xy 126.183971 -298.338994) (xy 126.191804 -298.393168) (xy 126.19228 -298.420536) (xy 127.221996 -298.420536)
			(xy 127.222484 -298.393167) (xy 127.230297 -298.338988) (xy 127.245781 -298.286486) (xy 127.268618 -298.236738)
			(xy 127.298337 -298.190771) (xy 127.315976 -298.169838) (xy 127.322072 -298.162726) (xy 127.328422 -298.145708)
			(xy 127.328422 -298.060364) (xy 127.322072 -298.043346) (xy 127.315976 -298.036234) (xy 127.298369 -298.015274)
			(xy 127.268639 -297.969312) (xy 127.245788 -297.91957) (xy 127.230287 -297.867072) (xy 127.222454 -297.812897)
			(xy 127.22245 -297.758158) (xy 127.230275 -297.703981) (xy 127.245769 -297.65148) (xy 127.268612 -297.601736)
			(xy 127.298336 -297.55577) (xy 127.315976 -297.534838) (xy 127.322072 -297.527726) (xy 127.328422 -297.510708)
			(xy 127.328422 -297.425364) (xy 127.322072 -297.408346) (xy 127.315976 -297.401234) (xy 127.298369 -297.380274)
			(xy 127.268639 -297.334312) (xy 127.245788 -297.28457) (xy 127.230287 -297.232072) (xy 127.222454 -297.177897)
			(xy 127.22245 -297.123158) (xy 127.230275 -297.068981) (xy 127.245769 -297.01648) (xy 127.268612 -296.966736)
			(xy 127.298336 -296.92077) (xy 127.315976 -296.899838) (xy 127.322072 -296.892726) (xy 127.328422 -296.875708)
			(xy 127.328422 -296.790364) (xy 127.322072 -296.773346) (xy 127.315976 -296.766234) (xy 127.298369 -296.745274)
			(xy 127.268639 -296.699312) (xy 127.245788 -296.64957) (xy 127.230287 -296.597072) (xy 127.222454 -296.542897)
			(xy 127.22245 -296.488158) (xy 127.230275 -296.433981) (xy 127.245769 -296.38148) (xy 127.268612 -296.331736)
			(xy 127.298336 -296.28577) (xy 127.315976 -296.264838) (xy 127.322072 -296.257726) (xy 127.328422 -296.240708)
			(xy 127.328422 -296.155364) (xy 127.322072 -296.138346) (xy 127.315976 -296.131234) (xy 127.298369 -296.110274)
			(xy 127.268639 -296.064312) (xy 127.245788 -296.01457) (xy 127.230287 -295.962072) (xy 127.222454 -295.907897)
			(xy 127.22245 -295.853158) (xy 127.230275 -295.798981) (xy 127.245769 -295.74648) (xy 127.268612 -295.696736)
			(xy 127.298336 -295.65077) (xy 127.315976 -295.629838) (xy 127.322072 -295.622726) (xy 127.328422 -295.605708)
			(xy 127.328422 -295.520364) (xy 127.322072 -295.503346) (xy 127.315976 -295.496234) (xy 127.298336 -295.475303)
			(xy 127.268625 -295.42933) (xy 127.24579 -295.379582) (xy 127.230299 -295.327081) (xy 127.22247 -295.272905)
			(xy 127.221996 -295.245536) (xy 127.222489 -295.218284) (xy 127.230241 -295.164334) (xy 127.245593 -295.112036)
			(xy 127.268231 -295.062456) (xy 127.297696 -295.016602) (xy 127.333387 -294.975409) (xy 127.374577 -294.939715)
			(xy 127.420428 -294.910247) (xy 127.470006 -294.887604) (xy 127.522302 -294.872248) (xy 127.576252 -294.864491)
			(xy 127.603504 -294.864028) (xy 127.630875 -294.864485) (xy 127.685054 -294.872304) (xy 127.737558 -294.887795)
			(xy 127.787305 -294.910639) (xy 127.833271 -294.940366) (xy 127.854202 -294.958008) (xy 127.861314 -294.964104)
			(xy 127.878332 -294.970454) (xy 127.963676 -294.970454) (xy 127.980694 -294.964104) (xy 127.987806 -294.958008)
			(xy 128.008726 -294.940354) (xy 128.054702 -294.910644) (xy 128.104453 -294.887811) (xy 128.156956 -294.872323)
			(xy 128.211134 -294.8645) (xy 128.238504 -294.864028) (xy 128.265759 -294.864452) (xy 128.319713 -294.87221)
			(xy 128.372014 -294.887569) (xy 128.421596 -294.910214) (xy 128.467451 -294.939686) (xy 128.508645 -294.975384)
			(xy 128.544338 -295.016581) (xy 128.573805 -295.062439) (xy 128.596445 -295.112024) (xy 128.611798 -295.164326)
			(xy 128.619551 -295.218281) (xy 128.620012 -295.245536) (xy 128.619564 -295.272907) (xy 128.611741 -295.327087)
			(xy 128.596248 -295.37959) (xy 128.573402 -295.429336) (xy 128.543675 -295.475303) (xy 128.526032 -295.496234)
			(xy 128.519936 -295.503346) (xy 128.513586 -295.520364) (xy 128.513586 -295.605708) (xy 128.519936 -295.622726)
			(xy 128.526032 -295.629838) (xy 128.54371 -295.650741) (xy 128.573436 -295.696713) (xy 128.596282 -295.746464)
			(xy 128.611777 -295.798971) (xy 128.619603 -295.853154) (xy 128.619599 -295.9079) (xy 128.611766 -295.962082)
			(xy 128.596263 -296.014587) (xy 128.57341 -296.064334) (xy 128.543677 -296.110302) (xy 128.526032 -296.131234)
			(xy 128.519936 -296.138346) (xy 128.513586 -296.155364) (xy 128.513586 -296.240708) (xy 128.519936 -296.257726)
			(xy 128.526032 -296.264838) (xy 128.54371 -296.285741) (xy 128.573436 -296.331713) (xy 128.596282 -296.381464)
			(xy 128.611777 -296.433971) (xy 128.619603 -296.488154) (xy 128.619599 -296.5429) (xy 128.611766 -296.597082)
			(xy 128.596263 -296.649587) (xy 128.57341 -296.699334) (xy 128.543677 -296.745302) (xy 128.526032 -296.766234)
			(xy 128.519936 -296.773346) (xy 128.513586 -296.790364) (xy 128.513586 -296.875708) (xy 128.519936 -296.892726)
			(xy 128.526032 -296.899838) (xy 128.54371 -296.920741) (xy 128.573436 -296.966713) (xy 128.596282 -297.016464)
			(xy 128.611777 -297.068971) (xy 128.619603 -297.123154) (xy 128.619599 -297.1779) (xy 128.611766 -297.232082)
			(xy 128.596263 -297.284587) (xy 128.57341 -297.334334) (xy 128.543677 -297.380302) (xy 128.526032 -297.401234)
			(xy 128.519936 -297.408346) (xy 128.513586 -297.425364) (xy 128.513586 -297.510708) (xy 128.519936 -297.527726)
			(xy 128.526032 -297.534838) (xy 128.54371 -297.555741) (xy 128.573436 -297.601713) (xy 128.596282 -297.651464)
			(xy 128.611777 -297.703971) (xy 128.619603 -297.758154) (xy 128.619599 -297.8129) (xy 128.611766 -297.867082)
			(xy 128.596263 -297.919587) (xy 128.57341 -297.969334) (xy 128.543677 -298.015302) (xy 128.526032 -298.036234)
			(xy 128.519936 -298.043346) (xy 128.513586 -298.060364) (xy 128.513586 -298.145708) (xy 128.519936 -298.162726)
			(xy 128.526032 -298.169838) (xy 128.54366 -298.190779) (xy 128.573373 -298.23675) (xy 128.59621 -298.286495)
			(xy 128.611704 -298.338994) (xy 128.619536 -298.393167) (xy 128.620012 -298.420536) (xy 131.862576 -298.420536)
			(xy 131.863045 -298.393166) (xy 131.870859 -298.338986) (xy 131.886346 -298.286482) (xy 131.909188 -298.236735)
			(xy 131.938914 -298.190769) (xy 131.956556 -298.169838) (xy 131.962652 -298.162726) (xy 131.969002 -298.145708)
			(xy 131.969002 -298.060364) (xy 131.962652 -298.043346) (xy 131.956556 -298.036234) (xy 131.938949 -298.015273)
			(xy 131.909221 -297.969311) (xy 131.886372 -297.91957) (xy 131.870871 -297.867072) (xy 131.863039 -297.812896)
			(xy 131.863035 -297.758158) (xy 131.87086 -297.703982) (xy 131.886353 -297.651481) (xy 131.909195 -297.601737)
			(xy 131.938917 -297.55577) (xy 131.956556 -297.534838) (xy 131.962652 -297.527726) (xy 131.969002 -297.510708)
			(xy 131.969002 -297.425364) (xy 131.962652 -297.408346) (xy 131.956556 -297.401234) (xy 131.938949 -297.380273)
			(xy 131.909221 -297.334311) (xy 131.886372 -297.28457) (xy 131.870871 -297.232072) (xy 131.863039 -297.177896)
			(xy 131.863035 -297.123158) (xy 131.87086 -297.068982) (xy 131.886353 -297.016481) (xy 131.909195 -296.966737)
			(xy 131.938917 -296.92077) (xy 131.956556 -296.899838) (xy 131.962652 -296.892726) (xy 131.969002 -296.875708)
			(xy 131.969002 -296.790364) (xy 131.962652 -296.773346) (xy 131.956556 -296.766234) (xy 131.938949 -296.745273)
			(xy 131.909221 -296.699311) (xy 131.886372 -296.64957) (xy 131.870871 -296.597072) (xy 131.863039 -296.542896)
			(xy 131.863035 -296.488158) (xy 131.87086 -296.433982) (xy 131.886353 -296.381481) (xy 131.909195 -296.331737)
			(xy 131.938917 -296.28577) (xy 131.956556 -296.264838) (xy 131.962652 -296.257726) (xy 131.969002 -296.240708)
			(xy 131.969002 -296.155364) (xy 131.962652 -296.138346) (xy 131.956556 -296.131234) (xy 131.938949 -296.110273)
			(xy 131.909221 -296.064311) (xy 131.886372 -296.01457) (xy 131.870871 -295.962072) (xy 131.863039 -295.907896)
			(xy 131.863035 -295.853158) (xy 131.87086 -295.798982) (xy 131.886353 -295.746481) (xy 131.909195 -295.696737)
			(xy 131.938917 -295.65077) (xy 131.956556 -295.629838) (xy 131.962652 -295.622726) (xy 131.969002 -295.605708)
			(xy 131.969002 -295.520364) (xy 131.962652 -295.503346) (xy 131.956556 -295.496234) (xy 131.938912 -295.475306)
			(xy 131.909202 -295.429331) (xy 131.886368 -295.379583) (xy 131.870878 -295.327081) (xy 131.86305 -295.272905)
			(xy 131.862576 -295.245536) (xy 131.863089 -295.218285) (xy 131.87084 -295.164336) (xy 131.886191 -295.11204)
			(xy 131.908828 -295.062462) (xy 131.938291 -295.016609) (xy 131.97398 -294.975416) (xy 132.015167 -294.939722)
			(xy 132.061016 -294.910253) (xy 132.110592 -294.887609) (xy 132.162886 -294.872251) (xy 132.216833 -294.864492)
			(xy 132.244084 -294.864028) (xy 132.271454 -294.864497) (xy 132.325633 -294.872313) (xy 132.378137 -294.887801)
			(xy 132.427884 -294.910642) (xy 132.47385 -294.940367) (xy 132.494782 -294.958008) (xy 132.501894 -294.964104)
			(xy 132.518912 -294.970454) (xy 132.604256 -294.970454) (xy 132.621274 -294.964104) (xy 132.628386 -294.958008)
			(xy 132.649314 -294.940363) (xy 132.695287 -294.910652) (xy 132.745036 -294.887817) (xy 132.797538 -294.872327)
			(xy 132.851714 -294.864501) (xy 132.879084 -294.864028) (xy 132.906338 -294.86447) (xy 132.960292 -294.872226)
			(xy 133.012592 -294.887582) (xy 133.062175 -294.910225) (xy 133.108029 -294.939695) (xy 133.149223 -294.975391)
			(xy 133.184917 -295.016587) (xy 133.214384 -295.062443) (xy 133.237025 -295.112027) (xy 133.252378 -295.164328)
			(xy 133.260131 -295.218282) (xy 133.260592 -295.245536) (xy 133.260149 -295.272907) (xy 133.252326 -295.327087)
			(xy 133.236832 -295.379591) (xy 133.213985 -295.429337) (xy 133.184255 -295.475303) (xy 133.166612 -295.496234)
			(xy 133.160516 -295.503346) (xy 133.154166 -295.520364) (xy 133.154166 -295.605708) (xy 133.160516 -295.622726)
			(xy 133.166612 -295.629838) (xy 133.184286 -295.650743) (xy 133.214007 -295.696717) (xy 133.236848 -295.746468)
			(xy 133.252339 -295.798974) (xy 133.260164 -295.853155) (xy 133.26016 -295.907899) (xy 133.252328 -295.962079)
			(xy 133.236828 -296.014583) (xy 133.213981 -296.064331) (xy 133.184254 -296.1103) (xy 133.166612 -296.131234)
			(xy 133.160516 -296.138346) (xy 133.154166 -296.155364) (xy 133.154166 -296.240708) (xy 133.160516 -296.257726)
			(xy 133.166612 -296.264838) (xy 133.184286 -296.285743) (xy 133.214007 -296.331717) (xy 133.236848 -296.381468)
			(xy 133.252339 -296.433974) (xy 133.260164 -296.488155) (xy 133.26016 -296.542899) (xy 133.252328 -296.597079)
			(xy 133.236828 -296.649583) (xy 133.213981 -296.699331) (xy 133.184254 -296.7453) (xy 133.166612 -296.766234)
			(xy 133.160516 -296.773346) (xy 133.154166 -296.790364) (xy 133.154166 -296.875708) (xy 133.160516 -296.892726)
			(xy 133.166612 -296.899838) (xy 133.184286 -296.920743) (xy 133.214007 -296.966717) (xy 133.236848 -297.016468)
			(xy 133.252339 -297.068974) (xy 133.260164 -297.123155) (xy 133.26016 -297.177899) (xy 133.252328 -297.232079)
			(xy 133.236828 -297.284583) (xy 133.213981 -297.334331) (xy 133.184254 -297.3803) (xy 133.166612 -297.401234)
			(xy 133.160516 -297.408346) (xy 133.154166 -297.425364) (xy 133.154166 -297.510708) (xy 133.160516 -297.527726)
			(xy 133.166612 -297.534838) (xy 133.184286 -297.555743) (xy 133.214007 -297.601717) (xy 133.236848 -297.651468)
			(xy 133.252339 -297.703974) (xy 133.260164 -297.758155) (xy 133.26016 -297.812899) (xy 133.252328 -297.867079)
			(xy 133.236828 -297.919583) (xy 133.213981 -297.969331) (xy 133.184254 -298.0153) (xy 133.166612 -298.036234)
			(xy 133.160516 -298.043346) (xy 133.154166 -298.060364) (xy 133.154166 -298.145708) (xy 133.160516 -298.162726)
			(xy 133.166612 -298.169838) (xy 133.184237 -298.190781) (xy 133.213951 -298.236751) (xy 133.236789 -298.286496)
			(xy 133.252284 -298.338994) (xy 133.260116 -298.393168) (xy 133.260592 -298.420536) (xy 133.260156 -298.447789)
			(xy 133.252394 -298.501739) (xy 133.237033 -298.554036) (xy 133.214387 -298.603614) (xy 133.184915 -298.649465)
			(xy 133.149219 -298.690655) (xy 133.108024 -298.726346) (xy 133.062169 -298.755812) (xy 133.012587 -298.778451)
			(xy 132.960288 -298.793805) (xy 132.906337 -298.801559) (xy 132.879084 -298.802044) (xy 132.851713 -298.801601)
			(xy 132.797532 -298.79378) (xy 132.745028 -298.778286) (xy 132.695282 -298.755439) (xy 132.649316 -298.725708)
			(xy 132.628386 -298.708064) (xy 132.621274 -298.701968) (xy 132.604256 -298.695618) (xy 132.518912 -298.695618)
			(xy 132.501894 -298.701968) (xy 132.494782 -298.708064) (xy 132.473825 -298.725673) (xy 132.42786 -298.75539)
			(xy 132.378119 -298.778233) (xy 132.325623 -298.793731) (xy 132.271452 -298.801566) (xy 132.244084 -298.802044)
			(xy 132.216834 -298.801537) (xy 132.162889 -298.793779) (xy 132.110597 -298.778424) (xy 132.061022 -298.755784)
			(xy 132.015173 -298.726319) (xy 131.973984 -298.69063) (xy 131.938293 -298.649443) (xy 131.908826 -298.603596)
			(xy 131.886183 -298.554022) (xy 131.870825 -298.501731) (xy 131.863064 -298.447786) (xy 131.862576 -298.420536)
			(xy 128.620012 -298.420536) (xy 128.619556 -298.447788) (xy 128.611794 -298.501737) (xy 128.596435 -298.554032)
			(xy 128.57379 -298.603609) (xy 128.54432 -298.649459) (xy 128.508626 -298.690648) (xy 128.467433 -298.726339)
			(xy 128.421581 -298.755805) (xy 128.372002 -298.778446) (xy 128.319705 -298.793801) (xy 128.265756 -298.801558)
			(xy 128.238504 -298.802044) (xy 128.211133 -298.801589) (xy 128.156953 -298.793771) (xy 128.104449 -298.77828)
			(xy 128.054703 -298.755435) (xy 128.008737 -298.725707) (xy 127.987806 -298.708064) (xy 127.980694 -298.701968)
			(xy 127.963676 -298.695618) (xy 127.878332 -298.695618) (xy 127.861314 -298.701968) (xy 127.854202 -298.708064)
			(xy 127.833275 -298.72571) (xy 127.787302 -298.755422) (xy 127.737553 -298.778257) (xy 127.685051 -298.793747)
			(xy 127.630874 -298.801572) (xy 127.603504 -298.802044) (xy 127.576254 -298.801519) (xy 127.52231 -298.793764)
			(xy 127.470018 -298.778411) (xy 127.420443 -298.755773) (xy 127.374595 -298.72631) (xy 127.333405 -298.690623)
			(xy 127.297714 -298.649437) (xy 127.268246 -298.603592) (xy 127.245603 -298.554019) (xy 127.230245 -298.501729)
			(xy 127.222484 -298.447785) (xy 127.221996 -298.420536) (xy 126.19228 -298.420536) (xy 126.191856 -298.447789)
			(xy 126.184093 -298.501741) (xy 126.168732 -298.554038) (xy 126.146085 -298.603618) (xy 126.116612 -298.649469)
			(xy 126.080914 -298.69066) (xy 126.039718 -298.726351) (xy 125.993861 -298.755816) (xy 125.944278 -298.778455)
			(xy 125.891978 -298.793807) (xy 125.838025 -298.80156) (xy 125.810772 -298.802044) (xy 125.783401 -298.801608)
			(xy 125.72922 -298.793785) (xy 125.676716 -298.77829) (xy 125.626969 -298.755441) (xy 125.581004 -298.725709)
			(xy 125.560074 -298.708064) (xy 125.552962 -298.701968) (xy 125.535944 -298.695618) (xy 125.4506 -298.695618)
			(xy 125.433582 -298.701968) (xy 125.42647 -298.708064) (xy 125.405518 -298.725678) (xy 125.359551 -298.755395)
			(xy 125.309809 -298.778236) (xy 125.257312 -298.793733) (xy 125.20314 -298.801567) (xy 125.175772 -298.802044)
			(xy 125.148522 -298.801548) (xy 125.094576 -298.793789) (xy 125.042284 -298.778432) (xy 124.992709 -298.75579)
			(xy 124.94686 -298.726324) (xy 124.905671 -298.690634) (xy 124.86998 -298.649446) (xy 124.840514 -298.603598)
			(xy 124.817871 -298.554024) (xy 124.802513 -298.501732) (xy 124.794752 -298.447786) (xy 124.794264 -298.420536)
			(xy 121.5517 -298.420536) (xy 121.551256 -298.447789) (xy 121.543494 -298.501738) (xy 121.528134 -298.554034)
			(xy 121.505488 -298.603612) (xy 121.476017 -298.649463) (xy 121.440321 -298.690653) (xy 121.399127 -298.726344)
			(xy 121.353273 -298.755809) (xy 121.303693 -298.778449) (xy 121.251395 -298.793803) (xy 121.197445 -298.801559)
			(xy 121.170192 -298.802044) (xy 121.142821 -298.801596) (xy 121.088641 -298.793776) (xy 121.036137 -298.778284)
			(xy 120.98639 -298.755437) (xy 120.940425 -298.725708) (xy 120.919494 -298.708064) (xy 120.912382 -298.701968)
			(xy 120.895364 -298.695618) (xy 120.81002 -298.695618) (xy 120.793002 -298.701968) (xy 120.78589 -298.708064)
			(xy 120.764968 -298.725716) (xy 120.718993 -298.755427) (xy 120.669243 -298.778261) (xy 120.61674 -298.793749)
			(xy 120.562562 -298.801573) (xy 120.535192 -298.802044) (xy 120.507942 -298.80153) (xy 120.453997 -298.793773)
			(xy 120.401705 -298.778419) (xy 120.35213 -298.755779) (xy 120.306282 -298.726316) (xy 120.265093 -298.690627)
			(xy 120.229401 -298.649441) (xy 120.199934 -298.603594) (xy 120.177291 -298.554021) (xy 120.161933 -298.50173)
			(xy 120.154172 -298.447786) (xy 120.153684 -298.420536) (xy 116.601494 -298.420536) (xy 116.601056 -298.447789)
			(xy 116.593294 -298.501739) (xy 116.577933 -298.554035) (xy 116.555287 -298.603614) (xy 116.525816 -298.649465)
			(xy 116.490119 -298.690655) (xy 116.448925 -298.726346) (xy 116.40307 -298.755811) (xy 116.353488 -298.778451)
			(xy 116.30119 -298.793805) (xy 116.247239 -298.801559) (xy 116.219986 -298.802044) (xy 116.192615 -298.8016)
			(xy 116.138434 -298.793779) (xy 116.08593 -298.778285) (xy 116.036184 -298.755438) (xy 115.990218 -298.725708)
			(xy 115.969288 -298.708064) (xy 115.962176 -298.701968) (xy 115.945158 -298.695618) (xy 115.859814 -298.695618)
			(xy 115.842796 -298.701968) (xy 115.835684 -298.708064) (xy 115.814726 -298.725672) (xy 115.768761 -298.755389)
			(xy 115.71902 -298.778232) (xy 115.666525 -298.79373) (xy 115.612354 -298.801566) (xy 115.584986 -298.802044)
			(xy 115.557736 -298.801535) (xy 115.503791 -298.793778) (xy 115.451499 -298.778423) (xy 115.401924 -298.755783)
			(xy 115.356075 -298.726318) (xy 115.314886 -298.690629) (xy 115.279195 -298.649442) (xy 115.249728 -298.603595)
			(xy 115.227085 -298.554022) (xy 115.211727 -298.501731) (xy 115.203966 -298.447786) (xy 115.203478 -298.420536)
			(xy 111.960914 -298.420536) (xy 111.960456 -298.447788) (xy 111.952694 -298.501736) (xy 111.937335 -298.554031)
			(xy 111.91469 -298.603608) (xy 111.885221 -298.649458) (xy 111.849526 -298.690648) (xy 111.808334 -298.726339)
			(xy 111.762482 -298.755805) (xy 111.712903 -298.778446) (xy 111.660607 -298.793801) (xy 111.606658 -298.801558)
			(xy 111.579406 -298.802044) (xy 111.552035 -298.801588) (xy 111.497855 -298.79377) (xy 111.445351 -298.778279)
			(xy 111.395605 -298.755435) (xy 111.349639 -298.725707) (xy 111.328708 -298.708064) (xy 111.321596 -298.701968)
			(xy 111.304578 -298.695618) (xy 111.219234 -298.695618) (xy 111.202216 -298.701968) (xy 111.195104 -298.708064)
			(xy 111.174177 -298.725709) (xy 111.128203 -298.755421) (xy 111.078454 -298.778257) (xy 111.025953 -298.793746)
			(xy 110.971776 -298.801572) (xy 110.944406 -298.802044) (xy 110.917157 -298.801517) (xy 110.863212 -298.793762)
			(xy 110.81092 -298.778409) (xy 110.761346 -298.755772) (xy 110.715497 -298.726309) (xy 110.674308 -298.690622)
			(xy 110.638616 -298.649437) (xy 110.609149 -298.603591) (xy 110.586505 -298.554019) (xy 110.571147 -298.501729)
			(xy 110.563386 -298.447785) (xy 110.562898 -298.420536) (xy 109.533182 -298.420536) (xy 109.532756 -298.447789)
			(xy 109.524994 -298.501741) (xy 109.509633 -298.554038) (xy 109.486985 -298.603617) (xy 109.457513 -298.649469)
			(xy 109.421815 -298.690659) (xy 109.380619 -298.72635) (xy 109.334763 -298.755815) (xy 109.28518 -298.778454)
			(xy 109.23288 -298.793807) (xy 109.178927 -298.80156) (xy 109.151674 -298.802044) (xy 109.124303 -298.801607)
			(xy 109.070122 -298.793784) (xy 109.017618 -298.778289) (xy 108.967871 -298.755441) (xy 108.921906 -298.725709)
			(xy 108.900976 -298.708064) (xy 108.893864 -298.701968) (xy 108.876846 -298.695618) (xy 108.791502 -298.695618)
			(xy 108.774484 -298.701968) (xy 108.767372 -298.708064) (xy 108.746419 -298.725677) (xy 108.700452 -298.755394)
			(xy 108.65071 -298.778236) (xy 108.598214 -298.793733) (xy 108.544042 -298.801567) (xy 108.516674 -298.802044)
			(xy 108.489424 -298.801546) (xy 108.435478 -298.793787) (xy 108.383186 -298.778431) (xy 108.333611 -298.755789)
			(xy 108.287763 -298.726324) (xy 108.246574 -298.690634) (xy 108.210882 -298.649445) (xy 108.181416 -298.603598)
			(xy 108.158773 -298.554023) (xy 108.143415 -298.501731) (xy 108.135654 -298.447786) (xy 108.135166 -298.420536)
			(xy 104.892602 -298.420536) (xy 104.892156 -298.447788) (xy 104.884394 -298.501738) (xy 104.869034 -298.554034)
			(xy 104.846388 -298.603611) (xy 104.816918 -298.649462) (xy 104.781222 -298.690652) (xy 104.740028 -298.726343)
			(xy 104.694175 -298.755808) (xy 104.644594 -298.778449) (xy 104.592297 -298.793803) (xy 104.538346 -298.801559)
			(xy 104.511094 -298.802044) (xy 104.483723 -298.801595) (xy 104.429543 -298.793775) (xy 104.377039 -298.778283)
			(xy 104.327292 -298.755437) (xy 104.281327 -298.725708) (xy 104.260396 -298.708064) (xy 104.253284 -298.701968)
			(xy 104.236266 -298.695618) (xy 104.150922 -298.695618) (xy 104.133904 -298.701968) (xy 104.126792 -298.708064)
			(xy 104.105869 -298.725715) (xy 104.059894 -298.755426) (xy 104.010145 -298.77826) (xy 103.957642 -298.793749)
			(xy 103.903464 -298.801573) (xy 103.876094 -298.802044) (xy 103.848844 -298.801528) (xy 103.794899 -298.793772)
			(xy 103.742607 -298.778417) (xy 103.693033 -298.755778) (xy 103.647184 -298.726315) (xy 103.605995 -298.690626)
			(xy 103.570303 -298.64944) (xy 103.540836 -298.603594) (xy 103.518193 -298.554021) (xy 103.502835 -298.50173)
			(xy 103.495074 -298.447786) (xy 103.494586 -298.420536) (xy 101.055932 -298.420536) (xy 101.055932 -301.424086)
			(xy 102.823518 -301.424086) (xy 102.823971 -301.396715) (xy 102.831792 -301.342535) (xy 102.847283 -301.290032)
			(xy 102.870128 -301.240285) (xy 102.899855 -301.194319) (xy 102.917498 -301.173388) (xy 102.923594 -301.166276)
			(xy 102.929944 -301.149258) (xy 102.929944 -301.063914) (xy 102.923594 -301.046896) (xy 102.917498 -301.039784)
			(xy 102.899845 -301.018862) (xy 102.870123 -300.972891) (xy 102.84728 -300.923143) (xy 102.831786 -300.87064)
			(xy 102.823959 -300.81646) (xy 102.823961 -300.761719) (xy 102.831791 -300.707539) (xy 102.847287 -300.655037)
			(xy 102.870133 -300.60529) (xy 102.899858 -300.559321) (xy 102.917498 -300.538388) (xy 102.923594 -300.531276)
			(xy 102.929944 -300.514258) (xy 102.929944 -300.428914) (xy 102.923594 -300.411896) (xy 102.917498 -300.404784)
			(xy 102.899845 -300.383862) (xy 102.870123 -300.337891) (xy 102.84728 -300.288143) (xy 102.831786 -300.23564)
			(xy 102.823959 -300.18146) (xy 102.823961 -300.126719) (xy 102.831791 -300.072539) (xy 102.847287 -300.020037)
			(xy 102.870133 -299.97029) (xy 102.899858 -299.924321) (xy 102.917498 -299.903388) (xy 102.923594 -299.896276)
			(xy 102.929944 -299.879258) (xy 102.929944 -299.793914) (xy 102.923594 -299.776896) (xy 102.917498 -299.769784)
			(xy 102.899885 -299.748831) (xy 102.870169 -299.702864) (xy 102.847328 -299.653122) (xy 102.831831 -299.600626)
			(xy 102.823996 -299.546454) (xy 102.823518 -299.519086) (xy 102.824004 -299.491835) (xy 102.83176 -299.437887)
			(xy 102.847115 -299.385592) (xy 102.869757 -299.336015) (xy 102.899223 -299.290165) (xy 102.934914 -299.248974)
			(xy 102.976105 -299.213283) (xy 103.021955 -299.183817) (xy 103.071532 -299.161175) (xy 103.123827 -299.14582)
			(xy 103.177775 -299.138064) (xy 103.232277 -299.138064) (xy 103.286225 -299.14582) (xy 103.33852 -299.161175)
			(xy 103.388097 -299.183817) (xy 103.433947 -299.213283) (xy 103.475138 -299.248974) (xy 103.510829 -299.290165)
			(xy 103.540295 -299.336015) (xy 103.562937 -299.385592) (xy 103.578292 -299.437887) (xy 103.586048 -299.491835)
			(xy 103.586534 -299.519086) (xy 103.586076 -299.546457) (xy 103.578259 -299.600637) (xy 103.562769 -299.653141)
			(xy 103.539925 -299.702887) (xy 103.510197 -299.748853) (xy 103.492554 -299.769784) (xy 103.486458 -299.776896)
			(xy 103.480108 -299.793914) (xy 103.480108 -299.879258) (xy 103.486458 -299.896276) (xy 103.492554 -299.903388)
			(xy 103.510182 -299.924331) (xy 103.539909 -299.970297) (xy 103.562756 -300.020041) (xy 103.578254 -300.072542)
			(xy 103.586084 -300.126719) (xy 103.586086 -300.18146) (xy 103.578259 -300.235637) (xy 103.562763 -300.288139)
			(xy 103.539919 -300.337885) (xy 103.510194 -300.383852) (xy 103.492554 -300.404784) (xy 103.486458 -300.411896)
			(xy 103.480108 -300.428914) (xy 103.480108 -300.514258) (xy 103.486458 -300.531276) (xy 103.492554 -300.538388)
			(xy 103.510182 -300.559331) (xy 103.539909 -300.605297) (xy 103.562756 -300.655041) (xy 103.578254 -300.707542)
			(xy 103.586084 -300.761719) (xy 103.586086 -300.81646) (xy 103.578259 -300.870637) (xy 103.562763 -300.923139)
			(xy 103.539919 -300.972885) (xy 103.510194 -301.018852) (xy 103.492554 -301.039784) (xy 103.486458 -301.046896)
			(xy 103.480108 -301.063914) (xy 103.480108 -301.149258) (xy 103.486458 -301.166276) (xy 103.492554 -301.173388)
			(xy 103.510194 -301.19432) (xy 103.539907 -301.240292) (xy 103.562744 -301.290039) (xy 103.578234 -301.34254)
			(xy 103.586061 -301.396717) (xy 103.586534 -301.424086) (xy 103.586048 -301.451337) (xy 103.582224 -301.477934)
			(xy 106.455718 -301.477934) (xy 106.4562 -301.450564) (xy 106.464013 -301.396386) (xy 106.479498 -301.343883)
			(xy 106.502337 -301.294135) (xy 106.532058 -301.248168) (xy 106.549698 -301.227236) (xy 106.555794 -301.220124)
			(xy 106.562144 -301.203106) (xy 106.562144 -301.117762) (xy 106.555794 -301.100744) (xy 106.549698 -301.093632)
			(xy 106.532092 -301.072672) (xy 106.502368 -301.026708) (xy 106.479522 -300.976966) (xy 106.464025 -300.924469)
			(xy 106.456193 -300.870294) (xy 106.45619 -300.815557) (xy 106.464014 -300.761382) (xy 106.479504 -300.708882)
			(xy 106.502343 -300.659137) (xy 106.532061 -300.613169) (xy 106.549698 -300.592236) (xy 106.555794 -300.585124)
			(xy 106.562144 -300.568106) (xy 106.562144 -300.482762) (xy 106.555794 -300.465744) (xy 106.549698 -300.458632)
			(xy 106.532092 -300.437672) (xy 106.502368 -300.391708) (xy 106.479522 -300.341966) (xy 106.464025 -300.289469)
			(xy 106.456193 -300.235294) (xy 106.45619 -300.180557) (xy 106.464014 -300.126382) (xy 106.479504 -300.073882)
			(xy 106.502343 -300.024137) (xy 106.532061 -299.978169) (xy 106.549698 -299.957236) (xy 106.555794 -299.950124)
			(xy 106.562144 -299.933106) (xy 106.562144 -299.847762) (xy 106.555794 -299.830744) (xy 106.549698 -299.823632)
			(xy 106.53206 -299.802699) (xy 106.502348 -299.756726) (xy 106.479512 -299.706979) (xy 106.464021 -299.654479)
			(xy 106.456192 -299.600303) (xy 106.455718 -299.572934) (xy 106.456204 -299.545683) (xy 106.46396 -299.491735)
			(xy 106.479315 -299.43944) (xy 106.501957 -299.389863) (xy 106.531423 -299.344013) (xy 106.567114 -299.302822)
			(xy 106.608305 -299.267131) (xy 106.654155 -299.237665) (xy 106.703732 -299.215023) (xy 106.756027 -299.199668)
			(xy 106.809975 -299.191912) (xy 106.864477 -299.191912) (xy 106.918425 -299.199668) (xy 106.97072 -299.215023)
			(xy 107.020297 -299.237665) (xy 107.066147 -299.267131) (xy 107.107338 -299.302822) (xy 107.143029 -299.344013)
			(xy 107.172495 -299.389863) (xy 107.195137 -299.43944) (xy 107.210492 -299.491735) (xy 107.218248 -299.545683)
			(xy 107.218734 -299.572934) (xy 107.218304 -299.600306) (xy 107.21048 -299.654487) (xy 107.194983 -299.706991)
			(xy 107.172133 -299.756737) (xy 107.1424 -299.802702) (xy 107.124754 -299.823632) (xy 107.118658 -299.830744)
			(xy 107.112308 -299.847762) (xy 107.112308 -299.933106) (xy 107.118658 -299.950124) (xy 107.124754 -299.957236)
			(xy 107.142429 -299.978141) (xy 107.172154 -300.024113) (xy 107.194998 -300.073864) (xy 107.210493 -300.126371)
			(xy 107.218318 -300.180553) (xy 107.218315 -300.235298) (xy 107.210482 -300.28948) (xy 107.19498 -300.341984)
			(xy 107.172129 -300.391732) (xy 107.142398 -300.4377) (xy 107.124754 -300.458632) (xy 107.118658 -300.465744)
			(xy 107.112308 -300.482762) (xy 107.112308 -300.568106) (xy 107.118658 -300.585124) (xy 107.124754 -300.592236)
			(xy 107.142429 -300.613141) (xy 107.172154 -300.659113) (xy 107.194998 -300.708864) (xy 107.210493 -300.761371)
			(xy 107.218318 -300.815553) (xy 107.218315 -300.870298) (xy 107.210482 -300.92448) (xy 107.19498 -300.976984)
			(xy 107.172129 -301.026732) (xy 107.142398 -301.0727) (xy 107.124754 -301.093632) (xy 107.118658 -301.100744)
			(xy 107.112308 -301.117762) (xy 107.112308 -301.203106) (xy 107.118658 -301.220124) (xy 107.124754 -301.227236)
			(xy 107.142369 -301.248187) (xy 107.172086 -301.294154) (xy 107.194928 -301.343897) (xy 107.210424 -301.396393)
			(xy 107.214428 -301.424086) (xy 109.663738 -301.424086) (xy 109.664187 -301.396715) (xy 109.672007 -301.342535)
			(xy 109.6875 -301.290031) (xy 109.710346 -301.240285) (xy 109.740075 -301.194319) (xy 109.757718 -301.173388)
			(xy 109.763814 -301.166276) (xy 109.770164 -301.149258) (xy 109.770164 -301.063914) (xy 109.763814 -301.046896)
			(xy 109.757718 -301.039784) (xy 109.740064 -301.018862) (xy 109.71034 -300.972892) (xy 109.687496 -300.923144)
			(xy 109.672002 -300.870641) (xy 109.664175 -300.816461) (xy 109.664176 -300.761718) (xy 109.672006 -300.707539)
			(xy 109.687504 -300.655036) (xy 109.710351 -300.605289) (xy 109.740077 -300.559321) (xy 109.757718 -300.538388)
			(xy 109.763814 -300.531276) (xy 109.770164 -300.514258) (xy 109.770164 -300.428914) (xy 109.763814 -300.411896)
			(xy 109.757718 -300.404784) (xy 109.740064 -300.383862) (xy 109.71034 -300.337892) (xy 109.687496 -300.288144)
			(xy 109.672002 -300.235641) (xy 109.664175 -300.181461) (xy 109.664176 -300.126718) (xy 109.672006 -300.072539)
			(xy 109.687504 -300.020036) (xy 109.710351 -299.970289) (xy 109.740077 -299.924321) (xy 109.757718 -299.903388)
			(xy 109.763814 -299.896276) (xy 109.770164 -299.879258) (xy 109.770164 -299.793914) (xy 109.763814 -299.776896)
			(xy 109.757718 -299.769784) (xy 109.740108 -299.748829) (xy 109.710391 -299.702863) (xy 109.687549 -299.653121)
			(xy 109.672051 -299.600625) (xy 109.664216 -299.546454) (xy 109.663738 -299.519086) (xy 109.664224 -299.491835)
			(xy 109.67198 -299.437887) (xy 109.687335 -299.385592) (xy 109.709977 -299.336015) (xy 109.739443 -299.290165)
			(xy 109.775134 -299.248974) (xy 109.816325 -299.213283) (xy 109.862175 -299.183817) (xy 109.911752 -299.161175)
			(xy 109.964047 -299.14582) (xy 110.017995 -299.138064) (xy 110.072497 -299.138064) (xy 110.126445 -299.14582)
			(xy 110.17874 -299.161175) (xy 110.228317 -299.183817) (xy 110.274167 -299.213283) (xy 110.315358 -299.248974)
			(xy 110.351049 -299.290165) (xy 110.380515 -299.336015) (xy 110.403157 -299.385592) (xy 110.418512 -299.437887)
			(xy 110.426268 -299.491835) (xy 110.426754 -299.519086) (xy 110.426291 -299.546456) (xy 110.418474 -299.600636)
			(xy 110.402985 -299.65314) (xy 110.380142 -299.702887) (xy 110.350416 -299.748853) (xy 110.332774 -299.769784)
			(xy 110.326678 -299.776896) (xy 110.320328 -299.793914) (xy 110.320328 -299.879258) (xy 110.326678 -299.896276)
			(xy 110.332774 -299.903388) (xy 110.350401 -299.924332) (xy 110.380126 -299.970298) (xy 110.402972 -300.020042)
			(xy 110.41847 -300.072543) (xy 110.4263 -300.12672) (xy 110.426301 -300.181459) (xy 110.418474 -300.235637)
			(xy 110.40298 -300.288138) (xy 110.380136 -300.337884) (xy 110.350414 -300.383851) (xy 110.332774 -300.404784)
			(xy 110.326678 -300.411896) (xy 110.320328 -300.428914) (xy 110.320328 -300.514258) (xy 110.326678 -300.531276)
			(xy 110.332774 -300.538388) (xy 110.350401 -300.559332) (xy 110.380126 -300.605298) (xy 110.402972 -300.655042)
			(xy 110.41847 -300.707543) (xy 110.4263 -300.76172) (xy 110.426301 -300.816459) (xy 110.418474 -300.870637)
			(xy 110.40298 -300.923138) (xy 110.380136 -300.972884) (xy 110.350414 -301.018851) (xy 110.332774 -301.039784)
			(xy 110.326678 -301.046896) (xy 110.320328 -301.063914) (xy 110.320328 -301.149258) (xy 110.326678 -301.166276)
			(xy 110.332774 -301.173388) (xy 110.350417 -301.194317) (xy 110.380129 -301.24029) (xy 110.402965 -301.290039)
			(xy 110.418455 -301.34254) (xy 110.426281 -301.396717) (xy 110.426754 -301.424086) (xy 110.426268 -301.451337)
			(xy 110.422444 -301.477934) (xy 113.295938 -301.477934) (xy 113.296415 -301.450564) (xy 113.304229 -301.396385)
			(xy 113.319715 -301.343882) (xy 113.342554 -301.294135) (xy 113.372277 -301.248168) (xy 113.389918 -301.227236)
			(xy 113.396014 -301.220124) (xy 113.402364 -301.203106) (xy 113.402364 -301.117762) (xy 113.396014 -301.100744)
			(xy 113.389918 -301.093632) (xy 113.372311 -301.072672) (xy 113.342586 -301.026709) (xy 113.319739 -300.976967)
			(xy 113.30424 -300.924469) (xy 113.296409 -300.870294) (xy 113.296405 -300.815557) (xy 113.304229 -300.761381)
			(xy 113.319721 -300.708881) (xy 113.342561 -300.659136) (xy 113.37228 -300.613169) (xy 113.389918 -300.592236)
			(xy 113.396014 -300.585124) (xy 113.402364 -300.568106) (xy 113.402364 -300.482762) (xy 113.396014 -300.465744)
			(xy 113.389918 -300.458632) (xy 113.372311 -300.437672) (xy 113.342586 -300.391709) (xy 113.319739 -300.341967)
			(xy 113.30424 -300.289469) (xy 113.296409 -300.235294) (xy 113.296405 -300.180557) (xy 113.304229 -300.126381)
			(xy 113.319721 -300.073881) (xy 113.342561 -300.024136) (xy 113.37228 -299.978169) (xy 113.389918 -299.957236)
			(xy 113.396014 -299.950124) (xy 113.402364 -299.933106) (xy 113.402364 -299.847762) (xy 113.396014 -299.830744)
			(xy 113.389918 -299.823632) (xy 113.372283 -299.802696) (xy 113.34257 -299.756725) (xy 113.319733 -299.706978)
			(xy 113.304241 -299.654478) (xy 113.296412 -299.600303) (xy 113.295938 -299.572934) (xy 113.296424 -299.545683)
			(xy 113.30418 -299.491735) (xy 113.319535 -299.43944) (xy 113.342177 -299.389863) (xy 113.371643 -299.344013)
			(xy 113.407334 -299.302822) (xy 113.448525 -299.267131) (xy 113.494375 -299.237665) (xy 113.543952 -299.215023)
			(xy 113.596247 -299.199668) (xy 113.650195 -299.191912) (xy 113.704697 -299.191912) (xy 113.758645 -299.199668)
			(xy 113.81094 -299.215023) (xy 113.860517 -299.237665) (xy 113.906367 -299.267131) (xy 113.947558 -299.302822)
			(xy 113.983249 -299.344013) (xy 114.012715 -299.389863) (xy 114.035357 -299.43944) (xy 114.050712 -299.491735)
			(xy 114.058468 -299.545683) (xy 114.058954 -299.572934) (xy 114.058519 -299.600305) (xy 114.050695 -299.654486)
			(xy 114.0352 -299.70699) (xy 114.012351 -299.756737) (xy 113.982619 -299.802702) (xy 113.964974 -299.823632)
			(xy 113.958878 -299.830744) (xy 113.952528 -299.847762) (xy 113.952528 -299.933106) (xy 113.958878 -299.950124)
			(xy 113.964974 -299.957236) (xy 113.982648 -299.978142) (xy 114.012371 -300.024114) (xy 114.035215 -300.073865)
			(xy 114.050708 -300.126371) (xy 114.058534 -300.180553) (xy 114.05853 -300.235298) (xy 114.050697 -300.289479)
			(xy 114.035197 -300.341983) (xy 114.012347 -300.391731) (xy 113.982617 -300.437699) (xy 113.964974 -300.458632)
			(xy 113.958878 -300.465744) (xy 113.952528 -300.482762) (xy 113.952528 -300.568106) (xy 113.958878 -300.585124)
			(xy 113.964974 -300.592236) (xy 113.982648 -300.613142) (xy 114.012371 -300.659114) (xy 114.035215 -300.708865)
			(xy 114.050708 -300.761371) (xy 114.058534 -300.815553) (xy 114.05853 -300.870298) (xy 114.050697 -300.924479)
			(xy 114.035197 -300.976983) (xy 114.012347 -301.026731) (xy 113.982617 -301.072699) (xy 113.964974 -301.093632)
			(xy 113.958878 -301.100744) (xy 113.952528 -301.117762) (xy 113.952528 -301.203106) (xy 113.958878 -301.220124)
			(xy 113.964974 -301.227236) (xy 113.982593 -301.248185) (xy 114.012308 -301.294153) (xy 114.035149 -301.343896)
			(xy 114.050644 -301.396393) (xy 114.054649 -301.424086) (xy 121.416826 -301.424086) (xy 121.417278 -301.396715)
			(xy 121.425098 -301.342535) (xy 121.44059 -301.290032) (xy 121.463435 -301.240285) (xy 121.493163 -301.194319)
			(xy 121.510806 -301.173388) (xy 121.516902 -301.166276) (xy 121.523252 -301.149258) (xy 121.523252 -301.063914)
			(xy 121.516902 -301.046896) (xy 121.510806 -301.039784) (xy 121.493152 -301.018862) (xy 121.46343 -300.972892)
			(xy 121.440587 -300.923144) (xy 121.425092 -300.87064) (xy 121.417265 -300.81646) (xy 121.417267 -300.761718)
			(xy 121.425097 -300.707539) (xy 121.440594 -300.655037) (xy 121.46344 -300.60529) (xy 121.493165 -300.559321)
			(xy 121.510806 -300.538388) (xy 121.516902 -300.531276) (xy 121.523252 -300.514258) (xy 121.523252 -300.428914)
			(xy 121.516902 -300.411896) (xy 121.510806 -300.404784) (xy 121.493152 -300.383862) (xy 121.46343 -300.337892)
			(xy 121.440587 -300.288144) (xy 121.425092 -300.23564) (xy 121.417265 -300.18146) (xy 121.417267 -300.126718)
			(xy 121.425097 -300.072539) (xy 121.440594 -300.020037) (xy 121.46344 -299.97029) (xy 121.493165 -299.924321)
			(xy 121.510806 -299.903388) (xy 121.516902 -299.896276) (xy 121.523252 -299.879258) (xy 121.523252 -299.793914)
			(xy 121.516902 -299.776896) (xy 121.510806 -299.769784) (xy 121.493194 -299.74883) (xy 121.463478 -299.702864)
			(xy 121.440636 -299.653122) (xy 121.425139 -299.600626) (xy 121.417304 -299.546454) (xy 121.416826 -299.519086)
			(xy 121.417312 -299.491835) (xy 121.425068 -299.437887) (xy 121.440423 -299.385592) (xy 121.463065 -299.336015)
			(xy 121.492531 -299.290165) (xy 121.528222 -299.248974) (xy 121.569413 -299.213283) (xy 121.615263 -299.183817)
			(xy 121.66484 -299.161175) (xy 121.717135 -299.14582) (xy 121.771083 -299.138064) (xy 121.825585 -299.138064)
			(xy 121.879533 -299.14582) (xy 121.931828 -299.161175) (xy 121.981405 -299.183817) (xy 122.027255 -299.213283)
			(xy 122.068446 -299.248974) (xy 122.104137 -299.290165) (xy 122.133603 -299.336015) (xy 122.156245 -299.385592)
			(xy 122.1716 -299.437887) (xy 122.179356 -299.491835) (xy 122.179842 -299.519086) (xy 122.179382 -299.546457)
			(xy 122.171565 -299.600637) (xy 122.156075 -299.65314) (xy 122.133232 -299.702887) (xy 122.103505 -299.748853)
			(xy 122.085862 -299.769784) (xy 122.079766 -299.776896) (xy 122.073416 -299.793914) (xy 122.073416 -299.879258)
			(xy 122.079766 -299.896276) (xy 122.085862 -299.903388) (xy 122.103489 -299.924332) (xy 122.133216 -299.970297)
			(xy 122.156062 -300.020042) (xy 122.17156 -300.072542) (xy 122.17939 -300.126719) (xy 122.179392 -300.18146)
			(xy 122.171565 -300.235637) (xy 122.15607 -300.288139) (xy 122.133226 -300.337884) (xy 122.103502 -300.383852)
			(xy 122.085862 -300.404784) (xy 122.079766 -300.411896) (xy 122.073416 -300.428914) (xy 122.073416 -300.514258)
			(xy 122.079766 -300.531276) (xy 122.085862 -300.538388) (xy 122.103489 -300.559332) (xy 122.133216 -300.605297)
			(xy 122.156062 -300.655042) (xy 122.17156 -300.707542) (xy 122.17939 -300.761719) (xy 122.179392 -300.81646)
			(xy 122.171565 -300.870637) (xy 122.15607 -300.923139) (xy 122.133226 -300.972884) (xy 122.103502 -301.018852)
			(xy 122.085862 -301.039784) (xy 122.079766 -301.046896) (xy 122.073416 -301.063914) (xy 122.073416 -301.149258)
			(xy 122.079766 -301.166276) (xy 122.085862 -301.173388) (xy 122.103503 -301.194319) (xy 122.133216 -301.240291)
			(xy 122.156052 -301.290039) (xy 122.171543 -301.34254) (xy 122.179369 -301.396717) (xy 122.179842 -301.424086)
			(xy 122.179356 -301.451337) (xy 122.175532 -301.477934) (xy 125.049026 -301.477934) (xy 125.049506 -301.450564)
			(xy 125.057319 -301.396385) (xy 125.072805 -301.343882) (xy 125.095644 -301.294135) (xy 125.125366 -301.248168)
			(xy 125.143006 -301.227236) (xy 125.149102 -301.220124) (xy 125.155452 -301.203106) (xy 125.155452 -301.117762)
			(xy 125.149102 -301.100744) (xy 125.143006 -301.093632) (xy 125.125399 -301.072672) (xy 125.095675 -301.026708)
			(xy 125.072829 -300.976966) (xy 125.057331 -300.924469) (xy 125.0495 -300.870294) (xy 125.049496 -300.815557)
			(xy 125.05732 -300.761381) (xy 125.072811 -300.708882) (xy 125.09565 -300.659137) (xy 125.125369 -300.613169)
			(xy 125.143006 -300.592236) (xy 125.149102 -300.585124) (xy 125.155452 -300.568106) (xy 125.155452 -300.482762)
			(xy 125.149102 -300.465744) (xy 125.143006 -300.458632) (xy 125.125399 -300.437672) (xy 125.095675 -300.391708)
			(xy 125.072829 -300.341966) (xy 125.057331 -300.289469) (xy 125.0495 -300.235294) (xy 125.049496 -300.180557)
			(xy 125.05732 -300.126381) (xy 125.072811 -300.073882) (xy 125.09565 -300.024137) (xy 125.125369 -299.978169)
			(xy 125.143006 -299.957236) (xy 125.149102 -299.950124) (xy 125.155452 -299.933106) (xy 125.155452 -299.847762)
			(xy 125.149102 -299.830744) (xy 125.143006 -299.823632) (xy 125.125369 -299.802698) (xy 125.095657 -299.756726)
			(xy 125.07282 -299.706979) (xy 125.057329 -299.654479) (xy 125.0495 -299.600303) (xy 125.049026 -299.572934)
			(xy 125.049512 -299.545683) (xy 125.057268 -299.491735) (xy 125.072623 -299.43944) (xy 125.095265 -299.389863)
			(xy 125.124731 -299.344013) (xy 125.160422 -299.302822) (xy 125.201613 -299.267131) (xy 125.247463 -299.237665)
			(xy 125.29704 -299.215023) (xy 125.349335 -299.199668) (xy 125.403283 -299.191912) (xy 125.457785 -299.191912)
			(xy 125.511733 -299.199668) (xy 125.564028 -299.215023) (xy 125.613605 -299.237665) (xy 125.659455 -299.267131)
			(xy 125.700646 -299.302822) (xy 125.736337 -299.344013) (xy 125.765803 -299.389863) (xy 125.788445 -299.43944)
			(xy 125.8038 -299.491735) (xy 125.811556 -299.545683) (xy 125.812042 -299.572934) (xy 125.81161 -299.600306)
			(xy 125.803786 -299.654487) (xy 125.78829 -299.706991) (xy 125.76544 -299.756737) (xy 125.735707 -299.802702)
			(xy 125.718062 -299.823632) (xy 125.711966 -299.830744) (xy 125.705616 -299.847762) (xy 125.705616 -299.933106)
			(xy 125.711966 -299.950124) (xy 125.718062 -299.957236) (xy 125.735736 -299.978142) (xy 125.765461 -300.024114)
			(xy 125.788305 -300.073864) (xy 125.803799 -300.126371) (xy 125.811625 -300.180553) (xy 125.811621 -300.235298)
			(xy 125.803788 -300.289479) (xy 125.788287 -300.341984) (xy 125.765436 -300.391731) (xy 125.735706 -300.437699)
			(xy 125.718062 -300.458632) (xy 125.711966 -300.465744) (xy 125.705616 -300.482762) (xy 125.705616 -300.568106)
			(xy 125.711966 -300.585124) (xy 125.718062 -300.592236) (xy 125.735736 -300.613142) (xy 125.765461 -300.659114)
			(xy 125.788305 -300.708864) (xy 125.803799 -300.761371) (xy 125.811625 -300.815553) (xy 125.811621 -300.870298)
			(xy 125.803788 -300.924479) (xy 125.788287 -300.976984) (xy 125.765436 -301.026731) (xy 125.735706 -301.072699)
			(xy 125.718062 -301.093632) (xy 125.711966 -301.100744) (xy 125.705616 -301.117762) (xy 125.705616 -301.203106)
			(xy 125.711966 -301.220124) (xy 125.718062 -301.227236) (xy 125.735679 -301.248186) (xy 125.765395 -301.294153)
			(xy 125.788236 -301.343896) (xy 125.803732 -301.396393) (xy 125.807736 -301.424086) (xy 128.257046 -301.424086)
			(xy 128.257493 -301.396715) (xy 128.265313 -301.342535) (xy 128.280806 -301.290031) (xy 128.303653 -301.240284)
			(xy 128.333382 -301.194319) (xy 128.351026 -301.173388) (xy 128.357122 -301.166276) (xy 128.363472 -301.149258)
			(xy 128.363472 -301.063914) (xy 128.357122 -301.046896) (xy 128.351026 -301.039784) (xy 128.333372 -301.018862)
			(xy 128.303647 -300.972893) (xy 128.280803 -300.923145) (xy 128.265308 -300.870641) (xy 128.257481 -300.816461)
			(xy 128.257482 -300.761718) (xy 128.265312 -300.707539) (xy 128.28081 -300.655036) (xy 128.303658 -300.605289)
			(xy 128.333384 -300.559321) (xy 128.351026 -300.538388) (xy 128.357122 -300.531276) (xy 128.363472 -300.514258)
			(xy 128.363472 -300.428914) (xy 128.357122 -300.411896) (xy 128.351026 -300.404784) (xy 128.333372 -300.383862)
			(xy 128.303647 -300.337893) (xy 128.280803 -300.288145) (xy 128.265308 -300.235641) (xy 128.257481 -300.181461)
			(xy 128.257482 -300.126718) (xy 128.265312 -300.072539) (xy 128.28081 -300.020036) (xy 128.303658 -299.970289)
			(xy 128.333384 -299.924321) (xy 128.351026 -299.903388) (xy 128.357122 -299.896276) (xy 128.363472 -299.879258)
			(xy 128.363472 -299.793914) (xy 128.357122 -299.776896) (xy 128.351026 -299.769784) (xy 128.333417 -299.748828)
			(xy 128.3037 -299.702862) (xy 128.280858 -299.653121) (xy 128.26536 -299.600625) (xy 128.257524 -299.546454)
			(xy 128.257046 -299.519086) (xy 128.257532 -299.491835) (xy 128.265288 -299.437887) (xy 128.280643 -299.385592)
			(xy 128.303285 -299.336015) (xy 128.332751 -299.290165) (xy 128.368442 -299.248974) (xy 128.409633 -299.213283)
			(xy 128.455483 -299.183817) (xy 128.50506 -299.161175) (xy 128.557355 -299.14582) (xy 128.611303 -299.138064)
			(xy 128.665805 -299.138064) (xy 128.719753 -299.14582) (xy 128.772048 -299.161175) (xy 128.821625 -299.183817)
			(xy 128.867475 -299.213283) (xy 128.908666 -299.248974) (xy 128.944357 -299.290165) (xy 128.973823 -299.336015)
			(xy 128.996465 -299.385592) (xy 129.01182 -299.437887) (xy 129.019576 -299.491835) (xy 129.020062 -299.519086)
			(xy 129.019597 -299.546456) (xy 129.01178 -299.600636) (xy 128.996292 -299.653139) (xy 128.973449 -299.702886)
			(xy 128.943724 -299.748853) (xy 128.926082 -299.769784) (xy 128.919986 -299.776896) (xy 128.913636 -299.793914)
			(xy 128.913636 -299.879258) (xy 128.919986 -299.896276) (xy 128.926082 -299.903388) (xy 128.943709 -299.924332)
			(xy 128.973433 -299.970298) (xy 128.996279 -300.020043) (xy 129.011776 -300.072543) (xy 129.019606 -300.12672)
			(xy 129.019607 -300.181459) (xy 129.01178 -300.235637) (xy 128.996286 -300.288138) (xy 128.973443 -300.337883)
			(xy 128.943721 -300.383851) (xy 128.926082 -300.404784) (xy 128.919986 -300.411896) (xy 128.913636 -300.428914)
			(xy 128.913636 -300.514258) (xy 128.919986 -300.531276) (xy 128.926082 -300.538388) (xy 128.943709 -300.559332)
			(xy 128.973433 -300.605298) (xy 128.996279 -300.655043) (xy 129.011776 -300.707543) (xy 129.019606 -300.76172)
			(xy 129.019607 -300.816459) (xy 129.01178 -300.870637) (xy 128.996286 -300.923138) (xy 128.973443 -300.972883)
			(xy 128.943721 -301.018851) (xy 128.926082 -301.039784) (xy 128.919986 -301.046896) (xy 128.913636 -301.063914)
			(xy 128.913636 -301.149258) (xy 128.919986 -301.166276) (xy 128.926082 -301.173388) (xy 128.943726 -301.194316)
			(xy 128.973438 -301.24029) (xy 128.996273 -301.290038) (xy 129.011763 -301.34254) (xy 129.019589 -301.396717)
			(xy 129.020062 -301.424086) (xy 129.019576 -301.451337) (xy 129.015752 -301.477934) (xy 131.889246 -301.477934)
			(xy 131.889721 -301.450564) (xy 131.897535 -301.396385) (xy 131.913021 -301.343881) (xy 131.935861 -301.294134)
			(xy 131.965585 -301.248168) (xy 131.983226 -301.227236) (xy 131.989322 -301.220124) (xy 131.995672 -301.203106)
			(xy 131.995672 -301.117762) (xy 131.989322 -301.100744) (xy 131.983226 -301.093632) (xy 131.965619 -301.072672)
			(xy 131.935893 -301.026709) (xy 131.913045 -300.976967) (xy 131.897546 -300.924469) (xy 131.889715 -300.870295)
			(xy 131.889711 -300.815557) (xy 131.897535 -300.761381) (xy 131.913027 -300.708881) (xy 131.935868 -300.659136)
			(xy 131.965588 -300.613169) (xy 131.983226 -300.592236) (xy 131.989322 -300.585124) (xy 131.995672 -300.568106)
			(xy 131.995672 -300.482762) (xy 131.989322 -300.465744) (xy 131.983226 -300.458632) (xy 131.965619 -300.437672)
			(xy 131.935893 -300.391709) (xy 131.913045 -300.341967) (xy 131.897546 -300.289469) (xy 131.889715 -300.235295)
			(xy 131.889711 -300.180557) (xy 131.897535 -300.126381) (xy 131.913027 -300.073881) (xy 131.935868 -300.024136)
			(xy 131.965588 -299.978169) (xy 131.983226 -299.957236) (xy 131.989322 -299.950124) (xy 131.995672 -299.933106)
			(xy 131.995672 -299.847762) (xy 131.989322 -299.830744) (xy 131.983226 -299.823632) (xy 131.965592 -299.802695)
			(xy 131.935879 -299.756724) (xy 131.913041 -299.706978) (xy 131.897549 -299.654478) (xy 131.88972 -299.600303)
			(xy 131.889246 -299.572934) (xy 131.889732 -299.545683) (xy 131.897488 -299.491735) (xy 131.912843 -299.43944)
			(xy 131.935485 -299.389863) (xy 131.964951 -299.344013) (xy 132.000642 -299.302822) (xy 132.041833 -299.267131)
			(xy 132.087683 -299.237665) (xy 132.13726 -299.215023) (xy 132.189555 -299.199668) (xy 132.243503 -299.191912)
			(xy 132.298005 -299.191912) (xy 132.351953 -299.199668) (xy 132.404248 -299.215023) (xy 132.453825 -299.237665)
			(xy 132.499675 -299.267131) (xy 132.540866 -299.302822) (xy 132.576557 -299.344013) (xy 132.606023 -299.389863)
			(xy 132.628665 -299.43944) (xy 132.64402 -299.491735) (xy 132.651776 -299.545683) (xy 132.652262 -299.572934)
			(xy 132.651825 -299.600305) (xy 132.644002 -299.654486) (xy 132.628506 -299.70699) (xy 132.605658 -299.756736)
			(xy 132.575927 -299.802702) (xy 132.558282 -299.823632) (xy 132.552186 -299.830744) (xy 132.545836 -299.847762)
			(xy 132.545836 -299.933106) (xy 132.552186 -299.950124) (xy 132.558282 -299.957236) (xy 132.575956 -299.978142)
			(xy 132.605678 -300.024115) (xy 132.628521 -300.073865) (xy 132.644014 -300.126371) (xy 132.65184 -300.180553)
			(xy 132.651836 -300.235298) (xy 132.644003 -300.289479) (xy 132.628503 -300.341983) (xy 132.605654 -300.39173)
			(xy 132.575925 -300.437699) (xy 132.558282 -300.458632) (xy 132.552186 -300.465744) (xy 132.545836 -300.482762)
			(xy 132.545836 -300.568106) (xy 132.552186 -300.585124) (xy 132.558282 -300.592236) (xy 132.575956 -300.613142)
			(xy 132.605678 -300.659115) (xy 132.628521 -300.708865) (xy 132.644014 -300.761371) (xy 132.65184 -300.815553)
			(xy 132.651836 -300.870298) (xy 132.644003 -300.924479) (xy 132.628503 -300.976983) (xy 132.605654 -301.02673)
			(xy 132.575925 -301.072699) (xy 132.558282 -301.093632) (xy 132.552186 -301.100744) (xy 132.545836 -301.117762)
			(xy 132.545836 -301.203106) (xy 132.552186 -301.220124) (xy 132.558282 -301.227236) (xy 132.575902 -301.248184)
			(xy 132.605617 -301.294152) (xy 132.628457 -301.343895) (xy 132.643953 -301.396393) (xy 132.651786 -301.450566)
			(xy 132.652262 -301.477934) (xy 132.651776 -301.505185) (xy 132.64402 -301.559133) (xy 132.628665 -301.611428)
			(xy 132.606023 -301.661005) (xy 132.576557 -301.706855) (xy 132.540866 -301.748046) (xy 132.499675 -301.783737)
			(xy 132.453825 -301.813203) (xy 132.404248 -301.835845) (xy 132.351953 -301.8512) (xy 132.298005 -301.858956)
			(xy 132.243503 -301.858956) (xy 132.189555 -301.8512) (xy 132.13726 -301.835845) (xy 132.087683 -301.813203)
			(xy 132.041833 -301.783737) (xy 132.000642 -301.748046) (xy 131.964951 -301.706855) (xy 131.935485 -301.661005)
			(xy 131.912843 -301.611428) (xy 131.897488 -301.559133) (xy 131.889732 -301.505185) (xy 131.889246 -301.477934)
			(xy 129.015752 -301.477934) (xy 129.01182 -301.505285) (xy 128.996465 -301.55758) (xy 128.973823 -301.607157)
			(xy 128.944357 -301.653007) (xy 128.908666 -301.694198) (xy 128.867475 -301.729889) (xy 128.821625 -301.759355)
			(xy 128.772048 -301.781997) (xy 128.719753 -301.797352) (xy 128.665805 -301.805108) (xy 128.611303 -301.805108)
			(xy 128.557355 -301.797352) (xy 128.50506 -301.781997) (xy 128.455483 -301.759355) (xy 128.409633 -301.729889)
			(xy 128.368442 -301.694198) (xy 128.332751 -301.653007) (xy 128.303285 -301.607157) (xy 128.280643 -301.55758)
			(xy 128.265288 -301.505285) (xy 128.257532 -301.451337) (xy 128.257046 -301.424086) (xy 125.807736 -301.424086)
			(xy 125.811565 -301.450566) (xy 125.812042 -301.477934) (xy 125.811556 -301.505185) (xy 125.8038 -301.559133)
			(xy 125.788445 -301.611428) (xy 125.765803 -301.661005) (xy 125.736337 -301.706855) (xy 125.700646 -301.748046)
			(xy 125.659455 -301.783737) (xy 125.613605 -301.813203) (xy 125.564028 -301.835845) (xy 125.511733 -301.8512)
			(xy 125.457785 -301.858956) (xy 125.403283 -301.858956) (xy 125.349335 -301.8512) (xy 125.29704 -301.835845)
			(xy 125.247463 -301.813203) (xy 125.201613 -301.783737) (xy 125.160422 -301.748046) (xy 125.124731 -301.706855)
			(xy 125.095265 -301.661005) (xy 125.072623 -301.611428) (xy 125.057268 -301.559133) (xy 125.049512 -301.505185)
			(xy 125.049026 -301.477934) (xy 122.175532 -301.477934) (xy 122.1716 -301.505285) (xy 122.156245 -301.55758)
			(xy 122.133603 -301.607157) (xy 122.104137 -301.653007) (xy 122.068446 -301.694198) (xy 122.027255 -301.729889)
			(xy 121.981405 -301.759355) (xy 121.931828 -301.781997) (xy 121.879533 -301.797352) (xy 121.825585 -301.805108)
			(xy 121.771083 -301.805108) (xy 121.717135 -301.797352) (xy 121.66484 -301.781997) (xy 121.615263 -301.759355)
			(xy 121.569413 -301.729889) (xy 121.528222 -301.694198) (xy 121.492531 -301.653007) (xy 121.463065 -301.607157)
			(xy 121.440423 -301.55758) (xy 121.425068 -301.505285) (xy 121.417312 -301.451337) (xy 121.416826 -301.424086)
			(xy 114.054649 -301.424086) (xy 114.058478 -301.450566) (xy 114.058954 -301.477934) (xy 114.058468 -301.505185)
			(xy 114.050712 -301.559133) (xy 114.035357 -301.611428) (xy 114.012715 -301.661005) (xy 113.983249 -301.706855)
			(xy 113.947558 -301.748046) (xy 113.906367 -301.783737) (xy 113.860517 -301.813203) (xy 113.81094 -301.835845)
			(xy 113.758645 -301.8512) (xy 113.704697 -301.858956) (xy 113.650195 -301.858956) (xy 113.596247 -301.8512)
			(xy 113.543952 -301.835845) (xy 113.494375 -301.813203) (xy 113.448525 -301.783737) (xy 113.407334 -301.748046)
			(xy 113.371643 -301.706855) (xy 113.342177 -301.661005) (xy 113.319535 -301.611428) (xy 113.30418 -301.559133)
			(xy 113.296424 -301.505185) (xy 113.295938 -301.477934) (xy 110.422444 -301.477934) (xy 110.418512 -301.505285)
			(xy 110.403157 -301.55758) (xy 110.380515 -301.607157) (xy 110.351049 -301.653007) (xy 110.315358 -301.694198)
			(xy 110.274167 -301.729889) (xy 110.228317 -301.759355) (xy 110.17874 -301.781997) (xy 110.126445 -301.797352)
			(xy 110.072497 -301.805108) (xy 110.017995 -301.805108) (xy 109.964047 -301.797352) (xy 109.911752 -301.781997)
			(xy 109.862175 -301.759355) (xy 109.816325 -301.729889) (xy 109.775134 -301.694198) (xy 109.739443 -301.653007)
			(xy 109.709977 -301.607157) (xy 109.687335 -301.55758) (xy 109.67198 -301.505285) (xy 109.664224 -301.451337)
			(xy 109.663738 -301.424086) (xy 107.214428 -301.424086) (xy 107.218257 -301.450566) (xy 107.218734 -301.477934)
			(xy 107.218248 -301.505185) (xy 107.210492 -301.559133) (xy 107.195137 -301.611428) (xy 107.172495 -301.661005)
			(xy 107.143029 -301.706855) (xy 107.107338 -301.748046) (xy 107.066147 -301.783737) (xy 107.020297 -301.813203)
			(xy 106.97072 -301.835845) (xy 106.918425 -301.8512) (xy 106.864477 -301.858956) (xy 106.809975 -301.858956)
			(xy 106.756027 -301.8512) (xy 106.703732 -301.835845) (xy 106.654155 -301.813203) (xy 106.608305 -301.783737)
			(xy 106.567114 -301.748046) (xy 106.531423 -301.706855) (xy 106.501957 -301.661005) (xy 106.479315 -301.611428)
			(xy 106.46396 -301.559133) (xy 106.456204 -301.505185) (xy 106.455718 -301.477934) (xy 103.582224 -301.477934)
			(xy 103.578292 -301.505285) (xy 103.562937 -301.55758) (xy 103.540295 -301.607157) (xy 103.510829 -301.653007)
			(xy 103.475138 -301.694198) (xy 103.433947 -301.729889) (xy 103.388097 -301.759355) (xy 103.33852 -301.781997)
			(xy 103.286225 -301.797352) (xy 103.232277 -301.805108) (xy 103.177775 -301.805108) (xy 103.123827 -301.797352)
			(xy 103.071532 -301.781997) (xy 103.021955 -301.759355) (xy 102.976105 -301.729889) (xy 102.934914 -301.694198)
			(xy 102.899223 -301.653007) (xy 102.869757 -301.607157) (xy 102.847115 -301.55758) (xy 102.83176 -301.505285)
			(xy 102.824004 -301.451337) (xy 102.823518 -301.424086) (xy 101.055932 -301.424086) (xy 101.055932 -302.815244)
			(xy 101.056296 -302.82529) (xy 101.063888 -302.843886) (xy 101.070664 -302.851312) (xy 101.282246 -303.062894)
			(xy 101.289671 -303.069702) (xy 101.308251 -303.077441) (xy 101.318314 -303.07788) (xy 102.136448 -303.07788)
			(xy 102.147171 -303.077294) (xy 102.166731 -303.068488) (xy 102.174294 -303.060862) (xy 102.232206 -302.996854)
			(xy 102.23881 -302.976534) (xy 102.23754 -302.965612) (xy 102.236577 -302.955671) (xy 102.235561 -302.935722)
			(xy 102.235508 -302.925734) (xy 102.235992 -302.898364) (xy 102.243805 -302.844186) (xy 102.25929 -302.791683)
			(xy 102.282128 -302.741936) (xy 102.311849 -302.695968) (xy 102.329488 -302.675036) (xy 102.335584 -302.667924)
			(xy 102.341934 -302.650906) (xy 102.341934 -302.565562) (xy 102.335584 -302.548544) (xy 102.329488 -302.541432)
			(xy 102.311849 -302.5205) (xy 102.282137 -302.474527) (xy 102.259302 -302.42478) (xy 102.24381 -302.372279)
			(xy 102.235982 -302.318103) (xy 102.235508 -302.290734) (xy 102.235994 -302.263483) (xy 102.24375 -302.209535)
			(xy 102.259105 -302.15724) (xy 102.281747 -302.107663) (xy 102.311213 -302.061813) (xy 102.346904 -302.020622)
			(xy 102.388095 -301.984931) (xy 102.433945 -301.955465) (xy 102.483522 -301.932823) (xy 102.535817 -301.917468)
			(xy 102.589765 -301.909712) (xy 102.644267 -301.909712) (xy 102.698215 -301.917468) (xy 102.75051 -301.932823)
			(xy 102.800087 -301.955465) (xy 102.845937 -301.984931) (xy 102.887128 -302.020622) (xy 102.922819 -302.061813)
			(xy 102.952285 -302.107663) (xy 102.974927 -302.15724) (xy 102.990282 -302.209535) (xy 102.998038 -302.263483)
			(xy 102.998524 -302.290734) (xy 102.998096 -302.318106) (xy 102.990272 -302.372287) (xy 102.974775 -302.424792)
			(xy 102.951924 -302.474538) (xy 102.92219 -302.520502) (xy 102.904544 -302.541432) (xy 102.898448 -302.548544)
			(xy 102.892098 -302.565562) (xy 102.892098 -302.650906) (xy 102.898448 -302.667924) (xy 102.904544 -302.675036)
			(xy 102.922174 -302.695975) (xy 102.951886 -302.741947) (xy 102.974723 -302.791693) (xy 102.990216 -302.844191)
			(xy 102.998048 -302.898365) (xy 102.998524 -302.925734) (xy 102.998472 -302.935722) (xy 102.997458 -302.955671)
			(xy 102.996492 -302.965612) (xy 102.995222 -302.976534) (xy 103.001826 -302.996854) (xy 103.059738 -303.060862)
			(xy 103.067233 -303.068582) (xy 103.086835 -303.077401) (xy 103.097584 -303.07788) (xy 105.556558 -303.07788)
			(xy 105.567282 -303.0773) (xy 105.586842 -303.06849) (xy 105.594404 -303.060862) (xy 105.652316 -302.996854)
			(xy 105.65892 -302.976534) (xy 105.65765 -302.965612) (xy 105.656687 -302.955671) (xy 105.655671 -302.935722)
			(xy 105.655618 -302.925734) (xy 105.6561 -302.898364) (xy 105.663913 -302.844186) (xy 105.679398 -302.791683)
			(xy 105.702237 -302.741935) (xy 105.731958 -302.695968) (xy 105.749598 -302.675036) (xy 105.755694 -302.667924)
			(xy 105.762044 -302.650906) (xy 105.762044 -302.565562) (xy 105.755694 -302.548544) (xy 105.749598 -302.541432)
			(xy 105.73196 -302.520499) (xy 105.702248 -302.474526) (xy 105.679412 -302.424779) (xy 105.663921 -302.372279)
			(xy 105.656092 -302.318103) (xy 105.655618 -302.290734) (xy 105.656104 -302.263483) (xy 105.66386 -302.209535)
			(xy 105.679215 -302.15724) (xy 105.701857 -302.107663) (xy 105.731323 -302.061813) (xy 105.767014 -302.020622)
			(xy 105.808205 -301.984931) (xy 105.854055 -301.955465) (xy 105.903632 -301.932823) (xy 105.955927 -301.917468)
			(xy 106.009875 -301.909712) (xy 106.064377 -301.909712) (xy 106.118325 -301.917468) (xy 106.17062 -301.932823)
			(xy 106.220197 -301.955465) (xy 106.266047 -301.984931) (xy 106.307238 -302.020622) (xy 106.342929 -302.061813)
			(xy 106.372395 -302.107663) (xy 106.395037 -302.15724) (xy 106.410392 -302.209535) (xy 106.418148 -302.263483)
			(xy 106.418634 -302.290734) (xy 106.418204 -302.318106) (xy 106.41038 -302.372287) (xy 106.394883 -302.424791)
			(xy 106.372033 -302.474537) (xy 106.3423 -302.520502) (xy 106.324654 -302.541432) (xy 106.318558 -302.548544)
			(xy 106.312208 -302.565562) (xy 106.312208 -302.650906) (xy 106.318558 -302.667924) (xy 106.324654 -302.675036)
			(xy 106.342269 -302.695987) (xy 106.371986 -302.741954) (xy 106.394828 -302.791697) (xy 106.410324 -302.844193)
			(xy 106.418157 -302.898366) (xy 106.418634 -302.925734) (xy 106.418582 -302.935722) (xy 106.417568 -302.955671)
			(xy 106.416602 -302.965612) (xy 106.415332 -302.976534) (xy 106.421936 -302.996854) (xy 106.479848 -303.060862)
			(xy 106.487339 -303.068587) (xy 106.506945 -303.077403) (xy 106.517694 -303.07788) (xy 106.944668 -303.07788)
			(xy 106.955392 -303.077305) (xy 106.974952 -303.068491) (xy 106.982514 -303.060862) (xy 107.040426 -302.996854)
			(xy 107.04703 -302.976534) (xy 107.04576 -302.965612) (xy 107.044797 -302.955671) (xy 107.043781 -302.935722)
			(xy 107.043728 -302.925734) (xy 107.044207 -302.898364) (xy 107.052021 -302.844185) (xy 107.067506 -302.791682)
			(xy 107.090345 -302.741935) (xy 107.120068 -302.695968) (xy 107.137708 -302.675036) (xy 107.143804 -302.667924)
			(xy 107.150154 -302.650906) (xy 107.150154 -302.565562) (xy 107.143804 -302.548544) (xy 107.137708 -302.541432)
			(xy 107.120072 -302.520498) (xy 107.090359 -302.474526) (xy 107.067523 -302.424779) (xy 107.052031 -302.372278)
			(xy 107.044202 -302.318103) (xy 107.043728 -302.290734) (xy 107.044214 -302.263483) (xy 107.05197 -302.209535)
			(xy 107.067325 -302.15724) (xy 107.089967 -302.107663) (xy 107.119433 -302.061813) (xy 107.155124 -302.020622)
			(xy 107.196315 -301.984931) (xy 107.242165 -301.955465) (xy 107.291742 -301.932823) (xy 107.344037 -301.917468)
			(xy 107.397985 -301.909712) (xy 107.452487 -301.909712) (xy 107.506435 -301.917468) (xy 107.55873 -301.932823)
			(xy 107.608307 -301.955465) (xy 107.654157 -301.984931) (xy 107.695348 -302.020622) (xy 107.731039 -302.061813)
			(xy 107.760505 -302.107663) (xy 107.783147 -302.15724) (xy 107.798502 -302.209535) (xy 107.806258 -302.263483)
			(xy 107.806744 -302.290734) (xy 107.806312 -302.318106) (xy 107.798488 -302.372287) (xy 107.782992 -302.424791)
			(xy 107.760142 -302.474537) (xy 107.730409 -302.520502) (xy 107.712764 -302.541432) (xy 107.706668 -302.548544)
			(xy 107.700318 -302.565562) (xy 107.700318 -302.650906) (xy 107.706668 -302.667924) (xy 107.712764 -302.675036)
			(xy 107.730381 -302.695986) (xy 107.760097 -302.741953) (xy 107.782938 -302.791696) (xy 107.798434 -302.844193)
			(xy 107.806267 -302.898366) (xy 107.806744 -302.925734) (xy 107.806692 -302.935722) (xy 107.805678 -302.955671)
			(xy 107.804712 -302.965612) (xy 107.803442 -302.976534) (xy 107.810046 -302.996854) (xy 107.867958 -303.060862)
			(xy 107.875445 -303.068591) (xy 107.895054 -303.077405) (xy 107.905804 -303.07788) (xy 108.976668 -303.07788)
			(xy 108.987392 -303.077305) (xy 109.006952 -303.068491) (xy 109.014514 -303.060862) (xy 109.072426 -302.996854)
			(xy 109.07903 -302.976534) (xy 109.07776 -302.965612) (xy 109.076797 -302.955671) (xy 109.075781 -302.935722)
			(xy 109.075728 -302.925734) (xy 109.076207 -302.898364) (xy 109.084021 -302.844185) (xy 109.099506 -302.791682)
			(xy 109.122345 -302.741935) (xy 109.152068 -302.695968) (xy 109.169708 -302.675036) (xy 109.175804 -302.667924)
			(xy 109.182154 -302.650906) (xy 109.182154 -302.565562) (xy 109.175804 -302.548544) (xy 109.169708 -302.541432)
			(xy 109.152072 -302.520498) (xy 109.122359 -302.474526) (xy 109.099523 -302.424779) (xy 109.084031 -302.372278)
			(xy 109.076202 -302.318103) (xy 109.075728 -302.290734) (xy 109.076214 -302.263483) (xy 109.08397 -302.209535)
			(xy 109.099325 -302.15724) (xy 109.121967 -302.107663) (xy 109.151433 -302.061813) (xy 109.187124 -302.020622)
			(xy 109.228315 -301.984931) (xy 109.274165 -301.955465) (xy 109.323742 -301.932823) (xy 109.376037 -301.917468)
			(xy 109.429985 -301.909712) (xy 109.484487 -301.909712) (xy 109.538435 -301.917468) (xy 109.59073 -301.932823)
			(xy 109.640307 -301.955465) (xy 109.686157 -301.984931) (xy 109.727348 -302.020622) (xy 109.763039 -302.061813)
			(xy 109.792505 -302.107663) (xy 109.815147 -302.15724) (xy 109.830502 -302.209535) (xy 109.838258 -302.263483)
			(xy 109.838744 -302.290734) (xy 109.838312 -302.318106) (xy 109.830488 -302.372287) (xy 109.814992 -302.424791)
			(xy 109.792142 -302.474537) (xy 109.762409 -302.520502) (xy 109.744764 -302.541432) (xy 109.738668 -302.548544)
			(xy 109.732318 -302.565562) (xy 109.732318 -302.650906) (xy 109.738668 -302.667924) (xy 109.744764 -302.675036)
			(xy 109.762381 -302.695986) (xy 109.792097 -302.741953) (xy 109.814938 -302.791696) (xy 109.830434 -302.844193)
			(xy 109.838267 -302.898366) (xy 109.838744 -302.925734) (xy 109.838692 -302.935722) (xy 109.837678 -302.955671)
			(xy 109.836712 -302.965612) (xy 109.835442 -302.976534) (xy 109.842046 -302.996854) (xy 109.899958 -303.060862)
			(xy 109.907445 -303.068591) (xy 109.927054 -303.077405) (xy 109.937804 -303.07788) (xy 113.784888 -303.07788)
			(xy 113.795614 -303.077316) (xy 113.815174 -303.068494) (xy 113.822734 -303.060862) (xy 113.880646 -302.996854)
			(xy 113.88725 -302.976534) (xy 113.88598 -302.965612) (xy 113.885017 -302.955671) (xy 113.884001 -302.935722)
			(xy 113.883948 -302.925734) (xy 113.884422 -302.898364) (xy 113.892236 -302.844185) (xy 113.907723 -302.791681)
			(xy 113.930563 -302.741934) (xy 113.960287 -302.695967) (xy 113.977928 -302.675036) (xy 113.984024 -302.667924)
			(xy 113.990374 -302.650906) (xy 113.990374 -302.565562) (xy 113.984024 -302.548544) (xy 113.977928 -302.541432)
			(xy 113.960295 -302.520495) (xy 113.930581 -302.474524) (xy 113.907744 -302.424778) (xy 113.892251 -302.372278)
			(xy 113.884422 -302.318103) (xy 113.883948 -302.290734) (xy 113.884434 -302.263483) (xy 113.89219 -302.209535)
			(xy 113.907545 -302.15724) (xy 113.930187 -302.107663) (xy 113.959653 -302.061813) (xy 113.995344 -302.020622)
			(xy 114.036535 -301.984931) (xy 114.082385 -301.955465) (xy 114.131962 -301.932823) (xy 114.184257 -301.917468)
			(xy 114.238205 -301.909712) (xy 114.292707 -301.909712) (xy 114.346655 -301.917468) (xy 114.39895 -301.932823)
			(xy 114.448527 -301.955465) (xy 114.494377 -301.984931) (xy 114.535568 -302.020622) (xy 114.571259 -302.061813)
			(xy 114.600725 -302.107663) (xy 114.623367 -302.15724) (xy 114.638722 -302.209535) (xy 114.646478 -302.263483)
			(xy 114.646964 -302.290734) (xy 114.646527 -302.318105) (xy 114.638703 -302.372286) (xy 114.623208 -302.42479)
			(xy 114.60036 -302.474536) (xy 114.570628 -302.520502) (xy 114.552984 -302.541432) (xy 114.546888 -302.548544)
			(xy 114.540538 -302.565562) (xy 114.540538 -302.650906) (xy 114.546888 -302.667924) (xy 114.552984 -302.675036)
			(xy 114.570604 -302.695983) (xy 114.600319 -302.741952) (xy 114.623159 -302.791695) (xy 114.638655 -302.844193)
			(xy 114.646488 -302.898366) (xy 114.646964 -302.925734) (xy 114.646912 -302.935722) (xy 114.645898 -302.955671)
			(xy 114.644932 -302.965612) (xy 114.643662 -302.976534) (xy 114.650266 -302.996854) (xy 114.708178 -303.060862)
			(xy 114.715657 -303.0686) (xy 114.735272 -303.077409) (xy 114.746024 -303.07788) (xy 116.66982 -303.07788)
			(xy 116.679891 -303.07747) (xy 116.698489 -303.069739) (xy 116.705888 -303.062894) (xy 116.896642 -302.871886)
			(xy 116.918275 -302.85114) (xy 116.96679 -302.81595) (xy 117.02021 -302.788778) (xy 117.077222 -302.770294)
			(xy 117.136423 -302.760952) (xy 117.16639 -302.76038) (xy 117.193626 -302.760818) (xy 117.247544 -302.768569)
			(xy 117.299809 -302.783916) (xy 117.349359 -302.806544) (xy 117.395183 -302.835995) (xy 117.436349 -302.871668)
			(xy 117.472019 -302.912836) (xy 117.501467 -302.958662) (xy 117.524093 -303.008213) (xy 117.539436 -303.06048)
			(xy 117.547184 -303.114398) (xy 117.547644 -303.141634) (xy 117.547109 -303.171606) (xy 117.537794 -303.230822)
			(xy 117.519319 -303.287847) (xy 117.49214 -303.341275) (xy 117.456929 -303.389787) (xy 117.436138 -303.411382)
			(xy 117.2337 -303.61382) (xy 117.226895 -303.621153) (xy 117.219251 -303.639627) (xy 117.219261 -303.659621)
			(xy 117.226922 -303.678088) (xy 117.2337 -303.685448) (xy 117.436138 -303.887886) (xy 117.456909 -303.909496)
			(xy 117.492095 -303.958017) (xy 117.519262 -304.011443) (xy 117.53774 -304.06846) (xy 117.547075 -304.127665)
			(xy 117.547644 -304.157634) (xy 117.5472 -304.184868) (xy 117.539444 -304.238782) (xy 117.524094 -304.291043)
			(xy 117.501463 -304.340588) (xy 117.472012 -304.386409) (xy 117.43634 -304.427571) (xy 117.395173 -304.463239)
			(xy 117.34935 -304.492684) (xy 117.299802 -304.515309) (xy 117.247539 -304.530653) (xy 117.193624 -304.538403)
			(xy 117.16639 -304.538888) (xy 117.136416 -304.538389) (xy 117.0772 -304.529063) (xy 117.020175 -304.510578)
			(xy 116.966747 -304.483393) (xy 116.918236 -304.448176) (xy 116.896642 -304.427382) (xy 116.705888 -304.236374)
			(xy 116.698489 -304.229532) (xy 116.679889 -304.221814) (xy 116.66982 -304.221388) (xy 100.981256 -304.221388)
			(xy 100.951284 -304.220847) (xy 100.89207 -304.211531) (xy 100.835045 -304.193056) (xy 100.781617 -304.16588)
			(xy 100.733104 -304.130672) (xy 100.711508 -304.109882) (xy 100.023676 -303.42205) (xy 100.002874 -303.400453)
			(xy 99.967621 -303.351951) (xy 99.940391 -303.298529) (xy 99.921857 -303.241505) (xy 99.912474 -303.182282)
			(xy 99.911916 -303.152302) (xy 99.911916 -297.234102) (xy 99.911542 -297.224057) (xy 99.903958 -297.20546)
			(xy 99.897184 -297.198034) (xy 94.385384 -291.686488) (xy 94.364553 -291.664917) (xy 94.329304 -291.616408)
			(xy 94.30208 -291.56298) (xy 94.283552 -291.505949) (xy 94.274177 -291.446722) (xy 94.273624 -291.41674)
			(xy 94.273624 -286.931608) (xy 94.274052 -286.906616) (xy 94.280641 -286.857066) (xy 94.293627 -286.808797)
			(xy 94.302834 -286.785558) (xy 94.654116 -285.937452) (xy 94.658081 -285.926311) (xy 94.656497 -285.902745)
			(xy 94.651068 -285.89224) (xy 94.603824 -285.811722) (xy 94.584012 -285.799022) (xy 94.57182 -285.797498)
			(xy 94.544259 -285.793835) (xy 94.490522 -285.779571) (xy 94.439426 -285.757656) (xy 94.392054 -285.728552)
			(xy 94.34941 -285.692879) (xy 94.312398 -285.651391) (xy 94.281803 -285.604968) (xy 94.258273 -285.554595)
			(xy 94.242307 -285.501339) (xy 94.234244 -285.446329) (xy 94.233746 -285.41853) (xy 93.644974 -285.41853)
			(xy 93.644974 -290.912804) (xy 93.669866 -290.941252) (xy 93.68917 -290.943792) (xy 93.716322 -290.947884)
			(xy 93.769153 -290.962851) (xy 93.819292 -290.985239) (xy 93.865702 -291.014584) (xy 93.907425 -291.050282)
			(xy 93.943598 -291.091593) (xy 93.973473 -291.137664) (xy 93.996433 -291.187543) (xy 94.012004 -291.240199)
			(xy 94.019864 -291.294543) (xy 94.020386 -291.321998) (xy 94.019858 -291.350485) (xy 94.011385 -291.406825)
			(xy 93.994627 -291.461278) (xy 93.969957 -291.512634) (xy 93.937924 -291.559749) (xy 93.89924 -291.601577)
			(xy 93.854766 -291.637186) (xy 93.830394 -291.651944) (xy 93.822901 -291.656723) (xy 93.811487 -291.670327)
			(xy 93.805395 -291.687008) (xy 93.804994 -291.695886) (xy 93.804994 -291.74821) (xy 93.805321 -291.757105)
			(xy 93.811396 -291.773825) (xy 93.82284 -291.787445) (xy 93.830394 -291.792152) (xy 93.854767 -291.806909)
			(xy 93.899242 -291.842518) (xy 93.937927 -291.884345) (xy 93.96996 -291.931461) (xy 93.994631 -291.982817)
			(xy 94.011389 -292.037271) (xy 94.019863 -292.093611) (xy 94.020386 -292.122098) (xy 94.019958 -292.147933)
			(xy 94.012992 -292.199131) (xy 93.999185 -292.248922) (xy 93.978792 -292.296397) (xy 93.952183 -292.340688)
			(xy 93.919845 -292.380988) (xy 93.882369 -292.416559) (xy 93.861636 -292.431978) (xy 93.851984 -292.438582)
			(xy 93.841062 -292.459156) (xy 93.838014 -292.525196) (xy 93.838064 -292.535761) (xy 93.845674 -292.555446)
			(xy 93.852746 -292.563296) (xy 99.123754 -297.834304) (xy 99.130605 -297.841701) (xy 99.138345 -297.860299)
			(xy 99.13874 -297.870372) (xy 99.13874 -303.96815) (xy 99.139204 -303.978026) (xy 99.146649 -303.996321)
			(xy 99.153218 -304.00371) (xy 99.153472 -304.003964) (xy 103.238554 -308.089046) (xy 103.239062 -308.089554)
			(xy 103.246444 -308.096135) (xy 103.264743 -308.103582) (xy 103.274622 -308.104032) (xy 116.87556 -308.104032)
			(xy 116.885625 -308.104467) (xy 116.90421 -308.1122) (xy 116.911628 -308.119018) (xy 117.85854 -309.06593)
			(xy 117.859048 -309.066438) (xy 117.866428 -309.073023) (xy 117.884727 -309.080477) (xy 117.894608 -309.080916)
			(xy 125.446028 -309.080916)
		)
		(stroke
			(width 0)
			(type solid)
		)
		(fill yes)
		(layer "In9.Cu")
		(net "GND")
	)
	(gr_poly
		(pts
			(xy 333.688436 -309.080408) (xy 333.69885 -309.078884) (xy 333.70901 -309.07609) (xy 333.725266 -309.062882)
			(xy 333.730346 -309.05323) (xy 333.730346 -309.052976) (xy 333.743518 -309.028317) (xy 333.775979 -308.982801)
			(xy 333.814731 -308.942506) (xy 333.858944 -308.908292) (xy 333.907674 -308.880892) (xy 333.959879 -308.860891)
			(xy 334.014442 -308.848717) (xy 334.070198 -308.84463) (xy 334.125954 -308.848717) (xy 334.180517 -308.860891)
			(xy 334.232722 -308.880892) (xy 334.281452 -308.908292) (xy 334.325665 -308.942506) (xy 334.364417 -308.982801)
			(xy 334.396878 -309.028317) (xy 334.41005 -309.052976) (xy 334.41005 -309.053484) (xy 334.413447 -309.059469)
			(xy 334.422839 -309.069521) (xy 334.428592 -309.073296) (xy 334.428846 -309.073296) (xy 334.434961 -309.076778)
			(xy 334.448484 -309.080647) (xy 334.455516 -309.080916) (xy 334.697578 -309.080916) (xy 334.704436 -309.080408)
			(xy 334.71485 -309.078884) (xy 334.72501 -309.07609) (xy 334.741266 -309.062882) (xy 334.746346 -309.05323)
			(xy 334.746346 -309.052976) (xy 334.759518 -309.028317) (xy 334.791979 -308.982801) (xy 334.830731 -308.942506)
			(xy 334.874944 -308.908292) (xy 334.923674 -308.880892) (xy 334.975879 -308.860891) (xy 335.030442 -308.848717)
			(xy 335.086198 -308.84463) (xy 335.141954 -308.848717) (xy 335.196517 -308.860891) (xy 335.248722 -308.880892)
			(xy 335.297452 -308.908292) (xy 335.341665 -308.942506) (xy 335.380417 -308.982801) (xy 335.412878 -309.028317)
			(xy 335.42605 -309.052976) (xy 335.42605 -309.053484) (xy 335.429447 -309.059469) (xy 335.438839 -309.069521)
			(xy 335.444592 -309.073296) (xy 335.444846 -309.073296) (xy 335.450961 -309.076778) (xy 335.464484 -309.080647)
			(xy 335.471516 -309.080916) (xy 335.713578 -309.080916) (xy 335.720436 -309.080408) (xy 335.73085 -309.078884)
			(xy 335.74101 -309.07609) (xy 335.757266 -309.062882) (xy 335.762346 -309.05323) (xy 335.762346 -309.052976)
			(xy 335.775518 -309.028317) (xy 335.807979 -308.982801) (xy 335.846731 -308.942506) (xy 335.890944 -308.908292)
			(xy 335.939674 -308.880892) (xy 335.991879 -308.860891) (xy 336.046442 -308.848717) (xy 336.102198 -308.84463)
			(xy 336.157954 -308.848717) (xy 336.212517 -308.860891) (xy 336.264722 -308.880892) (xy 336.313452 -308.908292)
			(xy 336.357665 -308.942506) (xy 336.396417 -308.982801) (xy 336.428878 -309.028317) (xy 336.44205 -309.052976)
			(xy 336.44205 -309.053484) (xy 336.445447 -309.059469) (xy 336.454839 -309.069521) (xy 336.460592 -309.073296)
			(xy 336.460846 -309.073296) (xy 336.466961 -309.076778) (xy 336.480484 -309.080647) (xy 336.487516 -309.080916)
			(xy 336.729578 -309.080916) (xy 336.736436 -309.080408) (xy 336.74685 -309.078884) (xy 336.75701 -309.07609)
			(xy 336.773266 -309.062882) (xy 336.778346 -309.05323) (xy 336.778346 -309.052976) (xy 336.791518 -309.028317)
			(xy 336.823979 -308.982801) (xy 336.862731 -308.942506) (xy 336.906944 -308.908292) (xy 336.955674 -308.880892)
			(xy 337.007879 -308.860891) (xy 337.062442 -308.848717) (xy 337.118198 -308.84463) (xy 337.173954 -308.848717)
			(xy 337.228517 -308.860891) (xy 337.280722 -308.880892) (xy 337.329452 -308.908292) (xy 337.373665 -308.942506)
			(xy 337.412417 -308.982801) (xy 337.444878 -309.028317) (xy 337.45805 -309.052976) (xy 337.45805 -309.053484)
			(xy 337.461447 -309.059469) (xy 337.470839 -309.069521) (xy 337.476592 -309.073296) (xy 337.476846 -309.073296)
			(xy 337.482961 -309.076778) (xy 337.496484 -309.080647) (xy 337.503516 -309.080916) (xy 337.745578 -309.080916)
			(xy 337.752436 -309.080408) (xy 337.76285 -309.078884) (xy 337.77301 -309.07609) (xy 337.789266 -309.062882)
			(xy 337.794346 -309.05323) (xy 337.794346 -309.052976) (xy 337.807518 -309.028317) (xy 337.839979 -308.982801)
			(xy 337.878731 -308.942506) (xy 337.922944 -308.908292) (xy 337.971674 -308.880892) (xy 338.023879 -308.860891)
			(xy 338.078442 -308.848717) (xy 338.134198 -308.84463) (xy 338.189954 -308.848717) (xy 338.244517 -308.860891)
			(xy 338.296722 -308.880892) (xy 338.345452 -308.908292) (xy 338.389665 -308.942506) (xy 338.428417 -308.982801)
			(xy 338.460878 -309.028317) (xy 338.47405 -309.052976) (xy 338.47405 -309.053484) (xy 338.477447 -309.059469)
			(xy 338.486839 -309.069521) (xy 338.492592 -309.073296) (xy 338.492846 -309.073296) (xy 338.498961 -309.076778)
			(xy 338.512484 -309.080647) (xy 338.519516 -309.080916) (xy 338.761578 -309.080916) (xy 338.768436 -309.080408)
			(xy 338.77885 -309.078884) (xy 338.78901 -309.07609) (xy 338.805266 -309.062882) (xy 338.810346 -309.05323)
			(xy 338.810346 -309.052976) (xy 338.823518 -309.028317) (xy 338.855979 -308.982801) (xy 338.894731 -308.942506)
			(xy 338.938944 -308.908292) (xy 338.987674 -308.880892) (xy 339.039879 -308.860891) (xy 339.094442 -308.848717)
			(xy 339.150198 -308.84463) (xy 339.205954 -308.848717) (xy 339.260517 -308.860891) (xy 339.312722 -308.880892)
			(xy 339.361452 -308.908292) (xy 339.405665 -308.942506) (xy 339.444417 -308.982801) (xy 339.476878 -309.028317)
			(xy 339.49005 -309.052976) (xy 339.49005 -309.053484) (xy 339.493447 -309.059469) (xy 339.502839 -309.069521)
			(xy 339.508592 -309.073296) (xy 339.508846 -309.073296) (xy 339.514961 -309.076778) (xy 339.528484 -309.080647)
			(xy 339.535516 -309.080916) (xy 339.777578 -309.080916) (xy 339.784436 -309.080408) (xy 339.79485 -309.078884)
			(xy 339.80501 -309.07609) (xy 339.821266 -309.062882) (xy 339.826346 -309.05323) (xy 339.826346 -309.052976)
			(xy 339.839518 -309.028317) (xy 339.871979 -308.982801) (xy 339.910731 -308.942506) (xy 339.954944 -308.908292)
			(xy 340.003674 -308.880892) (xy 340.055879 -308.860891) (xy 340.110442 -308.848717) (xy 340.166198 -308.84463)
			(xy 340.221954 -308.848717) (xy 340.276517 -308.860891) (xy 340.328722 -308.880892) (xy 340.377452 -308.908292)
			(xy 340.421665 -308.942506) (xy 340.460417 -308.982801) (xy 340.492878 -309.028317) (xy 340.50605 -309.052976)
			(xy 340.50605 -309.053484) (xy 340.509447 -309.059469) (xy 340.518839 -309.069521) (xy 340.524592 -309.073296)
			(xy 340.524846 -309.073296) (xy 340.530961 -309.076778) (xy 340.544484 -309.080647) (xy 340.551516 -309.080916)
			(xy 340.793578 -309.080916) (xy 340.800436 -309.080408) (xy 340.81085 -309.078884) (xy 340.82101 -309.07609)
			(xy 340.837266 -309.062882) (xy 340.842346 -309.05323) (xy 340.842346 -309.052976) (xy 340.855518 -309.028317)
			(xy 340.887979 -308.982801) (xy 340.926731 -308.942506) (xy 340.970944 -308.908292) (xy 341.019674 -308.880892)
			(xy 341.071879 -308.860891) (xy 341.126442 -308.848717) (xy 341.182198 -308.84463) (xy 341.237954 -308.848717)
			(xy 341.292517 -308.860891) (xy 341.344722 -308.880892) (xy 341.393452 -308.908292) (xy 341.437665 -308.942506)
			(xy 341.476417 -308.982801) (xy 341.508878 -309.028317) (xy 341.52205 -309.052976) (xy 341.52205 -309.053484)
			(xy 341.525447 -309.059469) (xy 341.534839 -309.069521) (xy 341.540592 -309.073296) (xy 341.540846 -309.073296)
			(xy 341.546961 -309.076778) (xy 341.560484 -309.080647) (xy 341.567516 -309.080916) (xy 341.809578 -309.080916)
			(xy 341.816436 -309.080408) (xy 341.82685 -309.078884) (xy 341.83701 -309.07609) (xy 341.853266 -309.062882)
			(xy 341.858346 -309.05323) (xy 341.858346 -309.052976) (xy 341.871518 -309.028317) (xy 341.903979 -308.982801)
			(xy 341.942731 -308.942506) (xy 341.986944 -308.908292) (xy 342.035674 -308.880892) (xy 342.087879 -308.860891)
			(xy 342.142442 -308.848717) (xy 342.198198 -308.84463) (xy 342.253954 -308.848717) (xy 342.308517 -308.860891)
			(xy 342.360722 -308.880892) (xy 342.409452 -308.908292) (xy 342.453665 -308.942506) (xy 342.492417 -308.982801)
			(xy 342.524878 -309.028317) (xy 342.53805 -309.052976) (xy 342.53805 -309.053484) (xy 342.541447 -309.059469)
			(xy 342.550839 -309.069521) (xy 342.556592 -309.073296) (xy 342.556846 -309.073296) (xy 342.562961 -309.076778)
			(xy 342.576484 -309.080647) (xy 342.583516 -309.080916) (xy 357.646224 -309.080916) (xy 357.656384 -309.07609)
			(xy 357.681925 -309.064601) (xy 357.735536 -309.048404) (xy 357.790942 -309.040235) (xy 357.818944 -309.039768)
			(xy 357.846943 -309.040268) (xy 357.902339 -309.048457) (xy 357.955948 -309.064639) (xy 357.981504 -309.07609)
			(xy 357.991664 -309.080916) (xy 358.662224 -309.080916) (xy 358.672384 -309.07609) (xy 358.697925 -309.064601)
			(xy 358.751536 -309.048404) (xy 358.806942 -309.040235) (xy 358.834944 -309.039768) (xy 358.862943 -309.040268)
			(xy 358.918339 -309.048457) (xy 358.971948 -309.064639) (xy 358.997504 -309.07609) (xy 359.007664 -309.080916)
			(xy 359.678224 -309.080916) (xy 359.688384 -309.07609) (xy 359.713925 -309.064601) (xy 359.767536 -309.048404)
			(xy 359.822942 -309.040235) (xy 359.850944 -309.039768) (xy 359.878943 -309.040268) (xy 359.934339 -309.048457)
			(xy 359.987948 -309.064639) (xy 360.013504 -309.07609) (xy 360.023664 -309.080916) (xy 360.694224 -309.080916)
			(xy 360.704384 -309.07609) (xy 360.729925 -309.064601) (xy 360.783536 -309.048404) (xy 360.838942 -309.040235)
			(xy 360.866944 -309.039768) (xy 360.894943 -309.040268) (xy 360.950339 -309.048457) (xy 361.003948 -309.064639)
			(xy 361.029504 -309.07609) (xy 361.039664 -309.080916) (xy 361.710224 -309.080916) (xy 361.720384 -309.07609)
			(xy 361.745925 -309.064601) (xy 361.799536 -309.048404) (xy 361.854942 -309.040235) (xy 361.882944 -309.039768)
			(xy 361.910943 -309.040268) (xy 361.966339 -309.048457) (xy 362.019948 -309.064639) (xy 362.045504 -309.07609)
			(xy 362.055664 -309.080916) (xy 362.726224 -309.080916) (xy 362.736384 -309.07609) (xy 362.761925 -309.064601)
			(xy 362.815536 -309.048404) (xy 362.870942 -309.040235) (xy 362.898944 -309.039768) (xy 362.926943 -309.040268)
			(xy 362.982339 -309.048457) (xy 363.035948 -309.064639) (xy 363.061504 -309.07609) (xy 363.071664 -309.080916)
			(xy 363.742224 -309.080916) (xy 363.752384 -309.07609) (xy 363.777925 -309.064601) (xy 363.831536 -309.048404)
			(xy 363.886942 -309.040235) (xy 363.914944 -309.039768) (xy 363.942943 -309.040268) (xy 363.998339 -309.048457)
			(xy 364.051948 -309.064639) (xy 364.077504 -309.07609) (xy 364.087664 -309.080916) (xy 364.758224 -309.080916)
			(xy 364.768384 -309.07609) (xy 364.793925 -309.064601) (xy 364.847536 -309.048404) (xy 364.902942 -309.040235)
			(xy 364.930944 -309.039768) (xy 364.958943 -309.040268) (xy 365.014339 -309.048457) (xy 365.067948 -309.064639)
			(xy 365.093504 -309.07609) (xy 365.103664 -309.080916) (xy 365.774224 -309.080916) (xy 365.784384 -309.07609)
			(xy 365.809925 -309.064601) (xy 365.863536 -309.048404) (xy 365.918942 -309.040235) (xy 365.946944 -309.039768)
			(xy 365.974943 -309.040268) (xy 366.030339 -309.048457) (xy 366.083948 -309.064639) (xy 366.109504 -309.07609)
			(xy 366.119664 -309.080916) (xy 366.97285 -309.080916) (xy 366.982725 -309.08045) (xy 367.001017 -309.073001)
			(xy 367.00841 -309.066438) (xy 367.008664 -309.066184) (xy 370.451126 -305.623722) (xy 370.453734 -305.620974)
			(xy 370.458198 -305.614854) (xy 370.460016 -305.61153) (xy 370.950744 -304.693574) (xy 370.974385 -304.650692)
			(xy 371.028846 -304.569306) (xy 371.091021 -304.493649) (xy 371.125242 -304.458624) (xy 373.694452 -301.889414)
			(xy 373.731638 -301.853097) (xy 373.812323 -301.787561) (xy 373.855488 -301.758604) (xy 373.865761 -301.751135)
			(xy 373.877904 -301.728867) (xy 373.878602 -301.716186) (xy 373.878602 -301.341536) (xy 373.878116 -301.331574)
			(xy 373.870529 -301.313149) (xy 373.86387 -301.305722) (xy 373.663972 -301.10557) (xy 373.503444 -300.945042)
			(xy 373.502682 -300.944534) (xy 373.485504 -300.927216) (xy 373.45633 -300.888127) (xy 373.433748 -300.844895)
			(xy 373.418333 -300.798619) (xy 373.410478 -300.750481) (xy 373.409972 -300.726094) (xy 373.409972 -284.619192)
			(xy 373.410579 -284.59208) (xy 373.420201 -284.538716) (xy 373.439104 -284.487893) (xy 373.45239 -284.464252)
			(xy 373.455692 -284.458918) (xy 373.458232 -284.451044) (xy 373.460671 -284.442459) (xy 373.460009 -284.424636)
			(xy 373.456962 -284.416246) (xy 373.449596 -284.398212) (xy 373.4435 -284.391354) (xy 373.425495 -284.370296)
			(xy 373.395122 -284.323961) (xy 373.371766 -284.273722) (xy 373.355917 -284.220634) (xy 373.347907 -284.165813)
			(xy 373.347906 -284.110411) (xy 373.355912 -284.055589) (xy 373.371758 -284.002501) (xy 373.395111 -283.95226)
			(xy 373.42548 -283.905923) (xy 373.4435 -283.884878) (xy 373.449596 -283.87802) (xy 373.456962 -283.859986)
			(xy 373.459948 -283.851585) (xy 373.460608 -283.833781) (xy 373.458232 -283.825188) (xy 373.455692 -283.817314)
			(xy 373.45239 -283.81198) (xy 373.439111 -283.788335) (xy 373.420213 -283.737511) (xy 373.410573 -283.684151)
			(xy 373.409972 -283.65704) (xy 373.409972 -279.594056) (xy 373.41009 -279.58896) (xy 373.412146 -279.578979)
			(xy 373.414036 -279.574244) (xy 373.417846 -279.5651) (xy 373.469408 -279.513538) (xy 373.57177 -279.410922)
			(xy 373.863616 -279.119076) (xy 373.870432 -279.111734) (xy 373.878169 -279.09327) (xy 373.878602 -279.083262)
			(xy 373.878602 -273.417792) (xy 373.878537 -273.413985) (xy 373.877392 -273.406458) (xy 373.876316 -273.402806)
			(xy 373.870474 -273.38401) (xy 373.867172 -273.378676) (xy 373.815312 -273.292253) (xy 373.718057 -273.115692)
			(xy 373.62834 -272.935183) (xy 373.54632 -272.75105) (xy 373.472142 -272.563619) (xy 373.405941 -272.373226)
			(xy 373.347832 -272.180208) (xy 373.29792 -271.98491) (xy 373.256294 -271.78768) (xy 373.223028 -271.588869)
			(xy 373.210074 -271.488916) (xy 373.209058 -271.48028) (xy 373.201692 -271.465294) (xy 370.090446 -268.354048)
			(xy 370.083603 -268.346649) (xy 370.07588 -268.32805) (xy 370.07546 -268.31798) (xy 370.07546 -262.197342)
			(xy 370.075025 -262.187277) (xy 370.067291 -262.168692) (xy 370.060474 -262.161274) (xy 369.603782 -261.704582)
			(xy 369.59667 -261.697216) (xy 369.577874 -261.689596) (xy 364.540038 -261.689596) (xy 364.508405 -261.689103)
			(xy 364.44568 -261.68085) (xy 364.384569 -261.66448) (xy 364.326117 -261.640272) (xy 364.271326 -261.608642)
			(xy 364.221132 -261.570131) (xy 364.176394 -261.525397) (xy 364.137879 -261.475206) (xy 364.106245 -261.420417)
			(xy 364.082033 -261.361967) (xy 364.065657 -261.300857) (xy 364.057399 -261.238133) (xy 364.057399 -261.174867)
			(xy 364.065657 -261.112143) (xy 364.082033 -261.051033) (xy 364.106245 -260.992583) (xy 364.137879 -260.937794)
			(xy 364.176394 -260.887603) (xy 364.221132 -260.842869) (xy 364.271326 -260.804358) (xy 364.326117 -260.772728)
			(xy 364.384569 -260.74852) (xy 364.44568 -260.73215) (xy 364.508405 -260.723897) (xy 364.540038 -260.72338)
			(xy 368.37747 -260.72338) (xy 368.392451 -260.722811) (xy 368.421107 -260.714048) (xy 368.445993 -260.697355)
			(xy 368.46497 -260.674164) (xy 368.47641 -260.646468) (xy 368.47933 -260.616645) (xy 368.473479 -260.587256)
			(xy 368.45936 -260.560825) (xy 368.449098 -260.549898) (xy 368.436652 -260.537452) (xy 368.429808 -260.530053)
			(xy 368.422082 -260.511455) (xy 368.421666 -260.501384) (xy 368.421666 -255.60655) (xy 368.421233 -255.596485)
			(xy 368.413502 -255.577896) (xy 368.40668 -255.570482) (xy 362.816394 -249.980196) (xy 362.809282 -249.97283)
			(xy 362.790486 -249.96521) (xy 361.04703 -249.96521) (xy 361.037081 -249.965751) (xy 361.018712 -249.97342)
			(xy 361.004614 -249.987472) (xy 361.000294 -249.996452) (xy 360.994198 -250.01093) (xy 361.00004 -250.040902)
			(xy 363.663484 -252.704092) (xy 363.681568 -252.722885) (xy 363.712196 -252.765097) (xy 363.73584 -252.811582)
			(xy 363.751919 -252.861194) (xy 363.760035 -252.912711) (xy 363.760512 -252.938788) (xy 363.760512 -255.362964)
			(xy 364.277908 -255.362964) (xy 364.281979 -255.307342) (xy 364.294105 -255.252905) (xy 364.314028 -255.200814)
			(xy 364.341324 -255.152179) (xy 364.37541 -255.108036) (xy 364.415559 -255.069327) (xy 364.460917 -255.036876)
			(xy 364.510517 -255.011375) (xy 364.563301 -254.993368) (xy 364.618144 -254.983238) (xy 364.673878 -254.981201)
			(xy 364.729315 -254.987301) (xy 364.783272 -255.001407) (xy 364.834601 -255.023219) (xy 364.882207 -255.052273)
			(xy 364.925075 -255.087948) (xy 364.962292 -255.129485) (xy 364.993065 -255.175998) (xy 365.016737 -255.226495)
			(xy 365.032805 -255.279902) (xy 365.040925 -255.335078) (xy 365.041434 -255.362964) (xy 365.040925 -255.39085)
			(xy 365.032805 -255.446026) (xy 365.016737 -255.499433) (xy 364.993065 -255.54993) (xy 364.962292 -255.596443)
			(xy 364.925075 -255.63798) (xy 364.882207 -255.673655) (xy 364.834601 -255.702709) (xy 364.783272 -255.724521)
			(xy 364.729315 -255.738627) (xy 364.673878 -255.744727) (xy 364.618144 -255.74269) (xy 364.563301 -255.73256)
			(xy 364.510517 -255.714553) (xy 364.460917 -255.689052) (xy 364.415559 -255.656601) (xy 364.37541 -255.617892)
			(xy 364.341324 -255.573749) (xy 364.314028 -255.525114) (xy 364.294105 -255.473023) (xy 364.281979 -255.418586)
			(xy 364.277908 -255.362964) (xy 363.760512 -255.362964) (xy 363.760512 -256.605024) (xy 365.598708 -256.605024)
			(xy 365.602779 -256.549402) (xy 365.614905 -256.494965) (xy 365.634828 -256.442874) (xy 365.662124 -256.394239)
			(xy 365.69621 -256.350096) (xy 365.736359 -256.311387) (xy 365.781717 -256.278936) (xy 365.831317 -256.253435)
			(xy 365.884101 -256.235428) (xy 365.938944 -256.225298) (xy 365.994678 -256.223261) (xy 366.050115 -256.229361)
			(xy 366.104072 -256.243467) (xy 366.155401 -256.265279) (xy 366.203007 -256.294333) (xy 366.245875 -256.330008)
			(xy 366.283092 -256.371545) (xy 366.313865 -256.418058) (xy 366.337537 -256.468555) (xy 366.353605 -256.521962)
			(xy 366.361725 -256.577138) (xy 366.362234 -256.605024) (xy 366.361725 -256.63291) (xy 366.353605 -256.688086)
			(xy 366.337537 -256.741493) (xy 366.313865 -256.79199) (xy 366.283092 -256.838503) (xy 366.245875 -256.88004)
			(xy 366.203007 -256.915715) (xy 366.155401 -256.944769) (xy 366.104072 -256.966581) (xy 366.050115 -256.980687)
			(xy 365.994678 -256.986787) (xy 365.938944 -256.98475) (xy 365.884101 -256.97462) (xy 365.831317 -256.956613)
			(xy 365.781717 -256.931112) (xy 365.736359 -256.898661) (xy 365.69621 -256.859952) (xy 365.662124 -256.815809)
			(xy 365.634828 -256.767174) (xy 365.614905 -256.715083) (xy 365.602779 -256.660646) (xy 365.598708 -256.605024)
			(xy 363.760512 -256.605024) (xy 363.760512 -258.639818) (xy 363.760049 -258.665896) (xy 363.751933 -258.717417)
			(xy 363.735857 -258.767034) (xy 363.712216 -258.813525) (xy 363.681594 -258.855744) (xy 363.663484 -258.874514)
			(xy 363.29366 -259.244338) (xy 363.28731 -259.255006) (xy 363.285278 -259.260848) (xy 363.276844 -259.286408)
			(xy 363.253794 -259.335045) (xy 363.224138 -259.379961) (xy 363.188465 -259.420265) (xy 363.147482 -259.455155)
			(xy 363.102004 -259.483941) (xy 363.052932 -259.506051) (xy 363.00124 -259.521046) (xy 362.947953 -259.528629)
			(xy 362.921042 -259.529072) (xy 362.893788 -259.528612) (xy 362.839835 -259.520859) (xy 362.787534 -259.505506)
			(xy 362.737951 -259.482866) (xy 362.692095 -259.453398) (xy 362.6509 -259.417704) (xy 362.615205 -259.37651)
			(xy 362.585737 -259.330655) (xy 362.563096 -259.281072) (xy 362.547742 -259.228771) (xy 362.539989 -259.174818)
			(xy 362.539534 -259.147564) (xy 362.539992 -259.12065) (xy 362.547552 -259.067356) (xy 362.562531 -259.015654)
			(xy 362.584631 -258.966572) (xy 362.613413 -258.921086) (xy 362.648305 -258.880098) (xy 362.688614 -258.844424)
			(xy 362.733539 -258.814773) (xy 362.782186 -258.791733) (xy 362.807758 -258.783328) (xy 362.8136 -258.781296)
			(xy 362.824268 -258.774946) (xy 362.925106 -258.674108) (xy 362.931667 -258.667007) (xy 362.939368 -258.649292)
			(xy 362.939959 -258.629985) (xy 362.937044 -258.620768) (xy 362.904278 -258.530852) (xy 362.88091 -258.512818)
			(xy 362.866178 -258.511548) (xy 362.838051 -258.50853) (xy 362.783063 -258.495251) (xy 362.730639 -258.473999)
			(xy 362.681926 -258.44524) (xy 362.637994 -258.409604) (xy 362.599805 -258.367872) (xy 362.568196 -258.32096)
			(xy 362.543859 -258.269894) (xy 362.527329 -258.215795) (xy 362.518968 -258.159848) (xy 362.518452 -258.131564)
			(xy 362.518932 -258.104429) (xy 362.526627 -258.050706) (xy 362.541857 -257.998616) (xy 362.564314 -257.94921)
			(xy 362.593545 -257.903484) (xy 362.628961 -257.862362) (xy 362.669846 -257.826673) (xy 362.715376 -257.797138)
			(xy 362.764631 -257.774352) (xy 362.816619 -257.758775) (xy 362.870289 -257.750722) (xy 362.89742 -257.750056)
			(xy 362.900214 -257.750056) (xy 362.921087 -257.750353) (xy 362.962582 -257.754939) (xy 362.983018 -257.7592)
			(xy 362.983526 -257.7592) (xy 362.994762 -257.761028) (xy 363.016902 -257.755867) (xy 363.026198 -257.749294)
			(xy 363.07776 -257.707892) (xy 363.086424 -257.700361) (xy 363.096453 -257.679734) (xy 363.097064 -257.668268)
			(xy 363.097064 -254.65786) (xy 363.096376 -254.646414) (xy 363.086355 -254.625824) (xy 363.07776 -254.618236)
			(xy 363.026198 -254.576834) (xy 363.016931 -254.570207) (xy 362.994768 -254.565072) (xy 362.983526 -254.566928)
			(xy 362.983018 -254.566928) (xy 362.963083 -254.571102) (xy 362.92261 -254.575679) (xy 362.902246 -254.576072)
			(xy 362.89742 -254.576072) (xy 362.870292 -254.575411) (xy 362.816628 -254.567358) (xy 362.764647 -254.551782)
			(xy 362.715398 -254.528997) (xy 362.669875 -254.499464) (xy 362.628996 -254.463777) (xy 362.593587 -254.422658)
			(xy 362.564362 -254.376936) (xy 362.541911 -254.327534) (xy 362.526687 -254.275449) (xy 362.518997 -254.221732)
			(xy 362.518997 -254.167468) (xy 362.526687 -254.113751) (xy 362.541911 -254.061666) (xy 362.564362 -254.012264)
			(xy 362.593587 -253.966542) (xy 362.628996 -253.925423) (xy 362.669875 -253.889736) (xy 362.715399 -253.860202)
			(xy 362.764648 -253.837418) (xy 362.816629 -253.821842) (xy 362.870292 -253.813789) (xy 362.89742 -253.813056)
			(xy 362.900214 -253.813056) (xy 362.921087 -253.813353) (xy 362.962582 -253.817939) (xy 362.983018 -253.8222)
			(xy 362.983526 -253.8222) (xy 362.994762 -253.824028) (xy 363.016902 -253.818867) (xy 363.026198 -253.812294)
			(xy 363.07776 -253.770892) (xy 363.086424 -253.763361) (xy 363.096453 -253.742734) (xy 363.097064 -253.731268)
			(xy 363.097064 -253.647194) (xy 363.096471 -253.636247) (xy 363.087237 -253.616389) (xy 363.079284 -253.60884)
			(xy 363.031024 -253.567184) (xy 363.026679 -253.563665) (xy 363.016811 -253.558412) (xy 363.011466 -253.55677)
			(xy 363.00029 -253.553722) (xy 362.983235 -253.556677) (xy 362.948764 -253.559858) (xy 362.931456 -253.560072)
			(xy 362.904542 -253.559613) (xy 362.851248 -253.552052) (xy 362.799547 -253.537073) (xy 362.750466 -253.514973)
			(xy 362.70498 -253.48619) (xy 362.663993 -253.451298) (xy 362.62832 -253.41099) (xy 362.598668 -253.366066)
			(xy 362.575628 -253.317418) (xy 362.56722 -253.291848) (xy 362.565188 -253.286006) (xy 362.558838 -253.275338)
			(xy 359.702608 -250.419108) (xy 359.693157 -250.410671) (xy 359.668901 -250.403465) (xy 359.65638 -250.405392)
			(xy 359.572052 -250.422918) (xy 359.552748 -250.439428) (xy 359.547922 -250.45162) (xy 359.537072 -250.478121)
			(xy 359.508584 -250.527795) (xy 359.472992 -250.572654) (xy 359.431097 -250.61169) (xy 359.383838 -250.644026)
			(xy 359.332277 -250.668937) (xy 359.277573 -250.685864) (xy 359.220953 -250.694424) (xy 359.192322 -250.694952)
			(xy 359.16535 -250.694481) (xy 359.111945 -250.686872) (xy 359.060144 -250.671817) (xy 359.01098 -250.649616)
			(xy 358.965433 -250.620711) (xy 358.924411 -250.58568) (xy 358.888733 -250.54522) (xy 358.859108 -250.500138)
			(xy 358.836129 -250.451332) (xy 358.820253 -250.399777) (xy 358.811797 -250.3465) (xy 358.810814 -250.31954)
			(xy 358.810814 -250.31319) (xy 358.811253 -250.28769) (xy 358.818076 -250.237149) (xy 358.831572 -250.187968)
			(xy 358.851501 -250.141023) (xy 358.864154 -250.11888) (xy 358.864408 -250.118372) (xy 358.868599 -250.110519)
			(xy 358.871764 -250.093014) (xy 358.868745 -250.075483) (xy 358.864662 -250.067572) (xy 358.820974 -249.990864)
			(xy 358.816244 -249.983249) (xy 358.802566 -249.971681) (xy 358.785736 -249.965542) (xy 358.776778 -249.96521)
			(xy 335.327752 -249.96521) (xy 335.317686 -249.965642) (xy 335.299095 -249.97337) (xy 335.291684 -249.980196)
			(xy 335.05902 -250.21286) (xy 335.051654 -250.219972) (xy 335.044034 -250.238768) (xy 335.044034 -250.951492)
			(xy 335.044542 -250.957842) (xy 335.045809 -250.965586) (xy 335.052397 -250.979818) (xy 335.057496 -250.985782)
			(xy 335.063084 -250.990862) (xy 335.133442 -251.047758) (xy 335.155794 -251.053092) (xy 335.167224 -251.050552)
			(xy 335.18717 -251.046501) (xy 335.227644 -251.042176) (xy 335.247996 -251.041916) (xy 335.2546 -251.041916)
			(xy 335.286664 -251.04309) (xy 335.349736 -251.054844) (xy 335.380076 -251.065284) (xy 335.391252 -251.069602)
			(xy 335.414874 -251.067062) (xy 335.503012 -251.01042) (xy 335.515204 -250.9901) (xy 335.51622 -250.978162)
			(xy 335.518987 -250.949821) (xy 335.531856 -250.894352) (xy 335.552825 -250.841412) (xy 335.581428 -250.792176)
			(xy 335.617031 -250.747737) (xy 335.658843 -250.709083) (xy 335.705934 -250.677071) (xy 335.75726 -250.652413)
			(xy 335.811681 -250.635657) (xy 335.867987 -250.627174) (xy 335.896458 -250.626626) (xy 335.925304 -250.627153)
			(xy 335.982338 -250.635836) (xy 336.037414 -250.65301) (xy 336.089275 -250.678285) (xy 336.136737 -250.711082)
			(xy 336.178718 -250.750653) (xy 336.21426 -250.796097) (xy 336.242552 -250.846375) (xy 336.262948 -250.900341)
			(xy 336.274983 -250.956763) (xy 336.277204 -250.985528) (xy 336.277966 -250.996704) (xy 336.28838 -251.016262)
			(xy 336.367882 -251.07646) (xy 336.38998 -251.081286) (xy 336.400902 -251.078746) (xy 336.421094 -251.074597)
			(xy 336.462078 -251.070139) (xy 336.48269 -251.069856) (xy 336.48523 -251.069856) (xy 336.516972 -251.070659)
			(xy 336.579529 -251.081519) (xy 336.60969 -251.091446) (xy 336.62112 -251.09551) (xy 336.644488 -251.092716)
			(xy 336.732626 -251.033788) (xy 336.744056 -251.013214) (xy 336.744818 -251.001022) (xy 336.74686 -250.9721)
			(xy 336.758592 -250.915322) (xy 336.778781 -250.860973) (xy 336.806961 -250.810304) (xy 336.842483 -250.764483)
			(xy 336.884529 -250.724564) (xy 336.932132 -250.691467) (xy 336.984195 -250.665955) (xy 337.039519 -250.648614)
			(xy 337.096829 -250.639843) (xy 337.125818 -250.639326) (xy 337.152088 -250.63976) (xy 337.204131 -250.646962)
			(xy 337.254692 -250.661243) (xy 337.302813 -250.68233) (xy 337.347584 -250.709825) (xy 337.368134 -250.726194)
			(xy 337.3755 -250.73229) (xy 337.393534 -250.738132) (xy 337.481164 -250.733306) (xy 337.498436 -250.725432)
			(xy 337.505294 -250.718574) (xy 337.52697 -250.697286) (xy 337.575822 -250.661169) (xy 337.629778 -250.63325)
			(xy 337.687477 -250.614232) (xy 337.74746 -250.604596) (xy 337.777836 -250.60402) (xy 337.80741 -250.604556)
			(xy 337.865856 -250.613645) (xy 337.922199 -250.631645) (xy 337.975088 -250.658127) (xy 338.023256 -250.692454)
			(xy 338.04479 -250.712732) (xy 338.051648 -250.71959) (xy 338.06892 -250.726956) (xy 338.156804 -250.72975)
			(xy 338.174584 -250.723654) (xy 338.18195 -250.717304) (xy 338.202809 -250.7) (xy 338.248494 -250.670843)
			(xy 338.297845 -250.648443) (xy 338.349868 -250.63325) (xy 338.403518 -250.62557) (xy 338.430616 -250.625102)
			(xy 338.457866 -250.625589) (xy 338.511812 -250.633348) (xy 338.564104 -250.648704) (xy 338.613678 -250.671347)
			(xy 338.659526 -250.700813) (xy 338.700713 -250.736505) (xy 338.736402 -250.777695) (xy 338.765866 -250.823545)
			(xy 338.788505 -250.873121) (xy 338.803858 -250.925414) (xy 338.811612 -250.97936) (xy 338.812124 -251.00661)
			(xy 338.81193 -251.023271) (xy 338.809003 -251.056465) (xy 338.806282 -251.072904) (xy 338.803996 -251.086366)
			(xy 338.81314 -251.111766) (xy 338.90077 -251.186188) (xy 338.927186 -251.191014) (xy 338.94014 -251.186442)
			(xy 338.970854 -251.17637) (xy 339.034569 -251.165519) (xy 339.066886 -251.164852) (xy 339.091965 -251.165232)
			(xy 339.141695 -251.17178) (xy 339.190132 -251.184805) (xy 339.213444 -251.194062) (xy 339.226398 -251.19965)
			(xy 339.25383 -251.19584) (xy 339.34527 -251.122688) (xy 339.355176 -251.09678) (xy 339.352636 -251.083064)
			(xy 339.350012 -251.066872) (xy 339.347211 -251.034188) (xy 339.347048 -251.017786) (xy 339.347512 -250.99053)
			(xy 339.355272 -250.936572) (xy 339.370632 -250.884268) (xy 339.39328 -250.834682) (xy 339.422754 -250.788824)
			(xy 339.458454 -250.747628) (xy 339.499654 -250.711931) (xy 339.545515 -250.682462) (xy 339.595103 -250.659819)
			(xy 339.647409 -250.644464) (xy 339.701367 -250.636709) (xy 339.75588 -250.636713) (xy 339.809838 -250.644474)
			(xy 339.862142 -250.659836) (xy 339.911727 -250.682485) (xy 339.957584 -250.71196) (xy 339.991292 -250.741173)
			(xy 354.92786 -250.741173) (xy 354.935613 -250.687223) (xy 354.950965 -250.634926) (xy 354.973603 -250.585345)
			(xy 355.003067 -250.539492) (xy 355.038757 -250.498298) (xy 355.079945 -250.462602) (xy 355.125795 -250.433131)
			(xy 355.175371 -250.410485) (xy 355.227666 -250.395126) (xy 355.281615 -250.387364) (xy 355.336119 -250.387359)
			(xy 355.390069 -250.395111) (xy 355.442366 -250.410462) (xy 355.491947 -250.433099) (xy 355.537801 -250.462562)
			(xy 355.578996 -250.49825) (xy 355.614693 -250.539438) (xy 355.644165 -250.585287) (xy 355.666812 -250.634863)
			(xy 355.682173 -250.687158) (xy 355.689935 -250.741106) (xy 355.690424 -250.768358) (xy 355.690217 -250.786829)
			(xy 355.686654 -250.823597) (xy 355.683312 -250.841764) (xy 355.681034 -250.856522) (xy 355.684063 -250.886212)
			(xy 355.695534 -250.913764) (xy 355.71447 -250.93683) (xy 355.73926 -250.953448) (xy 355.767791 -250.962201)
			(xy 355.797635 -250.962345) (xy 355.81209 -250.958604) (xy 355.838774 -250.951129) (xy 355.893603 -250.943096)
			(xy 355.92131 -250.942602) (xy 355.94856 -250.943089) (xy 356.002506 -250.950846) (xy 356.054798 -250.966202)
			(xy 356.104373 -250.988844) (xy 356.150221 -251.01831) (xy 356.191409 -251.054001) (xy 356.227098 -251.09519)
			(xy 356.256563 -251.141039) (xy 356.279202 -251.190614) (xy 356.294556 -251.242907) (xy 356.302312 -251.296853)
			(xy 356.302312 -251.32411) (xy 357.063292 -251.32411) (xy 357.067363 -251.268488) (xy 357.079489 -251.214051)
			(xy 357.099412 -251.16196) (xy 357.126708 -251.113325) (xy 357.160794 -251.069182) (xy 357.200943 -251.030473)
			(xy 357.246301 -250.998022) (xy 357.295901 -250.972521) (xy 357.348685 -250.954514) (xy 357.403528 -250.944384)
			(xy 357.459262 -250.942347) (xy 357.514699 -250.948447) (xy 357.568656 -250.962553) (xy 357.619985 -250.984365)
			(xy 357.667591 -251.013419) (xy 357.710459 -251.049094) (xy 357.747676 -251.090631) (xy 357.778449 -251.137144)
			(xy 357.802121 -251.187641) (xy 357.818189 -251.241048) (xy 357.826309 -251.296224) (xy 357.826818 -251.32411)
			(xy 357.826309 -251.351996) (xy 357.818189 -251.407172) (xy 357.802121 -251.460579) (xy 357.778449 -251.511076)
			(xy 357.747676 -251.557589) (xy 357.710459 -251.599126) (xy 357.667591 -251.634801) (xy 357.619985 -251.663855)
			(xy 357.568656 -251.685667) (xy 357.514699 -251.699773) (xy 357.459262 -251.705873) (xy 357.403528 -251.703836)
			(xy 357.348685 -251.693706) (xy 357.295901 -251.675699) (xy 357.246301 -251.650198) (xy 357.200943 -251.617747)
			(xy 357.160794 -251.579038) (xy 357.126708 -251.534895) (xy 357.099412 -251.48626) (xy 357.079489 -251.434169)
			(xy 357.067363 -251.379732) (xy 357.063292 -251.32411) (xy 356.302312 -251.32411) (xy 356.302312 -251.351354)
			(xy 356.294555 -251.405299) (xy 356.2792 -251.457592) (xy 356.25656 -251.507167) (xy 356.227094 -251.553016)
			(xy 356.191404 -251.594204) (xy 356.150216 -251.629894) (xy 356.104367 -251.65936) (xy 356.054792 -251.682)
			(xy 356.002499 -251.697355) (xy 355.948554 -251.705112) (xy 355.894053 -251.705112) (xy 355.840107 -251.697356)
			(xy 355.787814 -251.682002) (xy 355.738239 -251.659363) (xy 355.69239 -251.629898) (xy 355.651201 -251.594209)
			(xy 355.61551 -251.553021) (xy 355.586044 -251.507173) (xy 355.563402 -251.457598) (xy 355.548046 -251.405306)
			(xy 355.540289 -251.35136) (xy 355.539802 -251.32411) (xy 355.540004 -251.305639) (xy 355.54357 -251.268871)
			(xy 355.546914 -251.250704) (xy 355.549191 -251.235948) (xy 355.546155 -251.206261) (xy 355.534681 -251.178715)
			(xy 355.515745 -251.155652) (xy 355.490958 -251.139035) (xy 355.462431 -251.130279) (xy 355.432591 -251.130128)
			(xy 355.418136 -251.133864) (xy 355.39145 -251.141333) (xy 355.336623 -251.14937) (xy 355.308916 -251.149866)
			(xy 355.281664 -251.149439) (xy 355.227714 -251.141685) (xy 355.175418 -251.126332) (xy 355.125838 -251.103692)
			(xy 355.079985 -251.074228) (xy 355.038791 -251.038537) (xy 355.003097 -250.997348) (xy 354.973627 -250.951498)
			(xy 354.950982 -250.901921) (xy 354.935624 -250.849625) (xy 354.927864 -250.795677) (xy 354.92786 -250.741173)
			(xy 339.991292 -250.741173) (xy 339.99878 -250.747662) (xy 340.034475 -250.788862) (xy 340.063943 -250.834724)
			(xy 340.086584 -250.884313) (xy 340.101938 -250.936619) (xy 340.109691 -250.990577) (xy 340.109687 -251.04509)
			(xy 340.101924 -251.099048) (xy 340.086561 -251.151351) (xy 340.06391 -251.200936) (xy 340.034434 -251.246792)
			(xy 339.998731 -251.287987) (xy 339.95753 -251.323681) (xy 339.911667 -251.353148) (xy 339.862078 -251.375788)
			(xy 339.809772 -251.39114) (xy 339.755813 -251.398892) (xy 339.728556 -251.399294) (xy 339.703476 -251.398917)
			(xy 339.653746 -251.392373) (xy 339.605306 -251.379351) (xy 339.581998 -251.370084) (xy 339.569044 -251.364496)
			(xy 339.541612 -251.368306) (xy 339.450172 -251.441458) (xy 339.440266 -251.467366) (xy 339.442806 -251.481082)
			(xy 339.445428 -251.497274) (xy 339.448225 -251.529958) (xy 339.448394 -251.54636) (xy 339.447908 -251.573611)
			(xy 339.440152 -251.627559) (xy 339.424797 -251.679854) (xy 339.402155 -251.729431) (xy 339.372689 -251.775281)
			(xy 339.336998 -251.816472) (xy 339.295807 -251.852163) (xy 339.249957 -251.881629) (xy 339.20038 -251.904271)
			(xy 339.148085 -251.919626) (xy 339.113724 -251.924566) (xy 350.94113 -251.924566) (xy 350.945201 -251.868944)
			(xy 350.957327 -251.814507) (xy 350.97725 -251.762416) (xy 351.004546 -251.713781) (xy 351.038632 -251.669638)
			(xy 351.078781 -251.630929) (xy 351.124139 -251.598478) (xy 351.173739 -251.572977) (xy 351.226523 -251.55497)
			(xy 351.281366 -251.54484) (xy 351.3371 -251.542803) (xy 351.392537 -251.548903) (xy 351.446494 -251.563009)
			(xy 351.497823 -251.584821) (xy 351.545429 -251.613875) (xy 351.588297 -251.64955) (xy 351.625514 -251.691087)
			(xy 351.656287 -251.7376) (xy 351.679959 -251.788097) (xy 351.696027 -251.841504) (xy 351.704147 -251.89668)
			(xy 351.704656 -251.924566) (xy 351.704147 -251.952452) (xy 351.696027 -252.007628) (xy 351.679959 -252.061035)
			(xy 351.656287 -252.111532) (xy 351.655797 -252.112272) (xy 352.47275 -252.112272) (xy 352.476821 -252.05665)
			(xy 352.488947 -252.002213) (xy 352.50887 -251.950122) (xy 352.536166 -251.901487) (xy 352.570252 -251.857344)
			(xy 352.610401 -251.818635) (xy 352.655759 -251.786184) (xy 352.705359 -251.760683) (xy 352.758143 -251.742676)
			(xy 352.812986 -251.732546) (xy 352.86872 -251.730509) (xy 352.924157 -251.736609) (xy 352.978114 -251.750715)
			(xy 353.029443 -251.772527) (xy 353.077049 -251.801581) (xy 353.119917 -251.837256) (xy 353.157134 -251.878793)
			(xy 353.187907 -251.925306) (xy 353.211579 -251.975803) (xy 353.227647 -252.02921) (xy 353.230115 -252.045978)
			(xy 359.438954 -252.045978) (xy 359.443025 -251.990356) (xy 359.455151 -251.935919) (xy 359.475074 -251.883828)
			(xy 359.50237 -251.835193) (xy 359.536456 -251.79105) (xy 359.576605 -251.752341) (xy 359.621963 -251.71989)
			(xy 359.671563 -251.694389) (xy 359.724347 -251.676382) (xy 359.77919 -251.666252) (xy 359.834924 -251.664215)
			(xy 359.890361 -251.670315) (xy 359.944318 -251.684421) (xy 359.995647 -251.706233) (xy 360.043253 -251.735287)
			(xy 360.086121 -251.770962) (xy 360.123338 -251.812499) (xy 360.154111 -251.859012) (xy 360.177783 -251.909509)
			(xy 360.193851 -251.962916) (xy 360.201971 -252.018092) (xy 360.20248 -252.045978) (xy 360.201971 -252.073864)
			(xy 360.193851 -252.12904) (xy 360.177783 -252.182447) (xy 360.154111 -252.232944) (xy 360.123338 -252.279457)
			(xy 360.086121 -252.320994) (xy 360.043253 -252.356669) (xy 359.995647 -252.385723) (xy 359.944318 -252.407535)
			(xy 359.890361 -252.421641) (xy 359.834924 -252.427741) (xy 359.77919 -252.425704) (xy 359.724347 -252.415574)
			(xy 359.671563 -252.397567) (xy 359.621963 -252.372066) (xy 359.576605 -252.339615) (xy 359.536456 -252.300906)
			(xy 359.50237 -252.256763) (xy 359.475074 -252.208128) (xy 359.455151 -252.156037) (xy 359.443025 -252.1016)
			(xy 359.438954 -252.045978) (xy 353.230115 -252.045978) (xy 353.235767 -252.084386) (xy 353.236276 -252.112272)
			(xy 353.235767 -252.140158) (xy 353.227647 -252.195334) (xy 353.211579 -252.248741) (xy 353.187907 -252.299238)
			(xy 353.157134 -252.345751) (xy 353.119917 -252.387288) (xy 353.077049 -252.422963) (xy 353.029443 -252.452017)
			(xy 352.978114 -252.473829) (xy 352.924157 -252.487935) (xy 352.86872 -252.494035) (xy 352.812986 -252.491998)
			(xy 352.758143 -252.481868) (xy 352.705359 -252.463861) (xy 352.655759 -252.43836) (xy 352.610401 -252.405909)
			(xy 352.570252 -252.3672) (xy 352.536166 -252.323057) (xy 352.50887 -252.274422) (xy 352.488947 -252.222331)
			(xy 352.476821 -252.167894) (xy 352.47275 -252.112272) (xy 351.655797 -252.112272) (xy 351.625514 -252.158045)
			(xy 351.588297 -252.199582) (xy 351.545429 -252.235257) (xy 351.497823 -252.264311) (xy 351.446494 -252.286123)
			(xy 351.392537 -252.300229) (xy 351.3371 -252.306329) (xy 351.281366 -252.304292) (xy 351.226523 -252.294162)
			(xy 351.173739 -252.276155) (xy 351.124139 -252.250654) (xy 351.078781 -252.218203) (xy 351.038632 -252.179494)
			(xy 351.004546 -252.135351) (xy 350.97725 -252.086716) (xy 350.957327 -252.034625) (xy 350.945201 -251.980188)
			(xy 350.94113 -251.924566) (xy 339.113724 -251.924566) (xy 339.094137 -251.927382) (xy 339.039635 -251.927382)
			(xy 338.985687 -251.919626) (xy 338.933392 -251.904271) (xy 338.883815 -251.881629) (xy 338.837965 -251.852163)
			(xy 338.796774 -251.816472) (xy 338.761083 -251.775281) (xy 338.731617 -251.729431) (xy 338.708975 -251.679854)
			(xy 338.69362 -251.627559) (xy 338.685864 -251.573611) (xy 338.685378 -251.54636) (xy 338.685574 -251.529699)
			(xy 338.688503 -251.496505) (xy 338.69122 -251.480066) (xy 338.693506 -251.466604) (xy 338.684362 -251.441204)
			(xy 338.596732 -251.366782) (xy 338.570316 -251.361956) (xy 338.557362 -251.366528) (xy 338.526648 -251.376601)
			(xy 338.462933 -251.387452) (xy 338.430616 -251.388118) (xy 338.404107 -251.387664) (xy 338.351599 -251.380328)
			(xy 338.300612 -251.365793) (xy 338.252128 -251.34434) (xy 338.207081 -251.316383) (xy 338.166337 -251.282459)
			(xy 338.148168 -251.26315) (xy 338.140962 -251.255825) (xy 338.122346 -251.247173) (xy 338.1121 -251.246386)
			(xy 338.080096 -251.24537) (xy 338.069906 -251.245518) (xy 338.050909 -251.252853) (xy 338.043266 -251.259594)
			(xy 338.018374 -251.281692) (xy 338.031871 -251.304407) (xy 338.053161 -251.352765) (xy 338.067578 -251.403598)
			(xy 338.074845 -251.455933) (xy 338.07527 -251.482352) (xy 338.074767 -251.510787) (xy 338.066351 -251.56703)
			(xy 338.058506 -251.594366) (xy 338.056492 -251.601727) (xy 338.056478 -251.616982) (xy 338.058506 -251.624338)
			(xy 338.066335 -251.651678) (xy 338.074758 -251.707918) (xy 338.07527 -251.736352) (xy 338.074784 -251.763603)
			(xy 338.067028 -251.817551) (xy 338.051673 -251.869846) (xy 338.029031 -251.919423) (xy 337.999565 -251.965273)
			(xy 337.963874 -252.006464) (xy 337.922683 -252.042155) (xy 337.876833 -252.071621) (xy 337.827256 -252.094263)
			(xy 337.774961 -252.109618) (xy 337.721013 -252.117374) (xy 337.666511 -252.117374) (xy 337.612563 -252.109618)
			(xy 337.560268 -252.094263) (xy 337.510691 -252.071621) (xy 337.464841 -252.042155) (xy 337.42365 -252.006464)
			(xy 337.387959 -251.965273) (xy 337.358493 -251.919423) (xy 337.335851 -251.869846) (xy 337.320496 -251.817551)
			(xy 337.31274 -251.763603) (xy 337.312254 -251.736352) (xy 337.312721 -251.707852) (xy 337.321144 -251.651479)
			(xy 337.329018 -251.624084) (xy 337.330946 -251.616777) (xy 337.330953 -251.601671) (xy 337.329018 -251.594366)
			(xy 337.321934 -251.569794) (xy 337.313647 -251.51933) (xy 337.312508 -251.493782) (xy 337.312508 -251.493528)
			(xy 337.312 -251.482352) (xy 337.307174 -251.4727) (xy 337.304677 -251.467769) (xy 337.297882 -251.459056)
			(xy 337.293712 -251.455428) (xy 337.225132 -251.399802) (xy 337.204304 -251.394468) (xy 337.193128 -251.3965)
			(xy 337.176439 -251.39927) (xy 337.142734 -251.402194) (xy 337.125818 -251.402342) (xy 337.093437 -251.4017)
			(xy 337.029594 -251.390842) (xy 336.998818 -251.380752) (xy 336.987388 -251.376688) (xy 336.96402 -251.379482)
			(xy 336.875882 -251.43841) (xy 336.864452 -251.458984) (xy 336.86369 -251.471176) (xy 336.861648 -251.500098)
			(xy 336.849916 -251.556877) (xy 336.829728 -251.611227) (xy 336.801548 -251.661897) (xy 336.766026 -251.707719)
			(xy 336.72398 -251.747639) (xy 336.676377 -251.780736) (xy 336.624314 -251.80625) (xy 336.56899 -251.823592)
			(xy 336.511679 -251.832364) (xy 336.48269 -251.832872) (xy 336.453842 -251.832349) (xy 336.396802 -251.823671)
			(xy 336.34172 -251.806501) (xy 336.289853 -251.78123) (xy 336.242385 -251.748434) (xy 336.200398 -251.708862)
			(xy 336.164851 -251.663417) (xy 336.136556 -251.613136) (xy 336.116157 -251.559166) (xy 336.10412 -251.50274)
			(xy 336.101944 -251.47397) (xy 336.101182 -251.462794) (xy 336.090768 -251.443236) (xy 336.011266 -251.383038)
			(xy 335.989168 -251.378212) (xy 335.978246 -251.380752) (xy 335.958053 -251.384898) (xy 335.91707 -251.389351)
			(xy 335.896458 -251.389642) (xy 335.896204 -251.389642) (xy 335.862537 -251.388944) (xy 335.796237 -251.377182)
			(xy 335.764378 -251.366274) (xy 335.753202 -251.361956) (xy 335.72958 -251.364496) (xy 335.641442 -251.421138)
			(xy 335.62925 -251.441458) (xy 335.628234 -251.453396) (xy 335.625463 -251.481736) (xy 335.612589 -251.537201)
			(xy 335.591616 -251.590138) (xy 335.563011 -251.63937) (xy 335.527408 -251.683807) (xy 335.485598 -251.72246)
			(xy 335.438509 -251.754471) (xy 335.387186 -251.779131) (xy 335.332769 -251.795892) (xy 335.276466 -251.804381)
			(xy 335.247996 -251.804932) (xy 335.227644 -251.804662) (xy 335.187171 -251.80034) (xy 335.167224 -251.796296)
			(xy 335.155794 -251.793756) (xy 335.133442 -251.79909) (xy 335.063084 -251.855986) (xy 335.057496 -251.861066)
			(xy 335.05241 -251.867039) (xy 335.045824 -251.881266) (xy 335.044542 -251.889006) (xy 335.044034 -251.895356)
			(xy 335.044034 -252.546612) (xy 335.043812 -252.553652) (xy 335.039948 -252.56719) (xy 335.036414 -252.573282)
			(xy 335.032858 -252.579378) (xy 335.029048 -252.592586) (xy 335.029048 -253.05512) (xy 350.523808 -253.05512)
			(xy 350.527879 -252.999498) (xy 350.540005 -252.945061) (xy 350.559928 -252.89297) (xy 350.587224 -252.844335)
			(xy 350.62131 -252.800192) (xy 350.661459 -252.761483) (xy 350.706817 -252.729032) (xy 350.756417 -252.703531)
			(xy 350.809201 -252.685524) (xy 350.864044 -252.675394) (xy 350.919778 -252.673357) (xy 350.975215 -252.679457)
			(xy 351.029172 -252.693563) (xy 351.080501 -252.715375) (xy 351.128107 -252.744429) (xy 351.170975 -252.780104)
			(xy 351.208192 -252.821641) (xy 351.238965 -252.868154) (xy 351.262637 -252.918651) (xy 351.278705 -252.972058)
			(xy 351.286825 -253.027234) (xy 351.287334 -253.05512) (xy 351.286825 -253.083006) (xy 351.278705 -253.138182)
			(xy 351.262637 -253.191589) (xy 351.238965 -253.242086) (xy 351.208192 -253.288599) (xy 351.170975 -253.330136)
			(xy 351.128107 -253.365811) (xy 351.091979 -253.38786) (xy 358.443274 -253.38786) (xy 358.447345 -253.332238)
			(xy 358.459471 -253.277801) (xy 358.479394 -253.22571) (xy 358.50669 -253.177075) (xy 358.540776 -253.132932)
			(xy 358.580925 -253.094223) (xy 358.626283 -253.061772) (xy 358.675883 -253.036271) (xy 358.728667 -253.018264)
			(xy 358.78351 -253.008134) (xy 358.839244 -253.006097) (xy 358.894681 -253.012197) (xy 358.948638 -253.026303)
			(xy 358.999967 -253.048115) (xy 359.047573 -253.077169) (xy 359.090441 -253.112844) (xy 359.127658 -253.154381)
			(xy 359.143657 -253.178564) (xy 360.485942 -253.178564) (xy 360.490013 -253.122942) (xy 360.502139 -253.068505)
			(xy 360.522062 -253.016414) (xy 360.549358 -252.967779) (xy 360.583444 -252.923636) (xy 360.623593 -252.884927)
			(xy 360.668951 -252.852476) (xy 360.718551 -252.826975) (xy 360.771335 -252.808968) (xy 360.826178 -252.798838)
			(xy 360.881912 -252.796801) (xy 360.937349 -252.802901) (xy 360.991306 -252.817007) (xy 361.042635 -252.838819)
			(xy 361.090241 -252.867873) (xy 361.133109 -252.903548) (xy 361.170326 -252.945085) (xy 361.201099 -252.991598)
			(xy 361.224771 -253.042095) (xy 361.240839 -253.095502) (xy 361.248959 -253.150678) (xy 361.249468 -253.178564)
			(xy 361.248959 -253.20645) (xy 361.240839 -253.261626) (xy 361.224771 -253.315033) (xy 361.201099 -253.36553)
			(xy 361.170326 -253.412043) (xy 361.133109 -253.45358) (xy 361.090241 -253.489255) (xy 361.042635 -253.518309)
			(xy 360.991306 -253.540121) (xy 360.937349 -253.554227) (xy 360.881912 -253.560327) (xy 360.826178 -253.55829)
			(xy 360.771335 -253.54816) (xy 360.718551 -253.530153) (xy 360.668951 -253.504652) (xy 360.623593 -253.472201)
			(xy 360.583444 -253.433492) (xy 360.549358 -253.389349) (xy 360.522062 -253.340714) (xy 360.502139 -253.288623)
			(xy 360.490013 -253.234186) (xy 360.485942 -253.178564) (xy 359.143657 -253.178564) (xy 359.158431 -253.200894)
			(xy 359.182103 -253.251391) (xy 359.198171 -253.304798) (xy 359.206291 -253.359974) (xy 359.2068 -253.38786)
			(xy 359.206291 -253.415746) (xy 359.198171 -253.470922) (xy 359.182103 -253.524329) (xy 359.158431 -253.574826)
			(xy 359.127658 -253.621339) (xy 359.090441 -253.662876) (xy 359.047573 -253.698551) (xy 358.999967 -253.727605)
			(xy 358.948638 -253.749417) (xy 358.894681 -253.763523) (xy 358.839244 -253.769623) (xy 358.78351 -253.767586)
			(xy 358.728667 -253.757456) (xy 358.675883 -253.739449) (xy 358.626283 -253.713948) (xy 358.580925 -253.681497)
			(xy 358.540776 -253.642788) (xy 358.50669 -253.598645) (xy 358.479394 -253.55001) (xy 358.459471 -253.497919)
			(xy 358.447345 -253.443482) (xy 358.443274 -253.38786) (xy 351.091979 -253.38786) (xy 351.080501 -253.394865)
			(xy 351.029172 -253.416677) (xy 350.975215 -253.430783) (xy 350.919778 -253.436883) (xy 350.864044 -253.434846)
			(xy 350.809201 -253.424716) (xy 350.756417 -253.406709) (xy 350.706817 -253.381208) (xy 350.661459 -253.348757)
			(xy 350.62131 -253.310048) (xy 350.587224 -253.265905) (xy 350.559928 -253.21727) (xy 350.540005 -253.165179)
			(xy 350.527879 -253.110742) (xy 350.523808 -253.05512) (xy 335.029048 -253.05512) (xy 335.029048 -254.148844)
			(xy 349.868234 -254.148844) (xy 349.872305 -254.093222) (xy 349.884431 -254.038785) (xy 349.904354 -253.986694)
			(xy 349.93165 -253.938059) (xy 349.965736 -253.893916) (xy 350.005885 -253.855207) (xy 350.051243 -253.822756)
			(xy 350.100843 -253.797255) (xy 350.153627 -253.779248) (xy 350.20847 -253.769118) (xy 350.264204 -253.767081)
			(xy 350.319641 -253.773181) (xy 350.373598 -253.787287) (xy 350.424927 -253.809099) (xy 350.472533 -253.838153)
			(xy 350.515401 -253.873828) (xy 350.552618 -253.915365) (xy 350.583391 -253.961878) (xy 350.594237 -253.985014)
			(xy 353.918772 -253.985014) (xy 353.922843 -253.929392) (xy 353.934969 -253.874955) (xy 353.954892 -253.822864)
			(xy 353.982188 -253.774229) (xy 354.016274 -253.730086) (xy 354.056423 -253.691377) (xy 354.101781 -253.658926)
			(xy 354.151381 -253.633425) (xy 354.204165 -253.615418) (xy 354.259008 -253.605288) (xy 354.314742 -253.603251)
			(xy 354.370179 -253.609351) (xy 354.424136 -253.623457) (xy 354.475465 -253.645269) (xy 354.523071 -253.674323)
			(xy 354.565939 -253.709998) (xy 354.603156 -253.751535) (xy 354.633929 -253.798048) (xy 354.657601 -253.848545)
			(xy 354.673669 -253.901952) (xy 354.681789 -253.957128) (xy 354.682298 -253.985014) (xy 354.681789 -254.0129)
			(xy 354.673669 -254.068076) (xy 354.657601 -254.121483) (xy 354.633929 -254.17198) (xy 354.603156 -254.218493)
			(xy 354.565939 -254.26003) (xy 354.523071 -254.295705) (xy 354.475465 -254.324759) (xy 354.424136 -254.346571)
			(xy 354.370179 -254.360677) (xy 354.314742 -254.366777) (xy 354.259008 -254.36474) (xy 354.204165 -254.35461)
			(xy 354.151381 -254.336603) (xy 354.101781 -254.311102) (xy 354.056423 -254.278651) (xy 354.016274 -254.239942)
			(xy 353.982188 -254.195799) (xy 353.954892 -254.147164) (xy 353.934969 -254.095073) (xy 353.922843 -254.040636)
			(xy 353.918772 -253.985014) (xy 350.594237 -253.985014) (xy 350.607063 -254.012375) (xy 350.623131 -254.065782)
			(xy 350.631251 -254.120958) (xy 350.63176 -254.148844) (xy 350.631251 -254.17673) (xy 350.623131 -254.231906)
			(xy 350.607063 -254.285313) (xy 350.583391 -254.33581) (xy 350.552618 -254.382323) (xy 350.515401 -254.42386)
			(xy 350.472533 -254.459535) (xy 350.424927 -254.488589) (xy 350.373598 -254.510401) (xy 350.319641 -254.524507)
			(xy 350.264204 -254.530607) (xy 350.20847 -254.52857) (xy 350.153627 -254.51844) (xy 350.100843 -254.500433)
			(xy 350.051243 -254.474932) (xy 350.005885 -254.442481) (xy 349.965736 -254.403772) (xy 349.93165 -254.359629)
			(xy 349.904354 -254.310994) (xy 349.884431 -254.258903) (xy 349.872305 -254.204466) (xy 349.868234 -254.148844)
			(xy 335.029048 -254.148844) (xy 335.029048 -255.237856) (xy 346.269219 -255.237856) (xy 346.269219 -255.183344)
			(xy 346.276977 -255.129387) (xy 346.292335 -255.077084) (xy 346.31498 -255.027498) (xy 346.344452 -254.98164)
			(xy 346.38015 -254.940443) (xy 346.421348 -254.904746) (xy 346.467207 -254.875276) (xy 346.516793 -254.852631)
			(xy 346.569097 -254.837275) (xy 346.623054 -254.829518) (xy 346.65031 -254.829056) (xy 346.681683 -254.829689)
			(xy 346.743582 -254.839968) (xy 346.802967 -254.860231) (xy 346.830904 -254.874522) (xy 346.840556 -254.879602)
			(xy 346.8624 -254.881126) (xy 346.954602 -254.846582) (xy 346.970096 -254.831342) (xy 346.973906 -254.820928)
			(xy 346.984622 -254.794133) (xy 347.012917 -254.743842) (xy 347.048464 -254.698386) (xy 347.090451 -254.658801)
			(xy 347.137921 -254.625992) (xy 347.189791 -254.600706) (xy 347.244877 -254.583519) (xy 347.301924 -254.574825)
			(xy 347.330776 -254.574294) (xy 347.35803 -254.574752) (xy 347.411984 -254.582506) (xy 347.464285 -254.59786)
			(xy 347.513868 -254.620501) (xy 347.559725 -254.649969) (xy 347.60092 -254.685663) (xy 347.636617 -254.726856)
			(xy 347.666087 -254.772711) (xy 347.688732 -254.822293) (xy 347.704089 -254.874593) (xy 347.711847 -254.928546)
			(xy 347.711847 -254.983054) (xy 347.704089 -255.037007) (xy 347.688732 -255.089307) (xy 347.666087 -255.138889)
			(xy 347.636617 -255.184744) (xy 347.633171 -255.18872) (xy 348.495618 -255.18872) (xy 348.499689 -255.133098)
			(xy 348.511815 -255.078661) (xy 348.531738 -255.02657) (xy 348.559034 -254.977935) (xy 348.59312 -254.933792)
			(xy 348.633269 -254.895083) (xy 348.678627 -254.862632) (xy 348.728227 -254.837131) (xy 348.781011 -254.819124)
			(xy 348.835854 -254.808994) (xy 348.891588 -254.806957) (xy 348.947025 -254.813057) (xy 349.000982 -254.827163)
			(xy 349.052311 -254.848975) (xy 349.099917 -254.878029) (xy 349.142785 -254.913704) (xy 349.180002 -254.955241)
			(xy 349.210775 -255.001754) (xy 349.234447 -255.052251) (xy 349.250515 -255.105658) (xy 349.251338 -255.11125)
			(xy 353.193856 -255.11125) (xy 353.197927 -255.055628) (xy 353.210053 -255.001191) (xy 353.229976 -254.9491)
			(xy 353.257272 -254.900465) (xy 353.291358 -254.856322) (xy 353.331507 -254.817613) (xy 353.376865 -254.785162)
			(xy 353.426465 -254.759661) (xy 353.479249 -254.741654) (xy 353.534092 -254.731524) (xy 353.589826 -254.729487)
			(xy 353.645263 -254.735587) (xy 353.69922 -254.749693) (xy 353.750549 -254.771505) (xy 353.798155 -254.800559)
			(xy 353.841023 -254.836234) (xy 353.87824 -254.877771) (xy 353.909013 -254.924284) (xy 353.932685 -254.974781)
			(xy 353.948753 -255.028188) (xy 353.956873 -255.083364) (xy 353.957382 -255.11125) (xy 353.956873 -255.139136)
			(xy 353.948753 -255.194312) (xy 353.932685 -255.247719) (xy 353.909013 -255.298216) (xy 353.87824 -255.344729)
			(xy 353.841023 -255.386266) (xy 353.798155 -255.421941) (xy 353.750549 -255.450995) (xy 353.69922 -255.472807)
			(xy 353.645263 -255.486913) (xy 353.589826 -255.493013) (xy 353.534092 -255.490976) (xy 353.479249 -255.480846)
			(xy 353.426465 -255.462839) (xy 353.376865 -255.437338) (xy 353.331507 -255.404887) (xy 353.291358 -255.366178)
			(xy 353.257272 -255.322035) (xy 353.229976 -255.2734) (xy 353.210053 -255.221309) (xy 353.197927 -255.166872)
			(xy 353.193856 -255.11125) (xy 349.251338 -255.11125) (xy 349.258635 -255.160834) (xy 349.259144 -255.18872)
			(xy 349.258635 -255.216606) (xy 349.250515 -255.271782) (xy 349.234447 -255.325189) (xy 349.210775 -255.375686)
			(xy 349.180002 -255.422199) (xy 349.142785 -255.463736) (xy 349.099917 -255.499411) (xy 349.052311 -255.528465)
			(xy 349.000982 -255.550277) (xy 348.947025 -255.564383) (xy 348.891588 -255.570483) (xy 348.835854 -255.568446)
			(xy 348.781011 -255.558316) (xy 348.728227 -255.540309) (xy 348.678627 -255.514808) (xy 348.633269 -255.482357)
			(xy 348.59312 -255.443648) (xy 348.559034 -255.399505) (xy 348.531738 -255.35087) (xy 348.511815 -255.298779)
			(xy 348.499689 -255.244342) (xy 348.495618 -255.18872) (xy 347.633171 -255.18872) (xy 347.60092 -255.225937)
			(xy 347.559725 -255.261631) (xy 347.513868 -255.291099) (xy 347.464285 -255.31374) (xy 347.411984 -255.329094)
			(xy 347.35803 -255.336848) (xy 347.330776 -255.33731) (xy 347.299402 -255.336686) (xy 347.237503 -255.326404)
			(xy 347.178118 -255.306137) (xy 347.150182 -255.291844) (xy 347.14053 -255.286764) (xy 347.118686 -255.28524)
			(xy 347.026484 -255.319784) (xy 347.01099 -255.335024) (xy 347.00718 -255.345438) (xy 346.996458 -255.37223)
			(xy 346.968165 -255.422523) (xy 346.93262 -255.467981) (xy 346.890634 -255.507566) (xy 346.843165 -255.540377)
			(xy 346.791295 -255.565663) (xy 346.736209 -255.582849) (xy 346.679162 -255.591542) (xy 346.65031 -255.592072)
			(xy 346.623054 -255.591682) (xy 346.569097 -255.583925) (xy 346.516793 -255.568569) (xy 346.467207 -255.545924)
			(xy 346.421348 -255.516454) (xy 346.38015 -255.480757) (xy 346.344452 -255.43956) (xy 346.31498 -255.393702)
			(xy 346.292335 -255.344116) (xy 346.276977 -255.291813) (xy 346.269219 -255.237856) (xy 335.029048 -255.237856)
			(xy 335.029048 -256.226564) (xy 358.420668 -256.226564) (xy 358.424739 -256.170942) (xy 358.436865 -256.116505)
			(xy 358.456788 -256.064414) (xy 358.484084 -256.015779) (xy 358.51817 -255.971636) (xy 358.558319 -255.932927)
			(xy 358.603677 -255.900476) (xy 358.653277 -255.874975) (xy 358.706061 -255.856968) (xy 358.760904 -255.846838)
			(xy 358.816638 -255.844801) (xy 358.872075 -255.850901) (xy 358.926032 -255.865007) (xy 358.977361 -255.886819)
			(xy 359.024967 -255.915873) (xy 359.067835 -255.951548) (xy 359.105052 -255.993085) (xy 359.135825 -256.039598)
			(xy 359.159497 -256.090095) (xy 359.175565 -256.143502) (xy 359.183685 -256.198678) (xy 359.184194 -256.226564)
			(xy 360.485942 -256.226564) (xy 360.490013 -256.170942) (xy 360.502139 -256.116505) (xy 360.522062 -256.064414)
			(xy 360.549358 -256.015779) (xy 360.583444 -255.971636) (xy 360.623593 -255.932927) (xy 360.668951 -255.900476)
			(xy 360.718551 -255.874975) (xy 360.771335 -255.856968) (xy 360.826178 -255.846838) (xy 360.881912 -255.844801)
			(xy 360.937349 -255.850901) (xy 360.991306 -255.865007) (xy 361.042635 -255.886819) (xy 361.090241 -255.915873)
			(xy 361.133109 -255.951548) (xy 361.170326 -255.993085) (xy 361.201099 -256.039598) (xy 361.224771 -256.090095)
			(xy 361.240839 -256.143502) (xy 361.248959 -256.198678) (xy 361.249468 -256.226564) (xy 361.248959 -256.25445)
			(xy 361.240839 -256.309626) (xy 361.224771 -256.363033) (xy 361.201099 -256.41353) (xy 361.170326 -256.460043)
			(xy 361.133109 -256.50158) (xy 361.090241 -256.537255) (xy 361.042635 -256.566309) (xy 360.991306 -256.588121)
			(xy 360.937349 -256.602227) (xy 360.881912 -256.608327) (xy 360.826178 -256.60629) (xy 360.771335 -256.59616)
			(xy 360.718551 -256.578153) (xy 360.668951 -256.552652) (xy 360.623593 -256.520201) (xy 360.583444 -256.481492)
			(xy 360.549358 -256.437349) (xy 360.522062 -256.388714) (xy 360.502139 -256.336623) (xy 360.490013 -256.282186)
			(xy 360.485942 -256.226564) (xy 359.184194 -256.226564) (xy 359.183685 -256.25445) (xy 359.175565 -256.309626)
			(xy 359.159497 -256.363033) (xy 359.135825 -256.41353) (xy 359.105052 -256.460043) (xy 359.067835 -256.50158)
			(xy 359.024967 -256.537255) (xy 358.977361 -256.566309) (xy 358.926032 -256.588121) (xy 358.872075 -256.602227)
			(xy 358.816638 -256.608327) (xy 358.760904 -256.60629) (xy 358.706061 -256.59616) (xy 358.653277 -256.578153)
			(xy 358.603677 -256.552652) (xy 358.558319 -256.520201) (xy 358.51817 -256.481492) (xy 358.484084 -256.437349)
			(xy 358.456788 -256.388714) (xy 358.436865 -256.336623) (xy 358.424739 -256.282186) (xy 358.420668 -256.226564)
			(xy 335.029048 -256.226564) (xy 335.029048 -257.13055) (xy 348.495618 -257.13055) (xy 348.499689 -257.074928)
			(xy 348.511815 -257.020491) (xy 348.531738 -256.9684) (xy 348.559034 -256.919765) (xy 348.59312 -256.875622)
			(xy 348.633269 -256.836913) (xy 348.678627 -256.804462) (xy 348.728227 -256.778961) (xy 348.781011 -256.760954)
			(xy 348.835854 -256.750824) (xy 348.891588 -256.748787) (xy 348.947025 -256.754887) (xy 349.000982 -256.768993)
			(xy 349.052311 -256.790805) (xy 349.099917 -256.819859) (xy 349.142785 -256.855534) (xy 349.180002 -256.897071)
			(xy 349.210775 -256.943584) (xy 349.234447 -256.994081) (xy 349.250515 -257.047488) (xy 349.258635 -257.102664)
			(xy 349.25887 -257.115564) (xy 360.485942 -257.115564) (xy 360.490013 -257.059942) (xy 360.502139 -257.005505)
			(xy 360.522062 -256.953414) (xy 360.549358 -256.904779) (xy 360.583444 -256.860636) (xy 360.623593 -256.821927)
			(xy 360.668951 -256.789476) (xy 360.718551 -256.763975) (xy 360.771335 -256.745968) (xy 360.826178 -256.735838)
			(xy 360.881912 -256.733801) (xy 360.937349 -256.739901) (xy 360.991306 -256.754007) (xy 361.042635 -256.775819)
			(xy 361.090241 -256.804873) (xy 361.133109 -256.840548) (xy 361.170326 -256.882085) (xy 361.201099 -256.928598)
			(xy 361.224771 -256.979095) (xy 361.240839 -257.032502) (xy 361.248959 -257.087678) (xy 361.249468 -257.115564)
			(xy 361.248959 -257.14345) (xy 361.240839 -257.198626) (xy 361.224771 -257.252033) (xy 361.201099 -257.30253)
			(xy 361.170326 -257.349043) (xy 361.133109 -257.39058) (xy 361.090241 -257.426255) (xy 361.042635 -257.455309)
			(xy 360.991306 -257.477121) (xy 360.937349 -257.491227) (xy 360.881912 -257.497327) (xy 360.826178 -257.49529)
			(xy 360.771335 -257.48516) (xy 360.718551 -257.467153) (xy 360.668951 -257.441652) (xy 360.623593 -257.409201)
			(xy 360.583444 -257.370492) (xy 360.549358 -257.326349) (xy 360.522062 -257.277714) (xy 360.502139 -257.225623)
			(xy 360.490013 -257.171186) (xy 360.485942 -257.115564) (xy 349.25887 -257.115564) (xy 349.259144 -257.13055)
			(xy 349.258635 -257.158436) (xy 349.250515 -257.213612) (xy 349.234447 -257.267019) (xy 349.210775 -257.317516)
			(xy 349.180002 -257.364029) (xy 349.142785 -257.405566) (xy 349.099917 -257.441241) (xy 349.052311 -257.470295)
			(xy 349.000982 -257.492107) (xy 348.947025 -257.506213) (xy 348.891588 -257.512313) (xy 348.835854 -257.510276)
			(xy 348.781011 -257.500146) (xy 348.728227 -257.482139) (xy 348.678627 -257.456638) (xy 348.633269 -257.424187)
			(xy 348.59312 -257.385478) (xy 348.559034 -257.341335) (xy 348.531738 -257.2927) (xy 348.511815 -257.240609)
			(xy 348.499689 -257.186172) (xy 348.495618 -257.13055) (xy 335.029048 -257.13055) (xy 335.029048 -257.664966)
			(xy 335.029515 -257.67484) (xy 335.036965 -257.693131) (xy 335.043526 -257.700526) (xy 335.04378 -257.70078)
			(xy 335.36255 -258.01955) (xy 348.623128 -258.01955) (xy 348.623602 -257.992297) (xy 348.631353 -257.938344)
			(xy 348.646705 -257.886044) (xy 348.669344 -257.836462) (xy 348.69881 -257.790607) (xy 348.734503 -257.749413)
			(xy 348.775696 -257.713718) (xy 348.82155 -257.684251) (xy 348.871131 -257.661609) (xy 348.923431 -257.646256)
			(xy 348.977383 -257.638503) (xy 349.004636 -257.638042) (xy 349.031693 -257.638468) (xy 349.085261 -257.646131)
			(xy 349.13721 -257.661285) (xy 349.186497 -257.683626) (xy 349.232134 -257.712706) (xy 349.273205 -257.74794)
			(xy 349.308887 -257.788624) (xy 349.338463 -257.83394) (xy 349.35033 -257.85826) (xy 349.354394 -257.866642)
			(xy 349.367602 -257.879596) (xy 349.447104 -257.913886) (xy 349.465646 -257.914648) (xy 349.474536 -257.9116)
			(xy 349.50386 -257.902475) (xy 349.564481 -257.892654) (xy 349.595186 -257.892042) (xy 349.622443 -257.892404)
			(xy 349.676403 -257.90016) (xy 349.728709 -257.915517) (xy 349.778298 -257.938162) (xy 349.824158 -257.967633)
			(xy 349.865358 -258.003332) (xy 349.901058 -258.04453) (xy 349.930531 -258.09039) (xy 349.949335 -258.131564)
			(xy 358.458768 -258.131564) (xy 358.462839 -258.075942) (xy 358.474965 -258.021505) (xy 358.494888 -257.969414)
			(xy 358.522184 -257.920779) (xy 358.55627 -257.876636) (xy 358.596419 -257.837927) (xy 358.641777 -257.805476)
			(xy 358.691377 -257.779975) (xy 358.744161 -257.761968) (xy 358.799004 -257.751838) (xy 358.854738 -257.749801)
			(xy 358.910175 -257.755901) (xy 358.964132 -257.770007) (xy 359.015461 -257.791819) (xy 359.063067 -257.820873)
			(xy 359.105935 -257.856548) (xy 359.143152 -257.898085) (xy 359.173925 -257.944598) (xy 359.197597 -257.995095)
			(xy 359.213665 -258.048502) (xy 359.221785 -258.103678) (xy 359.222294 -258.131564) (xy 359.221785 -258.15945)
			(xy 359.213665 -258.214626) (xy 359.197597 -258.268033) (xy 359.173925 -258.31853) (xy 359.143152 -258.365043)
			(xy 359.105935 -258.40658) (xy 359.063067 -258.442255) (xy 359.015461 -258.471309) (xy 358.964132 -258.493121)
			(xy 358.910175 -258.507227) (xy 358.854738 -258.513327) (xy 358.799004 -258.51129) (xy 358.744161 -258.50116)
			(xy 358.691377 -258.483153) (xy 358.641777 -258.457652) (xy 358.596419 -258.425201) (xy 358.55627 -258.386492)
			(xy 358.522184 -258.342349) (xy 358.494888 -258.293714) (xy 358.474965 -258.241623) (xy 358.462839 -258.187186)
			(xy 358.458768 -258.131564) (xy 349.949335 -258.131564) (xy 349.953178 -258.139978) (xy 349.968537 -258.192284)
			(xy 349.976295 -258.246243) (xy 349.976295 -258.300757) (xy 349.968537 -258.354716) (xy 349.953178 -258.407022)
			(xy 349.930531 -258.45661) (xy 349.901058 -258.50247) (xy 349.865358 -258.543668) (xy 349.824158 -258.579367)
			(xy 349.778298 -258.608838) (xy 349.728709 -258.631483) (xy 349.676403 -258.64684) (xy 349.622443 -258.654596)
			(xy 349.595186 -258.655058) (xy 349.574638 -258.654758) (xy 349.533782 -258.650305) (xy 349.513652 -258.646168)
			(xy 349.501714 -258.643628) (xy 349.478346 -258.649724) (xy 349.39859 -258.720336) (xy 349.3897 -258.742688)
			(xy 349.390716 -258.75488) (xy 349.392494 -258.79044) (xy 349.392008 -258.817691) (xy 349.384252 -258.871639)
			(xy 349.368897 -258.923934) (xy 349.346255 -258.973511) (xy 349.316789 -259.019361) (xy 349.281098 -259.060552)
			(xy 349.239907 -259.096243) (xy 349.194057 -259.125709) (xy 349.14448 -259.148351) (xy 349.092185 -259.163706)
			(xy 349.038237 -259.171462) (xy 348.983735 -259.171462) (xy 348.929787 -259.163706) (xy 348.877492 -259.148351)
			(xy 348.827915 -259.125709) (xy 348.782065 -259.096243) (xy 348.740874 -259.060552) (xy 348.705183 -259.019361)
			(xy 348.675717 -258.973511) (xy 348.653075 -258.923934) (xy 348.63772 -258.871639) (xy 348.629964 -258.817691)
			(xy 348.629478 -258.79044) (xy 348.630055 -258.761315) (xy 348.638916 -258.703744) (xy 348.656424 -258.648188)
			(xy 348.682173 -258.595939) (xy 348.715562 -258.548209) (xy 348.755818 -258.506109) (xy 348.778576 -258.487926)
			(xy 348.787974 -258.48056) (xy 348.798388 -258.459224) (xy 348.797626 -258.354068) (xy 348.786958 -258.332986)
			(xy 348.777052 -258.325874) (xy 348.753624 -258.307704) (xy 348.712094 -258.265398) (xy 348.677603 -258.21718)
			(xy 348.650979 -258.164211) (xy 348.632864 -258.107762) (xy 348.623692 -258.049192) (xy 348.623128 -258.01955)
			(xy 335.36255 -258.01955) (xy 336.027014 -258.684014) (xy 336.033868 -258.691409) (xy 336.04161 -258.710008)
			(xy 336.042 -258.720082) (xy 336.042 -259.020564) (xy 344.490292 -259.020564) (xy 344.494363 -258.964942)
			(xy 344.506489 -258.910505) (xy 344.526412 -258.858414) (xy 344.553708 -258.809779) (xy 344.587794 -258.765636)
			(xy 344.627943 -258.726927) (xy 344.673301 -258.694476) (xy 344.722901 -258.668975) (xy 344.775685 -258.650968)
			(xy 344.830528 -258.640838) (xy 344.886262 -258.638801) (xy 344.941699 -258.644901) (xy 344.995656 -258.659007)
			(xy 345.046985 -258.680819) (xy 345.094591 -258.709873) (xy 345.137459 -258.745548) (xy 345.174676 -258.787085)
			(xy 345.205449 -258.833598) (xy 345.229121 -258.884095) (xy 345.245189 -258.937502) (xy 345.253309 -258.992678)
			(xy 345.253818 -259.020564) (xy 345.379292 -259.020564) (xy 345.383363 -258.964942) (xy 345.395489 -258.910505)
			(xy 345.415412 -258.858414) (xy 345.442708 -258.809779) (xy 345.476794 -258.765636) (xy 345.516943 -258.726927)
			(xy 345.562301 -258.694476) (xy 345.611901 -258.668975) (xy 345.664685 -258.650968) (xy 345.719528 -258.640838)
			(xy 345.775262 -258.638801) (xy 345.830699 -258.644901) (xy 345.884656 -258.659007) (xy 345.935985 -258.680819)
			(xy 345.983591 -258.709873) (xy 346.026459 -258.745548) (xy 346.063676 -258.787085) (xy 346.094449 -258.833598)
			(xy 346.118121 -258.884095) (xy 346.134189 -258.937502) (xy 346.142309 -258.992678) (xy 346.142818 -259.020564)
			(xy 346.142309 -259.04845) (xy 346.134189 -259.103626) (xy 346.118121 -259.157033) (xy 346.094449 -259.20753)
			(xy 346.063676 -259.254043) (xy 346.026459 -259.29558) (xy 345.983591 -259.331255) (xy 345.935985 -259.360309)
			(xy 345.884656 -259.382121) (xy 345.830699 -259.396227) (xy 345.775262 -259.402327) (xy 345.719528 -259.40029)
			(xy 345.664685 -259.39016) (xy 345.611901 -259.372153) (xy 345.562301 -259.346652) (xy 345.516943 -259.314201)
			(xy 345.476794 -259.275492) (xy 345.442708 -259.231349) (xy 345.415412 -259.182714) (xy 345.395489 -259.130623)
			(xy 345.383363 -259.076186) (xy 345.379292 -259.020564) (xy 345.253818 -259.020564) (xy 345.253309 -259.04845)
			(xy 345.245189 -259.103626) (xy 345.229121 -259.157033) (xy 345.205449 -259.20753) (xy 345.174676 -259.254043)
			(xy 345.137459 -259.29558) (xy 345.094591 -259.331255) (xy 345.046985 -259.360309) (xy 344.995656 -259.382121)
			(xy 344.941699 -259.396227) (xy 344.886262 -259.402327) (xy 344.830528 -259.40029) (xy 344.775685 -259.39016)
			(xy 344.722901 -259.372153) (xy 344.673301 -259.346652) (xy 344.627943 -259.314201) (xy 344.587794 -259.275492)
			(xy 344.553708 -259.231349) (xy 344.526412 -259.182714) (xy 344.506489 -259.130623) (xy 344.494363 -259.076186)
			(xy 344.490292 -259.020564) (xy 336.042 -259.020564) (xy 336.042 -259.535422) (xy 346.407738 -259.535422)
			(xy 346.411809 -259.4798) (xy 346.423935 -259.425363) (xy 346.443858 -259.373272) (xy 346.471154 -259.324637)
			(xy 346.50524 -259.280494) (xy 346.545389 -259.241785) (xy 346.590747 -259.209334) (xy 346.640347 -259.183833)
			(xy 346.693131 -259.165826) (xy 346.747974 -259.155696) (xy 346.803708 -259.153659) (xy 346.859145 -259.159759)
			(xy 346.913102 -259.173865) (xy 346.955213 -259.19176) (xy 355.780592 -259.19176) (xy 355.784663 -259.136138)
			(xy 355.796789 -259.081701) (xy 355.816712 -259.02961) (xy 355.844008 -258.980975) (xy 355.878094 -258.936832)
			(xy 355.918243 -258.898123) (xy 355.963601 -258.865672) (xy 356.013201 -258.840171) (xy 356.065985 -258.822164)
			(xy 356.120828 -258.812034) (xy 356.176562 -258.809997) (xy 356.231999 -258.816097) (xy 356.285956 -258.830203)
			(xy 356.337285 -258.852015) (xy 356.384891 -258.881069) (xy 356.427759 -258.916744) (xy 356.464976 -258.958281)
			(xy 356.495749 -259.004794) (xy 356.519421 -259.055291) (xy 356.535489 -259.108698) (xy 356.543609 -259.163874)
			(xy 356.544118 -259.19176) (xy 356.543609 -259.219646) (xy 356.535489 -259.274822) (xy 356.519421 -259.328229)
			(xy 356.495749 -259.378726) (xy 356.464976 -259.425239) (xy 356.427759 -259.466776) (xy 356.384891 -259.502451)
			(xy 356.337285 -259.531505) (xy 356.285956 -259.553317) (xy 356.231999 -259.567423) (xy 356.176562 -259.573523)
			(xy 356.120828 -259.571486) (xy 356.065985 -259.561356) (xy 356.013201 -259.543349) (xy 355.963601 -259.517848)
			(xy 355.918243 -259.485397) (xy 355.878094 -259.446688) (xy 355.844008 -259.402545) (xy 355.816712 -259.35391)
			(xy 355.796789 -259.301819) (xy 355.784663 -259.247382) (xy 355.780592 -259.19176) (xy 346.955213 -259.19176)
			(xy 346.964431 -259.195677) (xy 347.012037 -259.224731) (xy 347.054905 -259.260406) (xy 347.092122 -259.301943)
			(xy 347.122895 -259.348456) (xy 347.146567 -259.398953) (xy 347.162635 -259.45236) (xy 347.170755 -259.507536)
			(xy 347.171264 -259.535422) (xy 347.170755 -259.563308) (xy 347.162635 -259.618484) (xy 347.146567 -259.671891)
			(xy 347.122895 -259.722388) (xy 347.092122 -259.768901) (xy 347.054905 -259.810438) (xy 347.012037 -259.846113)
			(xy 346.964431 -259.875167) (xy 346.913102 -259.896979) (xy 346.859145 -259.911085) (xy 346.803708 -259.917185)
			(xy 346.747974 -259.915148) (xy 346.693131 -259.905018) (xy 346.640347 -259.887011) (xy 346.590747 -259.86151)
			(xy 346.545389 -259.829059) (xy 346.50524 -259.79035) (xy 346.471154 -259.746207) (xy 346.443858 -259.697572)
			(xy 346.423935 -259.645481) (xy 346.411809 -259.591044) (xy 346.407738 -259.535422) (xy 336.042 -259.535422)
			(xy 336.042 -261.346442) (xy 340.147402 -261.346442) (xy 340.147836 -261.320125) (xy 340.15506 -261.26799)
			(xy 340.169377 -261.217342) (xy 340.190515 -261.16914) (xy 340.218073 -261.124299) (xy 340.25153 -261.083668)
			(xy 340.270592 -261.065518) (xy 340.277986 -261.05799) (xy 340.286515 -261.038715) (xy 340.287102 -261.02818)
			(xy 340.287102 -260.953504) (xy 340.286583 -260.942953) (xy 340.278041 -260.923658) (xy 340.270592 -260.916166)
			(xy 340.251495 -260.89805) (xy 340.218019 -260.857425) (xy 340.190451 -260.812581) (xy 340.169315 -260.76437)
			(xy 340.155014 -260.713709) (xy 340.14782 -260.661563) (xy 340.147402 -260.635242) (xy 340.147894 -260.60799)
			(xy 340.155646 -260.554039) (xy 340.170997 -260.501741) (xy 340.193635 -260.452161) (xy 340.2231 -260.406307)
			(xy 340.258791 -260.365114) (xy 340.299981 -260.329419) (xy 340.345833 -260.299951) (xy 340.395411 -260.277308)
			(xy 340.447708 -260.261953) (xy 340.501658 -260.254197) (xy 340.52891 -260.253734) (xy 340.555226 -260.25419)
			(xy 340.60736 -260.261408) (xy 340.658009 -260.27572) (xy 340.706211 -260.296853) (xy 340.751053 -260.324409)
			(xy 340.791684 -260.357863) (xy 340.809834 -260.376924) (xy 340.817351 -260.384332) (xy 340.836634 -260.392855)
			(xy 340.847172 -260.393434) (xy 340.921848 -260.393434) (xy 340.932395 -260.39288) (xy 340.95169 -260.384361)
			(xy 340.959186 -260.376924) (xy 340.977332 -260.357856) (xy 341.01795 -260.324376) (xy 341.062788 -260.296803)
			(xy 341.110993 -260.275663) (xy 341.161649 -260.261356) (xy 341.213791 -260.254156) (xy 341.24011 -260.253734)
			(xy 341.267365 -260.254146) (xy 341.32132 -260.261905) (xy 341.373621 -260.277265) (xy 341.423205 -260.299911)
			(xy 341.46906 -260.329384) (xy 341.510253 -260.365083) (xy 341.545947 -260.406282) (xy 341.575414 -260.452141)
			(xy 341.598054 -260.501727) (xy 341.613406 -260.554031) (xy 341.621158 -260.607987) (xy 341.621618 -260.635242)
			(xy 341.621167 -260.661558) (xy 341.619781 -260.671564) (xy 344.363292 -260.671564) (xy 344.367363 -260.615942)
			(xy 344.379489 -260.561505) (xy 344.399412 -260.509414) (xy 344.426708 -260.460779) (xy 344.460794 -260.416636)
			(xy 344.500943 -260.377927) (xy 344.546301 -260.345476) (xy 344.595901 -260.319975) (xy 344.648685 -260.301968)
			(xy 344.703528 -260.291838) (xy 344.759262 -260.289801) (xy 344.814699 -260.295901) (xy 344.868656 -260.310007)
			(xy 344.919985 -260.331819) (xy 344.967591 -260.360873) (xy 345.010459 -260.396548) (xy 345.047676 -260.438085)
			(xy 345.078449 -260.484598) (xy 345.102121 -260.535095) (xy 345.118189 -260.588502) (xy 345.126309 -260.643678)
			(xy 345.126818 -260.671564) (xy 345.126309 -260.69945) (xy 345.118189 -260.754626) (xy 345.102121 -260.808033)
			(xy 345.078449 -260.85853) (xy 345.047676 -260.905043) (xy 345.010459 -260.94658) (xy 344.967591 -260.982255)
			(xy 344.919985 -261.011309) (xy 344.868656 -261.033121) (xy 344.814699 -261.047227) (xy 344.759262 -261.053327)
			(xy 344.703528 -261.05129) (xy 344.648685 -261.04116) (xy 344.595901 -261.023153) (xy 344.546301 -260.997652)
			(xy 344.500943 -260.965201) (xy 344.460794 -260.926492) (xy 344.426708 -260.882349) (xy 344.399412 -260.833714)
			(xy 344.379489 -260.781623) (xy 344.367363 -260.727186) (xy 344.363292 -260.671564) (xy 341.619781 -260.671564)
			(xy 341.613946 -260.713692) (xy 341.599632 -260.76434) (xy 341.578497 -260.812542) (xy 341.550942 -260.857384)
			(xy 341.517488 -260.898016) (xy 341.498428 -260.916166) (xy 341.491043 -260.923702) (xy 341.482508 -260.942971)
			(xy 341.481918 -260.953504) (xy 341.481918 -261.02818) (xy 341.482439 -261.038731) (xy 341.490979 -261.058026)
			(xy 341.498428 -261.065518) (xy 341.517502 -261.083658) (xy 341.550984 -261.124276) (xy 341.578557 -261.169115)
			(xy 341.599697 -261.217321) (xy 341.599794 -261.217664) (xy 346.340428 -261.217664) (xy 346.344499 -261.162042)
			(xy 346.356625 -261.107605) (xy 346.376548 -261.055514) (xy 346.403844 -261.006879) (xy 346.43793 -260.962736)
			(xy 346.478079 -260.924027) (xy 346.523437 -260.891576) (xy 346.573037 -260.866075) (xy 346.625821 -260.848068)
			(xy 346.680664 -260.837938) (xy 346.736398 -260.835901) (xy 346.791835 -260.842001) (xy 346.845792 -260.856107)
			(xy 346.897121 -260.877919) (xy 346.944727 -260.906973) (xy 346.987595 -260.942648) (xy 347.024812 -260.984185)
			(xy 347.055585 -261.030698) (xy 347.079257 -261.081195) (xy 347.095325 -261.134602) (xy 347.103445 -261.189778)
			(xy 347.103954 -261.217664) (xy 347.103445 -261.24555) (xy 347.095325 -261.300726) (xy 347.079257 -261.354133)
			(xy 347.055585 -261.40463) (xy 347.024812 -261.451143) (xy 346.987595 -261.49268) (xy 346.944727 -261.528355)
			(xy 346.897121 -261.557409) (xy 346.845792 -261.579221) (xy 346.791835 -261.593327) (xy 346.736398 -261.599427)
			(xy 346.680664 -261.59739) (xy 346.625821 -261.58726) (xy 346.573037 -261.569253) (xy 346.523437 -261.543752)
			(xy 346.478079 -261.511301) (xy 346.43793 -261.472592) (xy 346.403844 -261.428449) (xy 346.376548 -261.379814)
			(xy 346.356625 -261.327723) (xy 346.344499 -261.273286) (xy 346.340428 -261.217664) (xy 341.599794 -261.217664)
			(xy 341.614001 -261.267979) (xy 341.621198 -261.320122) (xy 341.621618 -261.346442) (xy 341.621161 -261.373694)
			(xy 341.613399 -261.427642) (xy 341.598039 -261.479937) (xy 341.575394 -261.529513) (xy 341.545924 -261.575363)
			(xy 341.51023 -261.616553) (xy 341.469038 -261.652244) (xy 341.423185 -261.681709) (xy 341.373607 -261.704351)
			(xy 341.321311 -261.719706) (xy 341.267362 -261.727464) (xy 341.24011 -261.72795) (xy 341.213792 -261.727553)
			(xy 341.161655 -261.720323) (xy 341.111005 -261.706001) (xy 341.062803 -261.684856) (xy 341.017962 -261.65729)
			(xy 340.977334 -261.623825) (xy 340.959186 -261.60476) (xy 340.951664 -261.597359) (xy 340.932385 -261.588832)
			(xy 340.921848 -261.58825) (xy 340.847172 -261.58825) (xy 340.836627 -261.588819) (xy 340.817332 -261.597328)
			(xy 340.809834 -261.60476) (xy 340.791675 -261.623815) (xy 340.751061 -261.657297) (xy 340.706226 -261.684872)
			(xy 340.658023 -261.706015) (xy 340.607369 -261.720324) (xy 340.555228 -261.727527) (xy 340.52891 -261.72795)
			(xy 340.501661 -261.727413) (xy 340.447717 -261.719659) (xy 340.395426 -261.704307) (xy 340.345852 -261.68167)
			(xy 340.300003 -261.652209) (xy 340.258814 -261.616523) (xy 340.223123 -261.575338) (xy 340.193655 -261.529494)
			(xy 340.171011 -261.479923) (xy 340.155653 -261.427634) (xy 340.147891 -261.373691) (xy 340.147402 -261.346442)
			(xy 336.042 -261.346442) (xy 336.042 -262.487918) (xy 336.04246 -262.497795) (xy 336.045261 -262.504682)
			(xy 338.447378 -262.504682) (xy 338.451449 -262.44906) (xy 338.463575 -262.394623) (xy 338.483498 -262.342532)
			(xy 338.510794 -262.293897) (xy 338.54488 -262.249754) (xy 338.585029 -262.211045) (xy 338.630387 -262.178594)
			(xy 338.679987 -262.153093) (xy 338.732771 -262.135086) (xy 338.787614 -262.124956) (xy 338.843348 -262.122919)
			(xy 338.898785 -262.129019) (xy 338.952742 -262.143125) (xy 339.004071 -262.164937) (xy 339.051677 -262.193991)
			(xy 339.094545 -262.229666) (xy 339.131762 -262.271203) (xy 339.162535 -262.317716) (xy 339.186207 -262.368213)
			(xy 339.202275 -262.42162) (xy 339.210395 -262.476796) (xy 339.210904 -262.504682) (xy 339.210395 -262.532568)
			(xy 339.202275 -262.587744) (xy 339.186207 -262.641151) (xy 339.162535 -262.691648) (xy 339.154651 -262.703564)
			(xy 344.363292 -262.703564) (xy 344.367363 -262.647942) (xy 344.379489 -262.593505) (xy 344.399412 -262.541414)
			(xy 344.426708 -262.492779) (xy 344.460794 -262.448636) (xy 344.500943 -262.409927) (xy 344.546301 -262.377476)
			(xy 344.595901 -262.351975) (xy 344.648685 -262.333968) (xy 344.703528 -262.323838) (xy 344.759262 -262.321801)
			(xy 344.814699 -262.327901) (xy 344.868656 -262.342007) (xy 344.919985 -262.363819) (xy 344.967591 -262.392873)
			(xy 345.010459 -262.428548) (xy 345.047676 -262.470085) (xy 345.078449 -262.516598) (xy 345.102121 -262.567095)
			(xy 345.118189 -262.620502) (xy 345.126309 -262.675678) (xy 345.126818 -262.703564) (xy 345.126309 -262.73145)
			(xy 345.118189 -262.786626) (xy 345.102121 -262.840033) (xy 345.078449 -262.89053) (xy 345.047676 -262.937043)
			(xy 345.010459 -262.97858) (xy 344.967591 -263.014255) (xy 344.919985 -263.043309) (xy 344.868656 -263.065121)
			(xy 344.842863 -263.071864) (xy 348.582488 -263.071864) (xy 348.583047 -263.041885) (xy 348.592444 -262.982668)
			(xy 348.610986 -262.925649) (xy 348.638216 -262.872231) (xy 348.673464 -262.823728) (xy 348.694248 -262.802116)
			(xy 348.826836 -262.669528) (xy 348.833531 -262.662116) (xy 348.841166 -262.643685) (xy 348.84117 -262.623735)
			(xy 348.833542 -262.605301) (xy 348.826836 -262.5979) (xy 348.694248 -262.465312) (xy 348.673441 -262.44372)
			(xy 348.638185 -262.395217) (xy 348.610956 -262.341795) (xy 348.592423 -262.284769) (xy 348.583044 -262.225545)
			(xy 348.582488 -262.195564) (xy 348.582944 -262.168312) (xy 348.590706 -262.114363) (xy 348.606065 -262.062068)
			(xy 348.62871 -262.012491) (xy 348.65818 -261.966641) (xy 348.693874 -261.925452) (xy 348.735067 -261.889761)
			(xy 348.780919 -261.860295) (xy 348.830498 -261.837654) (xy 348.882795 -261.822299) (xy 348.936744 -261.814542)
			(xy 348.963996 -261.814056) (xy 348.993973 -261.81465) (xy 349.053188 -261.82404) (xy 349.110206 -261.842574)
			(xy 349.163625 -261.869796) (xy 349.21213 -261.905036) (xy 349.233744 -261.925816) (xy 349.354648 -262.046974)
			(xy 349.362075 -262.05378) (xy 349.380654 -262.06152) (xy 349.390716 -262.06196) (xy 350.01581 -262.06196)
			(xy 350.025881 -262.06155) (xy 350.04448 -262.05382) (xy 350.051878 -262.046974) (xy 350.215454 -261.883398)
			(xy 350.222281 -261.875987) (xy 350.23001 -261.857396) (xy 350.23044 -261.84733) (xy 350.23044 -261.13613)
			(xy 350.230957 -261.106157) (xy 350.240277 -261.046941) (xy 350.258757 -260.989916) (xy 350.285939 -260.936488)
			(xy 350.321153 -260.887977) (xy 350.341946 -260.866382) (xy 350.963992 -260.244336) (xy 350.98558 -260.223524)
			(xy 351.034084 -260.18827) (xy 351.087508 -260.161041) (xy 351.144534 -260.142509) (xy 351.203759 -260.133131)
			(xy 351.23374 -260.132576) (xy 355.454458 -260.132576) (xy 355.484435 -260.133188) (xy 355.543649 -260.142572)
			(xy 355.600667 -260.161102) (xy 355.654086 -260.18832) (xy 355.702592 -260.223557) (xy 355.724206 -260.244336)
			(xy 359.149396 -263.66978) (xy 359.156849 -263.676509) (xy 359.17543 -263.684077) (xy 359.185464 -263.684512)
			(xy 363.44479 -263.684512) (xy 363.474766 -263.685122) (xy 363.53398 -263.69451) (xy 363.590998 -263.713041)
			(xy 363.644416 -263.740259) (xy 363.692923 -263.775494) (xy 363.714538 -263.796272) (xy 373.393716 -273.47545)
			(xy 373.414517 -273.497048) (xy 373.449771 -273.54555) (xy 373.477 -273.598972) (xy 373.495535 -273.655996)
			(xy 373.504918 -273.715218) (xy 373.505476 -273.745198) (xy 373.505476 -278.003) (xy 373.504876 -278.032977)
			(xy 373.495486 -278.092191) (xy 373.476953 -278.149209) (xy 373.449733 -278.202628) (xy 373.414495 -278.251133)
			(xy 373.393716 -278.272748) (xy 369.239292 -282.426918) (xy 369.232607 -282.434406) (xy 369.225011 -282.45296)
			(xy 369.22456 -282.462986) (xy 369.22456 -302.422052) (xy 369.223934 -302.452028) (xy 369.214551 -302.511241)
			(xy 369.196025 -302.568259) (xy 369.16881 -302.621678) (xy 369.133577 -302.670185) (xy 369.1128 -302.6918)
			(xy 367.694718 -304.109882) (xy 367.673114 -304.130659) (xy 367.62459 -304.165842) (xy 367.571162 -304.193007)
			(xy 367.514144 -304.211484) (xy 367.454939 -304.220819) (xy 367.42497 -304.221388) (xy 351.006156 -304.221388)
			(xy 350.996081 -304.221767) (xy 350.977482 -304.229518) (xy 350.970088 -304.236374) (xy 350.779334 -304.427382)
			(xy 350.757723 -304.448151) (xy 350.709201 -304.483336) (xy 350.655775 -304.510502) (xy 350.598759 -304.528981)
			(xy 350.539554 -304.538318) (xy 350.509586 -304.538888) (xy 350.482354 -304.538381) (xy 350.428445 -304.530629)
			(xy 350.376187 -304.515284) (xy 350.326645 -304.492659) (xy 350.280827 -304.463214) (xy 350.239666 -304.427549)
			(xy 350.203998 -304.386389) (xy 350.174551 -304.340572) (xy 350.151923 -304.291031) (xy 350.136575 -304.238775)
			(xy 350.12882 -304.184866) (xy 350.128332 -304.157634) (xy 350.128853 -304.127661) (xy 350.138173 -304.068446)
			(xy 350.156652 -304.01142) (xy 350.183833 -303.957993) (xy 350.219046 -303.909481) (xy 350.239838 -303.887886)
			(xy 350.442276 -303.685448) (xy 350.449015 -303.678062) (xy 350.456674 -303.659612) (xy 350.456683 -303.639636)
			(xy 350.449042 -303.621179) (xy 350.442276 -303.61382) (xy 350.239838 -303.411382) (xy 350.219095 -303.389746)
			(xy 350.183906 -303.341232) (xy 350.156735 -303.287812) (xy 350.13825 -303.230801) (xy 350.128906 -303.171601)
			(xy 350.128332 -303.141634) (xy 350.12884 -303.114401) (xy 350.136587 -303.060488) (xy 350.151928 -303.008227)
			(xy 350.17455 -302.958681) (xy 350.203994 -302.912858) (xy 350.239659 -302.871693) (xy 350.28082 -302.836023)
			(xy 350.326638 -302.806573) (xy 350.376182 -302.783945) (xy 350.428441 -302.768597) (xy 350.482353 -302.760844)
			(xy 350.509586 -302.76038) (xy 350.539559 -302.760903) (xy 350.598773 -302.770225) (xy 350.655798 -302.788704)
			(xy 350.709226 -302.815884) (xy 350.757739 -302.851095) (xy 350.779334 -302.871886) (xy 350.970088 -303.062894)
			(xy 350.977499 -303.06972) (xy 350.99609 -303.077448) (xy 351.006156 -303.07788) (xy 352.929952 -303.07788)
			(xy 352.940675 -303.077297) (xy 352.960236 -303.068489) (xy 352.967798 -303.060862) (xy 353.02571 -302.996854)
			(xy 353.032314 -302.976534) (xy 353.031044 -302.965612) (xy 353.030081 -302.955671) (xy 353.029065 -302.935722)
			(xy 353.029012 -302.925734) (xy 353.029495 -302.898364) (xy 353.037308 -302.844186) (xy 353.052793 -302.791683)
			(xy 353.075631 -302.741936) (xy 353.105352 -302.695968) (xy 353.122992 -302.675036) (xy 353.129088 -302.667924)
			(xy 353.135438 -302.650906) (xy 353.135438 -302.565562) (xy 353.129088 -302.548544) (xy 353.122992 -302.541432)
			(xy 353.105353 -302.5205) (xy 353.075642 -302.474527) (xy 353.052806 -302.424779) (xy 353.037315 -302.372279)
			(xy 353.029486 -302.318103) (xy 353.029012 -302.290734) (xy 353.029498 -302.263483) (xy 353.037254 -302.209535)
			(xy 353.052609 -302.15724) (xy 353.075251 -302.107663) (xy 353.104717 -302.061813) (xy 353.140408 -302.020622)
			(xy 353.181599 -301.984931) (xy 353.227449 -301.955465) (xy 353.277026 -301.932823) (xy 353.329321 -301.917468)
			(xy 353.383269 -301.909712) (xy 353.437771 -301.909712) (xy 353.491719 -301.917468) (xy 353.544014 -301.932823)
			(xy 353.593591 -301.955465) (xy 353.639441 -301.984931) (xy 353.680632 -302.020622) (xy 353.716323 -302.061813)
			(xy 353.745789 -302.107663) (xy 353.768431 -302.15724) (xy 353.783786 -302.209535) (xy 353.791542 -302.263483)
			(xy 353.792028 -302.290734) (xy 353.791599 -302.318106) (xy 353.783775 -302.372287) (xy 353.768278 -302.424791)
			(xy 353.745428 -302.474538) (xy 353.715694 -302.520502) (xy 353.698048 -302.541432) (xy 353.691952 -302.548544)
			(xy 353.685602 -302.565562) (xy 353.685602 -302.650906) (xy 353.691952 -302.667924) (xy 353.698048 -302.675036)
			(xy 353.715662 -302.695988) (xy 353.74538 -302.741955) (xy 353.768221 -302.791697) (xy 353.783718 -302.844193)
			(xy 353.791551 -302.898366) (xy 353.792028 -302.925734) (xy 353.791976 -302.935722) (xy 353.790962 -302.955671)
			(xy 353.789996 -302.965612) (xy 353.788726 -302.976534) (xy 353.79533 -302.996854) (xy 353.853242 -303.060862)
			(xy 353.860735 -303.068584) (xy 353.880339 -303.077402) (xy 353.891088 -303.07788) (xy 356.350062 -303.07788)
			(xy 356.360786 -303.077302) (xy 356.380346 -303.06849) (xy 356.387908 -303.060862) (xy 356.44582 -302.996854)
			(xy 356.452424 -302.976534) (xy 356.451154 -302.965612) (xy 356.450191 -302.955671) (xy 356.449175 -302.935722)
			(xy 356.449122 -302.925734) (xy 356.449603 -302.898364) (xy 356.457416 -302.844186) (xy 356.472902 -302.791682)
			(xy 356.49574 -302.741935) (xy 356.525462 -302.695968) (xy 356.543102 -302.675036) (xy 356.549198 -302.667924)
			(xy 356.555548 -302.650906) (xy 356.555548 -302.565562) (xy 356.549198 -302.548544) (xy 356.543102 -302.541432)
			(xy 356.525465 -302.520498) (xy 356.495753 -302.474526) (xy 356.472916 -302.424779) (xy 356.457425 -302.372279)
			(xy 356.449596 -302.318103) (xy 356.449122 -302.290734) (xy 356.449608 -302.263483) (xy 356.457364 -302.209535)
			(xy 356.472719 -302.15724) (xy 356.495361 -302.107663) (xy 356.524827 -302.061813) (xy 356.560518 -302.020622)
			(xy 356.601709 -301.984931) (xy 356.647559 -301.955465) (xy 356.697136 -301.932823) (xy 356.749431 -301.917468)
			(xy 356.803379 -301.909712) (xy 356.857881 -301.909712) (xy 356.911829 -301.917468) (xy 356.964124 -301.932823)
			(xy 357.013701 -301.955465) (xy 357.059551 -301.984931) (xy 357.100742 -302.020622) (xy 357.136433 -302.061813)
			(xy 357.165899 -302.107663) (xy 357.188541 -302.15724) (xy 357.203896 -302.209535) (xy 357.211652 -302.263483)
			(xy 357.212138 -302.290734) (xy 357.211707 -302.318106) (xy 357.203883 -302.372287) (xy 357.188387 -302.424791)
			(xy 357.165537 -302.474537) (xy 357.135804 -302.520502) (xy 357.118158 -302.541432) (xy 357.112062 -302.548544)
			(xy 357.105712 -302.565562) (xy 357.105712 -302.650906) (xy 357.112062 -302.667924) (xy 357.118158 -302.675036)
			(xy 357.135774 -302.695987) (xy 357.165491 -302.741954) (xy 357.188332 -302.791696) (xy 357.203828 -302.844193)
			(xy 357.211661 -302.898366) (xy 357.212138 -302.925734) (xy 357.212086 -302.935722) (xy 357.211072 -302.955671)
			(xy 357.210106 -302.965612) (xy 357.208836 -302.976534) (xy 357.21544 -302.996854) (xy 357.273352 -303.060862)
			(xy 357.280841 -303.068588) (xy 357.300448 -303.077404) (xy 357.311198 -303.07788) (xy 357.738172 -303.07788)
			(xy 357.748897 -303.077307) (xy 357.768457 -303.068492) (xy 357.776018 -303.060862) (xy 357.83393 -302.996854)
			(xy 357.840534 -302.976534) (xy 357.839264 -302.965612) (xy 357.838301 -302.955671) (xy 357.837285 -302.935722)
			(xy 357.837232 -302.925734) (xy 357.83771 -302.898364) (xy 357.845524 -302.844185) (xy 357.86101 -302.791682)
			(xy 357.883849 -302.741935) (xy 357.913572 -302.695968) (xy 357.931212 -302.675036) (xy 357.937308 -302.667924)
			(xy 357.943658 -302.650906) (xy 357.943658 -302.565562) (xy 357.937308 -302.548544) (xy 357.931212 -302.541432)
			(xy 357.913576 -302.520497) (xy 357.883864 -302.474525) (xy 357.861027 -302.424779) (xy 357.845535 -302.372278)
			(xy 357.837706 -302.318103) (xy 357.837232 -302.290734) (xy 357.837718 -302.263483) (xy 357.845474 -302.209535)
			(xy 357.860829 -302.15724) (xy 357.883471 -302.107663) (xy 357.912937 -302.061813) (xy 357.948628 -302.020622)
			(xy 357.989819 -301.984931) (xy 358.035669 -301.955465) (xy 358.085246 -301.932823) (xy 358.137541 -301.917468)
			(xy 358.191489 -301.909712) (xy 358.245991 -301.909712) (xy 358.299939 -301.917468) (xy 358.352234 -301.932823)
			(xy 358.401811 -301.955465) (xy 358.447661 -301.984931) (xy 358.488852 -302.020622) (xy 358.524543 -302.061813)
			(xy 358.554009 -302.107663) (xy 358.576651 -302.15724) (xy 358.592006 -302.209535) (xy 358.599762 -302.263483)
			(xy 358.600248 -302.290734) (xy 358.599815 -302.318106) (xy 358.591991 -302.372287) (xy 358.576495 -302.424791)
			(xy 358.553645 -302.474537) (xy 358.523913 -302.520502) (xy 358.506268 -302.541432) (xy 358.500172 -302.548544)
			(xy 358.493822 -302.565562) (xy 358.493822 -302.650906) (xy 358.500172 -302.667924) (xy 358.506268 -302.675036)
			(xy 358.523886 -302.695985) (xy 358.553602 -302.741953) (xy 358.576442 -302.791696) (xy 358.591938 -302.844193)
			(xy 358.599772 -302.898366) (xy 358.600248 -302.925734) (xy 358.600196 -302.935722) (xy 358.599182 -302.955671)
			(xy 358.598216 -302.965612) (xy 358.596946 -302.976534) (xy 358.60355 -302.996854) (xy 358.661462 -303.060862)
			(xy 358.668947 -303.068593) (xy 358.688557 -303.077406) (xy 358.699308 -303.07788) (xy 359.770172 -303.07788)
			(xy 359.780897 -303.077307) (xy 359.800457 -303.068492) (xy 359.808018 -303.060862) (xy 359.86593 -302.996854)
			(xy 359.872534 -302.976534) (xy 359.871264 -302.965612) (xy 359.870301 -302.955671) (xy 359.869285 -302.935722)
			(xy 359.869232 -302.925734) (xy 359.86971 -302.898364) (xy 359.877524 -302.844185) (xy 359.89301 -302.791682)
			(xy 359.915849 -302.741935) (xy 359.945572 -302.695968) (xy 359.963212 -302.675036) (xy 359.969308 -302.667924)
			(xy 359.975658 -302.650906) (xy 359.975658 -302.565562) (xy 359.969308 -302.548544) (xy 359.963212 -302.541432)
			(xy 359.945576 -302.520497) (xy 359.915864 -302.474525) (xy 359.893027 -302.424779) (xy 359.877535 -302.372278)
			(xy 359.869706 -302.318103) (xy 359.869232 -302.290734) (xy 359.869718 -302.263483) (xy 359.877474 -302.209535)
			(xy 359.892829 -302.15724) (xy 359.915471 -302.107663) (xy 359.944937 -302.061813) (xy 359.980628 -302.020622)
			(xy 360.021819 -301.984931) (xy 360.067669 -301.955465) (xy 360.117246 -301.932823) (xy 360.169541 -301.917468)
			(xy 360.223489 -301.909712) (xy 360.277991 -301.909712) (xy 360.331939 -301.917468) (xy 360.384234 -301.932823)
			(xy 360.433811 -301.955465) (xy 360.479661 -301.984931) (xy 360.520852 -302.020622) (xy 360.556543 -302.061813)
			(xy 360.586009 -302.107663) (xy 360.608651 -302.15724) (xy 360.624006 -302.209535) (xy 360.631762 -302.263483)
			(xy 360.632248 -302.290734) (xy 360.631815 -302.318106) (xy 360.623991 -302.372287) (xy 360.608495 -302.424791)
			(xy 360.585645 -302.474537) (xy 360.555913 -302.520502) (xy 360.538268 -302.541432) (xy 360.532172 -302.548544)
			(xy 360.525822 -302.565562) (xy 360.525822 -302.650906) (xy 360.532172 -302.667924) (xy 360.538268 -302.675036)
			(xy 360.555886 -302.695985) (xy 360.585602 -302.741953) (xy 360.608442 -302.791696) (xy 360.623938 -302.844193)
			(xy 360.631772 -302.898366) (xy 360.632248 -302.925734) (xy 360.632196 -302.935722) (xy 360.631182 -302.955671)
			(xy 360.630216 -302.965612) (xy 360.628946 -302.976534) (xy 360.63555 -302.996854) (xy 360.693462 -303.060862)
			(xy 360.700947 -303.068593) (xy 360.720557 -303.077406) (xy 360.731308 -303.07788) (xy 364.578392 -303.07788)
			(xy 364.589111 -303.077264) (xy 364.608672 -303.068479) (xy 364.616238 -303.060862) (xy 364.67415 -302.996854)
			(xy 364.680754 -302.976534) (xy 364.679484 -302.965612) (xy 364.678521 -302.955671) (xy 364.677505 -302.935722)
			(xy 364.677452 -302.925734) (xy 364.677925 -302.898364) (xy 364.685739 -302.844185) (xy 364.701226 -302.791681)
			(xy 364.724067 -302.741934) (xy 364.753791 -302.695967) (xy 364.771432 -302.675036) (xy 364.777528 -302.667924)
			(xy 364.783878 -302.650906) (xy 364.783878 -302.565562) (xy 364.777528 -302.548544) (xy 364.771432 -302.541432)
			(xy 364.753799 -302.520495) (xy 364.724086 -302.474524) (xy 364.701248 -302.424778) (xy 364.685755 -302.372278)
			(xy 364.677926 -302.318103) (xy 364.677452 -302.290734) (xy 364.677938 -302.263483) (xy 364.685694 -302.209535)
			(xy 364.701049 -302.15724) (xy 364.723691 -302.107663) (xy 364.753157 -302.061813) (xy 364.788848 -302.020622)
			(xy 364.830039 -301.984931) (xy 364.875889 -301.955465) (xy 364.925466 -301.932823) (xy 364.977761 -301.917468)
			(xy 365.031709 -301.909712) (xy 365.086211 -301.909712) (xy 365.140159 -301.917468) (xy 365.192454 -301.932823)
			(xy 365.242031 -301.955465) (xy 365.287881 -301.984931) (xy 365.329072 -302.020622) (xy 365.364763 -302.061813)
			(xy 365.394229 -302.107663) (xy 365.416871 -302.15724) (xy 365.432226 -302.209535) (xy 365.439982 -302.263483)
			(xy 365.440468 -302.290734) (xy 365.44003 -302.318105) (xy 365.432206 -302.372286) (xy 365.416711 -302.42479)
			(xy 365.393863 -302.474536) (xy 365.364132 -302.520501) (xy 365.346488 -302.541432) (xy 365.340392 -302.548544)
			(xy 365.334042 -302.565562) (xy 365.334042 -302.650906) (xy 365.340392 -302.667924) (xy 365.346488 -302.675036)
			(xy 365.364109 -302.695983) (xy 365.393824 -302.741951) (xy 365.416663 -302.791695) (xy 365.432159 -302.844193)
			(xy 365.439992 -302.898366) (xy 365.440468 -302.925734) (xy 365.440416 -302.935722) (xy 365.439402 -302.955671)
			(xy 365.438436 -302.965612) (xy 365.437166 -302.976534) (xy 365.44377 -302.996854) (xy 365.501682 -303.060862)
			(xy 365.509159 -303.068602) (xy 365.528775 -303.07741) (xy 365.539528 -303.07788) (xy 367.087912 -303.07788)
			(xy 367.097983 -303.077466) (xy 367.116581 -303.069738) (xy 367.12398 -303.062894) (xy 368.065812 -302.121062)
			(xy 368.072506 -302.113581) (xy 368.080097 -302.095022) (xy 368.080544 -302.084994) (xy 368.080544 -282.125928)
			(xy 368.081156 -282.095951) (xy 368.090542 -282.036738) (xy 368.109072 -281.97972) (xy 368.13629 -281.926301)
			(xy 368.171526 -281.877795) (xy 368.192304 -281.85618) (xy 372.346728 -277.70201) (xy 372.353447 -277.694549)
			(xy 372.361023 -277.675974) (xy 372.36146 -277.665942) (xy 372.36146 -274.082256) (xy 372.361098 -274.07221)
			(xy 372.353505 -274.053613) (xy 372.346728 -274.046188) (xy 363.1438 -264.84326) (xy 363.136309 -264.836579)
			(xy 363.117757 -264.828981) (xy 363.107732 -264.828528) (xy 358.848406 -264.828528) (xy 358.818429 -264.827938)
			(xy 358.759213 -264.818548) (xy 358.702195 -264.800013) (xy 358.648776 -264.77279) (xy 358.600272 -264.737549)
			(xy 358.578658 -264.716768) (xy 355.153468 -261.291324) (xy 355.145992 -261.284624) (xy 355.127429 -261.277039)
			(xy 355.1174 -261.276592) (xy 352.446336 -261.276592) (xy 352.434829 -261.277069) (xy 352.414071 -261.286999)
			(xy 352.406458 -261.295642) (xy 352.349562 -261.367524) (xy 352.344736 -261.389622) (xy 352.347276 -261.401306)
			(xy 352.348038 -261.404354) (xy 352.350324 -261.413752) (xy 352.360484 -261.429246) (xy 352.431858 -261.479538)
			(xy 352.449638 -261.48411) (xy 352.45929 -261.483094) (xy 352.470548 -261.481798) (xy 352.49317 -261.480402)
			(xy 352.504502 -261.4803) (xy 352.531754 -261.48077) (xy 352.585702 -261.488527) (xy 352.637998 -261.503882)
			(xy 352.687576 -261.526524) (xy 352.733427 -261.555991) (xy 352.774618 -261.591683) (xy 352.81031 -261.632874)
			(xy 352.839777 -261.678726) (xy 352.862418 -261.728304) (xy 352.877774 -261.7806) (xy 352.88553 -261.834548)
			(xy 352.88553 -261.889052) (xy 352.877774 -261.943) (xy 352.862418 -261.995296) (xy 352.839777 -262.044874)
			(xy 352.81031 -262.090726) (xy 352.774618 -262.131917) (xy 352.733427 -262.167609) (xy 352.687576 -262.197076)
			(xy 352.637998 -262.219718) (xy 352.585702 -262.235073) (xy 352.531754 -262.24283) (xy 352.504502 -262.243316)
			(xy 352.475905 -262.242779) (xy 352.419353 -262.234242) (xy 352.364708 -262.217357) (xy 352.313196 -262.192505)
			(xy 352.265972 -262.160241) (xy 352.224093 -262.121289) (xy 352.188498 -262.076522) (xy 352.159985 -262.026943)
			(xy 352.139193 -261.973663) (xy 352.132392 -261.945882) (xy 352.130106 -261.936484) (xy 352.119946 -261.92099)
			(xy 352.048572 -261.870698) (xy 352.030792 -261.866126) (xy 352.02114 -261.867142) (xy 352.009881 -261.868435)
			(xy 351.98726 -261.869833) (xy 351.975928 -261.869936) (xy 351.948679 -261.869396) (xy 351.894734 -261.861644)
			(xy 351.842442 -261.846294) (xy 351.792867 -261.823658) (xy 351.747018 -261.794197) (xy 351.705828 -261.758511)
			(xy 351.670136 -261.717327) (xy 351.640669 -261.671482) (xy 351.618026 -261.62191) (xy 351.602668 -261.56962)
			(xy 351.594908 -261.515677) (xy 351.59442 -261.488428) (xy 351.594786 -261.464129) (xy 351.600943 -261.415921)
			(xy 351.613162 -261.368884) (xy 351.621852 -261.346188) (xy 351.625662 -261.337044) (xy 351.625662 -261.327392)
			(xy 351.625286 -261.317365) (xy 351.617606 -261.298841) (xy 351.60342 -261.284668) (xy 351.584889 -261.277005)
			(xy 351.574862 -261.276592) (xy 351.570798 -261.276592) (xy 351.560752 -261.276962) (xy 351.542155 -261.284549)
			(xy 351.53473 -261.291324) (xy 351.388934 -261.43712) (xy 351.382098 -261.444523) (xy 351.374375 -261.46312)
			(xy 351.373948 -261.473188) (xy 351.373948 -262.184388) (xy 351.373585 -262.209183) (xy 351.367209 -262.258361)
			(xy 351.361248 -262.282432) (xy 351.359176 -262.291977) (xy 351.361526 -262.311346) (xy 351.370945 -262.328434)
			(xy 351.386068 -262.340763) (xy 351.404703 -262.346546) (xy 351.424149 -262.344946) (xy 351.441588 -262.336194)
			(xy 351.44837 -262.329168) (xy 351.46657 -262.309151) (xy 351.507653 -262.273952) (xy 351.553296 -262.244908)
			(xy 351.602584 -262.222601) (xy 351.654527 -262.207478) (xy 351.708086 -262.199843) (xy 351.735136 -262.199374)
			(xy 351.762384 -262.199917) (xy 351.816326 -262.207677) (xy 351.868613 -262.223036) (xy 351.918183 -262.245679)
			(xy 351.964026 -262.275146) (xy 352.005209 -262.310838) (xy 352.040893 -262.352027) (xy 352.070353 -262.397875)
			(xy 352.092987 -262.447448) (xy 352.108337 -262.499739) (xy 352.116088 -262.553682) (xy 352.116084 -262.608178)
			(xy 352.108324 -262.66212) (xy 352.092966 -262.714408) (xy 352.070324 -262.763978) (xy 352.040857 -262.809822)
			(xy 352.005167 -262.851005) (xy 351.963978 -262.88669) (xy 351.918131 -262.91615) (xy 351.868557 -262.938785)
			(xy 351.816267 -262.954135) (xy 351.762324 -262.961888) (xy 351.707828 -262.961884) (xy 351.653886 -262.954125)
			(xy 351.601598 -262.938768) (xy 351.552027 -262.916127) (xy 351.506183 -262.886661) (xy 351.464999 -262.850971)
			(xy 351.429314 -262.809783) (xy 351.399853 -262.763936) (xy 351.377217 -262.714363) (xy 351.361866 -262.662073)
			(xy 351.354113 -262.60813) (xy 351.353628 -262.580882) (xy 351.35405 -262.556016) (xy 351.360547 -262.50671)
			(xy 351.366582 -262.482584) (xy 351.368616 -262.473004) (xy 351.366243 -262.45359) (xy 351.356769 -262.436479)
			(xy 351.341574 -262.424164) (xy 351.322872 -262.418439) (xy 351.303387 -262.420138) (xy 351.285959 -262.429014)
			(xy 351.279206 -262.436102) (xy 351.262442 -262.454136) (xy 350.622616 -263.093962) (xy 350.601009 -263.114736)
			(xy 350.552487 -263.149921) (xy 350.49906 -263.177086) (xy 350.442042 -263.195564) (xy 350.382837 -263.204899)
			(xy 350.352868 -263.205468) (xy 349.390716 -263.205468) (xy 349.380645 -263.205884) (xy 349.362047 -263.213609)
			(xy 349.354648 -263.220454) (xy 349.233744 -263.341612) (xy 349.212148 -263.362415) (xy 349.163645 -263.397669)
			(xy 349.110224 -263.424898) (xy 349.053199 -263.443432) (xy 348.993977 -263.452814) (xy 348.963996 -263.453372)
			(xy 348.936741 -263.452948) (xy 348.882787 -263.44519) (xy 348.830486 -263.429831) (xy 348.780904 -263.407186)
			(xy 348.735049 -263.377714) (xy 348.693855 -263.342016) (xy 348.658162 -263.300819) (xy 348.628695 -263.254961)
			(xy 348.606055 -263.205376) (xy 348.590702 -263.153074) (xy 348.582949 -263.099119) (xy 348.582488 -263.071864)
			(xy 344.842863 -263.071864) (xy 344.814699 -263.079227) (xy 344.759262 -263.085327) (xy 344.703528 -263.08329)
			(xy 344.648685 -263.07316) (xy 344.595901 -263.055153) (xy 344.546301 -263.029652) (xy 344.500943 -262.997201)
			(xy 344.460794 -262.958492) (xy 344.426708 -262.914349) (xy 344.399412 -262.865714) (xy 344.379489 -262.813623)
			(xy 344.367363 -262.759186) (xy 344.363292 -262.703564) (xy 339.154651 -262.703564) (xy 339.131762 -262.738161)
			(xy 339.094545 -262.779698) (xy 339.051677 -262.815373) (xy 339.004071 -262.844427) (xy 338.952742 -262.866239)
			(xy 338.898785 -262.880345) (xy 338.843348 -262.886445) (xy 338.787614 -262.884408) (xy 338.732771 -262.874278)
			(xy 338.679987 -262.856271) (xy 338.630387 -262.83077) (xy 338.585029 -262.798319) (xy 338.54488 -262.75961)
			(xy 338.510794 -262.715467) (xy 338.483498 -262.666832) (xy 338.463575 -262.614741) (xy 338.451449 -262.560304)
			(xy 338.447378 -262.504682) (xy 336.045261 -262.504682) (xy 336.049903 -262.516094) (xy 336.056478 -262.523478)
			(xy 336.056732 -262.523732) (xy 336.662014 -263.129014) (xy 336.668868 -263.136409) (xy 336.67661 -263.155008)
			(xy 336.677 -263.165082) (xy 336.677 -264.12952) (xy 346.649292 -264.12952) (xy 346.653363 -264.073898)
			(xy 346.665489 -264.019461) (xy 346.685412 -263.96737) (xy 346.712708 -263.918735) (xy 346.746794 -263.874592)
			(xy 346.786943 -263.835883) (xy 346.832301 -263.803432) (xy 346.881901 -263.777931) (xy 346.934685 -263.759924)
			(xy 346.989528 -263.749794) (xy 347.045262 -263.747757) (xy 347.100699 -263.753857) (xy 347.154656 -263.767963)
			(xy 347.200951 -263.787636) (xy 349.771968 -263.787636) (xy 349.776039 -263.732014) (xy 349.788165 -263.677577)
			(xy 349.808088 -263.625486) (xy 349.835384 -263.576851) (xy 349.86947 -263.532708) (xy 349.909619 -263.493999)
			(xy 349.954977 -263.461548) (xy 350.004577 -263.436047) (xy 350.057361 -263.41804) (xy 350.112204 -263.40791)
			(xy 350.167938 -263.405873) (xy 350.223375 -263.411973) (xy 350.277332 -263.426079) (xy 350.328661 -263.447891)
			(xy 350.376267 -263.476945) (xy 350.419135 -263.51262) (xy 350.456352 -263.554157) (xy 350.487125 -263.60067)
			(xy 350.510797 -263.651167) (xy 350.526865 -263.704574) (xy 350.534985 -263.75975) (xy 350.535494 -263.787636)
			(xy 350.534985 -263.815522) (xy 350.534192 -263.82091) (xy 351.643948 -263.82091) (xy 351.648019 -263.765288)
			(xy 351.660145 -263.710851) (xy 351.680068 -263.65876) (xy 351.707364 -263.610125) (xy 351.74145 -263.565982)
			(xy 351.781599 -263.527273) (xy 351.826957 -263.494822) (xy 351.876557 -263.469321) (xy 351.929341 -263.451314)
			(xy 351.984184 -263.441184) (xy 352.039918 -263.439147) (xy 352.095355 -263.445247) (xy 352.149312 -263.459353)
			(xy 352.200641 -263.481165) (xy 352.248247 -263.510219) (xy 352.291115 -263.545894) (xy 352.328332 -263.587431)
			(xy 352.359105 -263.633944) (xy 352.382777 -263.684441) (xy 352.398845 -263.737848) (xy 352.406965 -263.793024)
			(xy 352.407474 -263.82091) (xy 352.406965 -263.848796) (xy 352.398845 -263.903972) (xy 352.382777 -263.957379)
			(xy 352.359105 -264.007876) (xy 352.328332 -264.054389) (xy 352.291115 -264.095926) (xy 352.248247 -264.131601)
			(xy 352.200641 -264.160655) (xy 352.149312 -264.182467) (xy 352.095355 -264.196573) (xy 352.039918 -264.202673)
			(xy 351.984184 -264.200636) (xy 351.929341 -264.190506) (xy 351.876557 -264.172499) (xy 351.826957 -264.146998)
			(xy 351.781599 -264.114547) (xy 351.74145 -264.075838) (xy 351.707364 -264.031695) (xy 351.680068 -263.98306)
			(xy 351.660145 -263.930969) (xy 351.648019 -263.876532) (xy 351.643948 -263.82091) (xy 350.534192 -263.82091)
			(xy 350.526865 -263.870698) (xy 350.510797 -263.924105) (xy 350.487125 -263.974602) (xy 350.456352 -264.021115)
			(xy 350.419135 -264.062652) (xy 350.376267 -264.098327) (xy 350.328661 -264.127381) (xy 350.277332 -264.149193)
			(xy 350.223375 -264.163299) (xy 350.167938 -264.169399) (xy 350.112204 -264.167362) (xy 350.057361 -264.157232)
			(xy 350.004577 -264.139225) (xy 349.954977 -264.113724) (xy 349.909619 -264.081273) (xy 349.86947 -264.042564)
			(xy 349.835384 -263.998421) (xy 349.808088 -263.949786) (xy 349.788165 -263.897695) (xy 349.776039 -263.843258)
			(xy 349.771968 -263.787636) (xy 347.200951 -263.787636) (xy 347.205985 -263.789775) (xy 347.253591 -263.818829)
			(xy 347.296459 -263.854504) (xy 347.333676 -263.896041) (xy 347.364449 -263.942554) (xy 347.388121 -263.993051)
			(xy 347.404189 -264.046458) (xy 347.412309 -264.101634) (xy 347.412818 -264.12952) (xy 347.412309 -264.157406)
			(xy 347.404189 -264.212582) (xy 347.388121 -264.265989) (xy 347.364449 -264.316486) (xy 347.333676 -264.362999)
			(xy 347.296459 -264.404536) (xy 347.253591 -264.440211) (xy 347.205985 -264.469265) (xy 347.154656 -264.491077)
			(xy 347.100699 -264.505183) (xy 347.045262 -264.511283) (xy 346.989528 -264.509246) (xy 346.934685 -264.499116)
			(xy 346.881901 -264.481109) (xy 346.832301 -264.455608) (xy 346.786943 -264.423157) (xy 346.746794 -264.384448)
			(xy 346.712708 -264.340305) (xy 346.685412 -264.29167) (xy 346.665489 -264.239579) (xy 346.653363 -264.185142)
			(xy 346.649292 -264.12952) (xy 336.677 -264.12952) (xy 336.677 -264.646918) (xy 336.676573 -264.656987)
			(xy 336.668854 -264.675586) (xy 336.662014 -264.682986) (xy 336.40903 -264.93597) (xy 352.61753 -264.93597)
			(xy 352.621601 -264.880348) (xy 352.633727 -264.825911) (xy 352.65365 -264.77382) (xy 352.680946 -264.725185)
			(xy 352.715032 -264.681042) (xy 352.755181 -264.642333) (xy 352.800539 -264.609882) (xy 352.850139 -264.584381)
			(xy 352.902923 -264.566374) (xy 352.957766 -264.556244) (xy 353.0135 -264.554207) (xy 353.068937 -264.560307)
			(xy 353.122894 -264.574413) (xy 353.174223 -264.596225) (xy 353.221829 -264.625279) (xy 353.264697 -264.660954)
			(xy 353.301914 -264.702491) (xy 353.332687 -264.749004) (xy 353.356359 -264.799501) (xy 353.372427 -264.852908)
			(xy 353.380547 -264.908084) (xy 353.381056 -264.93597) (xy 353.380547 -264.963856) (xy 353.372427 -265.019032)
			(xy 353.356359 -265.072439) (xy 353.332687 -265.122936) (xy 353.301914 -265.169449) (xy 353.264697 -265.210986)
			(xy 353.221829 -265.246661) (xy 353.174223 -265.275715) (xy 353.122894 -265.297527) (xy 353.068937 -265.311633)
			(xy 353.0135 -265.317733) (xy 352.957766 -265.315696) (xy 352.902923 -265.305566) (xy 352.850139 -265.287559)
			(xy 352.800539 -265.262058) (xy 352.755181 -265.229607) (xy 352.715032 -265.190898) (xy 352.680946 -265.146755)
			(xy 352.65365 -265.09812) (xy 352.633727 -265.046029) (xy 352.621601 -264.991592) (xy 352.61753 -264.93597)
			(xy 336.40903 -264.93597) (xy 335.929986 -265.415014) (xy 335.922591 -265.421868) (xy 335.903992 -265.42961)
			(xy 335.893918 -265.43) (xy 333.904082 -265.43) (xy 333.894013 -265.430427) (xy 333.875414 -265.438146)
			(xy 333.868014 -265.444986) (xy 333.447898 -265.865102) (xy 333.440532 -265.872214) (xy 333.432912 -265.89101)
			(xy 333.432912 -267.180822) (xy 333.432984 -267.18483) (xy 333.434265 -267.192741) (xy 333.435452 -267.19657)
			(xy 334.027018 -269.000986) (xy 334.037686 -269.03553) (xy 334.03794 -269.036546) (xy 334.071722 -269.138654)
			(xy 334.072885 -269.142357) (xy 334.074166 -269.150013) (xy 334.074262 -269.153894) (xy 334.075278 -269.26032)
			(xy 334.075278 -269.263368) (xy 334.076294 -269.308834) (xy 334.076294 -269.309342) (xy 334.07604 -269.316708)
			(xy 334.07604 -269.317724) (xy 334.077105 -269.417038) (xy 334.700626 -269.417038) (xy 334.701132 -269.388299)
			(xy 334.709762 -269.331471) (xy 334.726817 -269.276581) (xy 334.751912 -269.22487) (xy 334.784479 -269.177507)
			(xy 334.80375 -269.15618) (xy 334.810354 -269.149068) (xy 334.817466 -269.131542) (xy 334.817466 -269.042134)
			(xy 334.810354 -269.024608) (xy 334.80375 -269.017496) (xy 334.784499 -268.996152) (xy 334.75193 -268.948795)
			(xy 334.726833 -268.897087) (xy 334.709778 -268.8422) (xy 334.70115 -268.785376) (xy 334.700626 -268.756638)
			(xy 334.701091 -268.729385) (xy 334.708843 -268.675432) (xy 334.724196 -268.623132) (xy 334.746837 -268.57355)
			(xy 334.776304 -268.527695) (xy 334.811998 -268.486501) (xy 334.853192 -268.450807) (xy 334.899046 -268.421339)
			(xy 334.948628 -268.398698) (xy 335.000928 -268.383344) (xy 335.054881 -268.375591) (xy 335.082134 -268.37513)
			(xy 335.109505 -268.375569) (xy 335.163686 -268.383392) (xy 335.21619 -268.398887) (xy 335.265936 -268.421735)
			(xy 335.311901 -268.451466) (xy 335.332832 -268.46911) (xy 335.339944 -268.475206) (xy 335.356962 -268.481556)
			(xy 335.442306 -268.481556) (xy 335.459324 -268.475206) (xy 335.466436 -268.46911) (xy 335.487369 -268.451469)
			(xy 335.533337 -268.421745) (xy 335.583083 -268.398899) (xy 335.635585 -268.383403) (xy 335.689763 -268.375574)
			(xy 335.744505 -268.375574) (xy 335.798683 -268.383403) (xy 335.851185 -268.398899) (xy 335.900931 -268.421745)
			(xy 335.946899 -268.451469) (xy 335.967832 -268.46911) (xy 335.974944 -268.475206) (xy 335.991962 -268.481556)
			(xy 336.077306 -268.481556) (xy 336.094324 -268.475206) (xy 336.101436 -268.46911) (xy 336.122369 -268.451469)
			(xy 336.168337 -268.421745) (xy 336.218083 -268.398899) (xy 336.270585 -268.383403) (xy 336.324763 -268.375574)
			(xy 336.379505 -268.375574) (xy 336.433683 -268.383403) (xy 336.486185 -268.398899) (xy 336.535931 -268.421745)
			(xy 336.581899 -268.451469) (xy 336.602832 -268.46911) (xy 336.609944 -268.475206) (xy 336.626962 -268.481556)
			(xy 336.712306 -268.481556) (xy 336.729324 -268.475206) (xy 336.736436 -268.46911) (xy 336.757369 -268.451469)
			(xy 336.803337 -268.421745) (xy 336.853083 -268.398899) (xy 336.905585 -268.383403) (xy 336.959763 -268.375574)
			(xy 337.014505 -268.375574) (xy 337.068683 -268.383403) (xy 337.121185 -268.398899) (xy 337.170931 -268.421745)
			(xy 337.216899 -268.451469) (xy 337.237832 -268.46911) (xy 337.244944 -268.475206) (xy 337.261962 -268.481556)
			(xy 337.347306 -268.481556) (xy 337.364324 -268.475206) (xy 337.371436 -268.46911) (xy 337.392383 -268.451489)
			(xy 337.438351 -268.421774) (xy 337.488095 -268.398935) (xy 337.540593 -268.383439) (xy 337.594766 -268.375606)
			(xy 337.622134 -268.37513) (xy 337.649389 -268.375523) (xy 337.703345 -268.383286) (xy 337.755646 -268.398648)
			(xy 337.805229 -268.421297) (xy 337.851084 -268.450773) (xy 337.892277 -268.486474) (xy 337.927971 -268.527674)
			(xy 337.957437 -268.573534) (xy 337.980077 -268.623121) (xy 337.995429 -268.675426) (xy 338.003182 -268.729382)
			(xy 338.003642 -268.756638) (xy 338.00313 -268.785377) (xy 337.994503 -268.842205) (xy 337.977449 -268.897095)
			(xy 337.952356 -268.948807) (xy 337.919789 -268.996169) (xy 337.900518 -269.017496) (xy 337.893914 -269.024608)
			(xy 337.886802 -269.042134) (xy 337.886802 -269.131542) (xy 337.893914 -269.149068) (xy 337.900518 -269.15618)
			(xy 337.919799 -269.177498) (xy 337.952366 -269.224862) (xy 337.977457 -269.276575) (xy 337.994505 -269.331469)
			(xy 338.003124 -269.388298) (xy 338.003642 -269.417038) (xy 338.003158 -269.444289) (xy 337.995397 -269.498235)
			(xy 337.980039 -269.550527) (xy 337.957396 -269.600102) (xy 337.927928 -269.645951) (xy 337.892237 -269.68714)
			(xy 337.851048 -269.722831) (xy 337.805199 -269.752297) (xy 337.755624 -269.77494) (xy 337.703331 -269.790298)
			(xy 337.649385 -269.798058) (xy 337.622134 -269.798546) (xy 337.594764 -269.798073) (xy 337.540585 -269.790259)
			(xy 337.488081 -269.774772) (xy 337.438334 -269.751932) (xy 337.392367 -269.722207) (xy 337.371436 -269.704566)
			(xy 337.364324 -269.69847) (xy 337.347306 -269.69212) (xy 337.261962 -269.69212) (xy 337.244944 -269.69847)
			(xy 337.237832 -269.704566) (xy 337.216899 -269.722207) (xy 337.170931 -269.751931) (xy 337.121185 -269.774777)
			(xy 337.068683 -269.790273) (xy 337.014505 -269.798102) (xy 336.959763 -269.798102) (xy 336.905585 -269.790273)
			(xy 336.853083 -269.774777) (xy 336.803337 -269.751931) (xy 336.757369 -269.722207) (xy 336.736436 -269.704566)
			(xy 336.729324 -269.69847) (xy 336.712306 -269.69212) (xy 336.626962 -269.69212) (xy 336.609944 -269.69847)
			(xy 336.602832 -269.704566) (xy 336.581899 -269.722207) (xy 336.535931 -269.751931) (xy 336.486185 -269.774777)
			(xy 336.433683 -269.790273) (xy 336.379505 -269.798102) (xy 336.324763 -269.798102) (xy 336.270585 -269.790273)
			(xy 336.218083 -269.774777) (xy 336.168337 -269.751931) (xy 336.122369 -269.722207) (xy 336.101436 -269.704566)
			(xy 336.094324 -269.69847) (xy 336.077306 -269.69212) (xy 335.991962 -269.69212) (xy 335.974944 -269.69847)
			(xy 335.967832 -269.704566) (xy 335.946899 -269.722207) (xy 335.900931 -269.751931) (xy 335.851185 -269.774777)
			(xy 335.798683 -269.790273) (xy 335.744505 -269.798102) (xy 335.689763 -269.798102) (xy 335.635585 -269.790273)
			(xy 335.583083 -269.774777) (xy 335.533337 -269.751931) (xy 335.487369 -269.722207) (xy 335.466436 -269.704566)
			(xy 335.459324 -269.69847) (xy 335.442306 -269.69212) (xy 335.356962 -269.69212) (xy 335.339944 -269.69847)
			(xy 335.332832 -269.704566) (xy 335.311894 -269.722198) (xy 335.265924 -269.751912) (xy 335.216178 -269.77475)
			(xy 335.163678 -269.790243) (xy 335.109503 -269.798072) (xy 335.082134 -269.798546) (xy 335.054885 -269.79799)
			(xy 335.000942 -269.790239) (xy 334.948651 -269.77489) (xy 334.899077 -269.752256) (xy 334.853228 -269.722797)
			(xy 334.812038 -269.687113) (xy 334.776346 -269.64593) (xy 334.746878 -269.600087) (xy 334.724235 -269.550516)
			(xy 334.708876 -269.498228) (xy 334.701115 -269.444287) (xy 334.700626 -269.417038) (xy 334.077105 -269.417038)
			(xy 334.119728 -273.391376) (xy 334.119728 -273.391884) (xy 334.120236 -273.422618) (xy 334.120236 -273.4945)
			(xy 334.119671 -273.541443) (xy 334.110747 -273.634903) (xy 334.092999 -273.727095) (xy 334.066585 -273.817189)
			(xy 334.031745 -273.904371) (xy 334.010762 -273.946366) (xy 331.99609 -277.864824) (xy 335.665826 -277.864824)
			(xy 335.666352 -277.835907) (xy 335.675078 -277.778736) (xy 335.692334 -277.723537) (xy 335.717724 -277.671575)
			(xy 335.750667 -277.624041) (xy 335.790407 -277.582024) (xy 335.812892 -277.563834) (xy 335.821633 -277.556252)
			(xy 335.831828 -277.535509) (xy 335.83245 -277.523956) (xy 335.83245 -277.443692) (xy 335.831901 -277.432121)
			(xy 335.821693 -277.411349) (xy 335.812892 -277.403814) (xy 335.790414 -277.385617) (xy 335.750678 -277.343598)
			(xy 335.717739 -277.296065) (xy 335.69235 -277.244104) (xy 335.675092 -277.188908) (xy 335.666362 -277.13174)
			(xy 335.665826 -277.102824) (xy 335.666409 -277.073417) (xy 335.675439 -277.015299) (xy 335.693274 -276.959253)
			(xy 335.719492 -276.906605) (xy 335.753473 -276.858599) (xy 335.794413 -276.816372) (xy 335.841345 -276.780923)
			(xy 335.866994 -276.766528) (xy 335.878932 -276.760178) (xy 335.893156 -276.737826) (xy 335.898998 -276.624288)
			(xy 335.88706 -276.600412) (xy 335.876138 -276.593046) (xy 335.85438 -276.577735) (xy 335.814901 -276.542071)
			(xy 335.780757 -276.50127) (xy 335.75261 -276.456123) (xy 335.731005 -276.407505) (xy 335.716362 -276.356357)
			(xy 335.708964 -276.303671) (xy 335.708498 -276.27707) (xy 335.708947 -276.249699) (xy 335.716769 -276.195519)
			(xy 335.732262 -276.143016) (xy 335.755108 -276.09327) (xy 335.784835 -276.047303) (xy 335.802478 -276.026372)
			(xy 335.808574 -276.01926) (xy 335.814924 -276.002242) (xy 335.814924 -275.916898) (xy 335.808574 -275.89988)
			(xy 335.802478 -275.892768) (xy 335.784854 -275.871824) (xy 335.755141 -275.825854) (xy 335.732302 -275.77611)
			(xy 335.716807 -275.723612) (xy 335.708975 -275.669438) (xy 335.708498 -275.64207) (xy 335.709051 -275.612246)
			(xy 335.718305 -275.55332) (xy 335.736615 -275.496551) (xy 335.763534 -275.443323) (xy 335.798408 -275.394931)
			(xy 335.818988 -275.373338) (xy 335.826354 -275.366226) (xy 335.833974 -275.34743) (xy 335.832958 -275.25472)
			(xy 335.825084 -275.236178) (xy 335.817718 -275.229066) (xy 335.799761 -275.211015) (xy 335.768263 -275.171012)
			(xy 335.742365 -275.127176) (xy 335.722525 -275.080286) (xy 335.709097 -275.031173) (xy 335.70232 -274.980711)
			(xy 335.701894 -274.955254) (xy 335.702335 -274.928002) (xy 335.710098 -274.874052) (xy 335.725459 -274.821756)
			(xy 335.748106 -274.772179) (xy 335.777577 -274.726329) (xy 335.813273 -274.685139) (xy 335.854467 -274.649448)
			(xy 335.900321 -274.619983) (xy 335.949901 -274.597342) (xy 336.002199 -274.581988) (xy 336.056149 -274.574232)
			(xy 336.083402 -274.573746) (xy 336.11232 -274.574246) (xy 336.169493 -274.582976) (xy 336.224693 -274.600237)
			(xy 336.276655 -274.625632) (xy 336.324188 -274.658579) (xy 336.366203 -274.698324) (xy 336.384392 -274.720812)
			(xy 336.39196 -274.729568) (xy 336.412714 -274.739754) (xy 336.42427 -274.74037) (xy 336.504534 -274.74037)
			(xy 336.516099 -274.739772) (xy 336.536871 -274.729598) (xy 336.544412 -274.720812) (xy 336.561165 -274.700029)
			(xy 336.599519 -274.662899) (xy 336.642673 -274.631477) (xy 336.689787 -274.606378) (xy 336.739939 -274.588092)
			(xy 336.79215 -274.576975) (xy 336.845402 -274.573245) (xy 336.898654 -274.576975) (xy 336.950865 -274.588092)
			(xy 337.001017 -274.606378) (xy 337.048131 -274.631477) (xy 337.091285 -274.662899) (xy 337.129639 -274.700029)
			(xy 337.146392 -274.720812) (xy 337.15396 -274.729568) (xy 337.174714 -274.739754) (xy 337.18627 -274.74037)
			(xy 337.266534 -274.74037) (xy 337.278099 -274.739772) (xy 337.298871 -274.729598) (xy 337.306412 -274.720812)
			(xy 337.324599 -274.698325) (xy 337.366619 -274.65859) (xy 337.414155 -274.625651) (xy 337.466117 -274.600263)
			(xy 337.521315 -274.583007) (xy 337.578486 -274.57428) (xy 337.607402 -274.573746) (xy 337.634651 -274.574276)
			(xy 337.688595 -274.582031) (xy 337.740886 -274.597384) (xy 337.79046 -274.620022) (xy 337.836308 -274.649485)
			(xy 337.877497 -274.685171) (xy 337.913189 -274.726356) (xy 337.942656 -274.772201) (xy 337.9653 -274.821773)
			(xy 337.980659 -274.874062) (xy 337.988421 -274.928005) (xy 337.98891 -274.955254) (xy 337.98837 -274.985079)
			(xy 337.979112 -275.044005) (xy 337.960799 -275.100774) (xy 337.933877 -275.154002) (xy 337.899001 -275.202393)
			(xy 337.87842 -275.223986) (xy 337.871054 -275.231098) (xy 337.863434 -275.249894) (xy 337.86445 -275.342604)
			(xy 337.872324 -275.361146) (xy 337.87969 -275.368258) (xy 337.89766 -275.386296) (xy 337.929156 -275.426302)
			(xy 337.955053 -275.470141) (xy 337.97489 -275.517034) (xy 337.988315 -275.566148) (xy 337.99509 -275.616612)
			(xy 337.995514 -275.64207) (xy 337.995007 -275.670988) (xy 337.98628 -275.728161) (xy 337.969022 -275.783361)
			(xy 337.943629 -275.835324) (xy 337.910681 -275.882857) (xy 337.870936 -275.924872) (xy 337.848448 -275.94306)
			(xy 337.8397 -275.950635) (xy 337.829511 -275.971384) (xy 337.82889 -275.982938) (xy 337.82889 -276.063202)
			(xy 337.829463 -276.074769) (xy 337.839656 -276.09554) (xy 337.848448 -276.10308) (xy 337.870932 -276.12127)
			(xy 337.910665 -276.163292) (xy 337.943602 -276.210827) (xy 337.96899 -276.262788) (xy 337.986247 -276.317985)
			(xy 337.994978 -276.375154) (xy 337.995514 -276.40407) (xy 337.995017 -276.431322) (xy 337.987264 -276.485271)
			(xy 337.971912 -276.537568) (xy 337.949274 -276.587148) (xy 337.919809 -276.633001) (xy 337.884119 -276.674194)
			(xy 337.84293 -276.709888) (xy 337.797079 -276.739356) (xy 337.747502 -276.762) (xy 337.695206 -276.777356)
			(xy 337.641258 -276.785114) (xy 337.614006 -276.785578) (xy 337.585089 -276.785064) (xy 337.527917 -276.776335)
			(xy 337.472718 -276.759077) (xy 337.420756 -276.733684) (xy 337.373222 -276.70074) (xy 337.331206 -276.660998)
			(xy 337.313016 -276.638512) (xy 337.305441 -276.629764) (xy 337.284692 -276.619572) (xy 337.273138 -276.618954)
			(xy 337.192874 -276.618954) (xy 337.181309 -276.619548) (xy 337.160536 -276.629724) (xy 337.152996 -276.638512)
			(xy 337.142965 -276.651117) (xy 337.121089 -276.674769) (xy 337.109308 -276.685756) (xy 337.100418 -276.693884)
			(xy 337.091782 -276.715982) (xy 337.101688 -276.82063) (xy 337.114134 -276.84095) (xy 337.124294 -276.8473)
			(xy 337.147602 -276.862308) (xy 337.190041 -276.897972) (xy 337.226868 -276.939406) (xy 337.257308 -276.985735)
			(xy 337.28072 -277.035983) (xy 337.296609 -277.089091) (xy 337.304642 -277.143941) (xy 337.305142 -277.171658)
			(xy 337.304656 -277.198909) (xy 337.2969 -277.252857) (xy 337.281545 -277.305152) (xy 337.258903 -277.354729)
			(xy 337.229437 -277.400579) (xy 337.193746 -277.44177) (xy 337.152555 -277.477461) (xy 337.106705 -277.506927)
			(xy 337.057128 -277.529569) (xy 337.004833 -277.544924) (xy 336.950885 -277.55268) (xy 336.896383 -277.55268)
			(xy 336.842435 -277.544924) (xy 336.79014 -277.529569) (xy 336.740563 -277.506927) (xy 336.694713 -277.477461)
			(xy 336.653522 -277.44177) (xy 336.617831 -277.400579) (xy 336.588365 -277.354729) (xy 336.565723 -277.305152)
			(xy 336.550368 -277.252857) (xy 336.542612 -277.198909) (xy 336.542126 -277.171658) (xy 336.542599 -277.14524)
			(xy 336.549883 -277.09291) (xy 336.564319 -277.042086) (xy 336.585632 -276.99374) (xy 336.613413 -276.948798)
			(xy 336.647131 -276.908121) (xy 336.666332 -276.889972) (xy 336.675222 -276.881844) (xy 336.683858 -276.859746)
			(xy 336.673952 -276.755098) (xy 336.661506 -276.734778) (xy 336.651346 -276.728428) (xy 336.62973 -276.71459)
			(xy 336.590072 -276.682011) (xy 336.555155 -276.644394) (xy 336.525613 -276.602425) (xy 336.513424 -276.579838)
			(xy 336.507836 -276.56917) (xy 336.488786 -276.5552) (xy 336.384646 -276.537928) (xy 336.36204 -276.544786)
			(xy 336.35315 -276.553168) (xy 336.334296 -276.57061) (xy 336.292756 -276.600817) (xy 336.270346 -276.613366)
			(xy 336.258408 -276.619716) (xy 336.244184 -276.642068) (xy 336.238342 -276.755606) (xy 336.25028 -276.779482)
			(xy 336.261202 -276.786848) (xy 336.282944 -276.802182) (xy 336.322426 -276.83784) (xy 336.356574 -276.878636)
			(xy 336.384724 -276.923779) (xy 336.406331 -276.972394) (xy 336.420976 -277.02354) (xy 336.428376 -277.076224)
			(xy 336.428842 -277.102824) (xy 336.428291 -277.13174) (xy 336.419572 -277.188911) (xy 336.402322 -277.24411)
			(xy 336.376936 -277.296072) (xy 336.343997 -277.343607) (xy 336.30426 -277.385624) (xy 336.281776 -277.403814)
			(xy 336.273008 -277.41137) (xy 336.262829 -277.432133) (xy 336.262218 -277.443692) (xy 336.262218 -277.523956)
			(xy 336.262808 -277.535521) (xy 336.272988 -277.556293) (xy 336.281776 -277.563834) (xy 336.304271 -277.582012)
			(xy 336.344006 -277.624034) (xy 336.376945 -277.671571) (xy 336.402331 -277.723535) (xy 336.419585 -277.778735)
			(xy 336.42831 -277.835907) (xy 336.428842 -277.864824) (xy 336.428356 -277.892075) (xy 336.4206 -277.946023)
			(xy 336.405245 -277.998318) (xy 336.382603 -278.047895) (xy 336.353137 -278.093745) (xy 336.317446 -278.134936)
			(xy 336.276255 -278.170627) (xy 336.230405 -278.200093) (xy 336.180828 -278.222735) (xy 336.128533 -278.23809)
			(xy 336.074585 -278.245846) (xy 336.020083 -278.245846) (xy 335.966135 -278.23809) (xy 335.91384 -278.222735)
			(xy 335.864263 -278.200093) (xy 335.818413 -278.170627) (xy 335.777222 -278.134936) (xy 335.741531 -278.093745)
			(xy 335.712065 -278.047895) (xy 335.689423 -277.998318) (xy 335.674068 -277.946023) (xy 335.666312 -277.892075)
			(xy 335.665826 -277.864824) (xy 331.99609 -277.864824) (xy 331.851 -278.147018) (xy 331.789278 -278.266398)
			(xy 331.789278 -278.389334) (xy 331.788848 -278.399401) (xy 331.781123 -278.417994) (xy 331.774292 -278.425402)
			(xy 325.860156 -284.339538) (xy 325.85331 -284.346936) (xy 325.84558 -284.365535) (xy 325.84517 -284.375606)
			(xy 325.84517 -288.445448) (xy 325.862442 -288.470848) (xy 325.87692 -288.47669) (xy 325.903061 -288.487735)
			(xy 325.952022 -288.516427) (xy 325.996192 -288.552055) (xy 326.034597 -288.593832) (xy 326.066391 -288.640838)
			(xy 326.090872 -288.692034) (xy 326.1075 -288.746291) (xy 326.115907 -288.802413) (xy 326.115909 -288.859161)
			(xy 326.107505 -288.915284) (xy 326.090881 -288.969542) (xy 326.066404 -289.02074) (xy 326.034613 -289.067748)
			(xy 325.99621 -289.109528) (xy 325.952042 -289.145159) (xy 325.903084 -289.173854) (xy 325.87692 -289.184842)
			(xy 325.862442 -289.190684) (xy 325.84517 -289.216084) (xy 325.84517 -290.912804) (xy 325.870062 -290.941252)
			(xy 325.889366 -290.943792) (xy 325.916509 -290.947896) (xy 325.969317 -290.962883) (xy 326.019433 -290.985285)
			(xy 326.065819 -291.014639) (xy 326.107519 -291.050339) (xy 326.143671 -291.091647) (xy 326.173529 -291.137711)
			(xy 326.196475 -291.187579) (xy 326.212036 -291.240222) (xy 326.219891 -291.294551) (xy 326.220328 -291.321998)
			(xy 326.219799 -291.350484) (xy 326.211326 -291.406822) (xy 326.208273 -291.41674) (xy 326.47382 -291.41674)
			(xy 326.47382 -285.699962) (xy 326.474398 -285.669984) (xy 326.483793 -285.610769) (xy 326.502331 -285.553751)
			(xy 326.529557 -285.500333) (xy 326.564799 -285.451828) (xy 326.58558 -285.430214) (xy 332.41361 -279.602184)
			(xy 332.435182 -279.581354) (xy 332.483691 -279.546105) (xy 332.537119 -279.51888) (xy 332.594149 -279.500352)
			(xy 332.653376 -279.490977) (xy 332.683358 -279.490424) (xy 335.67751 -279.490424) (xy 335.687556 -279.490054)
			(xy 335.706153 -279.482467) (xy 335.713578 -279.475692) (xy 338.893404 -276.295866) (xy 338.900109 -276.288394)
			(xy 338.907691 -276.269827) (xy 338.908136 -276.259798) (xy 338.908136 -268.269974) (xy 338.908716 -268.239996)
			(xy 338.918111 -268.180781) (xy 338.936648 -268.123763) (xy 338.963873 -268.070345) (xy 338.999115 -268.02184)
			(xy 339.019896 -268.000226) (xy 340.599268 -266.420854) (xy 340.620884 -266.40009) (xy 340.669404 -266.364903)
			(xy 340.722829 -266.337736) (xy 340.779844 -266.319256) (xy 340.839048 -266.309918) (xy 340.869016 -266.309348)
			(xy 351.522284 -266.309348) (xy 351.532727 -266.308886) (xy 351.551874 -266.300546) (xy 351.566092 -266.285249)
			(xy 351.570036 -266.275566) (xy 351.607628 -266.170156) (xy 351.599246 -266.139422) (xy 351.586546 -266.129008)
			(xy 351.565137 -266.110798) (xy 351.527401 -266.069145) (xy 351.496183 -266.022408) (xy 351.472159 -265.971597)
			(xy 351.455847 -265.917812) (xy 351.447601 -265.862216) (xy 351.4471 -265.834114) (xy 351.447586 -265.806863)
			(xy 351.455342 -265.752915) (xy 351.470697 -265.70062) (xy 351.493339 -265.651043) (xy 351.522805 -265.605193)
			(xy 351.558496 -265.564002) (xy 351.599687 -265.528311) (xy 351.645537 -265.498845) (xy 351.695114 -265.476203)
			(xy 351.747409 -265.460848) (xy 351.801357 -265.453092) (xy 351.855859 -265.453092) (xy 351.909807 -265.460848)
			(xy 351.962102 -265.476203) (xy 352.011679 -265.498845) (xy 352.057529 -265.528311) (xy 352.09872 -265.564002)
			(xy 352.134411 -265.605193) (xy 352.163877 -265.651043) (xy 352.186519 -265.70062) (xy 352.201874 -265.752915)
			(xy 352.20963 -265.806863) (xy 352.210116 -265.834114) (xy 352.20967 -265.862218) (xy 352.20142 -265.917819)
			(xy 352.1851 -265.971606) (xy 352.161063 -266.022417) (xy 352.129831 -266.06915) (xy 352.09208 -266.110794)
			(xy 352.07067 -266.129008) (xy 352.05797 -266.139422) (xy 352.049588 -266.170156) (xy 352.08718 -266.275566)
			(xy 352.091186 -266.285199) (xy 352.105424 -266.30042) (xy 352.124515 -266.308784) (xy 352.134932 -266.309348)
			(xy 353.19462 -266.309348) (xy 353.204692 -266.308947) (xy 353.223291 -266.301211) (xy 353.230688 -266.294362)
			(xy 353.821746 -265.703304) (xy 353.828583 -265.695902) (xy 353.836303 -265.677304) (xy 353.836732 -265.667236)
			(xy 353.836732 -263.925304) (xy 353.837234 -263.89533) (xy 353.846559 -263.836114) (xy 353.865042 -263.779089)
			(xy 353.892228 -263.725661) (xy 353.927444 -263.67715) (xy 353.948238 -263.655556) (xy 354.391722 -263.212072)
			(xy 354.413303 -263.191252) (xy 354.461808 -263.155998) (xy 354.515233 -263.12877) (xy 354.572262 -263.11024)
			(xy 354.631488 -263.100865) (xy 354.66147 -263.100312) (xy 354.91293 -263.100312) (xy 355.080062 -263.09828)
			(xy 355.090088 -263.097744) (xy 355.108553 -263.089906) (xy 355.115876 -263.08304) (xy 355.278182 -262.916924)
			(xy 355.296205 -262.899109) (xy 355.336114 -262.867879) (xy 355.379806 -262.842208) (xy 355.426513 -262.822548)
			(xy 355.475411 -262.809244) (xy 355.52564 -262.802532) (xy 355.550978 -262.802116) (xy 355.578209 -262.802652)
			(xy 355.632118 -262.8104) (xy 355.684375 -262.82574) (xy 355.733917 -262.848361) (xy 355.779735 -262.877803)
			(xy 355.820898 -262.913465) (xy 355.856566 -262.954623) (xy 355.886014 -263.000437) (xy 355.908642 -263.049976)
			(xy 355.923989 -263.102232) (xy 355.931744 -263.156139) (xy 355.932232 -263.18337) (xy 355.931657 -263.212882)
			(xy 355.922571 -263.271202) (xy 355.904612 -263.327427) (xy 355.878208 -263.380215) (xy 355.843988 -263.428307)
			(xy 355.823774 -263.449816) (xy 355.658166 -263.619488) (xy 355.651538 -263.627003) (xy 355.644167 -263.645617)
			(xy 355.644455 -263.665636) (xy 355.652358 -263.68403) (xy 355.659182 -263.69137) (xy 355.731572 -263.761982)
			(xy 355.73843 -263.765538) (xy 355.761315 -263.777933) (xy 355.803803 -263.80799) (xy 355.841808 -263.843545)
			(xy 355.874625 -263.88394) (xy 355.901642 -263.928422) (xy 355.922358 -263.976166) (xy 355.936388 -264.026284)
			(xy 355.943471 -264.077844) (xy 355.943916 -264.103866) (xy 355.943459 -264.131113) (xy 355.935704 -264.185053)
			(xy 355.920348 -264.237339) (xy 355.897703 -264.286905) (xy 355.868231 -264.332742) (xy 355.832533 -264.373915)
			(xy 355.791335 -264.409586) (xy 355.745478 -264.439027) (xy 355.695897 -264.461638) (xy 355.6436 -264.476959)
			(xy 355.589655 -264.484677) (xy 355.562408 -264.48512) (xy 355.535992 -264.48512) (xy 355.506515 -264.484579)
			(xy 355.448262 -264.475509) (xy 355.392097 -264.457587) (xy 355.339358 -264.431238) (xy 355.2913 -264.39709)
			(xy 355.2698 -264.376916) (xy 355.146102 -264.256266) (xy 355.138588 -264.249684) (xy 355.120019 -264.24237)
			(xy 355.110034 -264.242042) (xy 355.030532 -264.242804) (xy 355.020595 -264.24341) (xy 355.002277 -264.251147)
			(xy 354.988282 -264.265273) (xy 354.980716 -264.283662) (xy 354.98024 -264.293604) (xy 354.98024 -266.004294)
			(xy 354.979744 -266.034268) (xy 354.970419 -266.093485) (xy 354.951935 -266.150511) (xy 354.924748 -266.203938)
			(xy 354.889529 -266.252448) (xy 354.868734 -266.274042) (xy 353.801426 -267.34135) (xy 353.779813 -267.362117)
			(xy 353.731292 -267.397304) (xy 353.677867 -267.42447) (xy 353.620851 -267.44295) (xy 353.561646 -267.452287)
			(xy 353.531678 -267.452856) (xy 341.206074 -267.452856) (xy 341.196001 -267.453253) (xy 341.177403 -267.460992)
			(xy 341.170006 -267.467842) (xy 340.066884 -268.570964) (xy 340.060178 -268.578436) (xy 340.052594 -268.597002)
			(xy 340.052152 -268.607032) (xy 340.052152 -269.417038) (xy 357.085646 -269.417038) (xy 357.086146 -269.388298)
			(xy 357.094777 -269.331471) (xy 357.111833 -269.27658) (xy 357.13693 -269.224869) (xy 357.169498 -269.177507)
			(xy 357.18877 -269.15618) (xy 357.195374 -269.149068) (xy 357.202486 -269.131542) (xy 357.202486 -269.042134)
			(xy 357.195374 -269.024608) (xy 357.18877 -269.017496) (xy 357.169523 -268.996149) (xy 357.136952 -268.948793)
			(xy 357.111854 -268.897086) (xy 357.094798 -268.8422) (xy 357.08617 -268.785376) (xy 357.085646 -268.756638)
			(xy 357.086213 -268.72939) (xy 357.093964 -268.675447) (xy 357.109312 -268.623157) (xy 357.131945 -268.573583)
			(xy 357.161403 -268.527735) (xy 357.197086 -268.486545) (xy 357.238267 -268.450853) (xy 357.284109 -268.421385)
			(xy 357.333678 -268.398741) (xy 357.385965 -268.383381) (xy 357.439906 -268.375619) (xy 357.467154 -268.37513)
			(xy 357.494524 -268.375616) (xy 357.548702 -268.383428) (xy 357.601205 -268.398912) (xy 357.650953 -268.421749)
			(xy 357.69692 -268.45147) (xy 357.717852 -268.46911) (xy 357.724964 -268.475206) (xy 357.741982 -268.481556)
			(xy 357.827326 -268.481556) (xy 357.844344 -268.475206) (xy 357.851456 -268.46911) (xy 357.872389 -268.451469)
			(xy 357.918357 -268.421745) (xy 357.968103 -268.398899) (xy 358.020605 -268.383403) (xy 358.074783 -268.375574)
			(xy 358.129525 -268.375574) (xy 358.183703 -268.383403) (xy 358.236205 -268.398899) (xy 358.285951 -268.421745)
			(xy 358.331919 -268.451469) (xy 358.352852 -268.46911) (xy 358.359964 -268.475206) (xy 358.376982 -268.481556)
			(xy 358.462326 -268.481556) (xy 358.479344 -268.475206) (xy 358.486456 -268.46911) (xy 358.507389 -268.451469)
			(xy 358.553357 -268.421745) (xy 358.603103 -268.398899) (xy 358.655605 -268.383403) (xy 358.709783 -268.375574)
			(xy 358.764525 -268.375574) (xy 358.818703 -268.383403) (xy 358.871205 -268.398899) (xy 358.920951 -268.421745)
			(xy 358.966919 -268.451469) (xy 358.987852 -268.46911) (xy 358.994964 -268.475206) (xy 359.011982 -268.481556)
			(xy 359.097326 -268.481556) (xy 359.114344 -268.475206) (xy 359.121456 -268.46911) (xy 359.142389 -268.451469)
			(xy 359.188357 -268.421745) (xy 359.238103 -268.398899) (xy 359.290605 -268.383403) (xy 359.344783 -268.375574)
			(xy 359.399525 -268.375574) (xy 359.453703 -268.383403) (xy 359.506205 -268.398899) (xy 359.555951 -268.421745)
			(xy 359.601919 -268.451469) (xy 359.622852 -268.46911) (xy 359.629964 -268.475206) (xy 359.646982 -268.481556)
			(xy 359.732326 -268.481556) (xy 359.749344 -268.475206) (xy 359.756456 -268.46911) (xy 359.777395 -268.45148)
			(xy 359.823366 -268.421766) (xy 359.873112 -268.398928) (xy 359.925611 -268.383435) (xy 359.979785 -268.375605)
			(xy 360.007154 -268.37513) (xy 360.034407 -268.375598) (xy 360.08836 -268.38335) (xy 360.14066 -268.398702)
			(xy 360.190243 -268.421342) (xy 360.236098 -268.450809) (xy 360.277292 -268.486502) (xy 360.312987 -268.527696)
			(xy 360.342454 -268.57355) (xy 360.365095 -268.623132) (xy 360.380448 -268.675432) (xy 360.388201 -268.729385)
			(xy 360.388662 -268.756638) (xy 360.388145 -268.785377) (xy 360.379518 -268.842204) (xy 360.362466 -268.897094)
			(xy 360.337373 -268.948806) (xy 360.304808 -268.996169) (xy 360.285538 -269.017496) (xy 360.278934 -269.024608)
			(xy 360.271822 -269.042134) (xy 360.271822 -269.131542) (xy 360.278934 -269.149068) (xy 360.285538 -269.15618)
			(xy 360.304823 -269.177495) (xy 360.337388 -269.22486) (xy 360.362478 -269.276574) (xy 360.379525 -269.331468)
			(xy 360.388144 -269.388298) (xy 360.388662 -269.417038) (xy 360.38828 -269.444294) (xy 360.380517 -269.49825)
			(xy 360.365154 -269.550552) (xy 360.342504 -269.600136) (xy 360.313027 -269.645991) (xy 360.277325 -269.687184)
			(xy 360.236124 -269.722878) (xy 360.190262 -269.752344) (xy 360.140674 -269.774983) (xy 360.088368 -269.790335)
			(xy 360.03441 -269.798086) (xy 360.007154 -269.798546) (xy 359.979784 -269.798061) (xy 359.925605 -269.79025)
			(xy 359.873102 -269.774766) (xy 359.823355 -269.751928) (xy 359.777388 -269.722206) (xy 359.756456 -269.704566)
			(xy 359.749344 -269.69847) (xy 359.732326 -269.69212) (xy 359.646982 -269.69212) (xy 359.629964 -269.69847)
			(xy 359.622852 -269.704566) (xy 359.601919 -269.722207) (xy 359.555951 -269.751931) (xy 359.506205 -269.774777)
			(xy 359.453703 -269.790273) (xy 359.399525 -269.798102) (xy 359.344783 -269.798102) (xy 359.290605 -269.790273)
			(xy 359.238103 -269.774777) (xy 359.188357 -269.751931) (xy 359.142389 -269.722207) (xy 359.121456 -269.704566)
			(xy 359.114344 -269.69847) (xy 359.097326 -269.69212) (xy 359.011982 -269.69212) (xy 358.994964 -269.69847)
			(xy 358.987852 -269.704566) (xy 358.966919 -269.722207) (xy 358.920951 -269.751931) (xy 358.871205 -269.774777)
			(xy 358.818703 -269.790273) (xy 358.764525 -269.798102) (xy 358.709783 -269.798102) (xy 358.655605 -269.790273)
			(xy 358.603103 -269.774777) (xy 358.553357 -269.751931) (xy 358.507389 -269.722207) (xy 358.486456 -269.704566)
			(xy 358.479344 -269.69847) (xy 358.462326 -269.69212) (xy 358.376982 -269.69212) (xy 358.359964 -269.69847)
			(xy 358.352852 -269.704566) (xy 358.331919 -269.722207) (xy 358.285951 -269.751931) (xy 358.236205 -269.774777)
			(xy 358.183703 -269.790273) (xy 358.129525 -269.798102) (xy 358.074783 -269.798102) (xy 358.020605 -269.790273)
			(xy 357.968103 -269.774777) (xy 357.918357 -269.751931) (xy 357.872389 -269.722207) (xy 357.851456 -269.704566)
			(xy 357.844344 -269.69847) (xy 357.827326 -269.69212) (xy 357.741982 -269.69212) (xy 357.724964 -269.69847)
			(xy 357.717852 -269.704566) (xy 357.696907 -269.722189) (xy 357.650938 -269.751904) (xy 357.601194 -269.774744)
			(xy 357.548696 -269.790239) (xy 357.494522 -269.79807) (xy 357.467154 -269.798546) (xy 357.439903 -269.798065)
			(xy 357.385957 -269.790303) (xy 357.333665 -269.774944) (xy 357.28409 -269.752301) (xy 357.238242 -269.722833)
			(xy 357.197053 -269.687141) (xy 357.161362 -269.645952) (xy 357.131896 -269.600103) (xy 357.109253 -269.550528)
			(xy 357.093895 -269.498235) (xy 357.086134 -269.444289) (xy 357.085646 -269.417038) (xy 340.052152 -269.417038)
			(xy 340.052152 -276.051264) (xy 341.2617 -276.051264) (xy 341.262145 -276.023893) (xy 341.269968 -275.969713)
			(xy 341.285462 -275.91721) (xy 341.308308 -275.867463) (xy 341.338037 -275.821497) (xy 341.35568 -275.800566)
			(xy 341.361776 -275.793454) (xy 341.368126 -275.776436) (xy 341.368126 -275.691092) (xy 341.361776 -275.674074)
			(xy 341.35568 -275.666962) (xy 341.338006 -275.646057) (xy 341.308286 -275.600083) (xy 341.285446 -275.550332)
			(xy 341.269954 -275.497826) (xy 341.26213 -275.443645) (xy 341.262134 -275.388901) (xy 341.269966 -275.334721)
			(xy 341.285465 -275.282217) (xy 341.308312 -275.232469) (xy 341.338039 -275.1865) (xy 341.35568 -275.165566)
			(xy 341.361776 -275.158454) (xy 341.368126 -275.141436) (xy 341.368126 -275.056092) (xy 341.361776 -275.039074)
			(xy 341.35568 -275.031962) (xy 341.338053 -275.01102) (xy 341.30834 -274.96505) (xy 341.285502 -274.915305)
			(xy 341.270008 -274.862806) (xy 341.262176 -274.808632) (xy 341.2617 -274.781264) (xy 341.262144 -274.754011)
			(xy 341.269906 -274.700062) (xy 341.285266 -274.647766) (xy 341.307912 -274.598188) (xy 341.337383 -274.552337)
			(xy 341.373079 -274.511147) (xy 341.414273 -274.475456) (xy 341.460127 -274.445991) (xy 341.509707 -274.423351)
			(xy 341.562005 -274.407997) (xy 341.615955 -274.400241) (xy 341.643208 -274.399756) (xy 341.670579 -274.400204)
			(xy 341.724759 -274.408024) (xy 341.777263 -274.423516) (xy 341.82701 -274.446363) (xy 341.872975 -274.476092)
			(xy 341.893906 -274.493736) (xy 341.901018 -274.499832) (xy 341.918036 -274.506182) (xy 342.00338 -274.506182)
			(xy 342.020398 -274.499832) (xy 342.02751 -274.493736) (xy 342.048432 -274.476084) (xy 342.094407 -274.446373)
			(xy 342.144157 -274.423539) (xy 342.19666 -274.408051) (xy 342.250838 -274.400227) (xy 342.278208 -274.399756)
			(xy 342.305458 -274.40027) (xy 342.359403 -274.408027) (xy 342.411695 -274.423381) (xy 342.46127 -274.446021)
			(xy 342.507118 -274.475484) (xy 342.548307 -274.511173) (xy 342.583999 -274.552359) (xy 342.613466 -274.598206)
			(xy 342.636109 -274.647779) (xy 342.651467 -274.70007) (xy 342.659228 -274.754014) (xy 342.659716 -274.781264)
			(xy 342.659249 -274.808634) (xy 342.651435 -274.862814) (xy 342.635947 -274.915318) (xy 342.613105 -274.965065)
			(xy 342.583379 -275.011031) (xy 342.565736 -275.031962) (xy 342.55964 -275.039074) (xy 342.55329 -275.056092)
			(xy 342.55329 -275.141436) (xy 342.55964 -275.158454) (xy 342.565736 -275.165566) (xy 342.583343 -275.186527)
			(xy 342.613072 -275.232489) (xy 342.635922 -275.28223) (xy 342.651422 -275.334728) (xy 342.659255 -275.388904)
			(xy 342.659259 -275.443642) (xy 342.651434 -275.497819) (xy 342.635941 -275.550319) (xy 342.613098 -275.600064)
			(xy 342.583376 -275.64603) (xy 342.565736 -275.666962) (xy 342.55964 -275.674074) (xy 342.55329 -275.691092)
			(xy 342.55329 -275.776436) (xy 342.55964 -275.793454) (xy 342.565736 -275.800566) (xy 342.583343 -275.821527)
			(xy 342.613072 -275.867489) (xy 342.635922 -275.91723) (xy 342.651422 -275.969728) (xy 342.659255 -276.023904)
			(xy 342.659255 -276.027896) (xy 352.727006 -276.027896) (xy 352.727468 -276.000526) (xy 352.735287 -275.946346)
			(xy 352.750777 -275.893843) (xy 352.773619 -275.844096) (xy 352.803344 -275.79813) (xy 352.820986 -275.777198)
			(xy 352.827082 -275.770086) (xy 352.833432 -275.753068) (xy 352.833432 -275.667724) (xy 352.827082 -275.650706)
			(xy 352.820986 -275.643594) (xy 352.803343 -275.622664) (xy 352.773622 -275.576694) (xy 352.750779 -275.526948)
			(xy 352.735285 -275.474445) (xy 352.727457 -275.420267) (xy 352.727458 -275.365527) (xy 352.735286 -275.311349)
			(xy 352.750781 -275.258847) (xy 352.773624 -275.2091) (xy 352.803347 -275.163132) (xy 352.820986 -275.142198)
			(xy 352.827082 -275.135086) (xy 352.833432 -275.118068) (xy 352.833432 -275.032724) (xy 352.827082 -275.015706)
			(xy 352.820986 -275.008594) (xy 352.803328 -274.987677) (xy 352.77362 -274.9417) (xy 352.750788 -274.891948)
			(xy 352.735301 -274.839444) (xy 352.727477 -274.785266) (xy 352.727006 -274.757896) (xy 352.727452 -274.730642)
			(xy 352.73521 -274.67669) (xy 352.750567 -274.624391) (xy 352.773211 -274.57481) (xy 352.80268 -274.528956)
			(xy 352.838376 -274.487763) (xy 352.879571 -274.45207) (xy 352.925426 -274.422602) (xy 352.975008 -274.39996)
			(xy 353.027308 -274.384606) (xy 353.08126 -274.37685) (xy 353.108514 -274.376388) (xy 353.135884 -274.376849)
			(xy 353.190064 -274.384668) (xy 353.242567 -274.400159) (xy 353.292313 -274.423002) (xy 353.33828 -274.452727)
			(xy 353.359212 -274.470368) (xy 353.366324 -274.476464) (xy 353.383342 -274.482814) (xy 353.468686 -274.482814)
			(xy 353.485704 -274.476464) (xy 353.492816 -274.470368) (xy 353.513765 -274.45275) (xy 353.559734 -274.423036)
			(xy 353.609477 -274.400196) (xy 353.661974 -274.3847) (xy 353.716146 -274.376866) (xy 353.743514 -274.376388)
			(xy 353.770765 -274.376865) (xy 353.824713 -274.384623) (xy 353.877008 -274.39998) (xy 353.926585 -274.422622)
			(xy 353.972435 -274.45209) (xy 354.013625 -274.487782) (xy 354.049316 -274.528973) (xy 354.078783 -274.574824)
			(xy 354.101424 -274.624401) (xy 354.116779 -274.676697) (xy 354.124536 -274.730645) (xy 354.125022 -274.757896)
			(xy 354.124573 -274.785267) (xy 354.116754 -274.839448) (xy 354.101262 -274.891952) (xy 354.078416 -274.941698)
			(xy 354.048686 -274.987664) (xy 354.031042 -275.008594) (xy 354.024946 -275.015706) (xy 354.018596 -275.032724)
			(xy 354.018596 -275.118068) (xy 354.024946 -275.135086) (xy 354.031042 -275.142198) (xy 354.04868 -275.163133)
			(xy 354.078407 -275.2091) (xy 354.101255 -275.258846) (xy 354.116753 -275.311347) (xy 354.124582 -275.365526)
			(xy 354.124583 -275.420268) (xy 354.116754 -275.474447) (xy 354.101257 -275.526949) (xy 354.07841 -275.576695)
			(xy 354.048684 -275.622662) (xy 354.031042 -275.643594) (xy 354.024946 -275.650706) (xy 354.018596 -275.667724)
			(xy 354.018596 -275.753068) (xy 354.024946 -275.770086) (xy 354.031042 -275.777198) (xy 354.04868 -275.798133)
			(xy 354.078407 -275.8441) (xy 354.101255 -275.893846) (xy 354.116753 -275.946347) (xy 354.124582 -276.000526)
			(xy 354.124583 -276.046184) (xy 356.66045 -276.046184) (xy 356.660895 -276.018813) (xy 356.668716 -275.964632)
			(xy 356.684209 -275.912129) (xy 356.707056 -275.862382) (xy 356.736786 -275.816417) (xy 356.75443 -275.795486)
			(xy 356.760526 -275.788374) (xy 356.766876 -275.771356) (xy 356.766876 -275.686012) (xy 356.760526 -275.668994)
			(xy 356.75443 -275.661882) (xy 356.736821 -275.640926) (xy 356.707103 -275.59496) (xy 356.684261 -275.545219)
			(xy 356.668763 -275.492723) (xy 356.660928 -275.438552) (xy 356.66045 -275.411184) (xy 356.660963 -275.383934)
			(xy 356.66872 -275.32999) (xy 356.684075 -275.277698) (xy 356.706715 -275.228124) (xy 356.736179 -275.182275)
			(xy 356.771868 -275.141086) (xy 356.813054 -275.105395) (xy 356.858901 -275.075928) (xy 356.908474 -275.053285)
			(xy 356.960764 -275.037926) (xy 357.014708 -275.030165) (xy 357.041958 -275.029676) (xy 357.069328 -275.030148)
			(xy 357.123508 -275.037962) (xy 357.176012 -275.053448) (xy 357.225759 -275.076289) (xy 357.271725 -275.106014)
			(xy 357.292656 -275.123656) (xy 357.299768 -275.129752) (xy 357.316786 -275.136102) (xy 357.40213 -275.136102)
			(xy 357.419148 -275.129752) (xy 357.42626 -275.123656) (xy 357.447193 -275.106015) (xy 357.493161 -275.076291)
			(xy 357.542907 -275.053445) (xy 357.595409 -275.037949) (xy 357.649587 -275.03012) (xy 357.704329 -275.03012)
			(xy 357.758507 -275.037949) (xy 357.811009 -275.053445) (xy 357.860755 -275.076291) (xy 357.906723 -275.106015)
			(xy 357.927656 -275.123656) (xy 357.934768 -275.129752) (xy 357.951786 -275.136102) (xy 358.03713 -275.136102)
			(xy 358.054148 -275.129752) (xy 358.06126 -275.123656) (xy 358.082193 -275.106015) (xy 358.128161 -275.076291)
			(xy 358.177907 -275.053445) (xy 358.230409 -275.037949) (xy 358.284587 -275.03012) (xy 358.339329 -275.03012)
			(xy 358.393507 -275.037949) (xy 358.446009 -275.053445) (xy 358.495755 -275.076291) (xy 358.541723 -275.106015)
			(xy 358.562656 -275.123656) (xy 358.569768 -275.129752) (xy 358.586786 -275.136102) (xy 358.67213 -275.136102)
			(xy 358.689148 -275.129752) (xy 358.69626 -275.123656) (xy 358.717193 -275.106015) (xy 358.763161 -275.076291)
			(xy 358.812907 -275.053445) (xy 358.865409 -275.037949) (xy 358.919587 -275.03012) (xy 358.974329 -275.03012)
			(xy 359.028507 -275.037949) (xy 359.081009 -275.053445) (xy 359.130755 -275.076291) (xy 359.176723 -275.106015)
			(xy 359.197656 -275.123656) (xy 359.204768 -275.129752) (xy 359.221786 -275.136102) (xy 359.30713 -275.136102)
			(xy 359.324148 -275.129752) (xy 359.33126 -275.123656) (xy 359.35219 -275.106015) (xy 359.398164 -275.076305)
			(xy 359.447912 -275.05347) (xy 359.500413 -275.037979) (xy 359.554589 -275.03015) (xy 359.581958 -275.029676)
			(xy 359.609209 -275.030194) (xy 359.663157 -275.037945) (xy 359.715453 -275.053295) (xy 359.765032 -275.075932)
			(xy 359.810885 -275.105394) (xy 359.852077 -275.141082) (xy 359.887772 -275.182269) (xy 359.917241 -275.228117)
			(xy 359.939885 -275.277693) (xy 359.955242 -275.329986) (xy 359.963002 -275.383933) (xy 359.963466 -275.411184)
			(xy 359.962999 -275.438554) (xy 359.955183 -275.492734) (xy 359.939694 -275.545237) (xy 359.916852 -275.594984)
			(xy 359.887128 -275.640951) (xy 359.869486 -275.661882) (xy 359.86339 -275.668994) (xy 359.85704 -275.686012)
			(xy 359.85704 -275.771356) (xy 359.86339 -275.788374) (xy 359.869486 -275.795486) (xy 359.88713 -275.816414)
			(xy 359.916841 -275.862388) (xy 359.939677 -275.912136) (xy 359.955167 -275.964638) (xy 359.962993 -276.018815)
			(xy 359.963466 -276.046184) (xy 359.96303 -276.073438) (xy 359.955274 -276.127392) (xy 359.939918 -276.179693)
			(xy 359.917274 -276.229276) (xy 359.887804 -276.275131) (xy 359.852107 -276.316325) (xy 359.810911 -276.352019)
			(xy 359.765053 -276.381486) (xy 359.715469 -276.404127) (xy 359.663167 -276.419479) (xy 359.609212 -276.427232)
			(xy 359.581958 -276.427692) (xy 359.554589 -276.427194) (xy 359.500411 -276.419384) (xy 359.447908 -276.403903)
			(xy 359.398161 -276.381068) (xy 359.352193 -276.35135) (xy 359.33126 -276.333712) (xy 359.324148 -276.327616)
			(xy 359.30713 -276.321266) (xy 359.221786 -276.321266) (xy 359.204768 -276.327616) (xy 359.197656 -276.333712)
			(xy 359.176723 -276.351353) (xy 359.130755 -276.381077) (xy 359.081009 -276.403923) (xy 359.028507 -276.419419)
			(xy 358.974329 -276.427248) (xy 358.919587 -276.427248) (xy 358.865409 -276.419419) (xy 358.812907 -276.403923)
			(xy 358.763161 -276.381077) (xy 358.717193 -276.351353) (xy 358.69626 -276.333712) (xy 358.689148 -276.327616)
			(xy 358.67213 -276.321266) (xy 358.586786 -276.321266) (xy 358.569768 -276.327616) (xy 358.562656 -276.333712)
			(xy 358.541723 -276.351353) (xy 358.495755 -276.381077) (xy 358.446009 -276.403923) (xy 358.393507 -276.419419)
			(xy 358.339329 -276.427248) (xy 358.284587 -276.427248) (xy 358.230409 -276.419419) (xy 358.177907 -276.403923)
			(xy 358.128161 -276.381077) (xy 358.082193 -276.351353) (xy 358.06126 -276.333712) (xy 358.054148 -276.327616)
			(xy 358.03713 -276.321266) (xy 357.951786 -276.321266) (xy 357.934768 -276.327616) (xy 357.927656 -276.333712)
			(xy 357.906723 -276.351353) (xy 357.860755 -276.381077) (xy 357.811009 -276.403923) (xy 357.758507 -276.419419)
			(xy 357.704329 -276.427248) (xy 357.649587 -276.427248) (xy 357.595409 -276.419419) (xy 357.542907 -276.403923)
			(xy 357.493161 -276.381077) (xy 357.447193 -276.351353) (xy 357.42626 -276.333712) (xy 357.419148 -276.327616)
			(xy 357.40213 -276.321266) (xy 357.316786 -276.321266) (xy 357.299768 -276.327616) (xy 357.292656 -276.333712)
			(xy 357.271715 -276.35134) (xy 357.225745 -276.381053) (xy 357.175999 -276.403891) (xy 357.123501 -276.419385)
			(xy 357.069327 -276.427216) (xy 357.041958 -276.427692) (xy 357.014705 -276.427261) (xy 356.960754 -276.419499)
			(xy 356.908458 -276.404137) (xy 356.858879 -276.38149) (xy 356.813028 -276.352018) (xy 356.771838 -276.316321)
			(xy 356.736147 -276.275125) (xy 356.706682 -276.22927) (xy 356.684042 -276.179688) (xy 356.668689 -276.127389)
			(xy 356.660935 -276.073437) (xy 356.66045 -276.046184) (xy 354.124583 -276.046184) (xy 354.124583 -276.055268)
			(xy 354.116754 -276.109447) (xy 354.101257 -276.161949) (xy 354.07841 -276.211695) (xy 354.048684 -276.257662)
			(xy 354.031042 -276.278594) (xy 354.024946 -276.285706) (xy 354.018596 -276.302724) (xy 354.018596 -276.388068)
			(xy 354.024946 -276.405086) (xy 354.031042 -276.412198) (xy 354.048701 -276.433114) (xy 354.078408 -276.479092)
			(xy 354.10124 -276.528844) (xy 354.116727 -276.581348) (xy 354.124551 -276.635526) (xy 354.125022 -276.662896)
			(xy 354.124536 -276.690147) (xy 354.11678 -276.744095) (xy 354.101425 -276.79639) (xy 354.078783 -276.845967)
			(xy 354.049317 -276.891817) (xy 354.013626 -276.933008) (xy 353.972435 -276.968699) (xy 353.926585 -276.998165)
			(xy 353.877008 -277.020807) (xy 353.824713 -277.036162) (xy 353.770765 -277.043918) (xy 353.716263 -277.043918)
			(xy 353.662315 -277.036162) (xy 353.61002 -277.020807) (xy 353.560443 -276.998165) (xy 353.514593 -276.968699)
			(xy 353.473402 -276.933008) (xy 353.437711 -276.891817) (xy 353.408245 -276.845967) (xy 353.385603 -276.79639)
			(xy 353.370248 -276.744095) (xy 353.362492 -276.690147) (xy 353.362006 -276.662896) (xy 353.362542 -276.633418)
			(xy 353.371612 -276.575165) (xy 353.389535 -276.519) (xy 353.415885 -276.466261) (xy 353.450035 -276.418203)
			(xy 353.47021 -276.396704) (xy 353.476737 -276.389364) (xy 353.484187 -276.371208) (xy 353.484688 -276.361398)
			(xy 353.484688 -276.308058) (xy 353.477322 -276.3012) (xy 353.469975 -276.294682) (xy 353.451824 -276.287227)
			(xy 353.442016 -276.286722) (xy 353.410012 -276.286722) (xy 353.400199 -276.287218) (xy 353.382034 -276.294656)
			(xy 353.374706 -276.3012) (xy 353.353196 -276.321362) (xy 353.30514 -276.35551) (xy 353.252404 -276.38186)
			(xy 353.196241 -276.399783) (xy 353.13799 -276.408854) (xy 353.108514 -276.409404) (xy 353.081261 -276.408932)
			(xy 353.027311 -276.401176) (xy 352.975013 -276.385822) (xy 352.925432 -276.363181) (xy 352.879579 -276.333714)
			(xy 352.838386 -276.298021) (xy 352.802692 -276.256829) (xy 352.773224 -276.210977) (xy 352.750581 -276.161397)
			(xy 352.735226 -276.109099) (xy 352.727469 -276.055149) (xy 352.727006 -276.027896) (xy 342.659255 -276.027896)
			(xy 342.659259 -276.078642) (xy 342.651434 -276.132819) (xy 342.635941 -276.185319) (xy 342.613098 -276.235064)
			(xy 342.583376 -276.28103) (xy 342.565736 -276.301962) (xy 342.55964 -276.309074) (xy 342.55329 -276.326092)
			(xy 342.55329 -276.411436) (xy 342.55964 -276.428454) (xy 342.565736 -276.435566) (xy 342.581893 -276.454665)
			(xy 342.609586 -276.496328) (xy 342.631575 -276.541263) (xy 342.639904 -276.564852) (xy 342.643714 -276.576282)
			(xy 342.660478 -276.593046) (xy 342.759538 -276.626574) (xy 342.78316 -276.623526) (xy 342.793066 -276.616668)
			(xy 342.816823 -276.601327) (xy 342.867881 -276.577017) (xy 342.921967 -276.560507) (xy 342.977897 -276.552158)
			(xy 343.006172 -276.551644) (xy 343.03342 -276.552204) (xy 343.087363 -276.559956) (xy 343.139653 -276.575305)
			(xy 343.189227 -276.597939) (xy 343.235075 -276.627398) (xy 343.276265 -276.663082) (xy 343.311956 -276.704264)
			(xy 343.341424 -276.750106) (xy 343.364069 -276.799675) (xy 343.379428 -276.851963) (xy 343.38719 -276.905904)
			(xy 343.38768 -276.933152) (xy 343.387248 -276.959469) (xy 343.380024 -277.011604) (xy 343.365708 -277.062253)
			(xy 343.344569 -277.110455) (xy 343.31701 -277.155296) (xy 343.283552 -277.195927) (xy 343.26449 -277.214076)
			(xy 343.257095 -277.221603) (xy 343.248567 -277.240879) (xy 343.24798 -277.251414) (xy 343.24798 -277.32609)
			(xy 343.248507 -277.33664) (xy 343.257044 -277.355935) (xy 343.26449 -277.363428) (xy 343.283581 -277.381551)
			(xy 343.317058 -277.422174) (xy 343.344628 -277.467017) (xy 343.365764 -277.515226) (xy 343.380066 -277.565886)
			(xy 343.387261 -277.618032) (xy 343.387518 -277.634192) (xy 352.285046 -277.634192) (xy 352.285601 -277.605067)
			(xy 352.294469 -277.547495) (xy 352.311982 -277.49194) (xy 352.337734 -277.43969) (xy 352.371127 -277.391961)
			(xy 352.411385 -277.349861) (xy 352.434144 -277.331678) (xy 352.443288 -277.324566) (xy 352.453702 -277.304246)
			(xy 352.456242 -277.202138) (xy 352.446844 -277.181056) (xy 352.437954 -277.17369) (xy 352.417226 -277.155498)
			(xy 352.380759 -277.114124) (xy 352.35063 -277.06793) (xy 352.327467 -277.017878) (xy 352.311754 -276.965013)
			(xy 352.303818 -276.910436) (xy 352.303334 -276.88286) (xy 352.30382 -276.855609) (xy 352.311576 -276.801661)
			(xy 352.326931 -276.749366) (xy 352.349573 -276.699789) (xy 352.379039 -276.653939) (xy 352.41473 -276.612748)
			(xy 352.455921 -276.577057) (xy 352.501771 -276.547591) (xy 352.551348 -276.524949) (xy 352.603643 -276.509594)
			(xy 352.657591 -276.501838) (xy 352.712093 -276.501838) (xy 352.766041 -276.509594) (xy 352.818336 -276.524949)
			(xy 352.867913 -276.547591) (xy 352.913763 -276.577057) (xy 352.954954 -276.612748) (xy 352.990645 -276.653939)
			(xy 353.020111 -276.699789) (xy 353.042753 -276.749366) (xy 353.058108 -276.801661) (xy 353.065864 -276.855609)
			(xy 353.06635 -276.88286) (xy 353.065762 -276.911984) (xy 353.056902 -276.969554) (xy 353.039395 -277.025109)
			(xy 353.013649 -277.077359) (xy 352.980262 -277.125088) (xy 352.940009 -277.16719) (xy 352.917252 -277.185374)
			(xy 352.908108 -277.192486) (xy 352.897694 -277.212806) (xy 352.895154 -277.314914) (xy 352.904552 -277.335996)
			(xy 352.913442 -277.343362) (xy 352.934146 -277.36158) (xy 352.970615 -277.402949) (xy 353.000747 -277.449137)
			(xy 353.023914 -277.499184) (xy 353.039632 -277.552045) (xy 353.040313 -277.556722) (xy 353.207826 -277.556722)
			(xy 353.211897 -277.5011) (xy 353.224023 -277.446663) (xy 353.243946 -277.394572) (xy 353.271242 -277.345937)
			(xy 353.305328 -277.301794) (xy 353.345477 -277.263085) (xy 353.390835 -277.230634) (xy 353.440435 -277.205133)
			(xy 353.493219 -277.187126) (xy 353.548062 -277.176996) (xy 353.603796 -277.174959) (xy 353.659233 -277.181059)
			(xy 353.71319 -277.195165) (xy 353.764519 -277.216977) (xy 353.812125 -277.246031) (xy 353.854993 -277.281706)
			(xy 353.89221 -277.323243) (xy 353.922983 -277.369756) (xy 353.946655 -277.420253) (xy 353.962723 -277.47366)
			(xy 353.970843 -277.528836) (xy 353.971352 -277.556722) (xy 353.970843 -277.584608) (xy 353.962723 -277.639784)
			(xy 353.961349 -277.644352) (xy 359.283762 -277.644352) (xy 359.284215 -277.618036) (xy 359.291437 -277.565903)
			(xy 359.305751 -277.515255) (xy 359.326885 -277.467053) (xy 359.35444 -277.422211) (xy 359.387893 -277.381579)
			(xy 359.406952 -277.363428) (xy 359.414336 -277.355891) (xy 359.422872 -277.336623) (xy 359.423462 -277.32609)
			(xy 359.423462 -277.251414) (xy 359.42295 -277.240862) (xy 359.414404 -277.221566) (xy 359.406952 -277.214076)
			(xy 359.387871 -277.195943) (xy 359.354391 -277.155323) (xy 359.326819 -277.110483) (xy 359.305681 -277.062275)
			(xy 359.291377 -277.011617) (xy 359.284181 -276.959472) (xy 359.283762 -276.933152) (xy 359.284248 -276.905901)
			(xy 359.292004 -276.851953) (xy 359.307359 -276.799658) (xy 359.330001 -276.750081) (xy 359.359467 -276.704231)
			(xy 359.395158 -276.66304) (xy 359.436349 -276.627349) (xy 359.482199 -276.597883) (xy 359.531776 -276.575241)
			(xy 359.584071 -276.559886) (xy 359.638019 -276.55213) (xy 359.692521 -276.55213) (xy 359.746469 -276.559886)
			(xy 359.798764 -276.575241) (xy 359.848341 -276.597883) (xy 359.894191 -276.627349) (xy 359.935382 -276.66304)
			(xy 359.971073 -276.704231) (xy 360.000539 -276.750081) (xy 360.023181 -276.799658) (xy 360.038536 -276.851953)
			(xy 360.046292 -276.905901) (xy 360.046778 -276.933152) (xy 360.046346 -276.959469) (xy 360.039123 -277.011604)
			(xy 360.024806 -277.062253) (xy 360.003668 -277.110455) (xy 359.976108 -277.155296) (xy 359.94265 -277.195927)
			(xy 359.923588 -277.214076) (xy 359.916193 -277.221603) (xy 359.907665 -277.240879) (xy 359.907078 -277.251414)
			(xy 359.907078 -277.32609) (xy 359.907605 -277.33664) (xy 359.916142 -277.355935) (xy 359.923588 -277.363428)
			(xy 359.942679 -277.381551) (xy 359.976156 -277.422174) (xy 360.003725 -277.467017) (xy 360.024862 -277.515227)
			(xy 360.039164 -277.565886) (xy 360.046359 -277.618032) (xy 360.046778 -277.644352) (xy 360.046292 -277.671603)
			(xy 360.038536 -277.725551) (xy 360.023181 -277.777846) (xy 360.000539 -277.827423) (xy 359.971073 -277.873273)
			(xy 359.935382 -277.914464) (xy 359.894191 -277.950155) (xy 359.848341 -277.979621) (xy 359.798764 -278.002263)
			(xy 359.746469 -278.017618) (xy 359.692521 -278.025374) (xy 359.638019 -278.025374) (xy 359.584071 -278.017618)
			(xy 359.531776 -278.002263) (xy 359.482199 -277.979621) (xy 359.436349 -277.950155) (xy 359.395158 -277.914464)
			(xy 359.359467 -277.873273) (xy 359.330001 -277.827423) (xy 359.307359 -277.777846) (xy 359.292004 -277.725551)
			(xy 359.284248 -277.671603) (xy 359.283762 -277.644352) (xy 353.961349 -277.644352) (xy 353.946655 -277.693191)
			(xy 353.922983 -277.743688) (xy 353.89221 -277.790201) (xy 353.854993 -277.831738) (xy 353.812125 -277.867413)
			(xy 353.764519 -277.896467) (xy 353.71319 -277.918279) (xy 353.659233 -277.932385) (xy 353.603796 -277.938485)
			(xy 353.548062 -277.936448) (xy 353.493219 -277.926318) (xy 353.440435 -277.908311) (xy 353.390835 -277.88281)
			(xy 353.345477 -277.850359) (xy 353.305328 -277.81165) (xy 353.271242 -277.767507) (xy 353.243946 -277.718872)
			(xy 353.224023 -277.666781) (xy 353.211897 -277.612344) (xy 353.207826 -277.556722) (xy 353.040313 -277.556722)
			(xy 353.047575 -277.606618) (xy 353.048062 -277.634192) (xy 353.047576 -277.661443) (xy 353.03982 -277.715391)
			(xy 353.024465 -277.767686) (xy 353.001823 -277.817263) (xy 352.972357 -277.863113) (xy 352.936666 -277.904304)
			(xy 352.895475 -277.939995) (xy 352.849625 -277.969461) (xy 352.800048 -277.992103) (xy 352.747753 -278.007458)
			(xy 352.693805 -278.015214) (xy 352.639303 -278.015214) (xy 352.585355 -278.007458) (xy 352.53306 -277.992103)
			(xy 352.483483 -277.969461) (xy 352.437633 -277.939995) (xy 352.396442 -277.904304) (xy 352.360751 -277.863113)
			(xy 352.331285 -277.817263) (xy 352.308643 -277.767686) (xy 352.293288 -277.715391) (xy 352.285532 -277.661443)
			(xy 352.285046 -277.634192) (xy 343.387518 -277.634192) (xy 343.38768 -277.644352) (xy 343.3872 -277.671605)
			(xy 343.379449 -277.725557) (xy 343.364097 -277.777856) (xy 343.341458 -277.827438) (xy 343.311993 -277.873293)
			(xy 343.276301 -277.914486) (xy 343.235109 -277.950181) (xy 343.189255 -277.979649) (xy 343.139675 -278.00229)
			(xy 343.087376 -278.017645) (xy 343.033425 -278.025399) (xy 343.006172 -278.02586) (xy 342.979701 -278.025468)
			(xy 342.927265 -278.01817) (xy 342.876343 -278.00369) (xy 342.827912 -277.982306) (xy 342.782904 -277.95443)
			(xy 342.742184 -277.920597) (xy 342.706535 -277.881457) (xy 342.676641 -277.837764) (xy 342.653077 -277.790356)
			(xy 342.636297 -277.740144) (xy 342.631014 -277.714202) (xy 342.628728 -277.701756) (xy 342.613488 -277.682198)
			(xy 342.513666 -277.638002) (xy 342.489028 -277.639526) (xy 342.478106 -277.646384) (xy 342.455452 -277.65976)
			(xy 342.40726 -277.680862) (xy 342.356627 -277.695148) (xy 342.304513 -277.702345) (xy 342.278208 -277.702772)
			(xy 342.250954 -277.702337) (xy 342.197 -277.69458) (xy 342.144699 -277.679223) (xy 342.095117 -277.656579)
			(xy 342.049262 -277.627109) (xy 342.008068 -277.591412) (xy 341.972374 -277.550216) (xy 341.942907 -277.504359)
			(xy 341.920267 -277.454774) (xy 341.904914 -277.402473) (xy 341.897161 -277.348518) (xy 341.8967 -277.321264)
			(xy 341.897145 -277.293893) (xy 341.904968 -277.239713) (xy 341.920462 -277.18721) (xy 341.943308 -277.137463)
			(xy 341.973037 -277.091497) (xy 341.99068 -277.070566) (xy 341.996776 -277.063454) (xy 342.003126 -277.046436)
			(xy 342.003126 -276.961092) (xy 341.996776 -276.944074) (xy 341.99068 -276.936962) (xy 341.973053 -276.91602)
			(xy 341.94334 -276.87005) (xy 341.920502 -276.820305) (xy 341.905008 -276.767806) (xy 341.897176 -276.713632)
			(xy 341.8967 -276.686264) (xy 341.89728 -276.656788) (xy 341.906339 -276.598537) (xy 341.924252 -276.542372)
			(xy 341.950593 -276.489632) (xy 341.984733 -276.441573) (xy 342.004904 -276.420072) (xy 342.011444 -276.412742)
			(xy 342.018886 -276.394578) (xy 342.019382 -276.384766) (xy 342.019382 -276.331426) (xy 342.012016 -276.324568)
			(xy 342.004674 -276.318043) (xy 341.986519 -276.310593) (xy 341.97671 -276.31009) (xy 341.944706 -276.31009)
			(xy 341.934893 -276.310591) (xy 341.916729 -276.318026) (xy 341.9094 -276.324568) (xy 341.887903 -276.344744)
			(xy 341.839843 -276.378888) (xy 341.787102 -276.405234) (xy 341.730938 -276.423154) (xy 341.672685 -276.432223)
			(xy 341.643208 -276.432772) (xy 341.615954 -276.432337) (xy 341.562 -276.42458) (xy 341.509699 -276.409223)
			(xy 341.460117 -276.386579) (xy 341.414262 -276.357109) (xy 341.373068 -276.321412) (xy 341.337374 -276.280216)
			(xy 341.307907 -276.234359) (xy 341.285267 -276.184774) (xy 341.269914 -276.132473) (xy 341.262161 -276.078518)
			(xy 341.2617 -276.051264) (xy 340.052152 -276.051264) (xy 340.052152 -276.596856) (xy 340.051531 -276.626832)
			(xy 340.042147 -276.686046) (xy 340.02362 -276.743064) (xy 339.996404 -276.796483) (xy 339.96117 -276.844989)
			(xy 339.940392 -276.866604) (xy 336.284316 -280.52268) (xy 336.262727 -280.543491) (xy 336.214223 -280.578745)
			(xy 336.1608 -280.605973) (xy 336.126351 -280.617168) (xy 337.73364 -280.617168) (xy 337.734126 -280.589917)
			(xy 337.741882 -280.535969) (xy 337.757237 -280.483674) (xy 337.779879 -280.434097) (xy 337.809345 -280.388247)
			(xy 337.845036 -280.347056) (xy 337.886227 -280.311365) (xy 337.932077 -280.281899) (xy 337.981654 -280.259257)
			(xy 338.033949 -280.243902) (xy 338.087897 -280.236146) (xy 338.142399 -280.236146) (xy 338.196347 -280.243902)
			(xy 338.248642 -280.259257) (xy 338.298219 -280.281899) (xy 338.344069 -280.311365) (xy 338.38526 -280.347056)
			(xy 338.420951 -280.388247) (xy 338.450417 -280.434097) (xy 338.473059 -280.483674) (xy 338.488414 -280.535969)
			(xy 338.49617 -280.589917) (xy 338.496656 -280.617168) (xy 338.496598 -280.627794) (xy 338.495455 -280.649015)
			(xy 338.49437 -280.659586) (xy 338.4931 -280.669238) (xy 338.497926 -280.687526) (xy 338.549488 -280.758392)
			(xy 338.56549 -280.768552) (xy 338.574888 -280.770584) (xy 338.590382 -280.77414) (xy 338.600034 -280.776426)
			(xy 338.619084 -280.773886) (xy 338.697824 -280.728674) (xy 338.709762 -280.713434) (xy 338.712556 -280.703782)
			(xy 338.720558 -280.677663) (xy 338.743109 -280.627908) (xy 338.77253 -280.58188) (xy 338.808218 -280.540522)
			(xy 338.849443 -280.50468) (xy 338.895361 -280.475089) (xy 338.945032 -280.452352) (xy 338.997439 -280.436938)
			(xy 339.05151 -280.429159) (xy 339.078824 -280.4287) (xy 339.103996 -280.42909) (xy 339.153903 -280.435712)
			(xy 339.202507 -280.448836) (xy 339.22589 -280.458164) (xy 339.23605 -280.462482) (xy 339.257386 -280.461974)
			(xy 339.345524 -280.420064) (xy 339.359494 -280.403808) (xy 339.362542 -280.39314) (xy 339.371311 -280.365229)
			(xy 339.396247 -280.312307) (xy 339.428972 -280.263814) (xy 339.468718 -280.220887) (xy 339.514554 -280.184532)
			(xy 339.565404 -280.155604) (xy 339.620075 -280.134781) (xy 339.677285 -280.122551) (xy 339.706458 -280.120344)
			(xy 339.718142 -280.119582) (xy 339.738208 -280.108406) (xy 339.797644 -280.02484) (xy 339.801708 -280.002234)
			(xy 339.798406 -279.991058) (xy 339.791642 -279.965556) (xy 339.784375 -279.913298) (xy 339.783928 -279.886918)
			(xy 339.784414 -279.859667) (xy 339.79217 -279.805719) (xy 339.807525 -279.753424) (xy 339.830167 -279.703847)
			(xy 339.859633 -279.657997) (xy 339.895324 -279.616806) (xy 339.936515 -279.581115) (xy 339.982365 -279.551649)
			(xy 340.031942 -279.529007) (xy 340.084237 -279.513652) (xy 340.138185 -279.505896) (xy 340.192687 -279.505896)
			(xy 340.246635 -279.513652) (xy 340.29893 -279.529007) (xy 340.348507 -279.551649) (xy 340.394357 -279.581115)
			(xy 340.435548 -279.616806) (xy 340.471239 -279.657997) (xy 340.500705 -279.703847) (xy 340.523347 -279.753424)
			(xy 340.538702 -279.805719) (xy 340.546458 -279.859667) (xy 340.546944 -279.886918) (xy 340.546465 -279.915793)
			(xy 340.537781 -279.972886) (xy 340.520585 -280.028016) (xy 340.495269 -280.079921) (xy 340.462413 -280.127413)
			(xy 340.422769 -280.169405) (xy 340.377244 -280.204938) (xy 340.326881 -280.233196) (xy 340.272831 -280.253534)
			(xy 340.216331 -280.265486) (xy 340.187534 -280.267664) (xy 340.17585 -280.268426) (xy 340.155784 -280.279602)
			(xy 340.096348 -280.363168) (xy 340.092284 -280.385774) (xy 340.095586 -280.39695) (xy 340.102351 -280.422452)
			(xy 340.109618 -280.47471) (xy 340.110064 -280.50109) (xy 340.109297 -280.535173) (xy 340.097165 -280.602251)
			(xy 340.09196 -280.617168) (xy 345.894152 -280.617168) (xy 345.894638 -280.589917) (xy 345.902394 -280.535969)
			(xy 345.917749 -280.483674) (xy 345.940391 -280.434097) (xy 345.969857 -280.388247) (xy 346.005548 -280.347056)
			(xy 346.046739 -280.311365) (xy 346.092589 -280.281899) (xy 346.142166 -280.259257) (xy 346.194461 -280.243902)
			(xy 346.248409 -280.236146) (xy 346.302911 -280.236146) (xy 346.356859 -280.243902) (xy 346.409154 -280.259257)
			(xy 346.458731 -280.281899) (xy 346.504581 -280.311365) (xy 346.545772 -280.347056) (xy 346.581463 -280.388247)
			(xy 346.610929 -280.434097) (xy 346.633571 -280.483674) (xy 346.648926 -280.535969) (xy 346.656682 -280.589917)
			(xy 346.657168 -280.617168) (xy 346.65711 -280.627794) (xy 346.655967 -280.649015) (xy 346.654882 -280.659586)
			(xy 346.653612 -280.669238) (xy 346.658438 -280.687526) (xy 346.71 -280.758392) (xy 346.726002 -280.768552)
			(xy 346.7354 -280.770584) (xy 346.750894 -280.77414) (xy 346.760546 -280.776426) (xy 346.779596 -280.773886)
			(xy 346.858336 -280.728674) (xy 346.870274 -280.713434) (xy 346.873068 -280.703782) (xy 346.881148 -280.67769)
			(xy 346.903692 -280.627939) (xy 346.933104 -280.581914) (xy 346.968783 -280.540557) (xy 347.009998 -280.504714)
			(xy 347.055905 -280.475119) (xy 347.105566 -280.452377) (xy 347.157964 -280.436954) (xy 347.212026 -280.429165)
			(xy 347.239336 -280.4287) (xy 347.264508 -280.429087) (xy 347.314415 -280.435709) (xy 347.363019 -280.448835)
			(xy 347.386402 -280.458164) (xy 347.396562 -280.462482) (xy 347.417898 -280.461974) (xy 347.506036 -280.420064)
			(xy 347.520006 -280.403808) (xy 347.523054 -280.39314) (xy 347.531813 -280.365226) (xy 347.55675 -280.312303)
			(xy 347.589476 -280.263809) (xy 347.629224 -280.220882) (xy 347.675062 -280.184528) (xy 347.725913 -280.155601)
			(xy 347.780586 -280.134779) (xy 347.837797 -280.12255) (xy 347.86697 -280.120344) (xy 347.878654 -280.119582)
			(xy 347.89872 -280.108406) (xy 347.958156 -280.02484) (xy 347.96222 -280.002234) (xy 347.958918 -279.991058)
			(xy 347.952155 -279.965556) (xy 347.944887 -279.913298) (xy 347.94444 -279.886918) (xy 347.944926 -279.859667)
			(xy 347.952682 -279.805719) (xy 347.968037 -279.753424) (xy 347.990679 -279.703847) (xy 348.020145 -279.657997)
			(xy 348.055836 -279.616806) (xy 348.097027 -279.581115) (xy 348.142877 -279.551649) (xy 348.192454 -279.529007)
			(xy 348.244749 -279.513652) (xy 348.298697 -279.505896) (xy 348.353199 -279.505896) (xy 348.407147 -279.513652)
			(xy 348.459442 -279.529007) (xy 348.509019 -279.551649) (xy 348.554869 -279.581115) (xy 348.59606 -279.616806)
			(xy 348.631751 -279.657997) (xy 348.661217 -279.703847) (xy 348.683859 -279.753424) (xy 348.699214 -279.805719)
			(xy 348.70697 -279.859667) (xy 348.707456 -279.886918) (xy 348.706966 -279.915793) (xy 348.698282 -279.972884)
			(xy 348.681086 -280.028013) (xy 348.655771 -280.079917) (xy 348.622917 -280.127409) (xy 348.583274 -280.169402)
			(xy 348.537751 -280.204934) (xy 348.487389 -280.233193) (xy 348.433341 -280.253532) (xy 348.376843 -280.265485)
			(xy 348.348046 -280.267664) (xy 348.336362 -280.268426) (xy 348.316296 -280.279602) (xy 348.25686 -280.363168)
			(xy 348.252796 -280.385774) (xy 348.256098 -280.39695) (xy 348.262863 -280.422452) (xy 348.27013 -280.47471)
			(xy 348.270576 -280.50109) (xy 348.269808 -280.535173) (xy 348.257676 -280.602251) (xy 348.252472 -280.617168)
			(xy 354.392738 -280.617168) (xy 354.393224 -280.589917) (xy 354.40098 -280.535969) (xy 354.416335 -280.483674)
			(xy 354.438977 -280.434097) (xy 354.468443 -280.388247) (xy 354.504134 -280.347056) (xy 354.545325 -280.311365)
			(xy 354.591175 -280.281899) (xy 354.640752 -280.259257) (xy 354.693047 -280.243902) (xy 354.746995 -280.236146)
			(xy 354.801497 -280.236146) (xy 354.855445 -280.243902) (xy 354.90774 -280.259257) (xy 354.957317 -280.281899)
			(xy 355.003167 -280.311365) (xy 355.044358 -280.347056) (xy 355.080049 -280.388247) (xy 355.109515 -280.434097)
			(xy 355.132157 -280.483674) (xy 355.147512 -280.535969) (xy 355.155268 -280.589917) (xy 355.155754 -280.617168)
			(xy 355.155696 -280.627794) (xy 355.154553 -280.649015) (xy 355.153468 -280.659586) (xy 355.152198 -280.669238)
			(xy 355.157024 -280.687526) (xy 355.208586 -280.758392) (xy 355.224588 -280.768552) (xy 355.233986 -280.770584)
			(xy 355.24948 -280.77414) (xy 355.259132 -280.776426) (xy 355.278182 -280.773886) (xy 355.356922 -280.728674)
			(xy 355.36886 -280.713434) (xy 355.371654 -280.703782) (xy 355.379657 -280.677664) (xy 355.402208 -280.627909)
			(xy 355.431629 -280.581881) (xy 355.467317 -280.540523) (xy 355.508542 -280.504681) (xy 355.55446 -280.475089)
			(xy 355.604131 -280.452353) (xy 355.656538 -280.436938) (xy 355.710608 -280.429159) (xy 355.737922 -280.4287)
			(xy 355.763094 -280.429091) (xy 355.813001 -280.435712) (xy 355.861605 -280.448836) (xy 355.884988 -280.458164)
			(xy 355.895148 -280.462482) (xy 355.916484 -280.461974) (xy 356.004622 -280.420064) (xy 356.018592 -280.403808)
			(xy 356.02164 -280.39314) (xy 356.03041 -280.36523) (xy 356.055346 -280.312308) (xy 356.088071 -280.263814)
			(xy 356.127817 -280.220887) (xy 356.173653 -280.184533) (xy 356.224503 -280.155605) (xy 356.279174 -280.134781)
			(xy 356.336383 -280.122551) (xy 356.365556 -280.120344) (xy 356.37724 -280.119582) (xy 356.397306 -280.108406)
			(xy 356.456742 -280.02484) (xy 356.460806 -280.002234) (xy 356.457504 -279.991058) (xy 356.45074 -279.965556)
			(xy 356.443473 -279.913298) (xy 356.443026 -279.886918) (xy 356.443512 -279.859667) (xy 356.451268 -279.805719)
			(xy 356.466623 -279.753424) (xy 356.489265 -279.703847) (xy 356.518731 -279.657997) (xy 356.554422 -279.616806)
			(xy 356.595613 -279.581115) (xy 356.641463 -279.551649) (xy 356.69104 -279.529007) (xy 356.743335 -279.513652)
			(xy 356.797283 -279.505896) (xy 356.851785 -279.505896) (xy 356.905733 -279.513652) (xy 356.958028 -279.529007)
			(xy 357.007605 -279.551649) (xy 357.053455 -279.581115) (xy 357.094646 -279.616806) (xy 357.130337 -279.657997)
			(xy 357.159803 -279.703847) (xy 357.182445 -279.753424) (xy 357.1978 -279.805719) (xy 357.205556 -279.859667)
			(xy 357.206042 -279.886918) (xy 357.205565 -279.915793) (xy 357.196881 -279.972886) (xy 357.179684 -280.028016)
			(xy 357.154368 -280.079921) (xy 357.121512 -280.127413) (xy 357.081868 -280.169406) (xy 357.036343 -280.204938)
			(xy 356.985979 -280.233196) (xy 356.931929 -280.253534) (xy 356.87543 -280.265486) (xy 356.846632 -280.267664)
			(xy 356.834948 -280.268426) (xy 356.814882 -280.279602) (xy 356.755446 -280.363168) (xy 356.751382 -280.385774)
			(xy 356.754684 -280.39695) (xy 356.761449 -280.422452) (xy 356.768716 -280.47471) (xy 356.769162 -280.50109)
			(xy 356.768395 -280.535173) (xy 356.756263 -280.602251) (xy 356.751058 -280.617168) (xy 362.55325 -280.617168)
			(xy 362.553736 -280.589917) (xy 362.561492 -280.535969) (xy 362.576847 -280.483674) (xy 362.599489 -280.434097)
			(xy 362.628955 -280.388247) (xy 362.664646 -280.347056) (xy 362.705837 -280.311365) (xy 362.751687 -280.281899)
			(xy 362.801264 -280.259257) (xy 362.853559 -280.243902) (xy 362.907507 -280.236146) (xy 362.962009 -280.236146)
			(xy 363.015957 -280.243902) (xy 363.068252 -280.259257) (xy 363.117829 -280.281899) (xy 363.163679 -280.311365)
			(xy 363.20487 -280.347056) (xy 363.240561 -280.388247) (xy 363.270027 -280.434097) (xy 363.292669 -280.483674)
			(xy 363.308024 -280.535969) (xy 363.31578 -280.589917) (xy 363.316266 -280.617168) (xy 363.316208 -280.627794)
			(xy 363.315065 -280.649015) (xy 363.31398 -280.659586) (xy 363.31271 -280.669238) (xy 363.317536 -280.687526)
			(xy 363.369098 -280.758392) (xy 363.3851 -280.768552) (xy 363.394498 -280.770584) (xy 363.409992 -280.77414)
			(xy 363.419644 -280.776426) (xy 363.438694 -280.773886) (xy 363.517434 -280.728674) (xy 363.529372 -280.713434)
			(xy 363.532166 -280.703782) (xy 363.540248 -280.67769) (xy 363.562792 -280.62794) (xy 363.592204 -280.581915)
			(xy 363.627882 -280.540558) (xy 363.669097 -280.504715) (xy 363.715004 -280.47512) (xy 363.764665 -280.452378)
			(xy 363.817062 -280.436954) (xy 363.871124 -280.429166) (xy 363.898434 -280.4287) (xy 363.923606 -280.429087)
			(xy 363.973513 -280.43571) (xy 364.022117 -280.448835) (xy 364.0455 -280.458164) (xy 364.05566 -280.462482)
			(xy 364.076996 -280.461974) (xy 364.165134 -280.420064) (xy 364.179104 -280.403808) (xy 364.182152 -280.39314)
			(xy 364.190912 -280.365226) (xy 364.215849 -280.312304) (xy 364.248575 -280.26381) (xy 364.288323 -280.220883)
			(xy 364.33416 -280.184529) (xy 364.385012 -280.155602) (xy 364.439684 -280.134779) (xy 364.496895 -280.12255)
			(xy 364.526068 -280.120344) (xy 364.537752 -280.119582) (xy 364.557818 -280.108406) (xy 364.617254 -280.02484)
			(xy 364.621318 -280.002234) (xy 364.618016 -279.991058) (xy 364.611252 -279.965556) (xy 364.603985 -279.913298)
			(xy 364.603538 -279.886918) (xy 364.604024 -279.859667) (xy 364.61178 -279.805719) (xy 364.627135 -279.753424)
			(xy 364.649777 -279.703847) (xy 364.679243 -279.657997) (xy 364.714934 -279.616806) (xy 364.756125 -279.581115)
			(xy 364.801975 -279.551649) (xy 364.851552 -279.529007) (xy 364.903847 -279.513652) (xy 364.957795 -279.505896)
			(xy 365.012297 -279.505896) (xy 365.066245 -279.513652) (xy 365.11854 -279.529007) (xy 365.168117 -279.551649)
			(xy 365.213967 -279.581115) (xy 365.255158 -279.616806) (xy 365.290849 -279.657997) (xy 365.320315 -279.703847)
			(xy 365.342957 -279.753424) (xy 365.358312 -279.805719) (xy 365.366068 -279.859667) (xy 365.366554 -279.886918)
			(xy 365.366066 -279.915793) (xy 365.357382 -279.972885) (xy 365.340186 -280.028014) (xy 365.314871 -280.079918)
			(xy 365.282016 -280.12741) (xy 365.242373 -280.169402) (xy 365.19685 -280.204934) (xy 365.146488 -280.233193)
			(xy 365.092439 -280.253532) (xy 365.035941 -280.265485) (xy 365.007144 -280.267664) (xy 364.99546 -280.268426)
			(xy 364.975394 -280.279602) (xy 364.915958 -280.363168) (xy 364.911894 -280.385774) (xy 364.915196 -280.39695)
			(xy 364.921961 -280.422452) (xy 364.929228 -280.47471) (xy 364.929674 -280.50109) (xy 364.928906 -280.535173)
			(xy 364.916774 -280.602251) (xy 364.905544 -280.63444) (xy 364.90148 -280.645616) (xy 364.90402 -280.669492)
			(xy 364.961424 -280.758138) (xy 364.981998 -280.77033) (xy 364.993936 -280.771092) (xy 365.022544 -280.773549)
			(xy 365.078611 -280.785929) (xy 365.13219 -280.806569) (xy 365.182073 -280.835001) (xy 365.227134 -280.870586)
			(xy 365.266356 -280.912519) (xy 365.298854 -280.959855) (xy 365.323894 -281.011524) (xy 365.325503 -281.01671)
			(xy 366.057178 -281.01671) (xy 366.061249 -280.961088) (xy 366.073375 -280.906651) (xy 366.093298 -280.85456)
			(xy 366.120594 -280.805925) (xy 366.15468 -280.761782) (xy 366.194829 -280.723073) (xy 366.240187 -280.690622)
			(xy 366.289787 -280.665121) (xy 366.342571 -280.647114) (xy 366.397414 -280.636984) (xy 366.453148 -280.634947)
			(xy 366.508585 -280.641047) (xy 366.562542 -280.655153) (xy 366.613871 -280.676965) (xy 366.661477 -280.706019)
			(xy 366.704345 -280.741694) (xy 366.741562 -280.783231) (xy 366.772335 -280.829744) (xy 366.796007 -280.880241)
			(xy 366.812075 -280.933648) (xy 366.820195 -280.988824) (xy 366.820704 -281.01671) (xy 366.820195 -281.044596)
			(xy 366.812075 -281.099772) (xy 366.796007 -281.153179) (xy 366.772335 -281.203676) (xy 366.741562 -281.250189)
			(xy 366.704345 -281.291726) (xy 366.661477 -281.327401) (xy 366.613871 -281.356455) (xy 366.562542 -281.378267)
			(xy 366.508585 -281.392373) (xy 366.453148 -281.398473) (xy 366.397414 -281.396436) (xy 366.342571 -281.386306)
			(xy 366.289787 -281.368299) (xy 366.240187 -281.342798) (xy 366.194829 -281.310347) (xy 366.15468 -281.271638)
			(xy 366.120594 -281.227495) (xy 366.093298 -281.17886) (xy 366.073375 -281.126769) (xy 366.061249 -281.072332)
			(xy 366.057178 -281.01671) (xy 365.325503 -281.01671) (xy 365.340911 -281.066362) (xy 365.349521 -281.123129)
			(xy 365.350044 -281.151838) (xy 365.349558 -281.179089) (xy 365.341802 -281.233037) (xy 365.326447 -281.285332)
			(xy 365.303805 -281.334909) (xy 365.274339 -281.380759) (xy 365.238648 -281.42195) (xy 365.197457 -281.457641)
			(xy 365.151607 -281.487107) (xy 365.10203 -281.509749) (xy 365.049735 -281.525104) (xy 364.995787 -281.53286)
			(xy 364.941285 -281.53286) (xy 364.887337 -281.525104) (xy 364.835042 -281.509749) (xy 364.785465 -281.487107)
			(xy 364.739615 -281.457641) (xy 364.698424 -281.42195) (xy 364.662733 -281.380759) (xy 364.633267 -281.334909)
			(xy 364.610625 -281.285332) (xy 364.59527 -281.233037) (xy 364.587514 -281.179089) (xy 364.587028 -281.151838)
			(xy 364.587777 -281.117754) (xy 364.599921 -281.050676) (xy 364.611158 -281.018488) (xy 364.615222 -281.007312)
			(xy 364.612682 -280.983436) (xy 364.555278 -280.89479) (xy 364.534704 -280.882598) (xy 364.522766 -280.881836)
			(xy 364.491468 -280.879091) (xy 364.430323 -280.86467) (xy 364.4011 -280.853134) (xy 364.39094 -280.848816)
			(xy 364.369604 -280.849324) (xy 364.281466 -280.891234) (xy 364.267496 -280.90749) (xy 364.264448 -280.918158)
			(xy 364.256256 -280.94413) (xy 364.233577 -280.99364) (xy 364.204088 -281.039422) (xy 364.168389 -281.080545)
			(xy 364.127205 -281.116175) (xy 364.081373 -281.145586) (xy 364.031825 -281.168182) (xy 363.979568 -281.183502)
			(xy 363.925663 -281.191237) (xy 363.898434 -281.191716) (xy 363.875078 -281.191348) (xy 363.828719 -281.185619)
			(xy 363.805978 -281.180286) (xy 363.796326 -281.178) (xy 363.777276 -281.18054) (xy 363.698536 -281.225752)
			(xy 363.686598 -281.240992) (xy 363.683804 -281.250644) (xy 363.675765 -281.27675) (xy 363.653216 -281.326501)
			(xy 363.623798 -281.372527) (xy 363.588113 -281.413883) (xy 363.546893 -281.449725) (xy 363.500981 -281.479318)
			(xy 363.451315 -281.502058) (xy 363.398914 -281.517477) (xy 363.344848 -281.525263) (xy 363.317536 -281.525726)
			(xy 363.290285 -281.525211) (xy 363.236337 -281.51746) (xy 363.184041 -281.502109) (xy 363.134462 -281.479472)
			(xy 363.08861 -281.45001) (xy 363.047417 -281.414321) (xy 363.011723 -281.373134) (xy 362.982254 -281.327285)
			(xy 362.95961 -281.27771) (xy 362.944252 -281.225416) (xy 362.936493 -281.171469) (xy 362.936028 -281.144218)
			(xy 362.936085 -281.133592) (xy 362.937228 -281.112371) (xy 362.938314 -281.1018) (xy 362.939584 -281.092148)
			(xy 362.934758 -281.07386) (xy 362.883196 -281.002994) (xy 362.867194 -280.992834) (xy 362.857796 -280.990802)
			(xy 362.829495 -280.984439) (xy 362.775108 -280.964278) (xy 362.724399 -280.936114) (xy 362.67854 -280.900598)
			(xy 362.638586 -280.858548) (xy 362.605459 -280.810934) (xy 362.579922 -280.758853) (xy 362.562566 -280.703507)
			(xy 362.553789 -280.64617) (xy 362.55325 -280.617168) (xy 356.751058 -280.617168) (xy 356.745032 -280.63444)
			(xy 356.740968 -280.645616) (xy 356.743508 -280.669492) (xy 356.800912 -280.758138) (xy 356.821486 -280.77033)
			(xy 356.833424 -280.771092) (xy 356.862031 -280.773559) (xy 356.918098 -280.785938) (xy 356.971677 -280.806576)
			(xy 357.02156 -280.835007) (xy 357.066621 -280.87059) (xy 357.105843 -280.912522) (xy 357.138341 -280.959857)
			(xy 357.157646 -280.999692) (xy 357.896666 -280.999692) (xy 357.900737 -280.94407) (xy 357.912863 -280.889633)
			(xy 357.932786 -280.837542) (xy 357.960082 -280.788907) (xy 357.994168 -280.744764) (xy 358.034317 -280.706055)
			(xy 358.079675 -280.673604) (xy 358.129275 -280.648103) (xy 358.182059 -280.630096) (xy 358.236902 -280.619966)
			(xy 358.292636 -280.617929) (xy 358.348073 -280.624029) (xy 358.40203 -280.638135) (xy 358.453359 -280.659947)
			(xy 358.500965 -280.689001) (xy 358.543833 -280.724676) (xy 358.58105 -280.766213) (xy 358.611823 -280.812726)
			(xy 358.635495 -280.863223) (xy 358.651563 -280.91663) (xy 358.659683 -280.971806) (xy 358.660192 -280.999692)
			(xy 358.659683 -281.027578) (xy 358.651563 -281.082754) (xy 358.635495 -281.136161) (xy 358.611823 -281.186658)
			(xy 358.58105 -281.233171) (xy 358.543833 -281.274708) (xy 358.500965 -281.310383) (xy 358.453359 -281.339437)
			(xy 358.40203 -281.361249) (xy 358.348073 -281.375355) (xy 358.292636 -281.381455) (xy 358.236902 -281.379418)
			(xy 358.182059 -281.369288) (xy 358.129275 -281.351281) (xy 358.079675 -281.32578) (xy 358.034317 -281.293329)
			(xy 357.994168 -281.25462) (xy 357.960082 -281.210477) (xy 357.932786 -281.161842) (xy 357.912863 -281.109751)
			(xy 357.900737 -281.055314) (xy 357.896666 -280.999692) (xy 357.157646 -280.999692) (xy 357.163381 -281.011526)
			(xy 357.180399 -281.066362) (xy 357.189009 -281.12313) (xy 357.189532 -281.151838) (xy 357.189046 -281.179089)
			(xy 357.18129 -281.233037) (xy 357.165935 -281.285332) (xy 357.143293 -281.334909) (xy 357.113827 -281.380759)
			(xy 357.078136 -281.42195) (xy 357.036945 -281.457641) (xy 356.991095 -281.487107) (xy 356.941518 -281.509749)
			(xy 356.889223 -281.525104) (xy 356.835275 -281.53286) (xy 356.780773 -281.53286) (xy 356.726825 -281.525104)
			(xy 356.67453 -281.509749) (xy 356.624953 -281.487107) (xy 356.579103 -281.457641) (xy 356.537912 -281.42195)
			(xy 356.502221 -281.380759) (xy 356.472755 -281.334909) (xy 356.450113 -281.285332) (xy 356.434758 -281.233037)
			(xy 356.427002 -281.179089) (xy 356.426516 -281.151838) (xy 356.427266 -281.117754) (xy 356.43941 -281.050676)
			(xy 356.450646 -281.018488) (xy 356.45471 -281.007312) (xy 356.45217 -280.983436) (xy 356.394766 -280.89479)
			(xy 356.374192 -280.882598) (xy 356.362254 -280.881836) (xy 356.330956 -280.879094) (xy 356.269811 -280.864671)
			(xy 356.240588 -280.853134) (xy 356.230428 -280.848816) (xy 356.209092 -280.849324) (xy 356.120954 -280.891234)
			(xy 356.106984 -280.90749) (xy 356.103936 -280.918158) (xy 356.095755 -280.944134) (xy 356.073075 -280.993644)
			(xy 356.043585 -281.039426) (xy 356.007884 -281.08055) (xy 355.966699 -281.11618) (xy 355.920866 -281.14559)
			(xy 355.871316 -281.168185) (xy 355.819057 -281.183505) (xy 355.765151 -281.191237) (xy 355.737922 -281.191716)
			(xy 355.714566 -281.191351) (xy 355.668207 -281.18562) (xy 355.645466 -281.180286) (xy 355.635814 -281.178)
			(xy 355.616764 -281.18054) (xy 355.538024 -281.225752) (xy 355.526086 -281.240992) (xy 355.523292 -281.250644)
			(xy 355.515264 -281.276753) (xy 355.492713 -281.326506) (xy 355.463294 -281.372531) (xy 355.427609 -281.413888)
			(xy 355.386387 -281.449729) (xy 355.340473 -281.479322) (xy 355.290806 -281.502061) (xy 355.238403 -281.51748)
			(xy 355.184336 -281.525263) (xy 355.157024 -281.525726) (xy 355.129773 -281.525222) (xy 355.075824 -281.517469)
			(xy 355.023528 -281.502117) (xy 354.973949 -281.479479) (xy 354.928097 -281.450015) (xy 354.886904 -281.414325)
			(xy 354.85121 -281.373137) (xy 354.821741 -281.327288) (xy 354.799098 -281.277711) (xy 354.78374 -281.225417)
			(xy 354.775981 -281.171469) (xy 354.775516 -281.144218) (xy 354.775573 -281.133592) (xy 354.776716 -281.112371)
			(xy 354.777802 -281.1018) (xy 354.779072 -281.092148) (xy 354.774246 -281.07386) (xy 354.722684 -281.002994)
			(xy 354.706682 -280.992834) (xy 354.697284 -280.990802) (xy 354.668981 -280.984448) (xy 354.614594 -280.964285)
			(xy 354.563886 -280.93612) (xy 354.518026 -280.900602) (xy 354.478073 -280.858552) (xy 354.444946 -280.810936)
			(xy 354.41941 -280.758855) (xy 354.402054 -280.703508) (xy 354.393277 -280.646171) (xy 354.392738 -280.617168)
			(xy 348.252472 -280.617168) (xy 348.246446 -280.63444) (xy 348.242382 -280.645616) (xy 348.244922 -280.669492)
			(xy 348.302326 -280.758138) (xy 348.3229 -280.77033) (xy 348.334838 -280.771092) (xy 348.363446 -280.773547)
			(xy 348.419513 -280.785928) (xy 348.473093 -280.806567) (xy 348.522976 -280.835) (xy 348.568036 -280.870585)
			(xy 348.607258 -280.912518) (xy 348.639756 -280.959854) (xy 348.664796 -281.011524) (xy 348.666405 -281.01671)
			(xy 349.39808 -281.01671) (xy 349.402151 -280.961088) (xy 349.414277 -280.906651) (xy 349.4342 -280.85456)
			(xy 349.461496 -280.805925) (xy 349.495582 -280.761782) (xy 349.535731 -280.723073) (xy 349.581089 -280.690622)
			(xy 349.630689 -280.665121) (xy 349.683473 -280.647114) (xy 349.738316 -280.636984) (xy 349.79405 -280.634947)
			(xy 349.849487 -280.641047) (xy 349.903444 -280.655153) (xy 349.954773 -280.676965) (xy 350.002379 -280.706019)
			(xy 350.045247 -280.741694) (xy 350.082464 -280.783231) (xy 350.113237 -280.829744) (xy 350.136909 -280.880241)
			(xy 350.152977 -280.933648) (xy 350.161097 -280.988824) (xy 350.161606 -281.01671) (xy 350.161097 -281.044596)
			(xy 350.152977 -281.099772) (xy 350.136909 -281.153179) (xy 350.113237 -281.203676) (xy 350.082464 -281.250189)
			(xy 350.045247 -281.291726) (xy 350.002379 -281.327401) (xy 349.954773 -281.356455) (xy 349.903444 -281.378267)
			(xy 349.849487 -281.392373) (xy 349.79405 -281.398473) (xy 349.738316 -281.396436) (xy 349.683473 -281.386306)
			(xy 349.630689 -281.368299) (xy 349.581089 -281.342798) (xy 349.535731 -281.310347) (xy 349.495582 -281.271638)
			(xy 349.461496 -281.227495) (xy 349.4342 -281.17886) (xy 349.414277 -281.126769) (xy 349.402151 -281.072332)
			(xy 349.39808 -281.01671) (xy 348.666405 -281.01671) (xy 348.681813 -281.066361) (xy 348.690423 -281.123129)
			(xy 348.690946 -281.151838) (xy 348.69046 -281.179089) (xy 348.682704 -281.233037) (xy 348.667349 -281.285332)
			(xy 348.644707 -281.334909) (xy 348.615241 -281.380759) (xy 348.57955 -281.42195) (xy 348.538359 -281.457641)
			(xy 348.492509 -281.487107) (xy 348.442932 -281.509749) (xy 348.390637 -281.525104) (xy 348.336689 -281.53286)
			(xy 348.282187 -281.53286) (xy 348.228239 -281.525104) (xy 348.175944 -281.509749) (xy 348.126367 -281.487107)
			(xy 348.080517 -281.457641) (xy 348.039326 -281.42195) (xy 348.003635 -281.380759) (xy 347.974169 -281.334909)
			(xy 347.951527 -281.285332) (xy 347.936172 -281.233037) (xy 347.928416 -281.179089) (xy 347.92793 -281.151838)
			(xy 347.928679 -281.117754) (xy 347.940823 -281.050676) (xy 347.95206 -281.018488) (xy 347.956124 -281.007312)
			(xy 347.953584 -280.983436) (xy 347.89618 -280.89479) (xy 347.875606 -280.882598) (xy 347.863668 -280.881836)
			(xy 347.83237 -280.87909) (xy 347.771225 -280.86467) (xy 347.742002 -280.853134) (xy 347.731842 -280.848816)
			(xy 347.710506 -280.849324) (xy 347.622368 -280.891234) (xy 347.608398 -280.90749) (xy 347.60535 -280.918158)
			(xy 347.597156 -280.944129) (xy 347.574477 -280.993639) (xy 347.544989 -281.039421) (xy 347.50929 -281.080545)
			(xy 347.468106 -281.116174) (xy 347.422275 -281.145586) (xy 347.372727 -281.168181) (xy 347.320469 -281.183502)
			(xy 347.266565 -281.191236) (xy 347.239336 -281.191716) (xy 347.21598 -281.191348) (xy 347.169622 -281.185619)
			(xy 347.14688 -281.180286) (xy 347.137228 -281.178) (xy 347.118178 -281.18054) (xy 347.039438 -281.225752)
			(xy 347.0275 -281.240992) (xy 347.024706 -281.250644) (xy 347.016665 -281.276749) (xy 346.994116 -281.326501)
			(xy 346.964698 -281.372526) (xy 346.929014 -281.413882) (xy 346.887794 -281.449724) (xy 346.841882 -281.479318)
			(xy 346.792217 -281.502057) (xy 346.739815 -281.517477) (xy 346.68575 -281.525262) (xy 346.658438 -281.525726)
			(xy 346.631187 -281.525209) (xy 346.577239 -281.517458) (xy 346.524943 -281.502108) (xy 346.475364 -281.479471)
			(xy 346.429512 -281.450009) (xy 346.388319 -281.41432) (xy 346.352625 -281.373133) (xy 346.323156 -281.327285)
			(xy 346.300512 -281.277709) (xy 346.285154 -281.225416) (xy 346.277395 -281.171469) (xy 346.27693 -281.144218)
			(xy 346.276987 -281.133592) (xy 346.27813 -281.112371) (xy 346.279216 -281.1018) (xy 346.280486 -281.092148)
			(xy 346.27566 -281.07386) (xy 346.224098 -281.002994) (xy 346.208096 -280.992834) (xy 346.198698 -280.990802)
			(xy 346.170398 -280.984438) (xy 346.11601 -280.964277) (xy 346.065302 -280.936114) (xy 346.019442 -280.900598)
			(xy 345.979488 -280.858548) (xy 345.946361 -280.810934) (xy 345.920825 -280.758853) (xy 345.903468 -280.703507)
			(xy 345.894691 -280.64617) (xy 345.894152 -280.617168) (xy 340.09196 -280.617168) (xy 340.085934 -280.63444)
			(xy 340.08187 -280.645616) (xy 340.08441 -280.669492) (xy 340.141814 -280.758138) (xy 340.162388 -280.77033)
			(xy 340.174326 -280.771092) (xy 340.202934 -280.773558) (xy 340.259 -280.785936) (xy 340.312579 -280.806574)
			(xy 340.362462 -280.835006) (xy 340.407523 -280.87059) (xy 340.446745 -280.912522) (xy 340.479243 -280.959857)
			(xy 340.498548 -280.999692) (xy 341.055196 -280.999692) (xy 341.059267 -280.94407) (xy 341.071393 -280.889633)
			(xy 341.091316 -280.837542) (xy 341.118612 -280.788907) (xy 341.152698 -280.744764) (xy 341.192847 -280.706055)
			(xy 341.238205 -280.673604) (xy 341.287805 -280.648103) (xy 341.340589 -280.630096) (xy 341.395432 -280.619966)
			(xy 341.451166 -280.617929) (xy 341.506603 -280.624029) (xy 341.56056 -280.638135) (xy 341.611889 -280.659947)
			(xy 341.659495 -280.689001) (xy 341.702363 -280.724676) (xy 341.73958 -280.766213) (xy 341.770353 -280.812726)
			(xy 341.794025 -280.863223) (xy 341.810093 -280.91663) (xy 341.818213 -280.971806) (xy 341.818722 -280.999692)
			(xy 341.818213 -281.027578) (xy 341.810093 -281.082754) (xy 341.794025 -281.136161) (xy 341.770353 -281.186658)
			(xy 341.73958 -281.233171) (xy 341.702363 -281.274708) (xy 341.659495 -281.310383) (xy 341.611889 -281.339437)
			(xy 341.56056 -281.361249) (xy 341.506603 -281.375355) (xy 341.451166 -281.381455) (xy 341.395432 -281.379418)
			(xy 341.340589 -281.369288) (xy 341.287805 -281.351281) (xy 341.238205 -281.32578) (xy 341.192847 -281.293329)
			(xy 341.152698 -281.25462) (xy 341.118612 -281.210477) (xy 341.091316 -281.161842) (xy 341.071393 -281.109751)
			(xy 341.059267 -281.055314) (xy 341.055196 -280.999692) (xy 340.498548 -280.999692) (xy 340.504283 -281.011525)
			(xy 340.521301 -281.066362) (xy 340.529911 -281.12313) (xy 340.530434 -281.151838) (xy 340.529948 -281.179089)
			(xy 340.522192 -281.233037) (xy 340.506837 -281.285332) (xy 340.484195 -281.334909) (xy 340.454729 -281.380759)
			(xy 340.419038 -281.42195) (xy 340.377847 -281.457641) (xy 340.331997 -281.487107) (xy 340.28242 -281.509749)
			(xy 340.230125 -281.525104) (xy 340.176177 -281.53286) (xy 340.121675 -281.53286) (xy 340.067727 -281.525104)
			(xy 340.015432 -281.509749) (xy 339.965855 -281.487107) (xy 339.920005 -281.457641) (xy 339.878814 -281.42195)
			(xy 339.843123 -281.380759) (xy 339.813657 -281.334909) (xy 339.791015 -281.285332) (xy 339.77566 -281.233037)
			(xy 339.767904 -281.179089) (xy 339.767418 -281.151838) (xy 339.768168 -281.117754) (xy 339.780312 -281.050676)
			(xy 339.791548 -281.018488) (xy 339.795612 -281.007312) (xy 339.793072 -280.983436) (xy 339.735668 -280.89479)
			(xy 339.715094 -280.882598) (xy 339.703156 -280.881836) (xy 339.671858 -280.879093) (xy 339.610713 -280.864671)
			(xy 339.58149 -280.853134) (xy 339.57133 -280.848816) (xy 339.549994 -280.849324) (xy 339.461856 -280.891234)
			(xy 339.447886 -280.90749) (xy 339.444838 -280.918158) (xy 339.436655 -280.944133) (xy 339.413975 -280.993643)
			(xy 339.384485 -281.039426) (xy 339.348785 -281.080549) (xy 339.3076 -281.116179) (xy 339.261767 -281.14559)
			(xy 339.212218 -281.168185) (xy 339.159959 -281.183504) (xy 339.106053 -281.191237) (xy 339.078824 -281.191716)
			(xy 339.055468 -281.19135) (xy 339.009109 -281.18562) (xy 338.986368 -281.180286) (xy 338.976716 -281.178)
			(xy 338.957666 -281.18054) (xy 338.878926 -281.225752) (xy 338.866988 -281.240992) (xy 338.864194 -281.250644)
			(xy 338.856164 -281.276753) (xy 338.833614 -281.326505) (xy 338.804195 -281.37253) (xy 338.76851 -281.413887)
			(xy 338.727288 -281.449729) (xy 338.681375 -281.479322) (xy 338.631708 -281.50206) (xy 338.579305 -281.517479)
			(xy 338.525238 -281.525263) (xy 338.497926 -281.525726) (xy 338.470675 -281.525221) (xy 338.416726 -281.517468)
			(xy 338.36443 -281.502116) (xy 338.314851 -281.479478) (xy 338.268999 -281.450014) (xy 338.227806 -281.414325)
			(xy 338.192112 -281.373136) (xy 338.162644 -281.327287) (xy 338.14 -281.277711) (xy 338.124642 -281.225417)
			(xy 338.116883 -281.171469) (xy 338.116418 -281.144218) (xy 338.116475 -281.133592) (xy 338.117618 -281.112371)
			(xy 338.118704 -281.1018) (xy 338.119974 -281.092148) (xy 338.115148 -281.07386) (xy 338.063586 -281.002994)
			(xy 338.047584 -280.992834) (xy 338.038186 -280.990802) (xy 338.009884 -280.984446) (xy 337.955496 -280.964284)
			(xy 337.904788 -280.936119) (xy 337.858928 -280.900602) (xy 337.818975 -280.858551) (xy 337.785848 -280.810936)
			(xy 337.760312 -280.758855) (xy 337.742956 -280.703507) (xy 337.734179 -280.64617) (xy 337.73364 -280.617168)
			(xy 336.126351 -280.617168) (xy 336.103773 -280.624505) (xy 336.044549 -280.633885) (xy 336.014568 -280.63444)
			(xy 333.020416 -280.63444) (xy 333.010367 -280.634781) (xy 332.991771 -280.642389) (xy 332.984348 -280.649172)
			(xy 330.729082 -282.904438) (xy 334.103218 -282.904438) (xy 334.103704 -282.876864) (xy 334.111651 -282.822292)
			(xy 334.127372 -282.769432) (xy 334.150538 -282.719386) (xy 334.180667 -282.673196) (xy 334.217132 -282.631824)
			(xy 334.237838 -282.613608) (xy 334.245954 -282.606004) (xy 334.255308 -282.585853) (xy 334.255872 -282.574746)
			(xy 334.255872 -282.49753) (xy 334.255312 -282.486419) (xy 334.245969 -282.46626) (xy 334.237838 -282.458668)
			(xy 334.217169 -282.440412) (xy 334.180702 -282.399047) (xy 334.150571 -282.352863) (xy 334.127405 -282.302821)
			(xy 334.111687 -282.249965) (xy 334.103743 -282.195396) (xy 334.103739 -282.140253) (xy 334.111676 -282.085683)
			(xy 334.127388 -282.032825) (xy 334.150548 -281.98278) (xy 334.180672 -281.936592) (xy 334.217134 -281.895223)
			(xy 334.237838 -281.877008) (xy 334.245954 -281.869404) (xy 334.255308 -281.849253) (xy 334.255872 -281.838146)
			(xy 334.255872 -281.76093) (xy 334.255312 -281.749819) (xy 334.245969 -281.72966) (xy 334.237838 -281.722068)
			(xy 334.217116 -281.703869) (xy 334.180645 -281.662498) (xy 334.150513 -281.616306) (xy 334.127349 -281.566256)
			(xy 334.111635 -281.513391) (xy 334.1037 -281.458814) (xy 334.103218 -281.431238) (xy 334.103691 -281.403985)
			(xy 334.111443 -281.350033) (xy 334.126796 -281.297734) (xy 334.149436 -281.248152) (xy 334.178902 -281.202297)
			(xy 334.214595 -281.161104) (xy 334.255788 -281.125409) (xy 334.301641 -281.095941) (xy 334.351222 -281.0733)
			(xy 334.403521 -281.057946) (xy 334.457473 -281.050192) (xy 334.484726 -281.04973) (xy 334.512583 -281.050207)
			(xy 334.567702 -281.058335) (xy 334.621054 -281.074386) (xy 334.671509 -281.098018) (xy 334.717994 -281.128731)
			(xy 334.759523 -281.165872) (xy 334.795215 -281.208653) (xy 334.824311 -281.256166) (xy 334.846196 -281.307402)
			(xy 334.853788 -281.33421) (xy 334.856074 -281.3431) (xy 334.866742 -281.35834) (xy 334.938624 -281.406092)
			(xy 334.956658 -281.410156) (xy 334.965802 -281.408886) (xy 334.978819 -281.407219) (xy 335.005003 -281.405438)
			(xy 335.018126 -281.40533) (xy 335.031249 -281.405426) (xy 335.057435 -281.407203) (xy 335.07045 -281.408886)
			(xy 335.079594 -281.410156) (xy 335.097628 -281.406092) (xy 335.16951 -281.35834) (xy 335.180178 -281.3431)
			(xy 335.182464 -281.33421) (xy 335.189975 -281.307375) (xy 335.211845 -281.25612) (xy 335.240938 -281.208592)
			(xy 335.276635 -281.165801) (xy 335.318177 -281.128657) (xy 335.36468 -281.097952) (xy 335.415154 -281.074337)
			(xy 335.468527 -281.058315) (xy 335.523663 -281.050228) (xy 335.551526 -281.04973) (xy 335.578781 -281.050131)
			(xy 335.632736 -281.057892) (xy 335.685038 -281.073254) (xy 335.734621 -281.095902) (xy 335.780476 -281.125376)
			(xy 335.821669 -281.161076) (xy 335.857362 -281.202276) (xy 335.886829 -281.248136) (xy 335.909469 -281.297722)
			(xy 335.924821 -281.350026) (xy 335.932574 -281.403983) (xy 335.933034 -281.431238) (xy 335.932564 -281.458537)
			(xy 335.924788 -281.512579) (xy 335.909386 -281.564959) (xy 335.886672 -281.614609) (xy 335.857111 -281.660512)
			(xy 335.839562 -281.681428) (xy 335.833212 -281.688794) (xy 335.826862 -281.706574) (xy 335.830418 -281.795982)
			(xy 335.838038 -281.813254) (xy 335.844896 -281.820112) (xy 335.866027 -281.841742) (xy 335.901827 -281.89047)
			(xy 335.929491 -281.944237) (xy 335.935762 -281.963368) (xy 340.481918 -281.963368) (xy 340.485989 -281.907746)
			(xy 340.498115 -281.853309) (xy 340.518038 -281.801218) (xy 340.545334 -281.752583) (xy 340.57942 -281.70844)
			(xy 340.619569 -281.669731) (xy 340.664927 -281.63728) (xy 340.714527 -281.611779) (xy 340.767311 -281.593772)
			(xy 340.822154 -281.583642) (xy 340.877888 -281.581605) (xy 340.933325 -281.587705) (xy 340.987282 -281.601811)
			(xy 341.038611 -281.623623) (xy 341.086217 -281.652677) (xy 341.129085 -281.688352) (xy 341.166302 -281.729889)
			(xy 341.197075 -281.776402) (xy 341.220747 -281.826899) (xy 341.236815 -281.880306) (xy 341.244935 -281.935482)
			(xy 341.245444 -281.963368) (xy 341.244935 -281.991254) (xy 341.236815 -282.04643) (xy 341.220747 -282.099837)
			(xy 341.197075 -282.150334) (xy 341.166302 -282.196847) (xy 341.129085 -282.238384) (xy 341.086217 -282.274059)
			(xy 341.038611 -282.303113) (xy 340.987282 -282.324925) (xy 340.933325 -282.339031) (xy 340.877888 -282.345131)
			(xy 340.822154 -282.343094) (xy 340.767311 -282.332964) (xy 340.714527 -282.314957) (xy 340.664927 -282.289456)
			(xy 340.619569 -282.257005) (xy 340.57942 -282.218296) (xy 340.545334 -282.174153) (xy 340.518038 -282.125518)
			(xy 340.498115 -282.073427) (xy 340.485989 -282.01899) (xy 340.481918 -281.963368) (xy 335.935762 -281.963368)
			(xy 335.948326 -282.001695) (xy 335.957859 -282.061405) (xy 335.958434 -282.091638) (xy 335.957939 -282.119276)
			(xy 335.949947 -282.173971) (xy 335.934149 -282.226942) (xy 335.910877 -282.277081) (xy 335.880617 -282.323339)
			(xy 335.862676 -282.344368) (xy 335.854294 -282.35402) (xy 335.848452 -282.378404) (xy 335.87563 -282.484576)
			(xy 335.892648 -282.503118) (xy 335.904586 -282.507436) (xy 335.931994 -282.517774) (xy 335.983509 -282.545656)
			(xy 336.030154 -282.581087) (xy 336.070833 -282.623236) (xy 336.104587 -282.671109) (xy 336.130623 -282.72358)
			(xy 336.148329 -282.779417) (xy 336.157288 -282.837304) (xy 336.157824 -282.866592) (xy 336.15729 -282.893854)
			(xy 336.487447 -282.893854) (xy 336.487447 -282.839346) (xy 336.495205 -282.785392) (xy 336.510562 -282.733092)
			(xy 336.533206 -282.68351) (xy 336.562676 -282.637655) (xy 336.598372 -282.596461) (xy 336.639568 -282.560767)
			(xy 336.685424 -282.531299) (xy 336.735007 -282.508657) (xy 336.787308 -282.493302) (xy 336.841262 -282.485546)
			(xy 336.868516 -282.485084) (xy 336.895888 -282.48552) (xy 336.950069 -282.493342) (xy 337.002573 -282.508837)
			(xy 337.052319 -282.531686) (xy 337.098284 -282.561419) (xy 337.119214 -282.579064) (xy 337.126326 -282.58516)
			(xy 337.143344 -282.59151) (xy 337.228688 -282.59151) (xy 337.245706 -282.58516) (xy 337.252818 -282.579064)
			(xy 337.273766 -282.561444) (xy 337.319735 -282.531731) (xy 337.369478 -282.508892) (xy 337.421975 -282.493396)
			(xy 337.476148 -282.485562) (xy 337.503516 -282.485084) (xy 337.530766 -282.485587) (xy 337.584711 -282.493345)
			(xy 337.637003 -282.508701) (xy 337.686577 -282.531343) (xy 337.732424 -282.560809) (xy 337.773612 -282.5965)
			(xy 337.809301 -282.637689) (xy 337.838765 -282.683537) (xy 337.861404 -282.733112) (xy 337.876758 -282.785405)
			(xy 337.884514 -282.83935) (xy 337.884514 -282.89385) (xy 337.882992 -282.904438) (xy 342.26373 -282.904438)
			(xy 342.264211 -282.876864) (xy 342.272159 -282.822291) (xy 342.28788 -282.769431) (xy 342.311047 -282.719385)
			(xy 342.341178 -282.673195) (xy 342.377644 -282.631824) (xy 342.39835 -282.613608) (xy 342.406468 -282.606006)
			(xy 342.415821 -282.585854) (xy 342.416384 -282.574746) (xy 342.416384 -282.49753) (xy 342.41582 -282.486419)
			(xy 342.406479 -282.46626) (xy 342.39835 -282.458668) (xy 342.37768 -282.440412) (xy 342.341212 -282.399048)
			(xy 342.311081 -282.352864) (xy 342.287914 -282.302822) (xy 342.272195 -282.249966) (xy 342.26425 -282.195397)
			(xy 342.264247 -282.140252) (xy 342.272184 -282.085682) (xy 342.287897 -282.032824) (xy 342.311057 -281.982779)
			(xy 342.341182 -281.936591) (xy 342.377645 -281.895222) (xy 342.39835 -281.877008) (xy 342.406468 -281.869406)
			(xy 342.415821 -281.849254) (xy 342.416384 -281.838146) (xy 342.416384 -281.76093) (xy 342.41582 -281.749819)
			(xy 342.406479 -281.72966) (xy 342.39835 -281.722068) (xy 342.37761 -281.703888) (xy 342.341144 -281.662512)
			(xy 342.311017 -281.616315) (xy 342.287857 -281.566261) (xy 342.272146 -281.513393) (xy 342.264212 -281.458814)
			(xy 342.26373 -281.431238) (xy 342.264191 -281.403984) (xy 342.271944 -281.350031) (xy 342.287297 -281.297731)
			(xy 342.309938 -281.248149) (xy 342.339405 -281.202293) (xy 342.375099 -281.161099) (xy 342.416293 -281.125405)
			(xy 342.462149 -281.095938) (xy 342.511731 -281.073297) (xy 342.564031 -281.057944) (xy 342.617984 -281.050191)
			(xy 342.645238 -281.04973) (xy 342.673095 -281.050197) (xy 342.728214 -281.058326) (xy 342.781567 -281.074378)
			(xy 342.832022 -281.098012) (xy 342.878507 -281.128726) (xy 342.920036 -281.165868) (xy 342.955727 -281.20865)
			(xy 342.984824 -281.256165) (xy 343.006708 -281.307402) (xy 343.0143 -281.33421) (xy 343.016586 -281.3431)
			(xy 343.027254 -281.35834) (xy 343.099136 -281.406092) (xy 343.11717 -281.410156) (xy 343.126314 -281.408886)
			(xy 343.139331 -281.407217) (xy 343.165515 -281.405437) (xy 343.178638 -281.40533) (xy 343.191761 -281.405424)
			(xy 343.217947 -281.407203) (xy 343.230962 -281.408886) (xy 343.240106 -281.410156) (xy 343.25814 -281.406092)
			(xy 343.330022 -281.35834) (xy 343.34069 -281.3431) (xy 343.342976 -281.33421) (xy 343.350566 -281.3074)
			(xy 343.37243 -281.25615) (xy 343.401514 -281.208625) (xy 343.437202 -281.165835) (xy 343.478733 -281.128691)
			(xy 343.525225 -281.097982) (xy 343.575689 -281.074362) (xy 343.629052 -281.058332) (xy 343.684179 -281.050234)
			(xy 343.712038 -281.04973) (xy 343.739292 -281.050143) (xy 343.793244 -281.057905) (xy 343.845543 -281.073267)
			(xy 343.895123 -281.095915) (xy 343.940975 -281.125389) (xy 343.982165 -281.161088) (xy 344.017856 -281.202286)
			(xy 344.047321 -281.248144) (xy 344.069959 -281.297729) (xy 344.085311 -281.35003) (xy 344.093063 -281.403984)
			(xy 344.093546 -281.431238) (xy 344.093073 -281.458537) (xy 344.085297 -281.512578) (xy 344.069896 -281.564959)
			(xy 344.047183 -281.614608) (xy 344.017623 -281.660512) (xy 344.000074 -281.681428) (xy 343.993724 -281.688794)
			(xy 343.987374 -281.706574) (xy 343.99093 -281.795982) (xy 343.99855 -281.813254) (xy 344.005408 -281.820112)
			(xy 344.026523 -281.841756) (xy 344.062329 -281.890479) (xy 344.089998 -281.944242) (xy 344.096269 -281.963368)
			(xy 348.64243 -281.963368) (xy 348.646501 -281.907746) (xy 348.658627 -281.853309) (xy 348.67855 -281.801218)
			(xy 348.705846 -281.752583) (xy 348.739932 -281.70844) (xy 348.780081 -281.669731) (xy 348.825439 -281.63728)
			(xy 348.875039 -281.611779) (xy 348.927823 -281.593772) (xy 348.982666 -281.583642) (xy 349.0384 -281.581605)
			(xy 349.093837 -281.587705) (xy 349.147794 -281.601811) (xy 349.199123 -281.623623) (xy 349.246729 -281.652677)
			(xy 349.289597 -281.688352) (xy 349.326814 -281.729889) (xy 349.357587 -281.776402) (xy 349.381259 -281.826899)
			(xy 349.397327 -281.880306) (xy 349.405447 -281.935482) (xy 349.405956 -281.963368) (xy 349.405447 -281.991254)
			(xy 349.397327 -282.04643) (xy 349.381259 -282.099837) (xy 349.357587 -282.150334) (xy 349.326814 -282.196847)
			(xy 349.289597 -282.238384) (xy 349.246729 -282.274059) (xy 349.199123 -282.303113) (xy 349.147794 -282.324925)
			(xy 349.093837 -282.339031) (xy 349.0384 -282.345131) (xy 348.982666 -282.343094) (xy 348.927823 -282.332964)
			(xy 348.875039 -282.314957) (xy 348.825439 -282.289456) (xy 348.780081 -282.257005) (xy 348.739932 -282.218296)
			(xy 348.705846 -282.174153) (xy 348.67855 -282.125518) (xy 348.658627 -282.073427) (xy 348.646501 -282.01899)
			(xy 348.64243 -281.963368) (xy 344.096269 -281.963368) (xy 344.108836 -282.001697) (xy 344.118371 -282.061406)
			(xy 344.118946 -282.091638) (xy 344.118448 -282.119276) (xy 344.110456 -282.173971) (xy 344.094659 -282.226942)
			(xy 344.071388 -282.27708) (xy 344.041128 -282.323338) (xy 344.023188 -282.344368) (xy 344.014806 -282.35402)
			(xy 344.008964 -282.378404) (xy 344.036142 -282.484576) (xy 344.05316 -282.503118) (xy 344.065098 -282.507436)
			(xy 344.092509 -282.517767) (xy 344.144023 -282.545651) (xy 344.190668 -282.581084) (xy 344.231346 -282.623233)
			(xy 344.2651 -282.671107) (xy 344.291136 -282.723579) (xy 344.308841 -282.779416) (xy 344.3178 -282.837304)
			(xy 344.318336 -282.866592) (xy 344.317801 -282.893855) (xy 344.647947 -282.893855) (xy 344.647947 -282.839345)
			(xy 344.655705 -282.785391) (xy 344.671063 -282.73309) (xy 344.693708 -282.683507) (xy 344.723179 -282.637651)
			(xy 344.758877 -282.596457) (xy 344.800074 -282.560763) (xy 344.845931 -282.531295) (xy 344.895516 -282.508653)
			(xy 344.947818 -282.493299) (xy 345.001773 -282.485545) (xy 345.029028 -282.485084) (xy 345.0564 -282.485513)
			(xy 345.110581 -282.493337) (xy 345.163086 -282.508833) (xy 345.212832 -282.531684) (xy 345.258796 -282.561418)
			(xy 345.279726 -282.579064) (xy 345.286838 -282.58516) (xy 345.303856 -282.59151) (xy 345.3892 -282.59151)
			(xy 345.406218 -282.58516) (xy 345.41333 -282.579064) (xy 345.434273 -282.561439) (xy 345.480243 -282.531726)
			(xy 345.529988 -282.508888) (xy 345.582486 -282.493394) (xy 345.63666 -282.485561) (xy 345.664028 -282.485084)
			(xy 345.691277 -282.485588) (xy 345.745221 -282.493347) (xy 345.797511 -282.508704) (xy 345.847084 -282.531347)
			(xy 345.89293 -282.560813) (xy 345.934116 -282.596504) (xy 345.969804 -282.637693) (xy 345.999267 -282.683541)
			(xy 346.021905 -282.733115) (xy 346.037259 -282.785406) (xy 346.045014 -282.839351) (xy 346.045014 -282.893849)
			(xy 346.043492 -282.904438) (xy 350.762316 -282.904438) (xy 350.762802 -282.876864) (xy 350.77075 -282.822292)
			(xy 350.78647 -282.769432) (xy 350.809637 -282.719386) (xy 350.839766 -282.673196) (xy 350.87623 -282.631824)
			(xy 350.896936 -282.613608) (xy 350.905052 -282.606004) (xy 350.914406 -282.585853) (xy 350.91497 -282.574746)
			(xy 350.91497 -282.49753) (xy 350.914411 -282.486419) (xy 350.905067 -282.466259) (xy 350.896936 -282.458668)
			(xy 350.876267 -282.440412) (xy 350.8398 -282.399047) (xy 350.80967 -282.352863) (xy 350.786504 -282.302821)
			(xy 350.770785 -282.249965) (xy 350.762841 -282.195396) (xy 350.762838 -282.140253) (xy 350.770775 -282.085683)
			(xy 350.786487 -282.032825) (xy 350.809646 -281.98278) (xy 350.83977 -281.936592) (xy 350.876232 -281.895223)
			(xy 350.896936 -281.877008) (xy 350.905052 -281.869404) (xy 350.914406 -281.849253) (xy 350.91497 -281.838146)
			(xy 350.91497 -281.76093) (xy 350.914411 -281.749819) (xy 350.905067 -281.729659) (xy 350.896936 -281.722068)
			(xy 350.876213 -281.703869) (xy 350.839742 -281.662499) (xy 350.809611 -281.616307) (xy 350.786447 -281.566256)
			(xy 350.770733 -281.513391) (xy 350.762798 -281.458814) (xy 350.762316 -281.431238) (xy 350.762791 -281.403985)
			(xy 350.770543 -281.350033) (xy 350.785896 -281.297734) (xy 350.808535 -281.248153) (xy 350.838002 -281.202298)
			(xy 350.873694 -281.161104) (xy 350.914887 -281.12541) (xy 350.96074 -281.095942) (xy 351.010321 -281.0733)
			(xy 351.06262 -281.057946) (xy 351.116571 -281.050192) (xy 351.143824 -281.04973) (xy 351.171681 -281.050209)
			(xy 351.226799 -281.058337) (xy 351.280152 -281.074387) (xy 351.330606 -281.098019) (xy 351.377091 -281.128732)
			(xy 351.418621 -281.165872) (xy 351.454312 -281.208653) (xy 351.483409 -281.256166) (xy 351.505294 -281.307402)
			(xy 351.512886 -281.33421) (xy 351.515172 -281.3431) (xy 351.52584 -281.35834) (xy 351.597722 -281.406092)
			(xy 351.615756 -281.410156) (xy 351.6249 -281.408886) (xy 351.637917 -281.407219) (xy 351.664101 -281.405438)
			(xy 351.677224 -281.40533) (xy 351.690347 -281.405426) (xy 351.716533 -281.407203) (xy 351.729548 -281.408886)
			(xy 351.738692 -281.410156) (xy 351.756726 -281.406092) (xy 351.828608 -281.35834) (xy 351.839276 -281.3431)
			(xy 351.841562 -281.33421) (xy 351.849075 -281.307376) (xy 351.870945 -281.256121) (xy 351.900038 -281.208593)
			(xy 351.935734 -281.165802) (xy 351.977276 -281.128658) (xy 352.023779 -281.097952) (xy 352.074253 -281.074337)
			(xy 352.127626 -281.058316) (xy 352.182761 -281.050228) (xy 352.210624 -281.04973) (xy 352.237879 -281.050133)
			(xy 352.291834 -281.057894) (xy 352.344136 -281.073255) (xy 352.393718 -281.095903) (xy 352.439573 -281.125377)
			(xy 352.480767 -281.161077) (xy 352.51646 -281.202276) (xy 352.545927 -281.248136) (xy 352.568567 -281.297722)
			(xy 352.583919 -281.350026) (xy 352.591672 -281.403983) (xy 352.592132 -281.431238) (xy 352.591663 -281.458537)
			(xy 352.583886 -281.512579) (xy 352.568484 -281.564959) (xy 352.54577 -281.614609) (xy 352.51621 -281.660512)
			(xy 352.49866 -281.681428) (xy 352.49231 -281.688794) (xy 352.48596 -281.706574) (xy 352.489516 -281.795982)
			(xy 352.497136 -281.813254) (xy 352.503994 -281.820112) (xy 352.525124 -281.841742) (xy 352.560925 -281.890471)
			(xy 352.588589 -281.944237) (xy 352.59486 -281.963368) (xy 357.141016 -281.963368) (xy 357.145087 -281.907746)
			(xy 357.157213 -281.853309) (xy 357.177136 -281.801218) (xy 357.204432 -281.752583) (xy 357.238518 -281.70844)
			(xy 357.278667 -281.669731) (xy 357.324025 -281.63728) (xy 357.373625 -281.611779) (xy 357.426409 -281.593772)
			(xy 357.481252 -281.583642) (xy 357.536986 -281.581605) (xy 357.592423 -281.587705) (xy 357.64638 -281.601811)
			(xy 357.697709 -281.623623) (xy 357.745315 -281.652677) (xy 357.788183 -281.688352) (xy 357.8254 -281.729889)
			(xy 357.856173 -281.776402) (xy 357.879845 -281.826899) (xy 357.895913 -281.880306) (xy 357.904033 -281.935482)
			(xy 357.904542 -281.963368) (xy 357.904033 -281.991254) (xy 357.895913 -282.04643) (xy 357.879845 -282.099837)
			(xy 357.856173 -282.150334) (xy 357.8254 -282.196847) (xy 357.788183 -282.238384) (xy 357.745315 -282.274059)
			(xy 357.697709 -282.303113) (xy 357.64638 -282.324925) (xy 357.592423 -282.339031) (xy 357.536986 -282.345131)
			(xy 357.481252 -282.343094) (xy 357.426409 -282.332964) (xy 357.373625 -282.314957) (xy 357.324025 -282.289456)
			(xy 357.278667 -282.257005) (xy 357.238518 -282.218296) (xy 357.204432 -282.174153) (xy 357.177136 -282.125518)
			(xy 357.157213 -282.073427) (xy 357.145087 -282.01899) (xy 357.141016 -281.963368) (xy 352.59486 -281.963368)
			(xy 352.607424 -282.001695) (xy 352.616957 -282.061405) (xy 352.617532 -282.091638) (xy 352.617037 -282.119276)
			(xy 352.609045 -282.173971) (xy 352.593248 -282.226942) (xy 352.569975 -282.277081) (xy 352.539715 -282.323339)
			(xy 352.521774 -282.344368) (xy 352.513392 -282.35402) (xy 352.50755 -282.378404) (xy 352.534728 -282.484576)
			(xy 352.551746 -282.503118) (xy 352.563684 -282.507436) (xy 352.591092 -282.517775) (xy 352.642607 -282.545657)
			(xy 352.689252 -282.581088) (xy 352.72993 -282.623236) (xy 352.763685 -282.671109) (xy 352.789721 -282.723581)
			(xy 352.807427 -282.779417) (xy 352.816386 -282.837304) (xy 352.816922 -282.866592) (xy 352.816388 -282.893854)
			(xy 353.146547 -282.893854) (xy 353.146547 -282.839346) (xy 353.154305 -282.785393) (xy 353.169662 -282.733093)
			(xy 353.192306 -282.683511) (xy 353.221776 -282.637656) (xy 353.257472 -282.596462) (xy 353.298667 -282.560767)
			(xy 353.344523 -282.531299) (xy 353.394106 -282.508657) (xy 353.446406 -282.493302) (xy 353.50036 -282.485546)
			(xy 353.527614 -282.485084) (xy 353.554986 -282.485521) (xy 353.609167 -282.493343) (xy 353.661671 -282.508838)
			(xy 353.711417 -282.531686) (xy 353.757382 -282.561419) (xy 353.778312 -282.579064) (xy 353.785424 -282.58516)
			(xy 353.802442 -282.59151) (xy 353.887786 -282.59151) (xy 353.904804 -282.58516) (xy 353.911916 -282.579064)
			(xy 353.932864 -282.561445) (xy 353.978833 -282.531732) (xy 354.028577 -282.508892) (xy 354.081074 -282.493396)
			(xy 354.135246 -282.485562) (xy 354.162614 -282.485084) (xy 354.189864 -282.485587) (xy 354.243809 -282.493345)
			(xy 354.296101 -282.508701) (xy 354.345676 -282.531342) (xy 354.391523 -282.560808) (xy 354.432711 -282.596499)
			(xy 354.4684 -282.637688) (xy 354.497865 -282.683537) (xy 354.520504 -282.733112) (xy 354.535858 -282.785405)
			(xy 354.543614 -282.83935) (xy 354.543614 -282.89385) (xy 354.542092 -282.904438) (xy 358.922828 -282.904438)
			(xy 358.92331 -282.876864) (xy 358.931258 -282.822291) (xy 358.946979 -282.769431) (xy 358.970146 -282.719385)
			(xy 359.000276 -282.673195) (xy 359.036742 -282.631824) (xy 359.057448 -282.613608) (xy 359.065566 -282.606005)
			(xy 359.074919 -282.585854) (xy 359.075482 -282.574746) (xy 359.075482 -282.49753) (xy 359.074919 -282.486419)
			(xy 359.065578 -282.46626) (xy 359.057448 -282.458668) (xy 359.036778 -282.440412) (xy 359.000311 -282.399048)
			(xy 358.970179 -282.352864) (xy 358.947013 -282.302822) (xy 358.931293 -282.249966) (xy 358.923349 -282.195397)
			(xy 358.923345 -282.140252) (xy 358.931283 -282.085682) (xy 358.946995 -282.032824) (xy 358.970155 -281.982779)
			(xy 359.000281 -281.936591) (xy 359.036743 -281.895222) (xy 359.057448 -281.877008) (xy 359.065566 -281.869405)
			(xy 359.074919 -281.849254) (xy 359.075482 -281.838146) (xy 359.075482 -281.76093) (xy 359.074919 -281.749819)
			(xy 359.065578 -281.72966) (xy 359.057448 -281.722068) (xy 359.036728 -281.703866) (xy 359.000256 -281.662497)
			(xy 358.970124 -281.616305) (xy 358.946959 -281.566255) (xy 358.931246 -281.51339) (xy 358.92331 -281.458813)
			(xy 358.922828 -281.431238) (xy 358.923291 -281.403984) (xy 358.931043 -281.350032) (xy 358.946397 -281.297732)
			(xy 358.969037 -281.248149) (xy 358.998505 -281.202294) (xy 359.034199 -281.1611) (xy 359.075393 -281.125406)
			(xy 359.121247 -281.095938) (xy 359.17083 -281.073297) (xy 359.22313 -281.057944) (xy 359.277082 -281.050191)
			(xy 359.304336 -281.04973) (xy 359.332193 -281.050198) (xy 359.387312 -281.058328) (xy 359.440665 -281.07438)
			(xy 359.491119 -281.098013) (xy 359.537604 -281.128727) (xy 359.579133 -281.165869) (xy 359.614825 -281.208651)
			(xy 359.643922 -281.256165) (xy 359.665806 -281.307402) (xy 359.673398 -281.33421) (xy 359.675684 -281.3431)
			(xy 359.686352 -281.35834) (xy 359.758234 -281.406092) (xy 359.776268 -281.410156) (xy 359.785412 -281.408886)
			(xy 359.798429 -281.407218) (xy 359.824613 -281.405437) (xy 359.837736 -281.40533) (xy 359.850859 -281.405425)
			(xy 359.877045 -281.407203) (xy 359.89006 -281.408886) (xy 359.899204 -281.410156) (xy 359.917238 -281.406092)
			(xy 359.98912 -281.35834) (xy 359.999788 -281.3431) (xy 360.002074 -281.33421) (xy 360.009666 -281.3074)
			(xy 360.031529 -281.256151) (xy 360.060614 -281.208626) (xy 360.096301 -281.165836) (xy 360.137832 -281.128692)
			(xy 360.184324 -281.097983) (xy 360.234788 -281.074362) (xy 360.28815 -281.058332) (xy 360.343277 -281.050234)
			(xy 360.371136 -281.04973) (xy 360.398392 -281.050122) (xy 360.452347 -281.057884) (xy 360.504649 -281.073247)
			(xy 360.554231 -281.095896) (xy 360.600086 -281.125372) (xy 360.64128 -281.161073) (xy 360.676973 -281.202273)
			(xy 360.706439 -281.248134) (xy 360.729079 -281.297721) (xy 360.744431 -281.350025) (xy 360.752184 -281.403982)
			(xy 360.752644 -281.431238) (xy 360.752172 -281.458537) (xy 360.744396 -281.512578) (xy 360.728994 -281.564959)
			(xy 360.706281 -281.614608) (xy 360.676721 -281.660512) (xy 360.659172 -281.681428) (xy 360.652822 -281.688794)
			(xy 360.646472 -281.706574) (xy 360.650028 -281.795982) (xy 360.657648 -281.813254) (xy 360.664506 -281.820112)
			(xy 360.685621 -281.841757) (xy 360.721427 -281.89048) (xy 360.749095 -281.944242) (xy 360.755366 -281.963368)
			(xy 365.301528 -281.963368) (xy 365.305599 -281.907746) (xy 365.317725 -281.853309) (xy 365.337648 -281.801218)
			(xy 365.364944 -281.752583) (xy 365.39903 -281.70844) (xy 365.439179 -281.669731) (xy 365.484537 -281.63728)
			(xy 365.534137 -281.611779) (xy 365.586921 -281.593772) (xy 365.641764 -281.583642) (xy 365.697498 -281.581605)
			(xy 365.752935 -281.587705) (xy 365.806892 -281.601811) (xy 365.858221 -281.623623) (xy 365.905827 -281.652677)
			(xy 365.948695 -281.688352) (xy 365.985912 -281.729889) (xy 366.016685 -281.776402) (xy 366.040357 -281.826899)
			(xy 366.056425 -281.880306) (xy 366.064545 -281.935482) (xy 366.065054 -281.963368) (xy 366.064545 -281.991254)
			(xy 366.056425 -282.04643) (xy 366.040357 -282.099837) (xy 366.016685 -282.150334) (xy 365.985912 -282.196847)
			(xy 365.948695 -282.238384) (xy 365.905827 -282.274059) (xy 365.858221 -282.303113) (xy 365.806892 -282.324925)
			(xy 365.752935 -282.339031) (xy 365.697498 -282.345131) (xy 365.641764 -282.343094) (xy 365.586921 -282.332964)
			(xy 365.534137 -282.314957) (xy 365.484537 -282.289456) (xy 365.439179 -282.257005) (xy 365.39903 -282.218296)
			(xy 365.364944 -282.174153) (xy 365.337648 -282.125518) (xy 365.317725 -282.073427) (xy 365.305599 -282.01899)
			(xy 365.301528 -281.963368) (xy 360.755366 -281.963368) (xy 360.767934 -282.001698) (xy 360.777469 -282.061406)
			(xy 360.778044 -282.091638) (xy 360.777546 -282.119276) (xy 360.769554 -282.173971) (xy 360.753757 -282.226942)
			(xy 360.730486 -282.27708) (xy 360.700226 -282.323338) (xy 360.682286 -282.344368) (xy 360.673904 -282.35402)
			(xy 360.668062 -282.378404) (xy 360.69524 -282.484576) (xy 360.712258 -282.503118) (xy 360.724196 -282.507436)
			(xy 360.751606 -282.517769) (xy 360.803121 -282.545652) (xy 360.849766 -282.581084) (xy 360.890444 -282.623233)
			(xy 360.924198 -282.671107) (xy 360.950234 -282.723579) (xy 360.967939 -282.779416) (xy 360.976898 -282.837304)
			(xy 360.977434 -282.866592) (xy 360.976899 -282.893855) (xy 361.307047 -282.893855) (xy 361.307047 -282.839345)
			(xy 361.314805 -282.785391) (xy 361.330163 -282.73309) (xy 361.352808 -282.683507) (xy 361.382279 -282.637652)
			(xy 361.417976 -282.596458) (xy 361.459173 -282.560763) (xy 361.50503 -282.531295) (xy 361.554614 -282.508654)
			(xy 361.606917 -282.4933) (xy 361.660871 -282.485546) (xy 361.688126 -282.485084) (xy 361.715498 -282.485514)
			(xy 361.769679 -282.493338) (xy 361.822183 -282.508834) (xy 361.87193 -282.531684) (xy 361.917894 -282.561418)
			(xy 361.938824 -282.579064) (xy 361.945936 -282.58516) (xy 361.962954 -282.59151) (xy 362.048298 -282.59151)
			(xy 362.065316 -282.58516) (xy 362.072428 -282.579064) (xy 362.093372 -282.56144) (xy 362.139342 -282.531727)
			(xy 362.189087 -282.508889) (xy 362.241584 -282.493394) (xy 362.295758 -282.485561) (xy 362.323126 -282.485084)
			(xy 362.350375 -282.485588) (xy 362.404319 -282.493347) (xy 362.45661 -282.508704) (xy 362.506183 -282.531346)
			(xy 362.552029 -282.560812) (xy 362.593215 -282.596503) (xy 362.628903 -282.637692) (xy 362.658366 -282.68354)
			(xy 362.681005 -282.733115) (xy 362.696359 -282.785406) (xy 362.704114 -282.839351) (xy 362.704114 -282.893849)
			(xy 362.696359 -282.947794) (xy 362.681005 -283.000085) (xy 362.658366 -283.04966) (xy 362.628903 -283.095508)
			(xy 362.593215 -283.136697) (xy 362.552029 -283.172388) (xy 362.506183 -283.201854) (xy 362.45661 -283.224496)
			(xy 362.404319 -283.239853) (xy 362.350375 -283.247612) (xy 362.323126 -283.2481) (xy 362.295756 -283.247619)
			(xy 362.241578 -283.239805) (xy 362.189075 -283.224319) (xy 362.139328 -283.201481) (xy 362.09336 -283.17176)
			(xy 362.072428 -283.15412) (xy 362.065316 -283.148024) (xy 362.048298 -283.141674) (xy 361.962954 -283.141674)
			(xy 361.945936 -283.148024) (xy 361.938824 -283.15412) (xy 361.917896 -283.171764) (xy 361.871922 -283.201475)
			(xy 361.822173 -283.224309) (xy 361.769672 -283.239799) (xy 361.715495 -283.247626) (xy 361.688126 -283.2481)
			(xy 361.660871 -283.247654) (xy 361.606917 -283.2399) (xy 361.554614 -283.224546) (xy 361.50503 -283.201905)
			(xy 361.459173 -283.172437) (xy 361.417976 -283.136742) (xy 361.382279 -283.095548) (xy 361.352808 -283.049693)
			(xy 361.330163 -283.00011) (xy 361.314805 -282.947809) (xy 361.307047 -282.893855) (xy 360.976899 -282.893855)
			(xy 360.976849 -282.89643) (xy 360.96754 -282.955376) (xy 360.958892 -282.98394) (xy 360.95559 -282.994354)
			(xy 360.957876 -283.015944) (xy 361.007914 -283.100526) (xy 361.025694 -283.112972) (xy 361.036362 -283.115004)
			(xy 361.062178 -283.120347) (xy 361.112094 -283.137315) (xy 361.159199 -283.160995) (xy 361.202593 -283.190935)
			(xy 361.241451 -283.226566) (xy 361.275033 -283.267209) (xy 361.302699 -283.312088) (xy 361.323921 -283.360349)
			(xy 361.338295 -283.411073) (xy 361.345547 -283.463293) (xy 361.345988 -283.489654) (xy 361.345406 -283.519777)
			(xy 361.33593 -283.579274) (xy 361.317223 -283.636542) (xy 361.289749 -283.69016) (xy 361.254191 -283.738794)
			(xy 361.233212 -283.760418) (xy 361.225846 -283.76753) (xy 361.218226 -283.786326) (xy 361.218226 -283.878782)
			(xy 361.225846 -283.897578) (xy 361.233212 -283.90469) (xy 361.254215 -283.926294) (xy 361.28978 -283.974929)
			(xy 361.317255 -284.02855) (xy 361.331634 -284.072584) (xy 366.233202 -284.072584) (xy 366.233658 -284.045213)
			(xy 366.241478 -283.991034) (xy 366.25697 -283.938531) (xy 366.279814 -283.888784) (xy 366.30954 -283.842817)
			(xy 366.327182 -283.821886) (xy 366.333278 -283.814774) (xy 366.339628 -283.797756) (xy 366.339628 -283.712412)
			(xy 366.333278 -283.695394) (xy 366.327182 -283.688282) (xy 366.309565 -283.667332) (xy 366.279851 -283.621364)
			(xy 366.257011 -283.571621) (xy 366.241514 -283.519124) (xy 366.23368 -283.464952) (xy 366.233202 -283.437584)
			(xy 366.233688 -283.410333) (xy 366.241444 -283.356385) (xy 366.256799 -283.30409) (xy 366.279441 -283.254513)
			(xy 366.308907 -283.208663) (xy 366.344598 -283.167472) (xy 366.385789 -283.131781) (xy 366.431639 -283.102315)
			(xy 366.481216 -283.079673) (xy 366.533511 -283.064318) (xy 366.587459 -283.056562) (xy 366.641961 -283.056562)
			(xy 366.695909 -283.064318) (xy 366.748204 -283.079673) (xy 366.797781 -283.102315) (xy 366.843631 -283.131781)
			(xy 366.884822 -283.167472) (xy 366.920513 -283.208663) (xy 366.949979 -283.254513) (xy 366.972621 -283.30409)
			(xy 366.987976 -283.356385) (xy 366.995732 -283.410333) (xy 366.996218 -283.437584) (xy 366.995763 -283.464955)
			(xy 366.987945 -283.519135) (xy 366.972455 -283.571639) (xy 366.94961 -283.621386) (xy 366.919882 -283.667352)
			(xy 366.902238 -283.688282) (xy 366.896142 -283.695394) (xy 366.889792 -283.712412) (xy 366.889792 -283.797756)
			(xy 366.896142 -283.814774) (xy 366.902238 -283.821886) (xy 366.91989 -283.842807) (xy 366.949599 -283.888784)
			(xy 366.972432 -283.938534) (xy 366.98792 -283.991037) (xy 366.995746 -284.045214) (xy 366.996218 -284.072584)
			(xy 366.995732 -284.099835) (xy 366.987976 -284.153783) (xy 366.972621 -284.206078) (xy 366.949979 -284.255655)
			(xy 366.920513 -284.301505) (xy 366.884822 -284.342696) (xy 366.843631 -284.378387) (xy 366.797781 -284.407853)
			(xy 366.748204 -284.430495) (xy 366.695909 -284.44585) (xy 366.641961 -284.453606) (xy 366.587459 -284.453606)
			(xy 366.533511 -284.44585) (xy 366.481216 -284.430495) (xy 366.431639 -284.407853) (xy 366.385789 -284.378387)
			(xy 366.344598 -284.342696) (xy 366.308907 -284.301505) (xy 366.279441 -284.255655) (xy 366.256799 -284.206078)
			(xy 366.241444 -284.153783) (xy 366.233688 -284.099835) (xy 366.233202 -284.072584) (xy 361.331634 -284.072584)
			(xy 361.335958 -284.085825) (xy 361.345423 -284.145328) (xy 361.345988 -284.175454) (xy 361.345502 -284.202705)
			(xy 361.337746 -284.256653) (xy 361.322391 -284.308948) (xy 361.299749 -284.358525) (xy 361.270283 -284.404375)
			(xy 361.234592 -284.445566) (xy 361.193401 -284.481257) (xy 361.147551 -284.510723) (xy 361.097974 -284.533365)
			(xy 361.045679 -284.54872) (xy 360.991731 -284.556476) (xy 360.937229 -284.556476) (xy 360.883281 -284.54872)
			(xy 360.830986 -284.533365) (xy 360.781409 -284.510723) (xy 360.735559 -284.481257) (xy 360.694368 -284.445566)
			(xy 360.658677 -284.404375) (xy 360.629211 -284.358525) (xy 360.606569 -284.308948) (xy 360.591214 -284.256653)
			(xy 360.583458 -284.202705) (xy 360.582972 -284.175454) (xy 360.583571 -284.145332) (xy 360.593044 -284.085836)
			(xy 360.611748 -284.028568) (xy 360.639218 -283.974951) (xy 360.674771 -283.926316) (xy 360.695748 -283.90469)
			(xy 360.703114 -283.897578) (xy 360.710734 -283.878782) (xy 360.710734 -283.786326) (xy 360.703114 -283.76753)
			(xy 360.695748 -283.760418) (xy 360.67476 -283.7388) (xy 360.63919 -283.690171) (xy 360.611711 -283.636552)
			(xy 360.593005 -283.57928) (xy 360.583538 -283.519779) (xy 360.582972 -283.489654) (xy 360.583545 -283.459815)
			(xy 360.592862 -283.400869) (xy 360.601514 -283.372306) (xy 360.604816 -283.361892) (xy 360.60253 -283.340302)
			(xy 360.552492 -283.25572) (xy 360.534712 -283.243274) (xy 360.524044 -283.241242) (xy 360.496194 -283.235394)
			(xy 360.44253 -283.216457) (xy 360.392273 -283.189761) (xy 360.346537 -283.1559) (xy 360.306335 -283.115623)
			(xy 360.272559 -283.069824) (xy 360.245957 -283.019517) (xy 360.22712 -282.965818) (xy 360.221276 -282.937966)
			(xy 360.218736 -282.925774) (xy 360.202988 -282.905962) (xy 360.102912 -282.862528) (xy 360.077766 -282.86456)
			(xy 360.067098 -282.871164) (xy 360.044129 -282.885204) (xy 359.995055 -282.907334) (xy 359.943352 -282.92233)
			(xy 359.890053 -282.929892) (xy 359.863136 -282.930346) (xy 359.845117 -282.930129) (xy 359.809242 -282.926692)
			(xy 359.791508 -282.923488) (xy 359.78211 -282.92171) (xy 359.76306 -282.92552) (xy 359.687876 -282.973272)
			(xy 359.676446 -282.98902) (xy 359.67416 -282.998418) (xy 359.666766 -283.025464) (xy 359.645138 -283.077192)
			(xy 359.616175 -283.125199) (xy 359.5805 -283.168452) (xy 359.53888 -283.20602) (xy 359.492211 -283.237094)
			(xy 359.441498 -283.261006) (xy 359.387833 -283.27724) (xy 359.33237 -283.285449) (xy 359.304336 -283.285946)
			(xy 359.277087 -283.285388) (xy 359.223144 -283.277638) (xy 359.170853 -283.262289) (xy 359.121279 -283.239655)
			(xy 359.07543 -283.210196) (xy 359.03424 -283.174512) (xy 358.998548 -283.133329) (xy 358.969081 -283.087486)
			(xy 358.946437 -283.037916) (xy 358.931078 -282.985628) (xy 358.923317 -282.931687) (xy 358.922828 -282.904438)
			(xy 354.542092 -282.904438) (xy 354.535858 -282.947795) (xy 354.520504 -283.000088) (xy 354.497865 -283.049663)
			(xy 354.4684 -283.095512) (xy 354.432711 -283.136701) (xy 354.391523 -283.172392) (xy 354.345676 -283.201858)
			(xy 354.296101 -283.224499) (xy 354.243809 -283.239855) (xy 354.189864 -283.247613) (xy 354.162614 -283.2481)
			(xy 354.135244 -283.247626) (xy 354.081065 -283.23981) (xy 354.028562 -283.224323) (xy 353.978815 -283.201483)
			(xy 353.932848 -283.17176) (xy 353.911916 -283.15412) (xy 353.904804 -283.148024) (xy 353.887786 -283.141674)
			(xy 353.802442 -283.141674) (xy 353.785424 -283.148024) (xy 353.778312 -283.15412) (xy 353.757389 -283.17177)
			(xy 353.711413 -283.20148) (xy 353.661663 -283.224313) (xy 353.609161 -283.239802) (xy 353.554984 -283.247627)
			(xy 353.527614 -283.2481) (xy 353.50036 -283.247654) (xy 353.446406 -283.239898) (xy 353.394106 -283.224543)
			(xy 353.344523 -283.201901) (xy 353.298667 -283.172433) (xy 353.257472 -283.136738) (xy 353.221776 -283.095544)
			(xy 353.192306 -283.049689) (xy 353.169662 -283.000107) (xy 353.154305 -282.947807) (xy 353.146547 -282.893854)
			(xy 352.816388 -282.893854) (xy 352.816337 -282.89643) (xy 352.807028 -282.955376) (xy 352.79838 -282.98394)
			(xy 352.795078 -282.994354) (xy 352.797364 -283.015944) (xy 352.847402 -283.100526) (xy 352.865182 -283.112972)
			(xy 352.87585 -283.115004) (xy 352.901664 -283.120356) (xy 352.951581 -283.137322) (xy 352.998685 -283.161001)
			(xy 353.04208 -283.19094) (xy 353.080938 -283.22657) (xy 353.11452 -283.267211) (xy 353.142186 -283.31209)
			(xy 353.163408 -283.360351) (xy 353.177783 -283.411074) (xy 353.185035 -283.463294) (xy 353.185476 -283.489654)
			(xy 353.184869 -283.519776) (xy 353.175396 -283.57927) (xy 353.156693 -283.636537) (xy 353.129225 -283.690155)
			(xy 353.093675 -283.738792) (xy 353.0727 -283.760418) (xy 353.065334 -283.76753) (xy 353.057714 -283.786326)
			(xy 353.057714 -283.878782) (xy 353.065334 -283.897578) (xy 353.0727 -283.90469) (xy 353.093701 -283.926296)
			(xy 353.129266 -283.97493) (xy 353.156743 -284.028551) (xy 353.171122 -284.072584) (xy 358.07269 -284.072584)
			(xy 358.073149 -284.045214) (xy 358.080969 -283.991034) (xy 358.09646 -283.938531) (xy 358.119303 -283.888784)
			(xy 358.149028 -283.842818) (xy 358.16667 -283.821886) (xy 358.172766 -283.814774) (xy 358.179116 -283.797756)
			(xy 358.179116 -283.712412) (xy 358.172766 -283.695394) (xy 358.16667 -283.688282) (xy 358.149051 -283.667334)
			(xy 358.119337 -283.621365) (xy 358.096498 -283.571621) (xy 358.081002 -283.519125) (xy 358.073168 -283.464952)
			(xy 358.07269 -283.437584) (xy 358.073176 -283.410333) (xy 358.080932 -283.356385) (xy 358.096287 -283.30409)
			(xy 358.118929 -283.254513) (xy 358.148395 -283.208663) (xy 358.184086 -283.167472) (xy 358.225277 -283.131781)
			(xy 358.271127 -283.102315) (xy 358.320704 -283.079673) (xy 358.372999 -283.064318) (xy 358.426947 -283.056562)
			(xy 358.481449 -283.056562) (xy 358.535397 -283.064318) (xy 358.587692 -283.079673) (xy 358.637269 -283.102315)
			(xy 358.683119 -283.131781) (xy 358.72431 -283.167472) (xy 358.760001 -283.208663) (xy 358.789467 -283.254513)
			(xy 358.812109 -283.30409) (xy 358.827464 -283.356385) (xy 358.83522 -283.410333) (xy 358.835706 -283.437584)
			(xy 358.835229 -283.464954) (xy 358.827414 -283.519132) (xy 358.811927 -283.571635) (xy 358.789088 -283.621382)
			(xy 358.759366 -283.66735) (xy 358.741726 -283.688282) (xy 358.73563 -283.695394) (xy 358.72928 -283.712412)
			(xy 358.72928 -283.797756) (xy 358.73563 -283.814774) (xy 358.741726 -283.821886) (xy 358.759376 -283.842809)
			(xy 358.789085 -283.888785) (xy 358.811919 -283.938535) (xy 358.827407 -283.991037) (xy 358.835233 -284.045214)
			(xy 358.835706 -284.072584) (xy 358.83522 -284.099835) (xy 358.827464 -284.153783) (xy 358.812109 -284.206078)
			(xy 358.789467 -284.255655) (xy 358.760001 -284.301505) (xy 358.72431 -284.342696) (xy 358.683119 -284.378387)
			(xy 358.637269 -284.407853) (xy 358.587692 -284.430495) (xy 358.535397 -284.44585) (xy 358.481449 -284.453606)
			(xy 358.426947 -284.453606) (xy 358.372999 -284.44585) (xy 358.320704 -284.430495) (xy 358.271127 -284.407853)
			(xy 358.225277 -284.378387) (xy 358.184086 -284.342696) (xy 358.148395 -284.301505) (xy 358.118929 -284.255655)
			(xy 358.096287 -284.206078) (xy 358.080932 -284.153783) (xy 358.073176 -284.099835) (xy 358.07269 -284.072584)
			(xy 353.171122 -284.072584) (xy 353.175446 -284.085826) (xy 353.184911 -284.145328) (xy 353.185476 -284.175454)
			(xy 353.18499 -284.202705) (xy 353.177234 -284.256653) (xy 353.161879 -284.308948) (xy 353.139237 -284.358525)
			(xy 353.109771 -284.404375) (xy 353.07408 -284.445566) (xy 353.032889 -284.481257) (xy 352.987039 -284.510723)
			(xy 352.937462 -284.533365) (xy 352.885167 -284.54872) (xy 352.831219 -284.556476) (xy 352.776717 -284.556476)
			(xy 352.722769 -284.54872) (xy 352.670474 -284.533365) (xy 352.620897 -284.510723) (xy 352.575047 -284.481257)
			(xy 352.533856 -284.445566) (xy 352.498165 -284.404375) (xy 352.468699 -284.358525) (xy 352.446057 -284.308948)
			(xy 352.430702 -284.256653) (xy 352.422946 -284.202705) (xy 352.42246 -284.175454) (xy 352.423062 -284.145332)
			(xy 352.432535 -284.085837) (xy 352.451239 -284.028569) (xy 352.478708 -283.974952) (xy 352.51426 -283.926316)
			(xy 352.535236 -283.90469) (xy 352.542602 -283.897578) (xy 352.550222 -283.878782) (xy 352.550222 -283.786326)
			(xy 352.542602 -283.76753) (xy 352.535236 -283.760418) (xy 352.514246 -283.738802) (xy 352.478677 -283.690172)
			(xy 352.451198 -283.636553) (xy 352.432493 -283.579281) (xy 352.423026 -283.519779) (xy 352.42246 -283.489654)
			(xy 352.423033 -283.459815) (xy 352.43235 -283.400869) (xy 352.441002 -283.372306) (xy 352.444304 -283.361892)
			(xy 352.442018 -283.340302) (xy 352.39198 -283.25572) (xy 352.3742 -283.243274) (xy 352.363532 -283.241242)
			(xy 352.33568 -283.235403) (xy 352.282016 -283.216463) (xy 352.231759 -283.189767) (xy 352.186023 -283.155904)
			(xy 352.145822 -283.115626) (xy 352.112046 -283.069825) (xy 352.085445 -283.019518) (xy 352.066608 -282.965818)
			(xy 352.060764 -282.937966) (xy 352.058224 -282.925774) (xy 352.042476 -282.905962) (xy 351.9424 -282.862528)
			(xy 351.917254 -282.86456) (xy 351.906586 -282.871164) (xy 351.883596 -282.885167) (xy 351.834529 -282.907307)
			(xy 351.782833 -282.922313) (xy 351.729539 -282.929886) (xy 351.702624 -282.930346) (xy 351.684604 -282.930131)
			(xy 351.64873 -282.926693) (xy 351.630996 -282.923488) (xy 351.621598 -282.92171) (xy 351.602548 -282.92552)
			(xy 351.527364 -282.973272) (xy 351.515934 -282.98902) (xy 351.513648 -282.998418) (xy 351.506265 -283.025467)
			(xy 351.484636 -283.077196) (xy 351.455672 -283.125203) (xy 351.419995 -283.168456) (xy 351.378374 -283.206024)
			(xy 351.331704 -283.237098) (xy 351.28099 -283.261009) (xy 351.227323 -283.277243) (xy 351.171858 -283.28545)
			(xy 351.143824 -283.285946) (xy 351.116575 -283.2854) (xy 351.062632 -283.277647) (xy 351.01034 -283.262297)
			(xy 350.960766 -283.239662) (xy 350.914917 -283.210201) (xy 350.873728 -283.174516) (xy 350.838036 -283.133333)
			(xy 350.808568 -283.087489) (xy 350.785925 -283.037918) (xy 350.770566 -282.985629) (xy 350.762805 -282.931687)
			(xy 350.762316 -282.904438) (xy 346.043492 -282.904438) (xy 346.037259 -282.947794) (xy 346.021905 -283.000085)
			(xy 345.999267 -283.049659) (xy 345.969804 -283.095507) (xy 345.934116 -283.136696) (xy 345.89293 -283.172387)
			(xy 345.847084 -283.201853) (xy 345.797511 -283.224496) (xy 345.745221 -283.239853) (xy 345.691277 -283.247612)
			(xy 345.664028 -283.2481) (xy 345.636658 -283.247618) (xy 345.58248 -283.239804) (xy 345.529977 -283.224318)
			(xy 345.48023 -283.20148) (xy 345.434262 -283.171759) (xy 345.41333 -283.15412) (xy 345.406218 -283.148024)
			(xy 345.3892 -283.141674) (xy 345.303856 -283.141674) (xy 345.286838 -283.148024) (xy 345.279726 -283.15412)
			(xy 345.258798 -283.171763) (xy 345.212823 -283.201474) (xy 345.163075 -283.224309) (xy 345.110574 -283.239799)
			(xy 345.056397 -283.247626) (xy 345.029028 -283.2481) (xy 345.001773 -283.247655) (xy 344.947818 -283.239901)
			(xy 344.895516 -283.224547) (xy 344.845931 -283.201905) (xy 344.800074 -283.172437) (xy 344.758877 -283.136743)
			(xy 344.723179 -283.095549) (xy 344.693708 -283.049693) (xy 344.671063 -283.00011) (xy 344.655705 -282.947809)
			(xy 344.647947 -282.893855) (xy 344.317801 -282.893855) (xy 344.31775 -282.89643) (xy 344.308442 -282.955376)
			(xy 344.299794 -282.98394) (xy 344.296492 -282.994354) (xy 344.298778 -283.015944) (xy 344.348816 -283.100526)
			(xy 344.366596 -283.112972) (xy 344.377264 -283.115004) (xy 344.403081 -283.120346) (xy 344.452997 -283.137314)
			(xy 344.500101 -283.160994) (xy 344.543495 -283.190935) (xy 344.582354 -283.226566) (xy 344.615935 -283.267208)
			(xy 344.643601 -283.312088) (xy 344.664823 -283.360349) (xy 344.679197 -283.411073) (xy 344.686449 -283.463293)
			(xy 344.68689 -283.489654) (xy 344.686307 -283.519777) (xy 344.676832 -283.579274) (xy 344.658125 -283.636542)
			(xy 344.630651 -283.69016) (xy 344.595093 -283.738793) (xy 344.574114 -283.760418) (xy 344.566748 -283.76753)
			(xy 344.559128 -283.786326) (xy 344.559128 -283.878782) (xy 344.566748 -283.897578) (xy 344.574114 -283.90469)
			(xy 344.595117 -283.926294) (xy 344.630682 -283.974929) (xy 344.658157 -284.02855) (xy 344.672536 -284.072584)
			(xy 349.574104 -284.072584) (xy 349.57456 -284.045213) (xy 349.58238 -283.991034) (xy 349.597871 -283.938531)
			(xy 349.620715 -283.888784) (xy 349.650442 -283.842817) (xy 349.668084 -283.821886) (xy 349.67418 -283.814774)
			(xy 349.68053 -283.797756) (xy 349.68053 -283.712412) (xy 349.67418 -283.695394) (xy 349.668084 -283.688282)
			(xy 349.650467 -283.667332) (xy 349.620753 -283.621364) (xy 349.597913 -283.571621) (xy 349.582416 -283.519124)
			(xy 349.574582 -283.464952) (xy 349.574104 -283.437584) (xy 349.57459 -283.410333) (xy 349.582346 -283.356385)
			(xy 349.597701 -283.30409) (xy 349.620343 -283.254513) (xy 349.649809 -283.208663) (xy 349.6855 -283.167472)
			(xy 349.726691 -283.131781) (xy 349.772541 -283.102315) (xy 349.822118 -283.079673) (xy 349.874413 -283.064318)
			(xy 349.928361 -283.056562) (xy 349.982863 -283.056562) (xy 350.036811 -283.064318) (xy 350.089106 -283.079673)
			(xy 350.138683 -283.102315) (xy 350.184533 -283.131781) (xy 350.225724 -283.167472) (xy 350.261415 -283.208663)
			(xy 350.290881 -283.254513) (xy 350.313523 -283.30409) (xy 350.328878 -283.356385) (xy 350.336634 -283.410333)
			(xy 350.33712 -283.437584) (xy 350.336664 -283.464955) (xy 350.328847 -283.519135) (xy 350.313356 -283.571639)
			(xy 350.290512 -283.621386) (xy 350.260783 -283.667351) (xy 350.24314 -283.688282) (xy 350.237044 -283.695394)
			(xy 350.230694 -283.712412) (xy 350.230694 -283.797756) (xy 350.237044 -283.814774) (xy 350.24314 -283.821886)
			(xy 350.260793 -283.842807) (xy 350.290501 -283.888784) (xy 350.313334 -283.938534) (xy 350.328822 -283.991037)
			(xy 350.336648 -284.045214) (xy 350.33712 -284.072584) (xy 350.336634 -284.099835) (xy 350.328878 -284.153783)
			(xy 350.313523 -284.206078) (xy 350.290881 -284.255655) (xy 350.261415 -284.301505) (xy 350.225724 -284.342696)
			(xy 350.184533 -284.378387) (xy 350.138683 -284.407853) (xy 350.089106 -284.430495) (xy 350.036811 -284.44585)
			(xy 349.982863 -284.453606) (xy 349.928361 -284.453606) (xy 349.874413 -284.44585) (xy 349.822118 -284.430495)
			(xy 349.772541 -284.407853) (xy 349.726691 -284.378387) (xy 349.6855 -284.342696) (xy 349.649809 -284.301505)
			(xy 349.620343 -284.255655) (xy 349.597701 -284.206078) (xy 349.582346 -284.153783) (xy 349.57459 -284.099835)
			(xy 349.574104 -284.072584) (xy 344.672536 -284.072584) (xy 344.67686 -284.085825) (xy 344.686325 -284.145328)
			(xy 344.68689 -284.175454) (xy 344.686404 -284.202705) (xy 344.678648 -284.256653) (xy 344.663293 -284.308948)
			(xy 344.640651 -284.358525) (xy 344.611185 -284.404375) (xy 344.575494 -284.445566) (xy 344.534303 -284.481257)
			(xy 344.488453 -284.510723) (xy 344.438876 -284.533365) (xy 344.386581 -284.54872) (xy 344.332633 -284.556476)
			(xy 344.278131 -284.556476) (xy 344.224183 -284.54872) (xy 344.171888 -284.533365) (xy 344.122311 -284.510723)
			(xy 344.076461 -284.481257) (xy 344.03527 -284.445566) (xy 343.999579 -284.404375) (xy 343.970113 -284.358525)
			(xy 343.947471 -284.308948) (xy 343.932116 -284.256653) (xy 343.92436 -284.202705) (xy 343.923874 -284.175454)
			(xy 343.924472 -284.145332) (xy 343.933946 -284.085836) (xy 343.95265 -284.028568) (xy 343.98012 -283.974951)
			(xy 344.015673 -283.926316) (xy 344.03665 -283.90469) (xy 344.044016 -283.897578) (xy 344.051636 -283.878782)
			(xy 344.051636 -283.786326) (xy 344.044016 -283.76753) (xy 344.03665 -283.760418) (xy 344.015662 -283.7388)
			(xy 343.980093 -283.69017) (xy 343.952613 -283.636552) (xy 343.933907 -283.57928) (xy 343.92444 -283.519779)
			(xy 343.923874 -283.489654) (xy 343.924447 -283.459815) (xy 343.933764 -283.400869) (xy 343.942416 -283.372306)
			(xy 343.945718 -283.361892) (xy 343.943432 -283.340302) (xy 343.893394 -283.25572) (xy 343.875614 -283.243274)
			(xy 343.864946 -283.241242) (xy 343.837096 -283.235393) (xy 343.783432 -283.216456) (xy 343.733175 -283.18976)
			(xy 343.687439 -283.155899) (xy 343.647237 -283.115623) (xy 343.613461 -283.069823) (xy 343.586859 -283.019517)
			(xy 343.568022 -282.965818) (xy 343.562178 -282.937966) (xy 343.559638 -282.925774) (xy 343.54389 -282.905962)
			(xy 343.443814 -282.862528) (xy 343.418668 -282.86456) (xy 343.408 -282.871164) (xy 343.38503 -282.885203)
			(xy 343.335956 -282.907334) (xy 343.284254 -282.92233) (xy 343.230955 -282.929892) (xy 343.204038 -282.930346)
			(xy 343.186019 -282.930129) (xy 343.150144 -282.926692) (xy 343.13241 -282.923488) (xy 343.123012 -282.92171)
			(xy 343.103962 -282.92552) (xy 343.028778 -282.973272) (xy 343.017348 -282.98902) (xy 343.015062 -282.998418)
			(xy 343.007666 -283.025463) (xy 342.986039 -283.077191) (xy 342.957076 -283.125198) (xy 342.9214 -283.168451)
			(xy 342.879781 -283.206019) (xy 342.833112 -283.237093) (xy 342.7824 -283.261005) (xy 342.728735 -283.27724)
			(xy 342.673272 -283.285449) (xy 342.645238 -283.285946) (xy 342.617989 -283.285387) (xy 342.564046 -283.277636)
			(xy 342.511755 -283.262288) (xy 342.462181 -283.239654) (xy 342.416332 -283.210195) (xy 342.375143 -283.174511)
			(xy 342.33945 -283.133329) (xy 342.309983 -283.087486) (xy 342.287339 -283.037916) (xy 342.27198 -282.985628)
			(xy 342.264219 -282.931686) (xy 342.26373 -282.904438) (xy 337.882992 -282.904438) (xy 337.876758 -282.947795)
			(xy 337.861404 -283.000088) (xy 337.838765 -283.049663) (xy 337.809301 -283.095511) (xy 337.773612 -283.1367)
			(xy 337.732424 -283.172391) (xy 337.686577 -283.201857) (xy 337.637003 -283.224499) (xy 337.584711 -283.239855)
			(xy 337.530766 -283.247613) (xy 337.503516 -283.2481) (xy 337.476146 -283.247625) (xy 337.421967 -283.239809)
			(xy 337.369464 -283.224322) (xy 337.319717 -283.201482) (xy 337.27375 -283.17176) (xy 337.252818 -283.15412)
			(xy 337.245706 -283.148024) (xy 337.228688 -283.141674) (xy 337.143344 -283.141674) (xy 337.126326 -283.148024)
			(xy 337.119214 -283.15412) (xy 337.09829 -283.171769) (xy 337.052315 -283.201479) (xy 337.002565 -283.224312)
			(xy 336.950063 -283.239801) (xy 336.895886 -283.247627) (xy 336.868516 -283.2481) (xy 336.841262 -283.247654)
			(xy 336.787308 -283.239898) (xy 336.735007 -283.224543) (xy 336.685424 -283.201901) (xy 336.639568 -283.172433)
			(xy 336.598372 -283.136739) (xy 336.562676 -283.095545) (xy 336.533206 -283.04969) (xy 336.510562 -283.000108)
			(xy 336.495205 -282.947808) (xy 336.487447 -282.893854) (xy 336.15729 -282.893854) (xy 336.157239 -282.89643)
			(xy 336.14793 -282.955376) (xy 336.139282 -282.98394) (xy 336.13598 -282.994354) (xy 336.138266 -283.015944)
			(xy 336.188304 -283.100526) (xy 336.206084 -283.112972) (xy 336.216752 -283.115004) (xy 336.242567 -283.120354)
			(xy 336.292483 -283.137321) (xy 336.339587 -283.161) (xy 336.382982 -283.190939) (xy 336.421841 -283.226569)
			(xy 336.455423 -283.267211) (xy 336.483088 -283.31209) (xy 336.50431 -283.36035) (xy 336.518685 -283.411074)
			(xy 336.525937 -283.463294) (xy 336.526378 -283.489654) (xy 336.52577 -283.519776) (xy 336.516297 -283.57927)
			(xy 336.497594 -283.636537) (xy 336.470127 -283.690155) (xy 336.434577 -283.738792) (xy 336.413602 -283.760418)
			(xy 336.406236 -283.76753) (xy 336.398616 -283.786326) (xy 336.398616 -283.878782) (xy 336.406236 -283.897578)
			(xy 336.413602 -283.90469) (xy 336.434603 -283.926296) (xy 336.470168 -283.97493) (xy 336.497645 -284.028551)
			(xy 336.512024 -284.072584) (xy 341.413592 -284.072584) (xy 341.414051 -284.045214) (xy 341.421871 -283.991034)
			(xy 341.437361 -283.938531) (xy 341.460205 -283.888784) (xy 341.48993 -283.842818) (xy 341.507572 -283.821886)
			(xy 341.513668 -283.814774) (xy 341.520018 -283.797756) (xy 341.520018 -283.712412) (xy 341.513668 -283.695394)
			(xy 341.507572 -283.688282) (xy 341.489954 -283.667333) (xy 341.46024 -283.621365) (xy 341.4374 -283.571621)
			(xy 341.421904 -283.519125) (xy 341.41407 -283.464952) (xy 341.413592 -283.437584) (xy 341.414078 -283.410333)
			(xy 341.421834 -283.356385) (xy 341.437189 -283.30409) (xy 341.459831 -283.254513) (xy 341.489297 -283.208663)
			(xy 341.524988 -283.167472) (xy 341.566179 -283.131781) (xy 341.612029 -283.102315) (xy 341.661606 -283.079673)
			(xy 341.713901 -283.064318) (xy 341.767849 -283.056562) (xy 341.822351 -283.056562) (xy 341.876299 -283.064318)
			(xy 341.928594 -283.079673) (xy 341.978171 -283.102315) (xy 342.024021 -283.131781) (xy 342.065212 -283.167472)
			(xy 342.100903 -283.208663) (xy 342.130369 -283.254513) (xy 342.153011 -283.30409) (xy 342.168366 -283.356385)
			(xy 342.176122 -283.410333) (xy 342.176608 -283.437584) (xy 342.176131 -283.464954) (xy 342.168315 -283.519132)
			(xy 342.152829 -283.571635) (xy 342.12999 -283.621382) (xy 342.100268 -283.66735) (xy 342.082628 -283.688282)
			(xy 342.076532 -283.695394) (xy 342.070182 -283.712412) (xy 342.070182 -283.797756) (xy 342.076532 -283.814774)
			(xy 342.082628 -283.821886) (xy 342.100278 -283.842809) (xy 342.129988 -283.888785) (xy 342.152821 -283.938535)
			(xy 342.168309 -283.991037) (xy 342.176135 -284.045214) (xy 342.176608 -284.072584) (xy 342.176122 -284.099835)
			(xy 342.168366 -284.153783) (xy 342.153011 -284.206078) (xy 342.130369 -284.255655) (xy 342.100903 -284.301505)
			(xy 342.065212 -284.342696) (xy 342.024021 -284.378387) (xy 341.978171 -284.407853) (xy 341.928594 -284.430495)
			(xy 341.876299 -284.44585) (xy 341.822351 -284.453606) (xy 341.767849 -284.453606) (xy 341.713901 -284.44585)
			(xy 341.661606 -284.430495) (xy 341.612029 -284.407853) (xy 341.566179 -284.378387) (xy 341.524988 -284.342696)
			(xy 341.489297 -284.301505) (xy 341.459831 -284.255655) (xy 341.437189 -284.206078) (xy 341.421834 -284.153783)
			(xy 341.414078 -284.099835) (xy 341.413592 -284.072584) (xy 336.512024 -284.072584) (xy 336.516348 -284.085826)
			(xy 336.525813 -284.145328) (xy 336.526378 -284.175454) (xy 336.525892 -284.202705) (xy 336.518136 -284.256653)
			(xy 336.502781 -284.308948) (xy 336.480139 -284.358525) (xy 336.450673 -284.404375) (xy 336.414982 -284.445566)
			(xy 336.373791 -284.481257) (xy 336.327941 -284.510723) (xy 336.278364 -284.533365) (xy 336.226069 -284.54872)
			(xy 336.172121 -284.556476) (xy 336.117619 -284.556476) (xy 336.063671 -284.54872) (xy 336.011376 -284.533365)
			(xy 335.961799 -284.510723) (xy 335.915949 -284.481257) (xy 335.874758 -284.445566) (xy 335.839067 -284.404375)
			(xy 335.809601 -284.358525) (xy 335.786959 -284.308948) (xy 335.771604 -284.256653) (xy 335.763848 -284.202705)
			(xy 335.763362 -284.175454) (xy 335.763964 -284.145332) (xy 335.773437 -284.085837) (xy 335.79214 -284.028569)
			(xy 335.819609 -283.974951) (xy 335.855162 -283.926316) (xy 335.876138 -283.90469) (xy 335.883504 -283.897578)
			(xy 335.891124 -283.878782) (xy 335.891124 -283.786326) (xy 335.883504 -283.76753) (xy 335.876138 -283.760418)
			(xy 335.855148 -283.738802) (xy 335.819579 -283.690172) (xy 335.7921 -283.636553) (xy 335.773395 -283.57928)
			(xy 335.763928 -283.519779) (xy 335.763362 -283.489654) (xy 335.763935 -283.459815) (xy 335.773252 -283.400869)
			(xy 335.781904 -283.372306) (xy 335.785206 -283.361892) (xy 335.78292 -283.340302) (xy 335.732882 -283.25572)
			(xy 335.715102 -283.243274) (xy 335.704434 -283.241242) (xy 335.676582 -283.235401) (xy 335.622919 -283.216462)
			(xy 335.572662 -283.189766) (xy 335.526925 -283.155903) (xy 335.486724 -283.115625) (xy 335.452948 -283.069825)
			(xy 335.426347 -283.019518) (xy 335.40751 -282.965818) (xy 335.401666 -282.937966) (xy 335.399126 -282.925774)
			(xy 335.383378 -282.905962) (xy 335.283302 -282.862528) (xy 335.258156 -282.86456) (xy 335.247488 -282.871164)
			(xy 335.224497 -282.885167) (xy 335.175431 -282.907306) (xy 335.123735 -282.922312) (xy 335.070441 -282.929886)
			(xy 335.043526 -282.930346) (xy 335.025506 -282.930131) (xy 334.989632 -282.926693) (xy 334.971898 -282.923488)
			(xy 334.9625 -282.92171) (xy 334.94345 -282.92552) (xy 334.868266 -282.973272) (xy 334.856836 -282.98902)
			(xy 334.85455 -282.998418) (xy 334.847165 -283.025466) (xy 334.825537 -283.077195) (xy 334.796572 -283.125203)
			(xy 334.760896 -283.168456) (xy 334.719275 -283.206023) (xy 334.672605 -283.237097) (xy 334.621891 -283.261008)
			(xy 334.568224 -283.277242) (xy 334.51276 -283.28545) (xy 334.484726 -283.285946) (xy 334.457477 -283.285398)
			(xy 334.403534 -283.277646) (xy 334.351242 -283.262296) (xy 334.301668 -283.23966) (xy 334.255819 -283.2102)
			(xy 334.21463 -283.174516) (xy 334.178938 -283.133332) (xy 334.14947 -283.087488) (xy 334.126827 -283.037918)
			(xy 334.111468 -282.985629) (xy 334.103707 -282.931687) (xy 334.103218 -282.904438) (xy 330.729082 -282.904438)
			(xy 329.149964 -284.483556) (xy 329.143607 -284.490568) (xy 329.136017 -284.507888) (xy 329.135172 -284.526779)
			(xy 329.137772 -284.53588) (xy 329.171554 -284.635702) (xy 329.193652 -284.654244) (xy 329.20813 -284.656276)
			(xy 329.235214 -284.660456) (xy 329.287909 -284.675501) (xy 329.337907 -284.697934) (xy 329.384179 -284.727293)
			(xy 329.425772 -284.762974) (xy 329.461829 -284.804241) (xy 329.491607 -284.850244) (xy 329.514494 -284.900036)
			(xy 329.530017 -284.952592) (xy 329.537858 -285.006828) (xy 329.53833 -285.034228) (xy 329.537871 -285.060962)
			(xy 329.530414 -285.113908) (xy 329.515635 -285.165294) (xy 329.493824 -285.214111) (xy 329.465409 -285.259405)
			(xy 329.430947 -285.300285) (xy 329.41133 -285.318454) (xy 329.403202 -285.325566) (xy 329.394566 -285.344362)
			(xy 329.392026 -285.439358) (xy 329.399392 -285.458408) (xy 329.407012 -285.466028) (xy 329.427747 -285.487637)
			(xy 329.462921 -285.536103) (xy 329.490087 -285.589472) (xy 329.508576 -285.646431) (xy 329.517934 -285.70558)
			(xy 329.518518 -285.735522) (xy 329.518032 -285.762773) (xy 329.510276 -285.816721) (xy 329.494921 -285.869016)
			(xy 329.472279 -285.918593) (xy 329.442813 -285.964443) (xy 329.407122 -286.005634) (xy 329.365931 -286.041325)
			(xy 329.320081 -286.070791) (xy 329.270504 -286.093433) (xy 329.218209 -286.108788) (xy 329.164261 -286.116544)
			(xy 329.109759 -286.116544) (xy 329.055811 -286.108788) (xy 329.003516 -286.093433) (xy 328.953939 -286.070791)
			(xy 328.908089 -286.041325) (xy 328.866898 -286.005634) (xy 328.831207 -285.964443) (xy 328.801741 -285.918593)
			(xy 328.779099 -285.869016) (xy 328.763744 -285.816721) (xy 328.755988 -285.762773) (xy 328.755502 -285.735522)
			(xy 328.755917 -285.708786) (xy 328.763382 -285.655838) (xy 328.778169 -285.604451) (xy 328.799988 -285.555633)
			(xy 328.828411 -285.510341) (xy 328.862881 -285.469463) (xy 328.882502 -285.451296) (xy 328.89063 -285.444184)
			(xy 328.899266 -285.425388) (xy 328.901806 -285.330392) (xy 328.89444 -285.311342) (xy 328.88682 -285.303722)
			(xy 328.865391 -285.281331) (xy 328.829298 -285.230953) (xy 328.801809 -285.17541) (xy 328.783647 -285.116158)
			(xy 328.77887 -285.085536) (xy 328.776838 -285.071058) (xy 328.758296 -285.04896) (xy 328.658474 -285.015178)
			(xy 328.649387 -285.012442) (xy 328.63044 -285.013233) (xy 328.613098 -285.020905) (xy 328.60615 -285.02737)
			(xy 327.632568 -286.000952) (xy 327.625865 -286.008426) (xy 327.61828 -286.026991) (xy 327.617836 -286.03702)
			(xy 327.617836 -286.699452) (xy 340.924132 -286.699452) (xy 340.928203 -286.64383) (xy 340.940329 -286.589393)
			(xy 340.960252 -286.537302) (xy 340.987548 -286.488667) (xy 341.021634 -286.444524) (xy 341.061783 -286.405815)
			(xy 341.107141 -286.373364) (xy 341.156741 -286.347863) (xy 341.209525 -286.329856) (xy 341.264368 -286.319726)
			(xy 341.320102 -286.317689) (xy 341.375539 -286.323789) (xy 341.429496 -286.337895) (xy 341.480825 -286.359707)
			(xy 341.528431 -286.388761) (xy 341.571299 -286.424436) (xy 341.608516 -286.465973) (xy 341.639289 -286.512486)
			(xy 341.662961 -286.562983) (xy 341.672993 -286.596328) (xy 341.832182 -286.596328) (xy 341.836253 -286.540706)
			(xy 341.848379 -286.486269) (xy 341.868302 -286.434178) (xy 341.895598 -286.385543) (xy 341.929684 -286.3414)
			(xy 341.969833 -286.302691) (xy 342.015191 -286.27024) (xy 342.064791 -286.244739) (xy 342.117575 -286.226732)
			(xy 342.172418 -286.216602) (xy 342.228152 -286.214565) (xy 342.283589 -286.220665) (xy 342.337546 -286.234771)
			(xy 342.388875 -286.256583) (xy 342.436481 -286.285637) (xy 342.479349 -286.321312) (xy 342.516566 -286.362849)
			(xy 342.547339 -286.409362) (xy 342.571011 -286.459859) (xy 342.587079 -286.513266) (xy 342.595199 -286.568442)
			(xy 342.595708 -286.596328) (xy 342.595199 -286.624214) (xy 342.587079 -286.67939) (xy 342.571011 -286.732797)
			(xy 342.547339 -286.783294) (xy 342.518786 -286.826452) (xy 357.611932 -286.826452) (xy 357.616003 -286.77083)
			(xy 357.628129 -286.716393) (xy 357.648052 -286.664302) (xy 357.675348 -286.615667) (xy 357.709434 -286.571524)
			(xy 357.749583 -286.532815) (xy 357.794941 -286.500364) (xy 357.844541 -286.474863) (xy 357.897325 -286.456856)
			(xy 357.952168 -286.446726) (xy 358.007902 -286.444689) (xy 358.063339 -286.450789) (xy 358.117296 -286.464895)
			(xy 358.168625 -286.486707) (xy 358.216231 -286.515761) (xy 358.259099 -286.551436) (xy 358.296316 -286.592973)
			(xy 358.327089 -286.639486) (xy 358.350761 -286.689983) (xy 358.365531 -286.739076) (xy 358.56494 -286.739076)
			(xy 358.569011 -286.683454) (xy 358.581137 -286.629017) (xy 358.60106 -286.576926) (xy 358.628356 -286.528291)
			(xy 358.662442 -286.484148) (xy 358.702591 -286.445439) (xy 358.747949 -286.412988) (xy 358.797549 -286.387487)
			(xy 358.850333 -286.36948) (xy 358.905176 -286.35935) (xy 358.96091 -286.357313) (xy 359.016347 -286.363413)
			(xy 359.070304 -286.377519) (xy 359.121633 -286.399331) (xy 359.169239 -286.428385) (xy 359.212107 -286.46406)
			(xy 359.249324 -286.505597) (xy 359.280097 -286.55211) (xy 359.303769 -286.602607) (xy 359.319837 -286.656014)
			(xy 359.327957 -286.71119) (xy 359.328466 -286.739076) (xy 359.327957 -286.766962) (xy 359.319837 -286.822138)
			(xy 359.303769 -286.875545) (xy 359.280097 -286.926042) (xy 359.249324 -286.972555) (xy 359.212107 -287.014092)
			(xy 359.169239 -287.049767) (xy 359.121633 -287.078821) (xy 359.070304 -287.100633) (xy 359.016347 -287.114739)
			(xy 358.96091 -287.120839) (xy 358.905176 -287.118802) (xy 358.850333 -287.108672) (xy 358.797549 -287.090665)
			(xy 358.747949 -287.065164) (xy 358.702591 -287.032713) (xy 358.662442 -286.994004) (xy 358.628356 -286.949861)
			(xy 358.60106 -286.901226) (xy 358.581137 -286.849135) (xy 358.569011 -286.794698) (xy 358.56494 -286.739076)
			(xy 358.365531 -286.739076) (xy 358.366829 -286.74339) (xy 358.374949 -286.798566) (xy 358.375458 -286.826452)
			(xy 358.374949 -286.854338) (xy 358.366829 -286.909514) (xy 358.350761 -286.962921) (xy 358.327089 -287.013418)
			(xy 358.296316 -287.059931) (xy 358.259099 -287.101468) (xy 358.216231 -287.137143) (xy 358.168625 -287.166197)
			(xy 358.117296 -287.188009) (xy 358.063339 -287.202115) (xy 358.007902 -287.208215) (xy 357.952168 -287.206178)
			(xy 357.897325 -287.196048) (xy 357.844541 -287.178041) (xy 357.794941 -287.15254) (xy 357.749583 -287.120089)
			(xy 357.709434 -287.08138) (xy 357.675348 -287.037237) (xy 357.648052 -286.988602) (xy 357.628129 -286.936511)
			(xy 357.616003 -286.882074) (xy 357.611932 -286.826452) (xy 342.518786 -286.826452) (xy 342.516566 -286.829807)
			(xy 342.479349 -286.871344) (xy 342.436481 -286.907019) (xy 342.388875 -286.936073) (xy 342.337546 -286.957885)
			(xy 342.283589 -286.971991) (xy 342.228152 -286.978091) (xy 342.172418 -286.976054) (xy 342.117575 -286.965924)
			(xy 342.064791 -286.947917) (xy 342.015191 -286.922416) (xy 341.969833 -286.889965) (xy 341.929684 -286.851256)
			(xy 341.895598 -286.807113) (xy 341.868302 -286.758478) (xy 341.848379 -286.706387) (xy 341.836253 -286.65195)
			(xy 341.832182 -286.596328) (xy 341.672993 -286.596328) (xy 341.679029 -286.61639) (xy 341.687149 -286.671566)
			(xy 341.687658 -286.699452) (xy 341.687149 -286.727338) (xy 341.679029 -286.782514) (xy 341.662961 -286.835921)
			(xy 341.639289 -286.886418) (xy 341.608516 -286.932931) (xy 341.571299 -286.974468) (xy 341.528431 -287.010143)
			(xy 341.480825 -287.039197) (xy 341.429496 -287.061009) (xy 341.375539 -287.075115) (xy 341.320102 -287.081215)
			(xy 341.264368 -287.079178) (xy 341.209525 -287.069048) (xy 341.156741 -287.051041) (xy 341.107141 -287.02554)
			(xy 341.061783 -286.993089) (xy 341.021634 -286.95438) (xy 340.987548 -286.910237) (xy 340.960252 -286.861602)
			(xy 340.940329 -286.809511) (xy 340.928203 -286.755074) (xy 340.924132 -286.699452) (xy 327.617836 -286.699452)
			(xy 327.617836 -291.079682) (xy 327.618179 -291.08973) (xy 327.625786 -291.108326) (xy 327.632568 -291.11575)
			(xy 330.699759 -294.1828) (xy 342.809828 -294.1828) (xy 342.813899 -294.127178) (xy 342.826025 -294.072741)
			(xy 342.845948 -294.02065) (xy 342.873244 -293.972015) (xy 342.90733 -293.927872) (xy 342.947479 -293.889163)
			(xy 342.992837 -293.856712) (xy 343.042437 -293.831211) (xy 343.095221 -293.813204) (xy 343.150064 -293.803074)
			(xy 343.205798 -293.801037) (xy 343.261235 -293.807137) (xy 343.315192 -293.821243) (xy 343.366521 -293.843055)
			(xy 343.414127 -293.872109) (xy 343.456995 -293.907784) (xy 343.494212 -293.949321) (xy 343.524985 -293.995834)
			(xy 343.548657 -294.046331) (xy 343.564725 -294.099738) (xy 343.572845 -294.154914) (xy 343.573354 -294.1828)
			(xy 359.468926 -294.1828) (xy 359.472997 -294.127178) (xy 359.485123 -294.072741) (xy 359.505046 -294.02065)
			(xy 359.532342 -293.972015) (xy 359.566428 -293.927872) (xy 359.606577 -293.889163) (xy 359.651935 -293.856712)
			(xy 359.701535 -293.831211) (xy 359.754319 -293.813204) (xy 359.809162 -293.803074) (xy 359.864896 -293.801037)
			(xy 359.920333 -293.807137) (xy 359.97429 -293.821243) (xy 360.025619 -293.843055) (xy 360.073225 -293.872109)
			(xy 360.116093 -293.907784) (xy 360.15331 -293.949321) (xy 360.184083 -293.995834) (xy 360.207755 -294.046331)
			(xy 360.223823 -294.099738) (xy 360.231943 -294.154914) (xy 360.232452 -294.1828) (xy 360.231943 -294.210686)
			(xy 360.223823 -294.265862) (xy 360.207755 -294.319269) (xy 360.184083 -294.369766) (xy 360.15331 -294.416279)
			(xy 360.116093 -294.457816) (xy 360.073225 -294.493491) (xy 360.025619 -294.522545) (xy 359.97429 -294.544357)
			(xy 359.920333 -294.558463) (xy 359.864896 -294.564563) (xy 359.809162 -294.562526) (xy 359.754319 -294.552396)
			(xy 359.701535 -294.534389) (xy 359.651935 -294.508888) (xy 359.606577 -294.476437) (xy 359.566428 -294.437728)
			(xy 359.532342 -294.393585) (xy 359.505046 -294.34495) (xy 359.485123 -294.292859) (xy 359.472997 -294.238422)
			(xy 359.468926 -294.1828) (xy 343.573354 -294.1828) (xy 343.572845 -294.210686) (xy 343.564725 -294.265862)
			(xy 343.548657 -294.319269) (xy 343.524985 -294.369766) (xy 343.494212 -294.416279) (xy 343.456995 -294.457816)
			(xy 343.414127 -294.493491) (xy 343.366521 -294.522545) (xy 343.315192 -294.544357) (xy 343.261235 -294.558463)
			(xy 343.205798 -294.564563) (xy 343.150064 -294.562526) (xy 343.095221 -294.552396) (xy 343.042437 -294.534389)
			(xy 342.992837 -294.508888) (xy 342.947479 -294.476437) (xy 342.90733 -294.437728) (xy 342.873244 -294.393585)
			(xy 342.845948 -294.34495) (xy 342.826025 -294.292859) (xy 342.813899 -294.238422) (xy 342.809828 -294.1828)
			(xy 330.699759 -294.1828) (xy 331.368826 -294.851836) (xy 334.24698 -294.851836) (xy 334.251051 -294.796214)
			(xy 334.263177 -294.741777) (xy 334.2831 -294.689686) (xy 334.310396 -294.641051) (xy 334.344482 -294.596908)
			(xy 334.384631 -294.558199) (xy 334.429989 -294.525748) (xy 334.479589 -294.500247) (xy 334.532373 -294.48224)
			(xy 334.587216 -294.47211) (xy 334.64295 -294.470073) (xy 334.698387 -294.476173) (xy 334.752344 -294.490279)
			(xy 334.803673 -294.512091) (xy 334.851279 -294.541145) (xy 334.894147 -294.57682) (xy 334.931364 -294.618357)
			(xy 334.962137 -294.66487) (xy 334.985809 -294.715367) (xy 335.001877 -294.768774) (xy 335.009997 -294.82395)
			(xy 335.010506 -294.851836) (xy 349.340676 -294.851836) (xy 349.344747 -294.796214) (xy 349.356873 -294.741777)
			(xy 349.376796 -294.689686) (xy 349.404092 -294.641051) (xy 349.438178 -294.596908) (xy 349.478327 -294.558199)
			(xy 349.523685 -294.525748) (xy 349.573285 -294.500247) (xy 349.626069 -294.48224) (xy 349.680912 -294.47211)
			(xy 349.736646 -294.470073) (xy 349.792083 -294.476173) (xy 349.84604 -294.490279) (xy 349.897369 -294.512091)
			(xy 349.944975 -294.541145) (xy 349.987843 -294.57682) (xy 350.02506 -294.618357) (xy 350.055833 -294.66487)
			(xy 350.079505 -294.715367) (xy 350.095573 -294.768774) (xy 350.103693 -294.82395) (xy 350.104202 -294.851836)
			(xy 350.906078 -294.851836) (xy 350.910149 -294.796214) (xy 350.922275 -294.741777) (xy 350.942198 -294.689686)
			(xy 350.969494 -294.641051) (xy 351.00358 -294.596908) (xy 351.043729 -294.558199) (xy 351.089087 -294.525748)
			(xy 351.138687 -294.500247) (xy 351.191471 -294.48224) (xy 351.246314 -294.47211) (xy 351.302048 -294.470073)
			(xy 351.357485 -294.476173) (xy 351.411442 -294.490279) (xy 351.462771 -294.512091) (xy 351.510377 -294.541145)
			(xy 351.553245 -294.57682) (xy 351.590462 -294.618357) (xy 351.621235 -294.66487) (xy 351.644907 -294.715367)
			(xy 351.660975 -294.768774) (xy 351.669095 -294.82395) (xy 351.669604 -294.851836) (xy 365.999774 -294.851836)
			(xy 366.003845 -294.796214) (xy 366.015971 -294.741777) (xy 366.035894 -294.689686) (xy 366.06319 -294.641051)
			(xy 366.097276 -294.596908) (xy 366.137425 -294.558199) (xy 366.182783 -294.525748) (xy 366.232383 -294.500247)
			(xy 366.285167 -294.48224) (xy 366.34001 -294.47211) (xy 366.395744 -294.470073) (xy 366.451181 -294.476173)
			(xy 366.505138 -294.490279) (xy 366.556467 -294.512091) (xy 366.604073 -294.541145) (xy 366.646941 -294.57682)
			(xy 366.684158 -294.618357) (xy 366.714931 -294.66487) (xy 366.738603 -294.715367) (xy 366.754671 -294.768774)
			(xy 366.762791 -294.82395) (xy 366.7633 -294.851836) (xy 366.762791 -294.879722) (xy 366.754671 -294.934898)
			(xy 366.738603 -294.988305) (xy 366.714931 -295.038802) (xy 366.684158 -295.085315) (xy 366.646941 -295.126852)
			(xy 366.604073 -295.162527) (xy 366.556467 -295.191581) (xy 366.505138 -295.213393) (xy 366.451181 -295.227499)
			(xy 366.395744 -295.233599) (xy 366.34001 -295.231562) (xy 366.285167 -295.221432) (xy 366.232383 -295.203425)
			(xy 366.182783 -295.177924) (xy 366.137425 -295.145473) (xy 366.097276 -295.106764) (xy 366.06319 -295.062621)
			(xy 366.035894 -295.013986) (xy 366.015971 -294.961895) (xy 366.003845 -294.907458) (xy 365.999774 -294.851836)
			(xy 351.669604 -294.851836) (xy 351.669095 -294.879722) (xy 351.660975 -294.934898) (xy 351.644907 -294.988305)
			(xy 351.621235 -295.038802) (xy 351.590462 -295.085315) (xy 351.553245 -295.126852) (xy 351.510377 -295.162527)
			(xy 351.462771 -295.191581) (xy 351.411442 -295.213393) (xy 351.357485 -295.227499) (xy 351.302048 -295.233599)
			(xy 351.246314 -295.231562) (xy 351.191471 -295.221432) (xy 351.138687 -295.203425) (xy 351.089087 -295.177924)
			(xy 351.043729 -295.145473) (xy 351.00358 -295.106764) (xy 350.969494 -295.062621) (xy 350.942198 -295.013986)
			(xy 350.922275 -294.961895) (xy 350.910149 -294.907458) (xy 350.906078 -294.851836) (xy 350.104202 -294.851836)
			(xy 350.103693 -294.879722) (xy 350.095573 -294.934898) (xy 350.079505 -294.988305) (xy 350.055833 -295.038802)
			(xy 350.02506 -295.085315) (xy 349.987843 -295.126852) (xy 349.944975 -295.162527) (xy 349.897369 -295.191581)
			(xy 349.84604 -295.213393) (xy 349.792083 -295.227499) (xy 349.736646 -295.233599) (xy 349.680912 -295.231562)
			(xy 349.626069 -295.221432) (xy 349.573285 -295.203425) (xy 349.523685 -295.177924) (xy 349.478327 -295.145473)
			(xy 349.438178 -295.106764) (xy 349.404092 -295.062621) (xy 349.376796 -295.013986) (xy 349.356873 -294.961895)
			(xy 349.344747 -294.907458) (xy 349.340676 -294.851836) (xy 335.010506 -294.851836) (xy 335.009997 -294.879722)
			(xy 335.001877 -294.934898) (xy 334.985809 -294.988305) (xy 334.962137 -295.038802) (xy 334.931364 -295.085315)
			(xy 334.894147 -295.126852) (xy 334.851279 -295.162527) (xy 334.803673 -295.191581) (xy 334.752344 -295.213393)
			(xy 334.698387 -295.227499) (xy 334.64295 -295.233599) (xy 334.587216 -295.231562) (xy 334.532373 -295.221432)
			(xy 334.479589 -295.203425) (xy 334.429989 -295.177924) (xy 334.384631 -295.145473) (xy 334.344482 -295.106764)
			(xy 334.310396 -295.062621) (xy 334.2831 -295.013986) (xy 334.263177 -294.961895) (xy 334.251051 -294.907458)
			(xy 334.24698 -294.851836) (xy 331.368826 -294.851836) (xy 333.144368 -296.627296) (xy 333.165182 -296.648882)
			(xy 333.200436 -296.697386) (xy 333.227664 -296.75081) (xy 333.246196 -296.807838) (xy 333.255573 -296.867063)
			(xy 333.256128 -296.897044) (xy 333.256128 -298.420536) (xy 335.694782 -298.420536) (xy 335.695249 -298.393166)
			(xy 335.703064 -298.338986) (xy 335.718551 -298.286482) (xy 335.741393 -298.236735) (xy 335.77112 -298.190769)
			(xy 335.788762 -298.169838) (xy 335.794858 -298.162726) (xy 335.801208 -298.145708) (xy 335.801208 -298.060364)
			(xy 335.794858 -298.043346) (xy 335.788762 -298.036234) (xy 335.771155 -298.015273) (xy 335.741426 -297.969311)
			(xy 335.718577 -297.91957) (xy 335.703076 -297.867072) (xy 335.695243 -297.812896) (xy 335.695239 -297.758158)
			(xy 335.703064 -297.703981) (xy 335.718558 -297.651481) (xy 335.7414 -297.601736) (xy 335.771122 -297.55577)
			(xy 335.788762 -297.534838) (xy 335.794858 -297.527726) (xy 335.801208 -297.510708) (xy 335.801208 -297.425364)
			(xy 335.794858 -297.408346) (xy 335.788762 -297.401234) (xy 335.771155 -297.380273) (xy 335.741426 -297.334311)
			(xy 335.718577 -297.28457) (xy 335.703076 -297.232072) (xy 335.695243 -297.177896) (xy 335.695239 -297.123158)
			(xy 335.703064 -297.068981) (xy 335.718558 -297.016481) (xy 335.7414 -296.966736) (xy 335.771122 -296.92077)
			(xy 335.788762 -296.899838) (xy 335.794858 -296.892726) (xy 335.801208 -296.875708) (xy 335.801208 -296.790364)
			(xy 335.794858 -296.773346) (xy 335.788762 -296.766234) (xy 335.771155 -296.745273) (xy 335.741426 -296.699311)
			(xy 335.718577 -296.64957) (xy 335.703076 -296.597072) (xy 335.695243 -296.542896) (xy 335.695239 -296.488158)
			(xy 335.703064 -296.433981) (xy 335.718558 -296.381481) (xy 335.7414 -296.331736) (xy 335.771122 -296.28577)
			(xy 335.788762 -296.264838) (xy 335.794858 -296.257726) (xy 335.801208 -296.240708) (xy 335.801208 -296.155364)
			(xy 335.794858 -296.138346) (xy 335.788762 -296.131234) (xy 335.771155 -296.110273) (xy 335.741426 -296.064311)
			(xy 335.718577 -296.01457) (xy 335.703076 -295.962072) (xy 335.695243 -295.907896) (xy 335.695239 -295.853158)
			(xy 335.703064 -295.798981) (xy 335.718558 -295.746481) (xy 335.7414 -295.696736) (xy 335.771122 -295.65077)
			(xy 335.788762 -295.629838) (xy 335.794858 -295.622726) (xy 335.801208 -295.605708) (xy 335.801208 -295.520364)
			(xy 335.794858 -295.503346) (xy 335.788762 -295.496234) (xy 335.771119 -295.475305) (xy 335.741409 -295.429331)
			(xy 335.718574 -295.379582) (xy 335.703084 -295.327081) (xy 335.695256 -295.272905) (xy 335.694782 -295.245536)
			(xy 335.695289 -295.218284) (xy 335.703041 -295.164336) (xy 335.718392 -295.112039) (xy 335.741029 -295.06246)
			(xy 335.770492 -295.016607) (xy 335.806182 -294.975414) (xy 335.84737 -294.93972) (xy 335.893219 -294.910251)
			(xy 335.942796 -294.887608) (xy 335.995091 -294.87225) (xy 336.049039 -294.864492) (xy 336.07629 -294.864028)
			(xy 336.10366 -294.864493) (xy 336.15784 -294.87231) (xy 336.210343 -294.887799) (xy 336.26009 -294.910641)
			(xy 336.306057 -294.940366) (xy 336.326988 -294.958008) (xy 336.3341 -294.964104) (xy 336.351118 -294.970454)
			(xy 336.436462 -294.970454) (xy 336.45348 -294.964104) (xy 336.460592 -294.958008) (xy 336.481517 -294.94036)
			(xy 336.527492 -294.91065) (xy 336.577241 -294.887815) (xy 336.629743 -294.872326) (xy 336.68392 -294.864501)
			(xy 336.71129 -294.864028) (xy 336.738544 -294.864465) (xy 336.792498 -294.872221) (xy 336.844799 -294.887578)
			(xy 336.894381 -294.910222) (xy 336.940236 -294.939692) (xy 336.98143 -294.975389) (xy 337.017123 -295.016585)
			(xy 337.046591 -295.062442) (xy 337.069231 -295.112026) (xy 337.084584 -295.164327) (xy 337.092337 -295.218282)
			(xy 337.092798 -295.245536) (xy 337.092354 -295.272907) (xy 337.084531 -295.327087) (xy 337.069036 -295.37959)
			(xy 337.04619 -295.429337) (xy 337.016461 -295.475303) (xy 336.998818 -295.496234) (xy 336.992722 -295.503346)
			(xy 336.986372 -295.520364) (xy 336.986372 -295.605708) (xy 336.992722 -295.622726) (xy 336.998818 -295.629838)
			(xy 337.016492 -295.650743) (xy 337.046212 -295.696717) (xy 337.069052 -295.746468) (xy 337.084544 -295.798974)
			(xy 337.092368 -295.853155) (xy 337.092364 -295.907899) (xy 337.084532 -295.962079) (xy 337.069033 -296.014583)
			(xy 337.046186 -296.064331) (xy 337.016459 -296.1103) (xy 336.998818 -296.131234) (xy 336.992722 -296.138346)
			(xy 336.986372 -296.155364) (xy 336.986372 -296.240708) (xy 336.992722 -296.257726) (xy 336.998818 -296.264838)
			(xy 337.016492 -296.285743) (xy 337.046212 -296.331717) (xy 337.069052 -296.381468) (xy 337.084544 -296.433974)
			(xy 337.092368 -296.488155) (xy 337.092364 -296.542899) (xy 337.084532 -296.597079) (xy 337.069033 -296.649583)
			(xy 337.046186 -296.699331) (xy 337.016459 -296.7453) (xy 336.998818 -296.766234) (xy 336.992722 -296.773346)
			(xy 336.986372 -296.790364) (xy 336.986372 -296.875708) (xy 336.992722 -296.892726) (xy 336.998818 -296.899838)
			(xy 337.016492 -296.920743) (xy 337.046212 -296.966717) (xy 337.069052 -297.016468) (xy 337.084544 -297.068974)
			(xy 337.092368 -297.123155) (xy 337.092364 -297.177899) (xy 337.084532 -297.232079) (xy 337.069033 -297.284583)
			(xy 337.046186 -297.334331) (xy 337.016459 -297.3803) (xy 336.998818 -297.401234) (xy 336.992722 -297.408346)
			(xy 336.986372 -297.425364) (xy 336.986372 -297.510708) (xy 336.992722 -297.527726) (xy 336.998818 -297.534838)
			(xy 337.016492 -297.555743) (xy 337.046212 -297.601717) (xy 337.069052 -297.651468) (xy 337.084544 -297.703974)
			(xy 337.092368 -297.758155) (xy 337.092364 -297.812899) (xy 337.084532 -297.867079) (xy 337.069033 -297.919583)
			(xy 337.046186 -297.969331) (xy 337.016459 -298.0153) (xy 336.998818 -298.036234) (xy 336.992722 -298.043346)
			(xy 336.986372 -298.060364) (xy 336.986372 -298.145708) (xy 336.992722 -298.162726) (xy 336.998818 -298.169838)
			(xy 337.016444 -298.19078) (xy 337.046157 -298.236751) (xy 337.068996 -298.286496) (xy 337.08449 -298.338994)
			(xy 337.092322 -298.393168) (xy 337.092798 -298.420536) (xy 340.335362 -298.420536) (xy 340.335834 -298.393166)
			(xy 340.343648 -298.338986) (xy 340.359135 -298.286483) (xy 340.381976 -298.236736) (xy 340.4117 -298.190769)
			(xy 340.429342 -298.169838) (xy 340.435438 -298.162726) (xy 340.441788 -298.145708) (xy 340.441788 -298.060364)
			(xy 340.435438 -298.043346) (xy 340.429342 -298.036234) (xy 340.411736 -298.015273) (xy 340.382009 -297.969311)
			(xy 340.35916 -297.919569) (xy 340.34366 -297.867071) (xy 340.335828 -297.812896) (xy 340.335824 -297.758158)
			(xy 340.343649 -297.703982) (xy 340.359141 -297.651482) (xy 340.381982 -297.601737) (xy 340.411703 -297.55577)
			(xy 340.429342 -297.534838) (xy 340.435438 -297.527726) (xy 340.441788 -297.510708) (xy 340.441788 -297.425364)
			(xy 340.435438 -297.408346) (xy 340.429342 -297.401234) (xy 340.411736 -297.380273) (xy 340.382009 -297.334311)
			(xy 340.35916 -297.284569) (xy 340.34366 -297.232071) (xy 340.335828 -297.177896) (xy 340.335824 -297.123158)
			(xy 340.343649 -297.068982) (xy 340.359141 -297.016482) (xy 340.381982 -296.966737) (xy 340.411703 -296.92077)
			(xy 340.429342 -296.899838) (xy 340.435438 -296.892726) (xy 340.441788 -296.875708) (xy 340.441788 -296.790364)
			(xy 340.435438 -296.773346) (xy 340.429342 -296.766234) (xy 340.411736 -296.745273) (xy 340.382009 -296.699311)
			(xy 340.35916 -296.649569) (xy 340.34366 -296.597071) (xy 340.335828 -296.542896) (xy 340.335824 -296.488158)
			(xy 340.343649 -296.433982) (xy 340.359141 -296.381482) (xy 340.381982 -296.331737) (xy 340.411703 -296.28577)
			(xy 340.429342 -296.264838) (xy 340.435438 -296.257726) (xy 340.441788 -296.240708) (xy 340.441788 -296.155364)
			(xy 340.435438 -296.138346) (xy 340.429342 -296.131234) (xy 340.411736 -296.110273) (xy 340.382009 -296.064311)
			(xy 340.35916 -296.014569) (xy 340.34366 -295.962071) (xy 340.335828 -295.907896) (xy 340.335824 -295.853158)
			(xy 340.343649 -295.798982) (xy 340.359141 -295.746482) (xy 340.381982 -295.696737) (xy 340.411703 -295.65077)
			(xy 340.429342 -295.629838) (xy 340.435438 -295.622726) (xy 340.441788 -295.605708) (xy 340.441788 -295.520364)
			(xy 340.435438 -295.503346) (xy 340.429342 -295.496234) (xy 340.411712 -295.475295) (xy 340.381997 -295.429324)
			(xy 340.359159 -295.379579) (xy 340.343666 -295.32708) (xy 340.335836 -295.272905) (xy 340.335362 -295.245536)
			(xy 340.335889 -295.218285) (xy 340.34364 -295.164338) (xy 340.35899 -295.112043) (xy 340.381626 -295.062465)
			(xy 340.411088 -295.016614) (xy 340.446775 -294.975421) (xy 340.487961 -294.939727) (xy 340.533807 -294.910258)
			(xy 340.583382 -294.887613) (xy 340.635674 -294.872254) (xy 340.689619 -294.864493) (xy 340.71687 -294.864028)
			(xy 340.74424 -294.864505) (xy 340.798419 -294.872319) (xy 340.850922 -294.887805) (xy 340.900669 -294.910645)
			(xy 340.946636 -294.940367) (xy 340.967568 -294.958008) (xy 340.97468 -294.964104) (xy 340.991698 -294.970454)
			(xy 341.077042 -294.970454) (xy 341.09406 -294.964104) (xy 341.101172 -294.958008) (xy 341.122105 -294.94037)
			(xy 341.168077 -294.910658) (xy 341.217825 -294.887821) (xy 341.270325 -294.87233) (xy 341.324501 -294.864502)
			(xy 341.35187 -294.864028) (xy 341.379124 -294.864483) (xy 341.433077 -294.872237) (xy 341.485377 -294.887591)
			(xy 341.534959 -294.910233) (xy 341.580814 -294.939701) (xy 341.622008 -294.975396) (xy 341.657703 -295.01659)
			(xy 341.68717 -295.062446) (xy 341.709811 -295.112029) (xy 341.725164 -295.164329) (xy 341.732917 -295.218282)
			(xy 341.733378 -295.245536) (xy 341.732938 -295.272907) (xy 341.725115 -295.327088) (xy 341.70962 -295.379591)
			(xy 341.686772 -295.429338) (xy 341.657042 -295.475303) (xy 341.639398 -295.496234) (xy 341.633302 -295.503346)
			(xy 341.626952 -295.520364) (xy 341.626952 -295.605708) (xy 341.633302 -295.622726) (xy 341.639398 -295.629838)
			(xy 341.657073 -295.650743) (xy 341.686794 -295.696716) (xy 341.709636 -295.746467) (xy 341.725128 -295.798973)
			(xy 341.732953 -295.853155) (xy 341.732949 -295.907899) (xy 341.725117 -295.96208) (xy 341.709617 -296.014584)
			(xy 341.686768 -296.064332) (xy 341.65704 -296.110301) (xy 341.639398 -296.131234) (xy 341.633302 -296.138346)
			(xy 341.626952 -296.155364) (xy 341.626952 -296.240708) (xy 341.633302 -296.257726) (xy 341.639398 -296.264838)
			(xy 341.657073 -296.285743) (xy 341.686794 -296.331716) (xy 341.709636 -296.381467) (xy 341.725128 -296.433973)
			(xy 341.732953 -296.488155) (xy 341.732949 -296.542899) (xy 341.725117 -296.59708) (xy 341.709617 -296.649584)
			(xy 341.686768 -296.699332) (xy 341.65704 -296.745301) (xy 341.639398 -296.766234) (xy 341.633302 -296.773346)
			(xy 341.626952 -296.790364) (xy 341.626952 -296.875708) (xy 341.633302 -296.892726) (xy 341.639398 -296.899838)
			(xy 341.657073 -296.920743) (xy 341.686794 -296.966716) (xy 341.709636 -297.016467) (xy 341.725128 -297.068973)
			(xy 341.732953 -297.123155) (xy 341.732949 -297.177899) (xy 341.725117 -297.23208) (xy 341.709617 -297.284584)
			(xy 341.686768 -297.334332) (xy 341.65704 -297.380301) (xy 341.639398 -297.401234) (xy 341.633302 -297.408346)
			(xy 341.626952 -297.425364) (xy 341.626952 -297.510708) (xy 341.633302 -297.527726) (xy 341.639398 -297.534838)
			(xy 341.657073 -297.555743) (xy 341.686794 -297.601716) (xy 341.709636 -297.651467) (xy 341.725128 -297.703973)
			(xy 341.732953 -297.758155) (xy 341.732949 -297.812899) (xy 341.725117 -297.86708) (xy 341.709617 -297.919584)
			(xy 341.686768 -297.969332) (xy 341.65704 -298.015301) (xy 341.639398 -298.036234) (xy 341.633302 -298.043346)
			(xy 341.626952 -298.060364) (xy 341.626952 -298.145708) (xy 341.633302 -298.162726) (xy 341.639398 -298.169838)
			(xy 341.657021 -298.190783) (xy 341.686735 -298.236752) (xy 341.709575 -298.286496) (xy 341.725069 -298.338994)
			(xy 341.732902 -298.393168) (xy 341.733378 -298.420536) (xy 342.763094 -298.420536) (xy 342.763583 -298.393167)
			(xy 342.771395 -298.338989) (xy 342.786879 -298.286486) (xy 342.809716 -298.236739) (xy 342.839435 -298.190771)
			(xy 342.857074 -298.169838) (xy 342.86317 -298.162726) (xy 342.86952 -298.145708) (xy 342.86952 -298.060364)
			(xy 342.86317 -298.043346) (xy 342.857074 -298.036234) (xy 342.839467 -298.015274) (xy 342.809737 -297.969312)
			(xy 342.786886 -297.91957) (xy 342.771385 -297.867072) (xy 342.763552 -297.812897) (xy 342.763548 -297.758158)
			(xy 342.771374 -297.703981) (xy 342.786867 -297.65148) (xy 342.809711 -297.601736) (xy 342.839434 -297.55577)
			(xy 342.857074 -297.534838) (xy 342.86317 -297.527726) (xy 342.86952 -297.510708) (xy 342.86952 -297.425364)
			(xy 342.86317 -297.408346) (xy 342.857074 -297.401234) (xy 342.839467 -297.380274) (xy 342.809737 -297.334312)
			(xy 342.786886 -297.28457) (xy 342.771385 -297.232072) (xy 342.763552 -297.177897) (xy 342.763548 -297.123158)
			(xy 342.771374 -297.068981) (xy 342.786867 -297.01648) (xy 342.809711 -296.966736) (xy 342.839434 -296.92077)
			(xy 342.857074 -296.899838) (xy 342.86317 -296.892726) (xy 342.86952 -296.875708) (xy 342.86952 -296.790364)
			(xy 342.86317 -296.773346) (xy 342.857074 -296.766234) (xy 342.839467 -296.745274) (xy 342.809737 -296.699312)
			(xy 342.786886 -296.64957) (xy 342.771385 -296.597072) (xy 342.763552 -296.542897) (xy 342.763548 -296.488158)
			(xy 342.771374 -296.433981) (xy 342.786867 -296.38148) (xy 342.809711 -296.331736) (xy 342.839434 -296.28577)
			(xy 342.857074 -296.264838) (xy 342.86317 -296.257726) (xy 342.86952 -296.240708) (xy 342.86952 -296.155364)
			(xy 342.86317 -296.138346) (xy 342.857074 -296.131234) (xy 342.839467 -296.110274) (xy 342.809737 -296.064312)
			(xy 342.786886 -296.01457) (xy 342.771385 -295.962072) (xy 342.763552 -295.907897) (xy 342.763548 -295.853158)
			(xy 342.771374 -295.798981) (xy 342.786867 -295.74648) (xy 342.809711 -295.696736) (xy 342.839434 -295.65077)
			(xy 342.857074 -295.629838) (xy 342.86317 -295.622726) (xy 342.86952 -295.605708) (xy 342.86952 -295.520364)
			(xy 342.86317 -295.503346) (xy 342.857074 -295.496234) (xy 342.839433 -295.475303) (xy 342.809723 -295.42933)
			(xy 342.786887 -295.379582) (xy 342.771397 -295.327081) (xy 342.763568 -295.272905) (xy 342.763094 -295.245536)
			(xy 342.763589 -295.218284) (xy 342.771341 -295.164334) (xy 342.786692 -295.112037) (xy 342.809331 -295.062457)
			(xy 342.838795 -295.016603) (xy 342.874486 -294.97541) (xy 342.915676 -294.939716) (xy 342.961527 -294.910247)
			(xy 343.011105 -294.887604) (xy 343.063401 -294.872248) (xy 343.11735 -294.864491) (xy 343.144602 -294.864028)
			(xy 343.171973 -294.864486) (xy 343.226152 -294.872305) (xy 343.278656 -294.887795) (xy 343.328403 -294.910639)
			(xy 343.374369 -294.940366) (xy 343.3953 -294.958008) (xy 343.402412 -294.964104) (xy 343.41943 -294.970454)
			(xy 343.504774 -294.970454) (xy 343.521792 -294.964104) (xy 343.528904 -294.958008) (xy 343.549825 -294.940355)
			(xy 343.595801 -294.910645) (xy 343.645551 -294.887811) (xy 343.698054 -294.872324) (xy 343.752232 -294.8645)
			(xy 343.779602 -294.864028) (xy 343.806857 -294.864454) (xy 343.860811 -294.872212) (xy 343.913111 -294.88757)
			(xy 343.962694 -294.910215) (xy 344.008549 -294.939687) (xy 344.049742 -294.975385) (xy 344.085436 -295.016582)
			(xy 344.114903 -295.062439) (xy 344.137543 -295.112024) (xy 344.152896 -295.164326) (xy 344.160649 -295.218281)
			(xy 344.16111 -295.245536) (xy 344.160663 -295.272907) (xy 344.15284 -295.327087) (xy 344.137346 -295.37959)
			(xy 344.114501 -295.429336) (xy 344.084773 -295.475303) (xy 344.06713 -295.496234) (xy 344.061034 -295.503346)
			(xy 344.054684 -295.520364) (xy 344.054684 -295.605708) (xy 344.061034 -295.622726) (xy 344.06713 -295.629838)
			(xy 344.084808 -295.650741) (xy 344.114534 -295.696713) (xy 344.13738 -295.746464) (xy 344.152876 -295.798971)
			(xy 344.160702 -295.853154) (xy 344.160698 -295.9079) (xy 344.152864 -295.962082) (xy 344.137361 -296.014587)
			(xy 344.114508 -296.064334) (xy 344.084775 -296.110302) (xy 344.06713 -296.131234) (xy 344.061034 -296.138346)
			(xy 344.054684 -296.155364) (xy 344.054684 -296.240708) (xy 344.061034 -296.257726) (xy 344.06713 -296.264838)
			(xy 344.084808 -296.285741) (xy 344.114534 -296.331713) (xy 344.13738 -296.381464) (xy 344.152876 -296.433971)
			(xy 344.160702 -296.488154) (xy 344.160698 -296.5429) (xy 344.152864 -296.597082) (xy 344.137361 -296.649587)
			(xy 344.114508 -296.699334) (xy 344.084775 -296.745302) (xy 344.06713 -296.766234) (xy 344.061034 -296.773346)
			(xy 344.054684 -296.790364) (xy 344.054684 -296.875708) (xy 344.061034 -296.892726) (xy 344.06713 -296.899838)
			(xy 344.084808 -296.920741) (xy 344.114534 -296.966713) (xy 344.13738 -297.016464) (xy 344.152876 -297.068971)
			(xy 344.160702 -297.123154) (xy 344.160698 -297.1779) (xy 344.152864 -297.232082) (xy 344.137361 -297.284587)
			(xy 344.114508 -297.334334) (xy 344.084775 -297.380302) (xy 344.06713 -297.401234) (xy 344.061034 -297.408346)
			(xy 344.054684 -297.425364) (xy 344.054684 -297.510708) (xy 344.061034 -297.527726) (xy 344.06713 -297.534838)
			(xy 344.084808 -297.555741) (xy 344.114534 -297.601713) (xy 344.13738 -297.651464) (xy 344.152876 -297.703971)
			(xy 344.160702 -297.758154) (xy 344.160698 -297.8129) (xy 344.152864 -297.867082) (xy 344.137361 -297.919587)
			(xy 344.114508 -297.969334) (xy 344.084775 -298.015302) (xy 344.06713 -298.036234) (xy 344.061034 -298.043346)
			(xy 344.054684 -298.060364) (xy 344.054684 -298.145708) (xy 344.061034 -298.162726) (xy 344.06713 -298.169838)
			(xy 344.084758 -298.190779) (xy 344.114471 -298.23675) (xy 344.137308 -298.286495) (xy 344.152802 -298.338994)
			(xy 344.160634 -298.393168) (xy 344.16111 -298.420536) (xy 347.403674 -298.420536) (xy 347.404143 -298.393166)
			(xy 347.411957 -298.338986) (xy 347.427445 -298.286482) (xy 347.450286 -298.236735) (xy 347.480012 -298.190769)
			(xy 347.497654 -298.169838) (xy 347.50375 -298.162726) (xy 347.5101 -298.145708) (xy 347.5101 -298.060364)
			(xy 347.50375 -298.043346) (xy 347.497654 -298.036234) (xy 347.480047 -298.015273) (xy 347.450319 -297.969311)
			(xy 347.42747 -297.91957) (xy 347.41197 -297.867071) (xy 347.404137 -297.812896) (xy 347.404133 -297.758158)
			(xy 347.411958 -297.703982) (xy 347.427451 -297.651481) (xy 347.450293 -297.601737) (xy 347.480015 -297.55577)
			(xy 347.497654 -297.534838) (xy 347.50375 -297.527726) (xy 347.5101 -297.510708) (xy 347.5101 -297.425364)
			(xy 347.50375 -297.408346) (xy 347.497654 -297.401234) (xy 347.480047 -297.380273) (xy 347.450319 -297.334311)
			(xy 347.42747 -297.28457) (xy 347.41197 -297.232071) (xy 347.404137 -297.177896) (xy 347.404133 -297.123158)
			(xy 347.411958 -297.068982) (xy 347.427451 -297.016481) (xy 347.450293 -296.966737) (xy 347.480015 -296.92077)
			(xy 347.497654 -296.899838) (xy 347.50375 -296.892726) (xy 347.5101 -296.875708) (xy 347.5101 -296.790364)
			(xy 347.50375 -296.773346) (xy 347.497654 -296.766234) (xy 347.480047 -296.745273) (xy 347.450319 -296.699311)
			(xy 347.42747 -296.64957) (xy 347.41197 -296.597071) (xy 347.404137 -296.542896) (xy 347.404133 -296.488158)
			(xy 347.411958 -296.433982) (xy 347.427451 -296.381481) (xy 347.450293 -296.331737) (xy 347.480015 -296.28577)
			(xy 347.497654 -296.264838) (xy 347.50375 -296.257726) (xy 347.5101 -296.240708) (xy 347.5101 -296.155364)
			(xy 347.50375 -296.138346) (xy 347.497654 -296.131234) (xy 347.480047 -296.110273) (xy 347.450319 -296.064311)
			(xy 347.42747 -296.01457) (xy 347.41197 -295.962071) (xy 347.404137 -295.907896) (xy 347.404133 -295.853158)
			(xy 347.411958 -295.798982) (xy 347.427451 -295.746481) (xy 347.450293 -295.696737) (xy 347.480015 -295.65077)
			(xy 347.497654 -295.629838) (xy 347.50375 -295.622726) (xy 347.5101 -295.605708) (xy 347.5101 -295.520364)
			(xy 347.50375 -295.503346) (xy 347.497654 -295.496234) (xy 347.480026 -295.475293) (xy 347.45031 -295.429323)
			(xy 347.427472 -295.379578) (xy 347.411978 -295.327079) (xy 347.404148 -295.272905) (xy 347.403674 -295.245536)
			(xy 347.404189 -295.218285) (xy 347.41194 -295.164337) (xy 347.427291 -295.112041) (xy 347.449928 -295.062462)
			(xy 347.47939 -295.01661) (xy 347.515079 -294.975417) (xy 347.556266 -294.939723) (xy 347.602115 -294.910254)
			(xy 347.65169 -294.88761) (xy 347.703984 -294.872252) (xy 347.757931 -294.864493) (xy 347.785182 -294.864028)
			(xy 347.812552 -294.864498) (xy 347.866731 -294.872314) (xy 347.919235 -294.887802) (xy 347.968982 -294.910643)
			(xy 348.014948 -294.940367) (xy 348.03588 -294.958008) (xy 348.042992 -294.964104) (xy 348.06001 -294.970454)
			(xy 348.145354 -294.970454) (xy 348.162372 -294.964104) (xy 348.169484 -294.958008) (xy 348.190412 -294.940364)
			(xy 348.236386 -294.910653) (xy 348.286134 -294.887818) (xy 348.338636 -294.872328) (xy 348.392813 -294.864501)
			(xy 348.420182 -294.864028) (xy 348.447436 -294.864472) (xy 348.50139 -294.872228) (xy 348.55369 -294.887583)
			(xy 348.603272 -294.910226) (xy 348.649127 -294.939696) (xy 348.690321 -294.975392) (xy 348.726015 -295.016587)
			(xy 348.755482 -295.062443) (xy 348.778123 -295.112027) (xy 348.793476 -295.164328) (xy 348.801229 -295.218282)
			(xy 348.80169 -295.245536) (xy 348.801247 -295.272907) (xy 348.793424 -295.327087) (xy 348.77793 -295.379591)
			(xy 348.755083 -295.429337) (xy 348.725353 -295.475303) (xy 348.70771 -295.496234) (xy 348.701614 -295.503346)
			(xy 348.695264 -295.520364) (xy 348.695264 -295.605708) (xy 348.701614 -295.622726) (xy 348.70771 -295.629838)
			(xy 348.725384 -295.650743) (xy 348.755105 -295.696716) (xy 348.777946 -295.746468) (xy 348.793438 -295.798974)
			(xy 348.801262 -295.853155) (xy 348.801258 -295.907899) (xy 348.793426 -295.96208) (xy 348.777927 -296.014583)
			(xy 348.755079 -296.064331) (xy 348.725352 -296.1103) (xy 348.70771 -296.131234) (xy 348.701614 -296.138346)
			(xy 348.695264 -296.155364) (xy 348.695264 -296.240708) (xy 348.701614 -296.257726) (xy 348.70771 -296.264838)
			(xy 348.725384 -296.285743) (xy 348.755105 -296.331716) (xy 348.777946 -296.381468) (xy 348.793438 -296.433974)
			(xy 348.801262 -296.488155) (xy 348.801258 -296.542899) (xy 348.793426 -296.59708) (xy 348.777927 -296.649583)
			(xy 348.755079 -296.699331) (xy 348.725352 -296.7453) (xy 348.70771 -296.766234) (xy 348.701614 -296.773346)
			(xy 348.695264 -296.790364) (xy 348.695264 -296.875708) (xy 348.701614 -296.892726) (xy 348.70771 -296.899838)
			(xy 348.725384 -296.920743) (xy 348.755105 -296.966716) (xy 348.777946 -297.016468) (xy 348.793438 -297.068974)
			(xy 348.801262 -297.123155) (xy 348.801258 -297.177899) (xy 348.793426 -297.23208) (xy 348.777927 -297.284583)
			(xy 348.755079 -297.334331) (xy 348.725352 -297.3803) (xy 348.70771 -297.401234) (xy 348.701614 -297.408346)
			(xy 348.695264 -297.425364) (xy 348.695264 -297.510708) (xy 348.701614 -297.527726) (xy 348.70771 -297.534838)
			(xy 348.725384 -297.555743) (xy 348.755105 -297.601716) (xy 348.777946 -297.651468) (xy 348.793438 -297.703974)
			(xy 348.801262 -297.758155) (xy 348.801258 -297.812899) (xy 348.793426 -297.86708) (xy 348.777927 -297.919583)
			(xy 348.755079 -297.969331) (xy 348.725352 -298.0153) (xy 348.70771 -298.036234) (xy 348.701614 -298.043346)
			(xy 348.695264 -298.060364) (xy 348.695264 -298.145708) (xy 348.701614 -298.162726) (xy 348.70771 -298.169838)
			(xy 348.725335 -298.190781) (xy 348.755049 -298.236751) (xy 348.777887 -298.286496) (xy 348.793382 -298.338994)
			(xy 348.801214 -298.393168) (xy 348.80169 -298.420536) (xy 352.35388 -298.420536) (xy 352.354348 -298.393166)
			(xy 352.362162 -298.338986) (xy 352.37765 -298.286482) (xy 352.400492 -298.236735) (xy 352.430218 -298.190769)
			(xy 352.44786 -298.169838) (xy 352.453956 -298.162726) (xy 352.460306 -298.145708) (xy 352.460306 -298.060364)
			(xy 352.453956 -298.043346) (xy 352.44786 -298.036234) (xy 352.430253 -298.015273) (xy 352.400524 -297.969311)
			(xy 352.377675 -297.91957) (xy 352.362174 -297.867072) (xy 352.354342 -297.812896) (xy 352.354338 -297.758158)
			(xy 352.362163 -297.703981) (xy 352.377656 -297.651481) (xy 352.400498 -297.601736) (xy 352.43022 -297.55577)
			(xy 352.44786 -297.534838) (xy 352.453956 -297.527726) (xy 352.460306 -297.510708) (xy 352.460306 -297.425364)
			(xy 352.453956 -297.408346) (xy 352.44786 -297.401234) (xy 352.430253 -297.380273) (xy 352.400524 -297.334311)
			(xy 352.377675 -297.28457) (xy 352.362174 -297.232072) (xy 352.354342 -297.177896) (xy 352.354338 -297.123158)
			(xy 352.362163 -297.068981) (xy 352.377656 -297.016481) (xy 352.400498 -296.966736) (xy 352.43022 -296.92077)
			(xy 352.44786 -296.899838) (xy 352.453956 -296.892726) (xy 352.460306 -296.875708) (xy 352.460306 -296.790364)
			(xy 352.453956 -296.773346) (xy 352.44786 -296.766234) (xy 352.430253 -296.745273) (xy 352.400524 -296.699311)
			(xy 352.377675 -296.64957) (xy 352.362174 -296.597072) (xy 352.354342 -296.542896) (xy 352.354338 -296.488158)
			(xy 352.362163 -296.433981) (xy 352.377656 -296.381481) (xy 352.400498 -296.331736) (xy 352.43022 -296.28577)
			(xy 352.44786 -296.264838) (xy 352.453956 -296.257726) (xy 352.460306 -296.240708) (xy 352.460306 -296.155364)
			(xy 352.453956 -296.138346) (xy 352.44786 -296.131234) (xy 352.430253 -296.110273) (xy 352.400524 -296.064311)
			(xy 352.377675 -296.01457) (xy 352.362174 -295.962072) (xy 352.354342 -295.907896) (xy 352.354338 -295.853158)
			(xy 352.362163 -295.798981) (xy 352.377656 -295.746481) (xy 352.400498 -295.696736) (xy 352.43022 -295.65077)
			(xy 352.44786 -295.629838) (xy 352.453956 -295.622726) (xy 352.460306 -295.605708) (xy 352.460306 -295.520364)
			(xy 352.453956 -295.503346) (xy 352.44786 -295.496234) (xy 352.430217 -295.475305) (xy 352.400507 -295.429331)
			(xy 352.377672 -295.379583) (xy 352.362182 -295.327081) (xy 352.354354 -295.272905) (xy 352.35388 -295.245536)
			(xy 352.354389 -295.218285) (xy 352.362141 -295.164336) (xy 352.377491 -295.11204) (xy 352.400129 -295.06246)
			(xy 352.429592 -295.016608) (xy 352.465281 -294.975415) (xy 352.506469 -294.939721) (xy 352.552318 -294.910252)
			(xy 352.601895 -294.887608) (xy 352.654189 -294.872251) (xy 352.708137 -294.864492) (xy 352.735388 -294.864028)
			(xy 352.762758 -294.864494) (xy 352.816938 -294.872311) (xy 352.869441 -294.8878) (xy 352.919188 -294.910642)
			(xy 352.965155 -294.940366) (xy 352.986086 -294.958008) (xy 352.993198 -294.964104) (xy 353.010216 -294.970454)
			(xy 353.09556 -294.970454) (xy 353.112578 -294.964104) (xy 353.11969 -294.958008) (xy 353.140616 -294.940361)
			(xy 353.18659 -294.91065) (xy 353.236339 -294.887816) (xy 353.288841 -294.872327) (xy 353.343018 -294.864501)
			(xy 353.370388 -294.864028) (xy 353.397642 -294.864467) (xy 353.451596 -294.872223) (xy 353.503896 -294.887579)
			(xy 353.553479 -294.910223) (xy 353.599334 -294.939693) (xy 353.640528 -294.975389) (xy 353.676221 -295.016585)
			(xy 353.705689 -295.062442) (xy 353.728329 -295.112026) (xy 353.743682 -295.164328) (xy 353.751435 -295.218282)
			(xy 353.751896 -295.245536) (xy 353.751452 -295.272907) (xy 353.743629 -295.327087) (xy 353.728135 -295.379591)
			(xy 353.705288 -295.429337) (xy 353.675559 -295.475303) (xy 353.657916 -295.496234) (xy 353.65182 -295.503346)
			(xy 353.64547 -295.520364) (xy 353.64547 -295.605708) (xy 353.65182 -295.622726) (xy 353.657916 -295.629838)
			(xy 353.67559 -295.650743) (xy 353.70531 -295.696717) (xy 353.728151 -295.746468) (xy 353.743643 -295.798974)
			(xy 353.751467 -295.853155) (xy 353.751463 -295.907899) (xy 353.743631 -295.962079) (xy 353.728132 -296.014583)
			(xy 353.705284 -296.064331) (xy 353.675557 -296.1103) (xy 353.657916 -296.131234) (xy 353.65182 -296.138346)
			(xy 353.64547 -296.155364) (xy 353.64547 -296.240708) (xy 353.65182 -296.257726) (xy 353.657916 -296.264838)
			(xy 353.67559 -296.285743) (xy 353.70531 -296.331717) (xy 353.728151 -296.381468) (xy 353.743643 -296.433974)
			(xy 353.751467 -296.488155) (xy 353.751463 -296.542899) (xy 353.743631 -296.597079) (xy 353.728132 -296.649583)
			(xy 353.705284 -296.699331) (xy 353.675557 -296.7453) (xy 353.657916 -296.766234) (xy 353.65182 -296.773346)
			(xy 353.64547 -296.790364) (xy 353.64547 -296.875708) (xy 353.65182 -296.892726) (xy 353.657916 -296.899838)
			(xy 353.67559 -296.920743) (xy 353.70531 -296.966717) (xy 353.728151 -297.016468) (xy 353.743643 -297.068974)
			(xy 353.751467 -297.123155) (xy 353.751463 -297.177899) (xy 353.743631 -297.232079) (xy 353.728132 -297.284583)
			(xy 353.705284 -297.334331) (xy 353.675557 -297.3803) (xy 353.657916 -297.401234) (xy 353.65182 -297.408346)
			(xy 353.64547 -297.425364) (xy 353.64547 -297.510708) (xy 353.65182 -297.527726) (xy 353.657916 -297.534838)
			(xy 353.67559 -297.555743) (xy 353.70531 -297.601717) (xy 353.728151 -297.651468) (xy 353.743643 -297.703974)
			(xy 353.751467 -297.758155) (xy 353.751463 -297.812899) (xy 353.743631 -297.867079) (xy 353.728132 -297.919583)
			(xy 353.705284 -297.969331) (xy 353.675557 -298.0153) (xy 353.657916 -298.036234) (xy 353.65182 -298.043346)
			(xy 353.64547 -298.060364) (xy 353.64547 -298.145708) (xy 353.65182 -298.162726) (xy 353.657916 -298.169838)
			(xy 353.675542 -298.190781) (xy 353.705255 -298.236751) (xy 353.728093 -298.286496) (xy 353.743588 -298.338994)
			(xy 353.75142 -298.393168) (xy 353.751896 -298.420536) (xy 356.99446 -298.420536) (xy 356.994933 -298.393166)
			(xy 357.002747 -298.338986) (xy 357.018233 -298.286483) (xy 357.041074 -298.236736) (xy 357.070798 -298.190769)
			(xy 357.08844 -298.169838) (xy 357.094536 -298.162726) (xy 357.100886 -298.145708) (xy 357.100886 -298.060364)
			(xy 357.094536 -298.043346) (xy 357.08844 -298.036234) (xy 357.070834 -298.015273) (xy 357.041107 -297.96931)
			(xy 357.018259 -297.919569) (xy 357.002759 -297.867071) (xy 356.994927 -297.812896) (xy 356.994923 -297.758158)
			(xy 357.002747 -297.703982) (xy 357.018239 -297.651482) (xy 357.041081 -297.601737) (xy 357.070801 -297.55577)
			(xy 357.08844 -297.534838) (xy 357.094536 -297.527726) (xy 357.100886 -297.510708) (xy 357.100886 -297.425364)
			(xy 357.094536 -297.408346) (xy 357.08844 -297.401234) (xy 357.070834 -297.380273) (xy 357.041107 -297.33431)
			(xy 357.018259 -297.284569) (xy 357.002759 -297.232071) (xy 356.994927 -297.177896) (xy 356.994923 -297.123158)
			(xy 357.002747 -297.068982) (xy 357.018239 -297.016482) (xy 357.041081 -296.966737) (xy 357.070801 -296.92077)
			(xy 357.08844 -296.899838) (xy 357.094536 -296.892726) (xy 357.100886 -296.875708) (xy 357.100886 -296.790364)
			(xy 357.094536 -296.773346) (xy 357.08844 -296.766234) (xy 357.070834 -296.745273) (xy 357.041107 -296.69931)
			(xy 357.018259 -296.649569) (xy 357.002759 -296.597071) (xy 356.994927 -296.542896) (xy 356.994923 -296.488158)
			(xy 357.002747 -296.433982) (xy 357.018239 -296.381482) (xy 357.041081 -296.331737) (xy 357.070801 -296.28577)
			(xy 357.08844 -296.264838) (xy 357.094536 -296.257726) (xy 357.100886 -296.240708) (xy 357.100886 -296.155364)
			(xy 357.094536 -296.138346) (xy 357.08844 -296.131234) (xy 357.070834 -296.110273) (xy 357.041107 -296.06431)
			(xy 357.018259 -296.014569) (xy 357.002759 -295.962071) (xy 356.994927 -295.907896) (xy 356.994923 -295.853158)
			(xy 357.002747 -295.798982) (xy 357.018239 -295.746482) (xy 357.041081 -295.696737) (xy 357.070801 -295.65077)
			(xy 357.08844 -295.629838) (xy 357.094536 -295.622726) (xy 357.100886 -295.605708) (xy 357.100886 -295.520364)
			(xy 357.094536 -295.503346) (xy 357.08844 -295.496234) (xy 357.07081 -295.475295) (xy 357.041095 -295.429325)
			(xy 357.018257 -295.379579) (xy 357.002764 -295.32708) (xy 356.994934 -295.272905) (xy 356.99446 -295.245536)
			(xy 356.994989 -295.218285) (xy 357.00274 -295.164339) (xy 357.01809 -295.112044) (xy 357.040726 -295.062466)
			(xy 357.070187 -295.016614) (xy 357.105874 -294.975422) (xy 357.14706 -294.939728) (xy 357.192906 -294.910258)
			(xy 357.24248 -294.887614) (xy 357.294772 -294.872254) (xy 357.348718 -294.864494) (xy 357.375968 -294.864028)
			(xy 357.403338 -294.864506) (xy 357.457517 -294.87232) (xy 357.51002 -294.887806) (xy 357.559767 -294.910645)
			(xy 357.605734 -294.940368) (xy 357.626666 -294.958008) (xy 357.633778 -294.964104) (xy 357.650796 -294.970454)
			(xy 357.73614 -294.970454) (xy 357.753158 -294.964104) (xy 357.76027 -294.958008) (xy 357.781204 -294.940371)
			(xy 357.827176 -294.910658) (xy 357.876923 -294.887822) (xy 357.929423 -294.87233) (xy 357.983599 -294.864502)
			(xy 358.010968 -294.864028) (xy 358.038222 -294.864485) (xy 358.092175 -294.872239) (xy 358.144475 -294.887593)
			(xy 358.194057 -294.910234) (xy 358.239912 -294.939702) (xy 358.281106 -294.975397) (xy 358.3168 -295.016591)
			(xy 358.346268 -295.062446) (xy 358.368909 -295.112029) (xy 358.384262 -295.164329) (xy 358.392015 -295.218282)
			(xy 358.392476 -295.245536) (xy 358.392037 -295.272907) (xy 358.384213 -295.327088) (xy 358.368718 -295.379591)
			(xy 358.345871 -295.429338) (xy 358.31614 -295.475303) (xy 358.298496 -295.496234) (xy 358.2924 -295.503346)
			(xy 358.28605 -295.520364) (xy 358.28605 -295.605708) (xy 358.2924 -295.622726) (xy 358.298496 -295.629838)
			(xy 358.316171 -295.650743) (xy 358.345893 -295.696716) (xy 358.368734 -295.746467) (xy 358.384227 -295.798973)
			(xy 358.392052 -295.853155) (xy 358.392048 -295.907899) (xy 358.384215 -295.96208) (xy 358.368715 -296.014584)
			(xy 358.345866 -296.064332) (xy 358.316138 -296.110301) (xy 358.298496 -296.131234) (xy 358.2924 -296.138346)
			(xy 358.28605 -296.155364) (xy 358.28605 -296.240708) (xy 358.2924 -296.257726) (xy 358.298496 -296.264838)
			(xy 358.316171 -296.285743) (xy 358.345893 -296.331716) (xy 358.368734 -296.381467) (xy 358.384227 -296.433973)
			(xy 358.392052 -296.488155) (xy 358.392048 -296.542899) (xy 358.384215 -296.59708) (xy 358.368715 -296.649584)
			(xy 358.345866 -296.699332) (xy 358.316138 -296.745301) (xy 358.298496 -296.766234) (xy 358.2924 -296.773346)
			(xy 358.28605 -296.790364) (xy 358.28605 -296.875708) (xy 358.2924 -296.892726) (xy 358.298496 -296.899838)
			(xy 358.316171 -296.920743) (xy 358.345893 -296.966716) (xy 358.368734 -297.016467) (xy 358.384227 -297.068973)
			(xy 358.392052 -297.123155) (xy 358.392048 -297.177899) (xy 358.384215 -297.23208) (xy 358.368715 -297.284584)
			(xy 358.345866 -297.334332) (xy 358.316138 -297.380301) (xy 358.298496 -297.401234) (xy 358.2924 -297.408346)
			(xy 358.28605 -297.425364) (xy 358.28605 -297.510708) (xy 358.2924 -297.527726) (xy 358.298496 -297.534838)
			(xy 358.316171 -297.555743) (xy 358.345893 -297.601716) (xy 358.368734 -297.651467) (xy 358.384227 -297.703973)
			(xy 358.392052 -297.758155) (xy 358.392048 -297.812899) (xy 358.384215 -297.86708) (xy 358.368715 -297.919584)
			(xy 358.345866 -297.969332) (xy 358.316138 -298.015301) (xy 358.298496 -298.036234) (xy 358.2924 -298.043346)
			(xy 358.28605 -298.060364) (xy 358.28605 -298.145708) (xy 358.2924 -298.162726) (xy 358.298496 -298.169838)
			(xy 358.316119 -298.190783) (xy 358.345833 -298.236752) (xy 358.368672 -298.286496) (xy 358.384167 -298.338994)
			(xy 358.392 -298.393168) (xy 358.392476 -298.420536) (xy 359.422192 -298.420536) (xy 359.422681 -298.393167)
			(xy 359.430494 -298.338989) (xy 359.445977 -298.286486) (xy 359.468814 -298.236739) (xy 359.498533 -298.190771)
			(xy 359.516172 -298.169838) (xy 359.522268 -298.162726) (xy 359.528618 -298.145708) (xy 359.528618 -298.060364)
			(xy 359.522268 -298.043346) (xy 359.516172 -298.036234) (xy 359.498565 -298.015274) (xy 359.468835 -297.969312)
			(xy 359.445985 -297.91957) (xy 359.430484 -297.867072) (xy 359.422651 -297.812897) (xy 359.422647 -297.758158)
			(xy 359.430472 -297.703981) (xy 359.445966 -297.651481) (xy 359.468809 -297.601736) (xy 359.498532 -297.55577)
			(xy 359.516172 -297.534838) (xy 359.522268 -297.527726) (xy 359.528618 -297.510708) (xy 359.528618 -297.425364)
			(xy 359.522268 -297.408346) (xy 359.516172 -297.401234) (xy 359.498565 -297.380274) (xy 359.468835 -297.334312)
			(xy 359.445985 -297.28457) (xy 359.430484 -297.232072) (xy 359.422651 -297.177897) (xy 359.422647 -297.123158)
			(xy 359.430472 -297.068981) (xy 359.445966 -297.016481) (xy 359.468809 -296.966736) (xy 359.498532 -296.92077)
			(xy 359.516172 -296.899838) (xy 359.522268 -296.892726) (xy 359.528618 -296.875708) (xy 359.528618 -296.790364)
			(xy 359.522268 -296.773346) (xy 359.516172 -296.766234) (xy 359.498565 -296.745274) (xy 359.468835 -296.699312)
			(xy 359.445985 -296.64957) (xy 359.430484 -296.597072) (xy 359.422651 -296.542897) (xy 359.422647 -296.488158)
			(xy 359.430472 -296.433981) (xy 359.445966 -296.381481) (xy 359.468809 -296.331736) (xy 359.498532 -296.28577)
			(xy 359.516172 -296.264838) (xy 359.522268 -296.257726) (xy 359.528618 -296.240708) (xy 359.528618 -296.155364)
			(xy 359.522268 -296.138346) (xy 359.516172 -296.131234) (xy 359.498565 -296.110274) (xy 359.468835 -296.064312)
			(xy 359.445985 -296.01457) (xy 359.430484 -295.962072) (xy 359.422651 -295.907897) (xy 359.422647 -295.853158)
			(xy 359.430472 -295.798981) (xy 359.445966 -295.746481) (xy 359.468809 -295.696736) (xy 359.498532 -295.65077)
			(xy 359.516172 -295.629838) (xy 359.522268 -295.622726) (xy 359.528618 -295.605708) (xy 359.528618 -295.520364)
			(xy 359.522268 -295.503346) (xy 359.516172 -295.496234) (xy 359.498531 -295.475304) (xy 359.46882 -295.42933)
			(xy 359.445985 -295.379582) (xy 359.430495 -295.327081) (xy 359.422666 -295.272905) (xy 359.422192 -295.245536)
			(xy 359.422689 -295.218284) (xy 359.430441 -295.164334) (xy 359.445792 -295.112037) (xy 359.468431 -295.062457)
			(xy 359.497895 -295.016604) (xy 359.533585 -294.975411) (xy 359.574775 -294.939716) (xy 359.620625 -294.910248)
			(xy 359.670203 -294.887605) (xy 359.722499 -294.872249) (xy 359.776448 -294.864491) (xy 359.8037 -294.864028)
			(xy 359.831071 -294.864487) (xy 359.88525 -294.872306) (xy 359.937754 -294.887796) (xy 359.9875 -294.910639)
			(xy 360.033467 -294.940366) (xy 360.054398 -294.958008) (xy 360.06151 -294.964104) (xy 360.078528 -294.970454)
			(xy 360.163872 -294.970454) (xy 360.18089 -294.964104) (xy 360.188002 -294.958008) (xy 360.208924 -294.940356)
			(xy 360.254899 -294.910646) (xy 360.304649 -294.887812) (xy 360.357152 -294.872324) (xy 360.41133 -294.8645)
			(xy 360.4387 -294.864028) (xy 360.465954 -294.864455) (xy 360.519909 -294.872213) (xy 360.572209 -294.887571)
			(xy 360.621792 -294.910216) (xy 360.667647 -294.939688) (xy 360.70884 -294.975385) (xy 360.744534 -295.016582)
			(xy 360.774001 -295.06244) (xy 360.796641 -295.112024) (xy 360.811994 -295.164327) (xy 360.819747 -295.218281)
			(xy 360.820208 -295.245536) (xy 360.819761 -295.272907) (xy 360.811938 -295.327087) (xy 360.796445 -295.37959)
			(xy 360.773599 -295.429336) (xy 360.743871 -295.475303) (xy 360.726228 -295.496234) (xy 360.720132 -295.503346)
			(xy 360.713782 -295.520364) (xy 360.713782 -295.605708) (xy 360.720132 -295.622726) (xy 360.726228 -295.629838)
			(xy 360.743906 -295.650741) (xy 360.773633 -295.696713) (xy 360.796479 -295.746464) (xy 360.811974 -295.798971)
			(xy 360.8198 -295.853154) (xy 360.819796 -295.9079) (xy 360.811962 -295.962082) (xy 360.79646 -296.014587)
			(xy 360.773606 -296.064335) (xy 360.743873 -296.110302) (xy 360.726228 -296.131234) (xy 360.720132 -296.138346)
			(xy 360.713782 -296.155364) (xy 360.713782 -296.240708) (xy 360.720132 -296.257726) (xy 360.726228 -296.264838)
			(xy 360.743906 -296.285741) (xy 360.773633 -296.331713) (xy 360.796479 -296.381464) (xy 360.811974 -296.433971)
			(xy 360.8198 -296.488154) (xy 360.819796 -296.5429) (xy 360.811962 -296.597082) (xy 360.79646 -296.649587)
			(xy 360.773606 -296.699335) (xy 360.743873 -296.745302) (xy 360.726228 -296.766234) (xy 360.720132 -296.773346)
			(xy 360.713782 -296.790364) (xy 360.713782 -296.875708) (xy 360.720132 -296.892726) (xy 360.726228 -296.899838)
			(xy 360.743906 -296.920741) (xy 360.773633 -296.966713) (xy 360.796479 -297.016464) (xy 360.811974 -297.068971)
			(xy 360.8198 -297.123154) (xy 360.819796 -297.1779) (xy 360.811962 -297.232082) (xy 360.79646 -297.284587)
			(xy 360.773606 -297.334335) (xy 360.743873 -297.380302) (xy 360.726228 -297.401234) (xy 360.720132 -297.408346)
			(xy 360.713782 -297.425364) (xy 360.713782 -297.510708) (xy 360.720132 -297.527726) (xy 360.726228 -297.534838)
			(xy 360.743906 -297.555741) (xy 360.773633 -297.601713) (xy 360.796479 -297.651464) (xy 360.811974 -297.703971)
			(xy 360.8198 -297.758154) (xy 360.819796 -297.8129) (xy 360.811962 -297.867082) (xy 360.79646 -297.919587)
			(xy 360.773606 -297.969335) (xy 360.743873 -298.015302) (xy 360.726228 -298.036234) (xy 360.720132 -298.043346)
			(xy 360.713782 -298.060364) (xy 360.713782 -298.145708) (xy 360.720132 -298.162726) (xy 360.726228 -298.169838)
			(xy 360.743856 -298.190779) (xy 360.773568 -298.23675) (xy 360.796406 -298.286495) (xy 360.8119 -298.338994)
			(xy 360.819732 -298.393168) (xy 360.820208 -298.420536) (xy 364.062772 -298.420536) (xy 364.063242 -298.393166)
			(xy 364.071056 -298.338986) (xy 364.086543 -298.286482) (xy 364.109385 -298.236735) (xy 364.13911 -298.190769)
			(xy 364.156752 -298.169838) (xy 364.162848 -298.162726) (xy 364.169198 -298.145708) (xy 364.169198 -298.060364)
			(xy 364.162848 -298.043346) (xy 364.156752 -298.036234) (xy 364.139146 -298.015273) (xy 364.109417 -297.969311)
			(xy 364.086568 -297.919569) (xy 364.071068 -297.867071) (xy 364.063236 -297.812896) (xy 364.063232 -297.758158)
			(xy 364.071057 -297.703982) (xy 364.086549 -297.651481) (xy 364.109391 -297.601737) (xy 364.139113 -297.55577)
			(xy 364.156752 -297.534838) (xy 364.162848 -297.527726) (xy 364.169198 -297.510708) (xy 364.169198 -297.425364)
			(xy 364.162848 -297.408346) (xy 364.156752 -297.401234) (xy 364.139146 -297.380273) (xy 364.109417 -297.334311)
			(xy 364.086568 -297.284569) (xy 364.071068 -297.232071) (xy 364.063236 -297.177896) (xy 364.063232 -297.123158)
			(xy 364.071057 -297.068982) (xy 364.086549 -297.016481) (xy 364.109391 -296.966737) (xy 364.139113 -296.92077)
			(xy 364.156752 -296.899838) (xy 364.162848 -296.892726) (xy 364.169198 -296.875708) (xy 364.169198 -296.790364)
			(xy 364.162848 -296.773346) (xy 364.156752 -296.766234) (xy 364.139146 -296.745273) (xy 364.109417 -296.699311)
			(xy 364.086568 -296.649569) (xy 364.071068 -296.597071) (xy 364.063236 -296.542896) (xy 364.063232 -296.488158)
			(xy 364.071057 -296.433982) (xy 364.086549 -296.381481) (xy 364.109391 -296.331737) (xy 364.139113 -296.28577)
			(xy 364.156752 -296.264838) (xy 364.162848 -296.257726) (xy 364.169198 -296.240708) (xy 364.169198 -296.155364)
			(xy 364.162848 -296.138346) (xy 364.156752 -296.131234) (xy 364.139146 -296.110273) (xy 364.109417 -296.064311)
			(xy 364.086568 -296.014569) (xy 364.071068 -295.962071) (xy 364.063236 -295.907896) (xy 364.063232 -295.853158)
			(xy 364.071057 -295.798982) (xy 364.086549 -295.746481) (xy 364.109391 -295.696737) (xy 364.139113 -295.65077)
			(xy 364.156752 -295.629838) (xy 364.162848 -295.622726) (xy 364.169198 -295.605708) (xy 364.169198 -295.520364)
			(xy 364.162848 -295.503346) (xy 364.156752 -295.496234) (xy 364.139123 -295.475293) (xy 364.109408 -295.429324)
			(xy 364.086569 -295.379578) (xy 364.071076 -295.327079) (xy 364.063246 -295.272905) (xy 364.062772 -295.245536)
			(xy 364.063289 -295.218285) (xy 364.07104 -295.164337) (xy 364.086391 -295.112041) (xy 364.109028 -295.062463)
			(xy 364.13849 -295.01661) (xy 364.174178 -294.975418) (xy 364.215365 -294.939724) (xy 364.261213 -294.910254)
			(xy 364.310789 -294.88761) (xy 364.363082 -294.872252) (xy 364.417029 -294.864493) (xy 364.44428 -294.864028)
			(xy 364.47165 -294.864499) (xy 364.525829 -294.872315) (xy 364.578333 -294.887802) (xy 364.62808 -294.910643)
			(xy 364.674046 -294.940367) (xy 364.694978 -294.958008) (xy 364.70209 -294.964104) (xy 364.719108 -294.970454)
			(xy 364.804452 -294.970454) (xy 364.82147 -294.964104) (xy 364.828582 -294.958008) (xy 364.849511 -294.940365)
			(xy 364.895485 -294.910654) (xy 364.945233 -294.887818) (xy 364.997734 -294.872328) (xy 365.051911 -294.864501)
			(xy 365.07928 -294.864028) (xy 365.106534 -294.864474) (xy 365.160487 -294.872229) (xy 365.212788 -294.887585)
			(xy 365.26237 -294.910227) (xy 365.308225 -294.939697) (xy 365.349419 -294.975392) (xy 365.385113 -295.016588)
			(xy 365.41458 -295.062444) (xy 365.437221 -295.112027) (xy 365.452574 -295.164328) (xy 365.460327 -295.218282)
			(xy 365.460788 -295.245536) (xy 365.460346 -295.272907) (xy 365.452523 -295.327087) (xy 365.437028 -295.379591)
			(xy 365.414181 -295.429337) (xy 365.384452 -295.475303) (xy 365.366808 -295.496234) (xy 365.360712 -295.503346)
			(xy 365.354362 -295.520364) (xy 365.354362 -295.605708) (xy 365.360712 -295.622726) (xy 365.366808 -295.629838)
			(xy 365.384482 -295.650743) (xy 365.414203 -295.696716) (xy 365.437044 -295.746467) (xy 365.452536 -295.798973)
			(xy 365.460361 -295.853155) (xy 365.460357 -295.907899) (xy 365.452525 -295.96208) (xy 365.437025 -296.014583)
			(xy 365.414177 -296.064331) (xy 365.38445 -296.110301) (xy 365.366808 -296.131234) (xy 365.360712 -296.138346)
			(xy 365.354362 -296.155364) (xy 365.354362 -296.240708) (xy 365.360712 -296.257726) (xy 365.366808 -296.264838)
			(xy 365.384482 -296.285743) (xy 365.414203 -296.331716) (xy 365.437044 -296.381467) (xy 365.452536 -296.433973)
			(xy 365.460361 -296.488155) (xy 365.460357 -296.542899) (xy 365.452525 -296.59708) (xy 365.437025 -296.649583)
			(xy 365.414177 -296.699331) (xy 365.38445 -296.745301) (xy 365.366808 -296.766234) (xy 365.360712 -296.773346)
			(xy 365.354362 -296.790364) (xy 365.354362 -296.875708) (xy 365.360712 -296.892726) (xy 365.366808 -296.899838)
			(xy 365.384482 -296.920743) (xy 365.414203 -296.966716) (xy 365.437044 -297.016467) (xy 365.452536 -297.068973)
			(xy 365.460361 -297.123155) (xy 365.460357 -297.177899) (xy 365.452525 -297.23208) (xy 365.437025 -297.284583)
			(xy 365.414177 -297.334331) (xy 365.38445 -297.380301) (xy 365.366808 -297.401234) (xy 365.360712 -297.408346)
			(xy 365.354362 -297.425364) (xy 365.354362 -297.510708) (xy 365.360712 -297.527726) (xy 365.366808 -297.534838)
			(xy 365.384482 -297.555743) (xy 365.414203 -297.601716) (xy 365.437044 -297.651467) (xy 365.452536 -297.703973)
			(xy 365.460361 -297.758155) (xy 365.460357 -297.812899) (xy 365.452525 -297.86708) (xy 365.437025 -297.919583)
			(xy 365.414177 -297.969331) (xy 365.38445 -298.015301) (xy 365.366808 -298.036234) (xy 365.360712 -298.043346)
			(xy 365.354362 -298.060364) (xy 365.354362 -298.145708) (xy 365.360712 -298.162726) (xy 365.366808 -298.169838)
			(xy 365.384433 -298.190782) (xy 365.414146 -298.236751) (xy 365.436985 -298.286496) (xy 365.45248 -298.338994)
			(xy 365.460312 -298.393168) (xy 365.460788 -298.420536) (xy 365.460356 -298.447789) (xy 365.452594 -298.50174)
			(xy 365.437233 -298.554037) (xy 365.414586 -298.603615) (xy 365.385114 -298.649467) (xy 365.349417 -298.690657)
			(xy 365.308222 -298.726348) (xy 365.262366 -298.755813) (xy 365.212784 -298.778453) (xy 365.160485 -298.793806)
			(xy 365.106533 -298.80156) (xy 365.07928 -298.802044) (xy 365.051909 -298.801603) (xy 364.997728 -298.793781)
			(xy 364.945224 -298.778287) (xy 364.895478 -298.755439) (xy 364.849512 -298.725708) (xy 364.828582 -298.708064)
			(xy 364.82147 -298.701968) (xy 364.804452 -298.695618) (xy 364.719108 -298.695618) (xy 364.70209 -298.701968)
			(xy 364.694978 -298.708064) (xy 364.674023 -298.725674) (xy 364.628057 -298.755392) (xy 364.578315 -298.778234)
			(xy 364.52582 -298.793731) (xy 364.471648 -298.801567) (xy 364.44428 -298.802044) (xy 364.41703 -298.801541)
			(xy 364.363085 -298.793783) (xy 364.310792 -298.778427) (xy 364.261218 -298.755786) (xy 364.215369 -298.726321)
			(xy 364.17418 -298.690631) (xy 364.138489 -298.649444) (xy 364.109022 -298.603597) (xy 364.086379 -298.554023)
			(xy 364.071021 -298.501731) (xy 364.06326 -298.447786) (xy 364.062772 -298.420536) (xy 360.820208 -298.420536)
			(xy 360.819756 -298.447788) (xy 360.811994 -298.501737) (xy 360.796635 -298.554032) (xy 360.773989 -298.60361)
			(xy 360.744519 -298.64946) (xy 360.708824 -298.69065) (xy 360.667631 -298.726341) (xy 360.621778 -298.755807)
			(xy 360.572199 -298.778447) (xy 360.519902 -298.793802) (xy 360.465952 -298.801558) (xy 360.4387 -298.802044)
			(xy 360.411329 -298.801592) (xy 360.357149 -298.793773) (xy 360.304645 -298.778281) (xy 360.254898 -298.755436)
			(xy 360.208933 -298.725707) (xy 360.188002 -298.708064) (xy 360.18089 -298.701968) (xy 360.163872 -298.695618)
			(xy 360.078528 -298.695618) (xy 360.06151 -298.701968) (xy 360.054398 -298.708064) (xy 360.033473 -298.725712)
			(xy 359.987499 -298.755424) (xy 359.93775 -298.778258) (xy 359.885247 -298.793747) (xy 359.83107 -298.801572)
			(xy 359.8037 -298.802044) (xy 359.77645 -298.801522) (xy 359.722506 -298.793767) (xy 359.670214 -298.778413)
			(xy 359.620639 -298.755775) (xy 359.57479 -298.726312) (xy 359.533601 -298.690624) (xy 359.49791 -298.649438)
			(xy 359.468442 -298.603593) (xy 359.445799 -298.55402) (xy 359.430441 -298.501729) (xy 359.42268 -298.447786)
			(xy 359.422192 -298.420536) (xy 358.392476 -298.420536) (xy 358.392056 -298.44779) (xy 358.384293 -298.501741)
			(xy 358.368932 -298.554039) (xy 358.346284 -298.603619) (xy 358.316811 -298.64947) (xy 358.281113 -298.690661)
			(xy 358.239916 -298.726352) (xy 358.194059 -298.755817) (xy 358.144475 -298.778456) (xy 358.092175 -298.793808)
			(xy 358.038222 -298.80156) (xy 358.010968 -298.802044) (xy 357.983596 -298.80161) (xy 357.929415 -298.793787)
			(xy 357.876911 -298.778291) (xy 357.827165 -298.755442) (xy 357.7812 -298.725709) (xy 357.76027 -298.708064)
			(xy 357.753158 -298.701968) (xy 357.73614 -298.695618) (xy 357.650796 -298.695618) (xy 357.633778 -298.701968)
			(xy 357.626666 -298.708064) (xy 357.605715 -298.72568) (xy 357.559748 -298.755397) (xy 357.510005 -298.778238)
			(xy 357.457509 -298.793734) (xy 357.403336 -298.801567) (xy 357.375968 -298.802044) (xy 357.348718 -298.801552)
			(xy 357.294772 -298.793792) (xy 357.24248 -298.778435) (xy 357.192905 -298.755793) (xy 357.147056 -298.726326)
			(xy 357.105867 -298.690636) (xy 357.070176 -298.649447) (xy 357.040709 -298.603599) (xy 357.018067 -298.554024)
			(xy 357.002709 -298.501732) (xy 356.994948 -298.447786) (xy 356.99446 -298.420536) (xy 353.751896 -298.420536)
			(xy 353.751456 -298.447789) (xy 353.743694 -298.501739) (xy 353.728334 -298.554035) (xy 353.705687 -298.603613)
			(xy 353.676216 -298.649464) (xy 353.64052 -298.690654) (xy 353.599325 -298.726345) (xy 353.553471 -298.75581)
			(xy 353.50389 -298.77845) (xy 353.451592 -298.793804) (xy 353.397641 -298.801559) (xy 353.370388 -298.802044)
			(xy 353.343017 -298.801599) (xy 353.288836 -298.793778) (xy 353.236332 -298.778285) (xy 353.186586 -298.755438)
			(xy 353.14062 -298.725708) (xy 353.11969 -298.708064) (xy 353.112578 -298.701968) (xy 353.09556 -298.695618)
			(xy 353.010216 -298.695618) (xy 352.993198 -298.701968) (xy 352.986086 -298.708064) (xy 352.965128 -298.725671)
			(xy 352.919163 -298.755389) (xy 352.869422 -298.778231) (xy 352.816927 -298.79373) (xy 352.762755 -298.801566)
			(xy 352.735388 -298.802044) (xy 352.708138 -298.801533) (xy 352.654193 -298.793776) (xy 352.601901 -298.778421)
			(xy 352.552326 -298.755782) (xy 352.506478 -298.726317) (xy 352.465288 -298.690629) (xy 352.429597 -298.649442)
			(xy 352.40013 -298.603595) (xy 352.377487 -298.554021) (xy 352.362129 -298.50173) (xy 352.354368 -298.447786)
			(xy 352.35388 -298.420536) (xy 348.80169 -298.420536) (xy 348.801256 -298.447789) (xy 348.793494 -298.501739)
			(xy 348.778133 -298.554036) (xy 348.755486 -298.603615) (xy 348.726015 -298.649466) (xy 348.690318 -298.690656)
			(xy 348.649123 -298.726347) (xy 348.603267 -298.755812) (xy 348.553686 -298.778452) (xy 348.501387 -298.793805)
			(xy 348.447435 -298.801559) (xy 348.420182 -298.802044) (xy 348.392811 -298.801602) (xy 348.33863 -298.793781)
			(xy 348.286126 -298.778287) (xy 348.23638 -298.755439) (xy 348.190414 -298.725708) (xy 348.169484 -298.708064)
			(xy 348.162372 -298.701968) (xy 348.145354 -298.695618) (xy 348.06001 -298.695618) (xy 348.042992 -298.701968)
			(xy 348.03588 -298.708064) (xy 348.014924 -298.725673) (xy 347.968958 -298.755391) (xy 347.919217 -298.778233)
			(xy 347.866721 -298.793731) (xy 347.81255 -298.801566) (xy 347.785182 -298.802044) (xy 347.757932 -298.801539)
			(xy 347.703987 -298.793781) (xy 347.651695 -298.778425) (xy 347.60212 -298.755785) (xy 347.556271 -298.72632)
			(xy 347.515082 -298.690631) (xy 347.479391 -298.649443) (xy 347.449924 -298.603596) (xy 347.427281 -298.554022)
			(xy 347.411923 -298.501731) (xy 347.404162 -298.447786) (xy 347.403674 -298.420536) (xy 344.16111 -298.420536)
			(xy 344.160656 -298.447788) (xy 344.152894 -298.501737) (xy 344.137535 -298.554032) (xy 344.11489 -298.603609)
			(xy 344.08542 -298.649459) (xy 344.049725 -298.690649) (xy 344.008532 -298.72634) (xy 343.962679 -298.755806)
			(xy 343.9131 -298.778447) (xy 343.860804 -298.793802) (xy 343.806854 -298.801558) (xy 343.779602 -298.802044)
			(xy 343.752231 -298.80159) (xy 343.698051 -298.793772) (xy 343.645547 -298.77828) (xy 343.595801 -298.755436)
			(xy 343.549835 -298.725707) (xy 343.528904 -298.708064) (xy 343.521792 -298.701968) (xy 343.504774 -298.695618)
			(xy 343.41943 -298.695618) (xy 343.402412 -298.701968) (xy 343.3953 -298.708064) (xy 343.374374 -298.725711)
			(xy 343.3284 -298.755423) (xy 343.278651 -298.778258) (xy 343.226149 -298.793747) (xy 343.171972 -298.801572)
			(xy 343.144602 -298.802044) (xy 343.117352 -298.80152) (xy 343.063408 -298.793765) (xy 343.011116 -298.778412)
			(xy 342.961541 -298.755774) (xy 342.915693 -298.726311) (xy 342.874503 -298.690624) (xy 342.838812 -298.649438)
			(xy 342.809344 -298.603592) (xy 342.786701 -298.55402) (xy 342.771343 -298.501729) (xy 342.763582 -298.447786)
			(xy 342.763094 -298.420536) (xy 341.733378 -298.420536) (xy 341.732956 -298.44779) (xy 341.725193 -298.501741)
			(xy 341.709832 -298.554039) (xy 341.687185 -298.603618) (xy 341.657712 -298.64947) (xy 341.622014 -298.69066)
			(xy 341.580817 -298.726351) (xy 341.53496 -298.755816) (xy 341.485377 -298.778455) (xy 341.433076 -298.793807)
			(xy 341.379124 -298.80156) (xy 341.35187 -298.802044) (xy 341.324498 -298.801609) (xy 341.270318 -298.793786)
			(xy 341.217814 -298.77829) (xy 341.168067 -298.755441) (xy 341.122102 -298.725709) (xy 341.101172 -298.708064)
			(xy 341.09406 -298.701968) (xy 341.077042 -298.695618) (xy 340.991698 -298.695618) (xy 340.97468 -298.701968)
			(xy 340.967568 -298.708064) (xy 340.946616 -298.725679) (xy 340.90065 -298.755396) (xy 340.850907 -298.778237)
			(xy 340.798411 -298.793733) (xy 340.744238 -298.801567) (xy 340.71687 -298.802044) (xy 340.68962 -298.80155)
			(xy 340.635674 -298.793791) (xy 340.583382 -298.778433) (xy 340.533807 -298.755791) (xy 340.487958 -298.726325)
			(xy 340.446769 -298.690635) (xy 340.411078 -298.649447) (xy 340.381611 -298.603599) (xy 340.358969 -298.554024)
			(xy 340.343611 -298.501732) (xy 340.33585 -298.447786) (xy 340.335362 -298.420536) (xy 337.092798 -298.420536)
			(xy 337.092356 -298.447789) (xy 337.084594 -298.501738) (xy 337.069234 -298.554035) (xy 337.046588 -298.603613)
			(xy 337.017117 -298.649463) (xy 336.981421 -298.690653) (xy 336.940226 -298.726344) (xy 336.894372 -298.75581)
			(xy 336.844791 -298.77845) (xy 336.792493 -298.793804) (xy 336.738543 -298.801559) (xy 336.71129 -298.802044)
			(xy 336.683919 -298.801597) (xy 336.629738 -298.793777) (xy 336.577235 -298.778284) (xy 336.527488 -298.755438)
			(xy 336.481523 -298.725708) (xy 336.460592 -298.708064) (xy 336.45348 -298.701968) (xy 336.436462 -298.695618)
			(xy 336.351118 -298.695618) (xy 336.3341 -298.701968) (xy 336.326988 -298.708064) (xy 336.306029 -298.72567)
			(xy 336.260064 -298.755388) (xy 336.210324 -298.778231) (xy 336.157829 -298.79373) (xy 336.103657 -298.801566)
			(xy 336.07629 -298.802044) (xy 336.04904 -298.801532) (xy 335.995095 -298.793775) (xy 335.942803 -298.77842)
			(xy 335.893228 -298.75578) (xy 335.84738 -298.726316) (xy 335.806191 -298.690628) (xy 335.770499 -298.649441)
			(xy 335.741032 -298.603595) (xy 335.718389 -298.554021) (xy 335.703031 -298.50173) (xy 335.69527 -298.447786)
			(xy 335.694782 -298.420536) (xy 333.256128 -298.420536) (xy 333.256128 -301.424086) (xy 335.023714 -301.424086)
			(xy 335.024168 -301.396715) (xy 335.031989 -301.342536) (xy 335.04748 -301.290032) (xy 335.070325 -301.240286)
			(xy 335.100052 -301.194319) (xy 335.117694 -301.173388) (xy 335.12379 -301.166276) (xy 335.13014 -301.149258)
			(xy 335.13014 -301.063914) (xy 335.12379 -301.046896) (xy 335.117694 -301.039784) (xy 335.100041 -301.018862)
			(xy 335.070319 -300.972891) (xy 335.047477 -300.923143) (xy 335.031983 -300.87064) (xy 335.024156 -300.81646)
			(xy 335.024158 -300.761719) (xy 335.031987 -300.70754) (xy 335.047484 -300.655037) (xy 335.070329 -300.60529)
			(xy 335.100054 -300.559321) (xy 335.117694 -300.538388) (xy 335.12379 -300.531276) (xy 335.13014 -300.514258)
			(xy 335.13014 -300.428914) (xy 335.12379 -300.411896) (xy 335.117694 -300.404784) (xy 335.100041 -300.383862)
			(xy 335.070319 -300.337891) (xy 335.047477 -300.288143) (xy 335.031983 -300.23564) (xy 335.024156 -300.18146)
			(xy 335.024158 -300.126719) (xy 335.031987 -300.07254) (xy 335.047484 -300.020037) (xy 335.070329 -299.97029)
			(xy 335.100054 -299.924321) (xy 335.117694 -299.903388) (xy 335.12379 -299.896276) (xy 335.13014 -299.879258)
			(xy 335.13014 -299.793914) (xy 335.12379 -299.776896) (xy 335.117694 -299.769784) (xy 335.10008 -299.748832)
			(xy 335.070365 -299.702864) (xy 335.047524 -299.653122) (xy 335.032027 -299.600626) (xy 335.024192 -299.546454)
			(xy 335.023714 -299.519086) (xy 335.0242 -299.491835) (xy 335.031956 -299.437887) (xy 335.047311 -299.385592)
			(xy 335.069953 -299.336015) (xy 335.099419 -299.290165) (xy 335.13511 -299.248974) (xy 335.176301 -299.213283)
			(xy 335.222151 -299.183817) (xy 335.271728 -299.161175) (xy 335.324023 -299.14582) (xy 335.377971 -299.138064)
			(xy 335.432473 -299.138064) (xy 335.486421 -299.14582) (xy 335.538716 -299.161175) (xy 335.588293 -299.183817)
			(xy 335.634143 -299.213283) (xy 335.675334 -299.248974) (xy 335.711025 -299.290165) (xy 335.740491 -299.336015)
			(xy 335.763133 -299.385592) (xy 335.778488 -299.437887) (xy 335.786244 -299.491835) (xy 335.78673 -299.519086)
			(xy 335.786273 -299.546457) (xy 335.778455 -299.600637) (xy 335.762965 -299.653141) (xy 335.740121 -299.702888)
			(xy 335.710393 -299.748853) (xy 335.69275 -299.769784) (xy 335.686654 -299.776896) (xy 335.680304 -299.793914)
			(xy 335.680304 -299.879258) (xy 335.686654 -299.896276) (xy 335.69275 -299.903388) (xy 335.710378 -299.924331)
			(xy 335.740105 -299.970297) (xy 335.762953 -300.020041) (xy 335.778451 -300.072542) (xy 335.786281 -300.126719)
			(xy 335.786283 -300.18146) (xy 335.778455 -300.235638) (xy 335.76296 -300.288139) (xy 335.740115 -300.337885)
			(xy 335.710391 -300.383852) (xy 335.69275 -300.404784) (xy 335.686654 -300.411896) (xy 335.680304 -300.428914)
			(xy 335.680304 -300.514258) (xy 335.686654 -300.531276) (xy 335.69275 -300.538388) (xy 335.710378 -300.559331)
			(xy 335.740105 -300.605297) (xy 335.762953 -300.655041) (xy 335.778451 -300.707542) (xy 335.786281 -300.761719)
			(xy 335.786283 -300.81646) (xy 335.778455 -300.870638) (xy 335.76296 -300.923139) (xy 335.740115 -300.972885)
			(xy 335.710391 -301.018852) (xy 335.69275 -301.039784) (xy 335.686654 -301.046896) (xy 335.680304 -301.063914)
			(xy 335.680304 -301.149258) (xy 335.686654 -301.166276) (xy 335.69275 -301.173388) (xy 335.710389 -301.19432)
			(xy 335.740103 -301.240292) (xy 335.762939 -301.29004) (xy 335.77843 -301.342541) (xy 335.786257 -301.396717)
			(xy 335.78673 -301.424086) (xy 335.786244 -301.451337) (xy 335.78242 -301.477934) (xy 338.655914 -301.477934)
			(xy 338.656397 -301.450564) (xy 338.66421 -301.396386) (xy 338.679695 -301.343883) (xy 338.702533 -301.294136)
			(xy 338.732254 -301.248168) (xy 338.749894 -301.227236) (xy 338.75599 -301.220124) (xy 338.76234 -301.203106)
			(xy 338.76234 -301.117762) (xy 338.75599 -301.100744) (xy 338.749894 -301.093632) (xy 338.732288 -301.072672)
			(xy 338.702564 -301.026708) (xy 338.679719 -300.976966) (xy 338.664222 -300.924468) (xy 338.65639 -300.870294)
			(xy 338.656387 -300.815557) (xy 338.664211 -300.761382) (xy 338.679701 -300.708882) (xy 338.70254 -300.659137)
			(xy 338.732257 -300.613169) (xy 338.749894 -300.592236) (xy 338.75599 -300.585124) (xy 338.76234 -300.568106)
			(xy 338.76234 -300.482762) (xy 338.75599 -300.465744) (xy 338.749894 -300.458632) (xy 338.732288 -300.437672)
			(xy 338.702564 -300.391708) (xy 338.679719 -300.341966) (xy 338.664222 -300.289468) (xy 338.65639 -300.235294)
			(xy 338.656387 -300.180557) (xy 338.664211 -300.126382) (xy 338.679701 -300.073882) (xy 338.70254 -300.024137)
			(xy 338.732257 -299.978169) (xy 338.749894 -299.957236) (xy 338.75599 -299.950124) (xy 338.76234 -299.933106)
			(xy 338.76234 -299.847762) (xy 338.75599 -299.830744) (xy 338.749894 -299.823632) (xy 338.732256 -299.802699)
			(xy 338.702544 -299.756727) (xy 338.679708 -299.706979) (xy 338.664217 -299.654479) (xy 338.656388 -299.600303)
			(xy 338.655914 -299.572934) (xy 338.6564 -299.545683) (xy 338.664156 -299.491735) (xy 338.679511 -299.43944)
			(xy 338.702153 -299.389863) (xy 338.731619 -299.344013) (xy 338.76731 -299.302822) (xy 338.808501 -299.267131)
			(xy 338.854351 -299.237665) (xy 338.903928 -299.215023) (xy 338.956223 -299.199668) (xy 339.010171 -299.191912)
			(xy 339.064673 -299.191912) (xy 339.118621 -299.199668) (xy 339.170916 -299.215023) (xy 339.220493 -299.237665)
			(xy 339.266343 -299.267131) (xy 339.307534 -299.302822) (xy 339.343225 -299.344013) (xy 339.372691 -299.389863)
			(xy 339.395333 -299.43944) (xy 339.410688 -299.491735) (xy 339.418444 -299.545683) (xy 339.41893 -299.572934)
			(xy 339.418501 -299.600306) (xy 339.410677 -299.654487) (xy 339.39518 -299.706991) (xy 339.37233 -299.756738)
			(xy 339.342596 -299.802702) (xy 339.32495 -299.823632) (xy 339.318854 -299.830744) (xy 339.312504 -299.847762)
			(xy 339.312504 -299.933106) (xy 339.318854 -299.950124) (xy 339.32495 -299.957236) (xy 339.342625 -299.978141)
			(xy 339.37235 -300.024113) (xy 339.395195 -300.073864) (xy 339.41069 -300.12637) (xy 339.418515 -300.180553)
			(xy 339.418512 -300.235298) (xy 339.410679 -300.28948) (xy 339.395177 -300.341984) (xy 339.372325 -300.391732)
			(xy 339.342594 -300.4377) (xy 339.32495 -300.458632) (xy 339.318854 -300.465744) (xy 339.312504 -300.482762)
			(xy 339.312504 -300.568106) (xy 339.318854 -300.585124) (xy 339.32495 -300.592236) (xy 339.342625 -300.613141)
			(xy 339.37235 -300.659113) (xy 339.395195 -300.708864) (xy 339.41069 -300.76137) (xy 339.418515 -300.815553)
			(xy 339.418512 -300.870298) (xy 339.410679 -300.92448) (xy 339.395177 -300.976984) (xy 339.372325 -301.026732)
			(xy 339.342594 -301.0727) (xy 339.32495 -301.093632) (xy 339.318854 -301.100744) (xy 339.312504 -301.117762)
			(xy 339.312504 -301.203106) (xy 339.318854 -301.220124) (xy 339.32495 -301.227236) (xy 339.342565 -301.248188)
			(xy 339.372282 -301.294154) (xy 339.395123 -301.343897) (xy 339.41062 -301.396393) (xy 339.414624 -301.424086)
			(xy 341.863934 -301.424086) (xy 341.864384 -301.396715) (xy 341.872204 -301.342535) (xy 341.887697 -301.290031)
			(xy 341.910542 -301.240285) (xy 341.940271 -301.194319) (xy 341.957914 -301.173388) (xy 341.96401 -301.166276)
			(xy 341.97036 -301.149258) (xy 341.97036 -301.063914) (xy 341.96401 -301.046896) (xy 341.957914 -301.039784)
			(xy 341.94026 -301.018862) (xy 341.910537 -300.972892) (xy 341.887693 -300.923144) (xy 341.872199 -300.87064)
			(xy 341.864372 -300.816461) (xy 341.864373 -300.761718) (xy 341.872203 -300.707539) (xy 341.887701 -300.655036)
			(xy 341.910547 -300.605289) (xy 341.940273 -300.559321) (xy 341.957914 -300.538388) (xy 341.96401 -300.531276)
			(xy 341.97036 -300.514258) (xy 341.97036 -300.428914) (xy 341.96401 -300.411896) (xy 341.957914 -300.404784)
			(xy 341.94026 -300.383862) (xy 341.910537 -300.337892) (xy 341.887693 -300.288144) (xy 341.872199 -300.23564)
			(xy 341.864372 -300.181461) (xy 341.864373 -300.126718) (xy 341.872203 -300.072539) (xy 341.887701 -300.020036)
			(xy 341.910547 -299.970289) (xy 341.940273 -299.924321) (xy 341.957914 -299.903388) (xy 341.96401 -299.896276)
			(xy 341.97036 -299.879258) (xy 341.97036 -299.793914) (xy 341.96401 -299.776896) (xy 341.957914 -299.769784)
			(xy 341.940303 -299.748829) (xy 341.910586 -299.702863) (xy 341.887745 -299.653121) (xy 341.872247 -299.600625)
			(xy 341.864412 -299.546454) (xy 341.863934 -299.519086) (xy 341.86442 -299.491835) (xy 341.872176 -299.437887)
			(xy 341.887531 -299.385592) (xy 341.910173 -299.336015) (xy 341.939639 -299.290165) (xy 341.97533 -299.248974)
			(xy 342.016521 -299.213283) (xy 342.062371 -299.183817) (xy 342.111948 -299.161175) (xy 342.164243 -299.14582)
			(xy 342.218191 -299.138064) (xy 342.272693 -299.138064) (xy 342.326641 -299.14582) (xy 342.378936 -299.161175)
			(xy 342.428513 -299.183817) (xy 342.474363 -299.213283) (xy 342.515554 -299.248974) (xy 342.551245 -299.290165)
			(xy 342.580711 -299.336015) (xy 342.603353 -299.385592) (xy 342.618708 -299.437887) (xy 342.626464 -299.491835)
			(xy 342.62695 -299.519086) (xy 342.626488 -299.546457) (xy 342.618671 -299.600636) (xy 342.603182 -299.65314)
			(xy 342.580339 -299.702887) (xy 342.550612 -299.748853) (xy 342.53297 -299.769784) (xy 342.526874 -299.776896)
			(xy 342.520524 -299.793914) (xy 342.520524 -299.879258) (xy 342.526874 -299.896276) (xy 342.53297 -299.903388)
			(xy 342.550597 -299.924332) (xy 342.580323 -299.970298) (xy 342.603169 -300.020042) (xy 342.618667 -300.072542)
			(xy 342.626497 -300.126719) (xy 342.626498 -300.181459) (xy 342.618671 -300.235637) (xy 342.603176 -300.288138)
			(xy 342.580333 -300.337884) (xy 342.55061 -300.383851) (xy 342.53297 -300.404784) (xy 342.526874 -300.411896)
			(xy 342.520524 -300.428914) (xy 342.520524 -300.514258) (xy 342.526874 -300.531276) (xy 342.53297 -300.538388)
			(xy 342.550597 -300.559332) (xy 342.580323 -300.605298) (xy 342.603169 -300.655042) (xy 342.618667 -300.707542)
			(xy 342.626497 -300.761719) (xy 342.626498 -300.816459) (xy 342.618671 -300.870637) (xy 342.603176 -300.923138)
			(xy 342.580333 -300.972884) (xy 342.55061 -301.018851) (xy 342.53297 -301.039784) (xy 342.526874 -301.046896)
			(xy 342.520524 -301.063914) (xy 342.520524 -301.149258) (xy 342.526874 -301.166276) (xy 342.53297 -301.173388)
			(xy 342.550612 -301.194318) (xy 342.580325 -301.240291) (xy 342.60316 -301.290039) (xy 342.618651 -301.34254)
			(xy 342.626477 -301.396717) (xy 342.62695 -301.424086) (xy 342.626464 -301.451337) (xy 342.62264 -301.477934)
			(xy 345.496134 -301.477934) (xy 345.496612 -301.450564) (xy 345.504425 -301.396385) (xy 345.519911 -301.343882)
			(xy 345.542751 -301.294135) (xy 345.572473 -301.248168) (xy 345.590114 -301.227236) (xy 345.59621 -301.220124)
			(xy 345.60256 -301.203106) (xy 345.60256 -301.117762) (xy 345.59621 -301.100744) (xy 345.590114 -301.093632)
			(xy 345.572507 -301.072672) (xy 345.542782 -301.026709) (xy 345.519935 -300.976967) (xy 345.504437 -300.924469)
			(xy 345.496606 -300.870294) (xy 345.496602 -300.815557) (xy 345.504426 -300.761381) (xy 345.519917 -300.708881)
			(xy 345.542757 -300.659136) (xy 345.572476 -300.613169) (xy 345.590114 -300.592236) (xy 345.59621 -300.585124)
			(xy 345.60256 -300.568106) (xy 345.60256 -300.482762) (xy 345.59621 -300.465744) (xy 345.590114 -300.458632)
			(xy 345.572507 -300.437672) (xy 345.542782 -300.391709) (xy 345.519935 -300.341967) (xy 345.504437 -300.289469)
			(xy 345.496606 -300.235294) (xy 345.496602 -300.180557) (xy 345.504426 -300.126381) (xy 345.519917 -300.073881)
			(xy 345.542757 -300.024136) (xy 345.572476 -299.978169) (xy 345.590114 -299.957236) (xy 345.59621 -299.950124)
			(xy 345.60256 -299.933106) (xy 345.60256 -299.847762) (xy 345.59621 -299.830744) (xy 345.590114 -299.823632)
			(xy 345.572479 -299.802697) (xy 345.542766 -299.756725) (xy 345.519929 -299.706978) (xy 345.504437 -299.654478)
			(xy 345.496608 -299.600303) (xy 345.496134 -299.572934) (xy 345.49662 -299.545683) (xy 345.504376 -299.491735)
			(xy 345.519731 -299.43944) (xy 345.542373 -299.389863) (xy 345.571839 -299.344013) (xy 345.60753 -299.302822)
			(xy 345.648721 -299.267131) (xy 345.694571 -299.237665) (xy 345.744148 -299.215023) (xy 345.796443 -299.199668)
			(xy 345.850391 -299.191912) (xy 345.904893 -299.191912) (xy 345.958841 -299.199668) (xy 346.011136 -299.215023)
			(xy 346.060713 -299.237665) (xy 346.106563 -299.267131) (xy 346.147754 -299.302822) (xy 346.183445 -299.344013)
			(xy 346.212911 -299.389863) (xy 346.235553 -299.43944) (xy 346.250908 -299.491735) (xy 346.258664 -299.545683)
			(xy 346.25915 -299.572934) (xy 346.258716 -299.600306) (xy 346.250892 -299.654486) (xy 346.235396 -299.70699)
			(xy 346.212547 -299.756737) (xy 346.182815 -299.802702) (xy 346.16517 -299.823632) (xy 346.159074 -299.830744)
			(xy 346.152724 -299.847762) (xy 346.152724 -299.933106) (xy 346.159074 -299.950124) (xy 346.16517 -299.957236)
			(xy 346.182844 -299.978142) (xy 346.212568 -300.024114) (xy 346.235411 -300.073865) (xy 346.250905 -300.126371)
			(xy 346.258731 -300.180553) (xy 346.258727 -300.235298) (xy 346.250894 -300.289479) (xy 346.235393 -300.341983)
			(xy 346.212543 -300.391731) (xy 346.182813 -300.437699) (xy 346.16517 -300.458632) (xy 346.159074 -300.465744)
			(xy 346.152724 -300.482762) (xy 346.152724 -300.568106) (xy 346.159074 -300.585124) (xy 346.16517 -300.592236)
			(xy 346.182844 -300.613142) (xy 346.212568 -300.659114) (xy 346.235411 -300.708865) (xy 346.250905 -300.761371)
			(xy 346.258731 -300.815553) (xy 346.258727 -300.870298) (xy 346.250894 -300.924479) (xy 346.235393 -300.976983)
			(xy 346.212543 -301.026731) (xy 346.182813 -301.072699) (xy 346.16517 -301.093632) (xy 346.159074 -301.100744)
			(xy 346.152724 -301.117762) (xy 346.152724 -301.203106) (xy 346.159074 -301.220124) (xy 346.16517 -301.227236)
			(xy 346.182788 -301.248185) (xy 346.212504 -301.294153) (xy 346.235344 -301.343896) (xy 346.25084 -301.396393)
			(xy 346.254845 -301.424086) (xy 353.617022 -301.424086) (xy 353.617475 -301.396715) (xy 353.625295 -301.342535)
			(xy 353.640787 -301.290032) (xy 353.663632 -301.240285) (xy 353.693359 -301.194319) (xy 353.711002 -301.173388)
			(xy 353.717098 -301.166276) (xy 353.723448 -301.149258) (xy 353.723448 -301.063914) (xy 353.717098 -301.046896)
			(xy 353.711002 -301.039784) (xy 353.693349 -301.018862) (xy 353.663626 -300.972892) (xy 353.640783 -300.923143)
			(xy 353.625289 -300.87064) (xy 353.617462 -300.81646) (xy 353.617464 -300.761718) (xy 353.625294 -300.707539)
			(xy 353.640791 -300.655037) (xy 353.663636 -300.60529) (xy 353.693361 -300.559321) (xy 353.711002 -300.538388)
			(xy 353.717098 -300.531276) (xy 353.723448 -300.514258) (xy 353.723448 -300.428914) (xy 353.717098 -300.411896)
			(xy 353.711002 -300.404784) (xy 353.693349 -300.383862) (xy 353.663626 -300.337892) (xy 353.640783 -300.288143)
			(xy 353.625289 -300.23564) (xy 353.617462 -300.18146) (xy 353.617464 -300.126718) (xy 353.625294 -300.072539)
			(xy 353.640791 -300.020037) (xy 353.663636 -299.97029) (xy 353.693361 -299.924321) (xy 353.711002 -299.903388)
			(xy 353.717098 -299.896276) (xy 353.723448 -299.879258) (xy 353.723448 -299.793914) (xy 353.717098 -299.776896)
			(xy 353.711002 -299.769784) (xy 353.693389 -299.748831) (xy 353.663673 -299.702864) (xy 353.640832 -299.653122)
			(xy 353.625335 -299.600626) (xy 353.6175 -299.546454) (xy 353.617022 -299.519086) (xy 353.617508 -299.491835)
			(xy 353.625264 -299.437887) (xy 353.640619 -299.385592) (xy 353.663261 -299.336015) (xy 353.692727 -299.290165)
			(xy 353.728418 -299.248974) (xy 353.769609 -299.213283) (xy 353.815459 -299.183817) (xy 353.865036 -299.161175)
			(xy 353.917331 -299.14582) (xy 353.971279 -299.138064) (xy 354.025781 -299.138064) (xy 354.079729 -299.14582)
			(xy 354.132024 -299.161175) (xy 354.181601 -299.183817) (xy 354.227451 -299.213283) (xy 354.268642 -299.248974)
			(xy 354.304333 -299.290165) (xy 354.333799 -299.336015) (xy 354.356441 -299.385592) (xy 354.371796 -299.437887)
			(xy 354.379552 -299.491835) (xy 354.380038 -299.519086) (xy 354.379579 -299.546457) (xy 354.371762 -299.600637)
			(xy 354.356272 -299.65314) (xy 354.333428 -299.702887) (xy 354.303701 -299.748853) (xy 354.286058 -299.769784)
			(xy 354.279962 -299.776896) (xy 354.273612 -299.793914) (xy 354.273612 -299.879258) (xy 354.279962 -299.896276)
			(xy 354.286058 -299.903388) (xy 354.303686 -299.924332) (xy 354.333412 -299.970297) (xy 354.356259 -300.020041)
			(xy 354.371757 -300.072542) (xy 354.379587 -300.126719) (xy 354.379589 -300.18146) (xy 354.371762 -300.235637)
			(xy 354.356267 -300.288139) (xy 354.333422 -300.337884) (xy 354.303698 -300.383852) (xy 354.286058 -300.404784)
			(xy 354.279962 -300.411896) (xy 354.273612 -300.428914) (xy 354.273612 -300.514258) (xy 354.279962 -300.531276)
			(xy 354.286058 -300.538388) (xy 354.303686 -300.559332) (xy 354.333412 -300.605297) (xy 354.356259 -300.655041)
			(xy 354.371757 -300.707542) (xy 354.379587 -300.761719) (xy 354.379589 -300.81646) (xy 354.371762 -300.870637)
			(xy 354.356267 -300.923139) (xy 354.333422 -300.972884) (xy 354.303698 -301.018852) (xy 354.286058 -301.039784)
			(xy 354.279962 -301.046896) (xy 354.273612 -301.063914) (xy 354.273612 -301.149258) (xy 354.279962 -301.166276)
			(xy 354.286058 -301.173388) (xy 354.303698 -301.194319) (xy 354.333411 -301.240292) (xy 354.356248 -301.290039)
			(xy 354.371738 -301.34254) (xy 354.379565 -301.396717) (xy 354.380038 -301.424086) (xy 354.379552 -301.451337)
			(xy 354.375728 -301.477934) (xy 357.249222 -301.477934) (xy 357.249703 -301.450564) (xy 357.257516 -301.396386)
			(xy 357.273002 -301.343882) (xy 357.29584 -301.294135) (xy 357.325562 -301.248168) (xy 357.343202 -301.227236)
			(xy 357.349298 -301.220124) (xy 357.355648 -301.203106) (xy 357.355648 -301.117762) (xy 357.349298 -301.100744)
			(xy 357.343202 -301.093632) (xy 357.325596 -301.072672) (xy 357.295871 -301.026708) (xy 357.273026 -300.976966)
			(xy 357.257528 -300.924469) (xy 357.249697 -300.870294) (xy 357.249693 -300.815557) (xy 357.257517 -300.761381)
			(xy 357.273008 -300.708882) (xy 357.295847 -300.659137) (xy 357.325565 -300.613169) (xy 357.343202 -300.592236)
			(xy 357.349298 -300.585124) (xy 357.355648 -300.568106) (xy 357.355648 -300.482762) (xy 357.349298 -300.465744)
			(xy 357.343202 -300.458632) (xy 357.325596 -300.437672) (xy 357.295871 -300.391708) (xy 357.273026 -300.341966)
			(xy 357.257528 -300.289469) (xy 357.249697 -300.235294) (xy 357.249693 -300.180557) (xy 357.257517 -300.126381)
			(xy 357.273008 -300.073882) (xy 357.295847 -300.024137) (xy 357.325565 -299.978169) (xy 357.343202 -299.957236)
			(xy 357.349298 -299.950124) (xy 357.355648 -299.933106) (xy 357.355648 -299.847762) (xy 357.349298 -299.830744)
			(xy 357.343202 -299.823632) (xy 357.325565 -299.802698) (xy 357.295853 -299.756726) (xy 357.273016 -299.706979)
			(xy 357.257525 -299.654479) (xy 357.249696 -299.600303) (xy 357.249222 -299.572934) (xy 357.249708 -299.545683)
			(xy 357.257464 -299.491735) (xy 357.272819 -299.43944) (xy 357.295461 -299.389863) (xy 357.324927 -299.344013)
			(xy 357.360618 -299.302822) (xy 357.401809 -299.267131) (xy 357.447659 -299.237665) (xy 357.497236 -299.215023)
			(xy 357.549531 -299.199668) (xy 357.603479 -299.191912) (xy 357.657981 -299.191912) (xy 357.711929 -299.199668)
			(xy 357.764224 -299.215023) (xy 357.813801 -299.237665) (xy 357.859651 -299.267131) (xy 357.900842 -299.302822)
			(xy 357.936533 -299.344013) (xy 357.965999 -299.389863) (xy 357.988641 -299.43944) (xy 358.003996 -299.491735)
			(xy 358.011752 -299.545683) (xy 358.012238 -299.572934) (xy 358.011807 -299.600306) (xy 358.003983 -299.654487)
			(xy 357.988487 -299.706991) (xy 357.965637 -299.756737) (xy 357.935904 -299.802702) (xy 357.918258 -299.823632)
			(xy 357.912162 -299.830744) (xy 357.905812 -299.847762) (xy 357.905812 -299.933106) (xy 357.912162 -299.950124)
			(xy 357.918258 -299.957236) (xy 357.935933 -299.978141) (xy 357.965657 -300.024114) (xy 357.988501 -300.073864)
			(xy 358.003996 -300.126371) (xy 358.011822 -300.180553) (xy 358.011818 -300.235298) (xy 358.003985 -300.289479)
			(xy 357.988483 -300.341984) (xy 357.965633 -300.391731) (xy 357.935902 -300.437699) (xy 357.918258 -300.458632)
			(xy 357.912162 -300.465744) (xy 357.905812 -300.482762) (xy 357.905812 -300.568106) (xy 357.912162 -300.585124)
			(xy 357.918258 -300.592236) (xy 357.935933 -300.613141) (xy 357.965657 -300.659114) (xy 357.988501 -300.708864)
			(xy 358.003996 -300.761371) (xy 358.011822 -300.815553) (xy 358.011818 -300.870298) (xy 358.003985 -300.924479)
			(xy 357.988483 -300.976984) (xy 357.965633 -301.026731) (xy 357.935902 -301.072699) (xy 357.918258 -301.093632)
			(xy 357.912162 -301.100744) (xy 357.905812 -301.117762) (xy 357.905812 -301.203106) (xy 357.912162 -301.220124)
			(xy 357.918258 -301.227236) (xy 357.935874 -301.248187) (xy 357.965591 -301.294154) (xy 357.988432 -301.343896)
			(xy 358.003928 -301.396393) (xy 358.007932 -301.424086) (xy 360.457242 -301.424086) (xy 360.45769 -301.396715)
			(xy 360.46551 -301.342535) (xy 360.481003 -301.290031) (xy 360.503849 -301.240284) (xy 360.533578 -301.194319)
			(xy 360.551222 -301.173388) (xy 360.557318 -301.166276) (xy 360.563668 -301.149258) (xy 360.563668 -301.063914)
			(xy 360.557318 -301.046896) (xy 360.551222 -301.039784) (xy 360.533568 -301.018862) (xy 360.503844 -300.972892)
			(xy 360.481 -300.923144) (xy 360.465505 -300.870641) (xy 360.457678 -300.816461) (xy 360.457679 -300.761718)
			(xy 360.465509 -300.707539) (xy 360.481007 -300.655036) (xy 360.503854 -300.605289) (xy 360.533581 -300.559321)
			(xy 360.551222 -300.538388) (xy 360.557318 -300.531276) (xy 360.563668 -300.514258) (xy 360.563668 -300.428914)
			(xy 360.557318 -300.411896) (xy 360.551222 -300.404784) (xy 360.533568 -300.383862) (xy 360.503844 -300.337892)
			(xy 360.481 -300.288144) (xy 360.465505 -300.235641) (xy 360.457678 -300.181461) (xy 360.457679 -300.126718)
			(xy 360.465509 -300.072539) (xy 360.481007 -300.020036) (xy 360.503854 -299.970289) (xy 360.533581 -299.924321)
			(xy 360.551222 -299.903388) (xy 360.557318 -299.896276) (xy 360.563668 -299.879258) (xy 360.563668 -299.793914)
			(xy 360.557318 -299.776896) (xy 360.551222 -299.769784) (xy 360.533612 -299.748828) (xy 360.503895 -299.702862)
			(xy 360.481053 -299.653121) (xy 360.465555 -299.600625) (xy 360.45772 -299.546454) (xy 360.457242 -299.519086)
			(xy 360.457728 -299.491835) (xy 360.465484 -299.437887) (xy 360.480839 -299.385592) (xy 360.503481 -299.336015)
			(xy 360.532947 -299.290165) (xy 360.568638 -299.248974) (xy 360.609829 -299.213283) (xy 360.655679 -299.183817)
			(xy 360.705256 -299.161175) (xy 360.757551 -299.14582) (xy 360.811499 -299.138064) (xy 360.866001 -299.138064)
			(xy 360.919949 -299.14582) (xy 360.972244 -299.161175) (xy 361.021821 -299.183817) (xy 361.067671 -299.213283)
			(xy 361.108862 -299.248974) (xy 361.144553 -299.290165) (xy 361.174019 -299.336015) (xy 361.196661 -299.385592)
			(xy 361.212016 -299.437887) (xy 361.219772 -299.491835) (xy 361.220258 -299.519086) (xy 361.219794 -299.546456)
			(xy 361.211977 -299.600636) (xy 361.196488 -299.65314) (xy 361.173646 -299.702886) (xy 361.14392 -299.748853)
			(xy 361.126278 -299.769784) (xy 361.120182 -299.776896) (xy 361.113832 -299.793914) (xy 361.113832 -299.879258)
			(xy 361.120182 -299.896276) (xy 361.126278 -299.903388) (xy 361.143905 -299.924332) (xy 361.17363 -299.970298)
			(xy 361.196476 -300.020042) (xy 361.211973 -300.072543) (xy 361.219803 -300.12672) (xy 361.219804 -300.181459)
			(xy 361.211977 -300.235637) (xy 361.196483 -300.288138) (xy 361.17364 -300.337884) (xy 361.143917 -300.383851)
			(xy 361.126278 -300.404784) (xy 361.120182 -300.411896) (xy 361.113832 -300.428914) (xy 361.113832 -300.514258)
			(xy 361.120182 -300.531276) (xy 361.126278 -300.538388) (xy 361.143905 -300.559332) (xy 361.17363 -300.605298)
			(xy 361.196476 -300.655042) (xy 361.211973 -300.707543) (xy 361.219803 -300.76172) (xy 361.219804 -300.816459)
			(xy 361.211977 -300.870637) (xy 361.196483 -300.923138) (xy 361.17364 -300.972884) (xy 361.143917 -301.018851)
			(xy 361.126278 -301.039784) (xy 361.120182 -301.046896) (xy 361.113832 -301.063914) (xy 361.113832 -301.149258)
			(xy 361.120182 -301.166276) (xy 361.126278 -301.173388) (xy 361.143922 -301.194317) (xy 361.173633 -301.24029)
			(xy 361.196469 -301.290038) (xy 361.211959 -301.34254) (xy 361.219785 -301.396717) (xy 361.220258 -301.424086)
			(xy 361.219772 -301.451337) (xy 361.215948 -301.477934) (xy 364.089442 -301.477934) (xy 364.089918 -301.450564)
			(xy 364.097732 -301.396385) (xy 364.113218 -301.343882) (xy 364.136058 -301.294134) (xy 364.165781 -301.248168)
			(xy 364.183422 -301.227236) (xy 364.189518 -301.220124) (xy 364.195868 -301.203106) (xy 364.195868 -301.117762)
			(xy 364.189518 -301.100744) (xy 364.183422 -301.093632) (xy 364.165815 -301.072672) (xy 364.136089 -301.026709)
			(xy 364.113242 -300.976967) (xy 364.097743 -300.924469) (xy 364.089912 -300.870295) (xy 364.089908 -300.815557)
			(xy 364.097732 -300.761381) (xy 364.113224 -300.708881) (xy 364.136064 -300.659136) (xy 364.165784 -300.613169)
			(xy 364.183422 -300.592236) (xy 364.189518 -300.585124) (xy 364.195868 -300.568106) (xy 364.195868 -300.482762)
			(xy 364.189518 -300.465744) (xy 364.183422 -300.458632) (xy 364.165815 -300.437672) (xy 364.136089 -300.391709)
			(xy 364.113242 -300.341967) (xy 364.097743 -300.289469) (xy 364.089912 -300.235295) (xy 364.089908 -300.180557)
			(xy 364.097732 -300.126381) (xy 364.113224 -300.073881) (xy 364.136064 -300.024136) (xy 364.165784 -299.978169)
			(xy 364.183422 -299.957236) (xy 364.189518 -299.950124) (xy 364.195868 -299.933106) (xy 364.195868 -299.847762)
			(xy 364.189518 -299.830744) (xy 364.183422 -299.823632) (xy 364.165788 -299.802696) (xy 364.136075 -299.756725)
			(xy 364.113237 -299.706978) (xy 364.097745 -299.654478) (xy 364.089916 -299.600303) (xy 364.089442 -299.572934)
			(xy 364.089928 -299.545683) (xy 364.097684 -299.491735) (xy 364.113039 -299.43944) (xy 364.135681 -299.389863)
			(xy 364.165147 -299.344013) (xy 364.200838 -299.302822) (xy 364.242029 -299.267131) (xy 364.287879 -299.237665)
			(xy 364.337456 -299.215023) (xy 364.389751 -299.199668) (xy 364.443699 -299.191912) (xy 364.498201 -299.191912)
			(xy 364.552149 -299.199668) (xy 364.604444 -299.215023) (xy 364.654021 -299.237665) (xy 364.699871 -299.267131)
			(xy 364.741062 -299.302822) (xy 364.776753 -299.344013) (xy 364.806219 -299.389863) (xy 364.828861 -299.43944)
			(xy 364.844216 -299.491735) (xy 364.851972 -299.545683) (xy 364.852458 -299.572934) (xy 364.852022 -299.600305)
			(xy 364.844199 -299.654486) (xy 364.828703 -299.70699) (xy 364.805854 -299.756736) (xy 364.776123 -299.802702)
			(xy 364.758478 -299.823632) (xy 364.752382 -299.830744) (xy 364.746032 -299.847762) (xy 364.746032 -299.933106)
			(xy 364.752382 -299.950124) (xy 364.758478 -299.957236) (xy 364.776152 -299.978142) (xy 364.805875 -300.024114)
			(xy 364.828718 -300.073865) (xy 364.844211 -300.126371) (xy 364.852037 -300.180553) (xy 364.852033 -300.235298)
			(xy 364.8442 -300.289479) (xy 364.8287 -300.341983) (xy 364.80585 -300.391731) (xy 364.776121 -300.437699)
			(xy 364.758478 -300.458632) (xy 364.752382 -300.465744) (xy 364.746032 -300.482762) (xy 364.746032 -300.568106)
			(xy 364.752382 -300.585124) (xy 364.758478 -300.592236) (xy 364.776152 -300.613142) (xy 364.805875 -300.659114)
			(xy 364.828718 -300.708865) (xy 364.844211 -300.761371) (xy 364.852037 -300.815553) (xy 364.852033 -300.870298)
			(xy 364.8442 -300.924479) (xy 364.8287 -300.976983) (xy 364.80585 -301.026731) (xy 364.776121 -301.072699)
			(xy 364.758478 -301.093632) (xy 364.752382 -301.100744) (xy 364.746032 -301.117762) (xy 364.746032 -301.203106)
			(xy 364.752382 -301.220124) (xy 364.758478 -301.227236) (xy 364.776097 -301.248184) (xy 364.805813 -301.294152)
			(xy 364.828653 -301.343896) (xy 364.844149 -301.396393) (xy 364.851982 -301.450566) (xy 364.852458 -301.477934)
			(xy 364.851972 -301.505185) (xy 364.844216 -301.559133) (xy 364.828861 -301.611428) (xy 364.806219 -301.661005)
			(xy 364.776753 -301.706855) (xy 364.741062 -301.748046) (xy 364.699871 -301.783737) (xy 364.654021 -301.813203)
			(xy 364.604444 -301.835845) (xy 364.552149 -301.8512) (xy 364.498201 -301.858956) (xy 364.443699 -301.858956)
			(xy 364.389751 -301.8512) (xy 364.337456 -301.835845) (xy 364.287879 -301.813203) (xy 364.242029 -301.783737)
			(xy 364.200838 -301.748046) (xy 364.165147 -301.706855) (xy 364.135681 -301.661005) (xy 364.113039 -301.611428)
			(xy 364.097684 -301.559133) (xy 364.089928 -301.505185) (xy 364.089442 -301.477934) (xy 361.215948 -301.477934)
			(xy 361.212016 -301.505285) (xy 361.196661 -301.55758) (xy 361.174019 -301.607157) (xy 361.144553 -301.653007)
			(xy 361.108862 -301.694198) (xy 361.067671 -301.729889) (xy 361.021821 -301.759355) (xy 360.972244 -301.781997)
			(xy 360.919949 -301.797352) (xy 360.866001 -301.805108) (xy 360.811499 -301.805108) (xy 360.757551 -301.797352)
			(xy 360.705256 -301.781997) (xy 360.655679 -301.759355) (xy 360.609829 -301.729889) (xy 360.568638 -301.694198)
			(xy 360.532947 -301.653007) (xy 360.503481 -301.607157) (xy 360.480839 -301.55758) (xy 360.465484 -301.505285)
			(xy 360.457728 -301.451337) (xy 360.457242 -301.424086) (xy 358.007932 -301.424086) (xy 358.011761 -301.450566)
			(xy 358.012238 -301.477934) (xy 358.011752 -301.505185) (xy 358.003996 -301.559133) (xy 357.988641 -301.611428)
			(xy 357.965999 -301.661005) (xy 357.936533 -301.706855) (xy 357.900842 -301.748046) (xy 357.859651 -301.783737)
			(xy 357.813801 -301.813203) (xy 357.764224 -301.835845) (xy 357.711929 -301.8512) (xy 357.657981 -301.858956)
			(xy 357.603479 -301.858956) (xy 357.549531 -301.8512) (xy 357.497236 -301.835845) (xy 357.447659 -301.813203)
			(xy 357.401809 -301.783737) (xy 357.360618 -301.748046) (xy 357.324927 -301.706855) (xy 357.295461 -301.661005)
			(xy 357.272819 -301.611428) (xy 357.257464 -301.559133) (xy 357.249708 -301.505185) (xy 357.249222 -301.477934)
			(xy 354.375728 -301.477934) (xy 354.371796 -301.505285) (xy 354.356441 -301.55758) (xy 354.333799 -301.607157)
			(xy 354.304333 -301.653007) (xy 354.268642 -301.694198) (xy 354.227451 -301.729889) (xy 354.181601 -301.759355)
			(xy 354.132024 -301.781997) (xy 354.079729 -301.797352) (xy 354.025781 -301.805108) (xy 353.971279 -301.805108)
			(xy 353.917331 -301.797352) (xy 353.865036 -301.781997) (xy 353.815459 -301.759355) (xy 353.769609 -301.729889)
			(xy 353.728418 -301.694198) (xy 353.692727 -301.653007) (xy 353.663261 -301.607157) (xy 353.640619 -301.55758)
			(xy 353.625264 -301.505285) (xy 353.617508 -301.451337) (xy 353.617022 -301.424086) (xy 346.254845 -301.424086)
			(xy 346.258674 -301.450566) (xy 346.25915 -301.477934) (xy 346.258664 -301.505185) (xy 346.250908 -301.559133)
			(xy 346.235553 -301.611428) (xy 346.212911 -301.661005) (xy 346.183445 -301.706855) (xy 346.147754 -301.748046)
			(xy 346.106563 -301.783737) (xy 346.060713 -301.813203) (xy 346.011136 -301.835845) (xy 345.958841 -301.8512)
			(xy 345.904893 -301.858956) (xy 345.850391 -301.858956) (xy 345.796443 -301.8512) (xy 345.744148 -301.835845)
			(xy 345.694571 -301.813203) (xy 345.648721 -301.783737) (xy 345.60753 -301.748046) (xy 345.571839 -301.706855)
			(xy 345.542373 -301.661005) (xy 345.519731 -301.611428) (xy 345.504376 -301.559133) (xy 345.49662 -301.505185)
			(xy 345.496134 -301.477934) (xy 342.62264 -301.477934) (xy 342.618708 -301.505285) (xy 342.603353 -301.55758)
			(xy 342.580711 -301.607157) (xy 342.551245 -301.653007) (xy 342.515554 -301.694198) (xy 342.474363 -301.729889)
			(xy 342.428513 -301.759355) (xy 342.378936 -301.781997) (xy 342.326641 -301.797352) (xy 342.272693 -301.805108)
			(xy 342.218191 -301.805108) (xy 342.164243 -301.797352) (xy 342.111948 -301.781997) (xy 342.062371 -301.759355)
			(xy 342.016521 -301.729889) (xy 341.97533 -301.694198) (xy 341.939639 -301.653007) (xy 341.910173 -301.607157)
			(xy 341.887531 -301.55758) (xy 341.872176 -301.505285) (xy 341.86442 -301.451337) (xy 341.863934 -301.424086)
			(xy 339.414624 -301.424086) (xy 339.418453 -301.450566) (xy 339.41893 -301.477934) (xy 339.418444 -301.505185)
			(xy 339.410688 -301.559133) (xy 339.395333 -301.611428) (xy 339.372691 -301.661005) (xy 339.343225 -301.706855)
			(xy 339.307534 -301.748046) (xy 339.266343 -301.783737) (xy 339.220493 -301.813203) (xy 339.170916 -301.835845)
			(xy 339.118621 -301.8512) (xy 339.064673 -301.858956) (xy 339.010171 -301.858956) (xy 338.956223 -301.8512)
			(xy 338.903928 -301.835845) (xy 338.854351 -301.813203) (xy 338.808501 -301.783737) (xy 338.76731 -301.748046)
			(xy 338.731619 -301.706855) (xy 338.702153 -301.661005) (xy 338.679511 -301.611428) (xy 338.664156 -301.559133)
			(xy 338.6564 -301.505185) (xy 338.655914 -301.477934) (xy 335.78242 -301.477934) (xy 335.778488 -301.505285)
			(xy 335.763133 -301.55758) (xy 335.740491 -301.607157) (xy 335.711025 -301.653007) (xy 335.675334 -301.694198)
			(xy 335.634143 -301.729889) (xy 335.588293 -301.759355) (xy 335.538716 -301.781997) (xy 335.486421 -301.797352)
			(xy 335.432473 -301.805108) (xy 335.377971 -301.805108) (xy 335.324023 -301.797352) (xy 335.271728 -301.781997)
			(xy 335.222151 -301.759355) (xy 335.176301 -301.729889) (xy 335.13511 -301.694198) (xy 335.099419 -301.653007)
			(xy 335.069953 -301.607157) (xy 335.047311 -301.55758) (xy 335.031956 -301.505285) (xy 335.0242 -301.451337)
			(xy 335.023714 -301.424086) (xy 333.256128 -301.424086) (xy 333.256128 -302.815244) (xy 333.256493 -302.82529)
			(xy 333.264085 -302.843886) (xy 333.27086 -302.851312) (xy 333.482442 -303.062894) (xy 333.489834 -303.069744)
			(xy 333.508439 -303.077458) (xy 333.51851 -303.07788) (xy 334.336644 -303.07788) (xy 334.347367 -303.077292)
			(xy 334.366927 -303.068487) (xy 334.37449 -303.060862) (xy 334.432402 -302.996854) (xy 334.439006 -302.976534)
			(xy 334.437736 -302.965612) (xy 334.436773 -302.955671) (xy 334.435757 -302.935722) (xy 334.435704 -302.925734)
			(xy 334.436189 -302.898364) (xy 334.444002 -302.844186) (xy 334.459487 -302.791683) (xy 334.482324 -302.741936)
			(xy 334.512045 -302.695968) (xy 334.529684 -302.675036) (xy 334.53578 -302.667924) (xy 334.54213 -302.650906)
			(xy 334.54213 -302.565562) (xy 334.53578 -302.548544) (xy 334.529684 -302.541432) (xy 334.512044 -302.520501)
			(xy 334.482333 -302.474527) (xy 334.459497 -302.42478) (xy 334.444006 -302.372279) (xy 334.436178 -302.318103)
			(xy 334.435704 -302.290734) (xy 334.43619 -302.263483) (xy 334.443946 -302.209535) (xy 334.459301 -302.15724)
			(xy 334.481943 -302.107663) (xy 334.511409 -302.061813) (xy 334.5471 -302.020622) (xy 334.588291 -301.984931)
			(xy 334.634141 -301.955465) (xy 334.683718 -301.932823) (xy 334.736013 -301.917468) (xy 334.789961 -301.909712)
			(xy 334.844463 -301.909712) (xy 334.898411 -301.917468) (xy 334.950706 -301.932823) (xy 335.000283 -301.955465)
			(xy 335.046133 -301.984931) (xy 335.087324 -302.020622) (xy 335.123015 -302.061813) (xy 335.152481 -302.107663)
			(xy 335.175123 -302.15724) (xy 335.190478 -302.209535) (xy 335.198234 -302.263483) (xy 335.19872 -302.290734)
			(xy 335.198293 -302.318106) (xy 335.190469 -302.372287) (xy 335.174972 -302.424792) (xy 335.152121 -302.474538)
			(xy 335.122386 -302.520502) (xy 335.10474 -302.541432) (xy 335.098644 -302.548544) (xy 335.092294 -302.565562)
			(xy 335.092294 -302.650906) (xy 335.098644 -302.667924) (xy 335.10474 -302.675036) (xy 335.122369 -302.695976)
			(xy 335.152081 -302.741947) (xy 335.174919 -302.791693) (xy 335.190412 -302.844191) (xy 335.198244 -302.898365)
			(xy 335.19872 -302.925734) (xy 335.198668 -302.935722) (xy 335.197654 -302.955671) (xy 335.196688 -302.965612)
			(xy 335.195418 -302.976534) (xy 335.202022 -302.996854) (xy 335.259934 -303.060862) (xy 335.26743 -303.06858)
			(xy 335.287032 -303.0774) (xy 335.29778 -303.07788) (xy 337.756754 -303.07788) (xy 337.767477 -303.077298)
			(xy 337.787038 -303.068489) (xy 337.7946 -303.060862) (xy 337.852512 -302.996854) (xy 337.859116 -302.976534)
			(xy 337.857846 -302.965612) (xy 337.856883 -302.955671) (xy 337.855867 -302.935722) (xy 337.855814 -302.925734)
			(xy 337.856297 -302.898364) (xy 337.86411 -302.844186) (xy 337.879595 -302.791683) (xy 337.902433 -302.741936)
			(xy 337.932154 -302.695968) (xy 337.949794 -302.675036) (xy 337.95589 -302.667924) (xy 337.96224 -302.650906)
			(xy 337.96224 -302.565562) (xy 337.95589 -302.548544) (xy 337.949794 -302.541432) (xy 337.932156 -302.520499)
			(xy 337.902444 -302.474527) (xy 337.879608 -302.424779) (xy 337.864117 -302.372279) (xy 337.856288 -302.318103)
			(xy 337.855814 -302.290734) (xy 337.8563 -302.263483) (xy 337.864056 -302.209535) (xy 337.879411 -302.15724)
			(xy 337.902053 -302.107663) (xy 337.931519 -302.061813) (xy 337.96721 -302.020622) (xy 338.008401 -301.984931)
			(xy 338.054251 -301.955465) (xy 338.103828 -301.932823) (xy 338.156123 -301.917468) (xy 338.210071 -301.909712)
			(xy 338.264573 -301.909712) (xy 338.318521 -301.917468) (xy 338.370816 -301.932823) (xy 338.420393 -301.955465)
			(xy 338.466243 -301.984931) (xy 338.507434 -302.020622) (xy 338.543125 -302.061813) (xy 338.572591 -302.107663)
			(xy 338.595233 -302.15724) (xy 338.610588 -302.209535) (xy 338.618344 -302.263483) (xy 338.61883 -302.290734)
			(xy 338.618401 -302.318106) (xy 338.610577 -302.372287) (xy 338.59508 -302.424791) (xy 338.57223 -302.474538)
			(xy 338.542496 -302.520502) (xy 338.52485 -302.541432) (xy 338.518754 -302.548544) (xy 338.512404 -302.565562)
			(xy 338.512404 -302.650906) (xy 338.518754 -302.667924) (xy 338.52485 -302.675036) (xy 338.542465 -302.695988)
			(xy 338.572182 -302.741954) (xy 338.595023 -302.791697) (xy 338.61052 -302.844193) (xy 338.618353 -302.898366)
			(xy 338.61883 -302.925734) (xy 338.618778 -302.935722) (xy 338.617764 -302.955671) (xy 338.616798 -302.965612)
			(xy 338.615528 -302.976534) (xy 338.622132 -302.996854) (xy 338.680044 -303.060862) (xy 338.687536 -303.068585)
			(xy 338.707141 -303.077402) (xy 338.71789 -303.07788) (xy 339.144864 -303.07788) (xy 339.155588 -303.077303)
			(xy 339.175148 -303.06849) (xy 339.18271 -303.060862) (xy 339.240622 -302.996854) (xy 339.247226 -302.976534)
			(xy 339.245956 -302.965612) (xy 339.244993 -302.955671) (xy 339.243977 -302.935722) (xy 339.243924 -302.925734)
			(xy 339.244404 -302.898364) (xy 339.252218 -302.844185) (xy 339.267703 -302.791682) (xy 339.290542 -302.741935)
			(xy 339.320264 -302.695968) (xy 339.337904 -302.675036) (xy 339.344 -302.667924) (xy 339.35035 -302.650906)
			(xy 339.35035 -302.565562) (xy 339.344 -302.548544) (xy 339.337904 -302.541432) (xy 339.320267 -302.520498)
			(xy 339.290555 -302.474526) (xy 339.267718 -302.424779) (xy 339.252227 -302.372279) (xy 339.244398 -302.318103)
			(xy 339.243924 -302.290734) (xy 339.24441 -302.263483) (xy 339.252166 -302.209535) (xy 339.267521 -302.15724)
			(xy 339.290163 -302.107663) (xy 339.319629 -302.061813) (xy 339.35532 -302.020622) (xy 339.396511 -301.984931)
			(xy 339.442361 -301.955465) (xy 339.491938 -301.932823) (xy 339.544233 -301.917468) (xy 339.598181 -301.909712)
			(xy 339.652683 -301.909712) (xy 339.706631 -301.917468) (xy 339.758926 -301.932823) (xy 339.808503 -301.955465)
			(xy 339.854353 -301.984931) (xy 339.895544 -302.020622) (xy 339.931235 -302.061813) (xy 339.960701 -302.107663)
			(xy 339.983343 -302.15724) (xy 339.998698 -302.209535) (xy 340.006454 -302.263483) (xy 340.00694 -302.290734)
			(xy 340.006508 -302.318106) (xy 339.998685 -302.372287) (xy 339.983188 -302.424791) (xy 339.960338 -302.474537)
			(xy 339.930605 -302.520502) (xy 339.91296 -302.541432) (xy 339.906864 -302.548544) (xy 339.900514 -302.565562)
			(xy 339.900514 -302.650906) (xy 339.906864 -302.667924) (xy 339.91296 -302.675036) (xy 339.930576 -302.695987)
			(xy 339.960293 -302.741954) (xy 339.983134 -302.791696) (xy 339.99863 -302.844193) (xy 340.006463 -302.898366)
			(xy 340.00694 -302.925734) (xy 340.006888 -302.935722) (xy 340.005874 -302.955671) (xy 340.004908 -302.965612)
			(xy 340.003638 -302.976534) (xy 340.010242 -302.996854) (xy 340.068154 -303.060862) (xy 340.075642 -303.068589)
			(xy 340.09525 -303.077404) (xy 340.106 -303.07788) (xy 341.176864 -303.07788) (xy 341.187588 -303.077303)
			(xy 341.207148 -303.06849) (xy 341.21471 -303.060862) (xy 341.272622 -302.996854) (xy 341.279226 -302.976534)
			(xy 341.277956 -302.965612) (xy 341.276993 -302.955671) (xy 341.275977 -302.935722) (xy 341.275924 -302.925734)
			(xy 341.276404 -302.898364) (xy 341.284218 -302.844185) (xy 341.299703 -302.791682) (xy 341.322542 -302.741935)
			(xy 341.352264 -302.695968) (xy 341.369904 -302.675036) (xy 341.376 -302.667924) (xy 341.38235 -302.650906)
			(xy 341.38235 -302.565562) (xy 341.376 -302.548544) (xy 341.369904 -302.541432) (xy 341.352267 -302.520498)
			(xy 341.322555 -302.474526) (xy 341.299718 -302.424779) (xy 341.284227 -302.372279) (xy 341.276398 -302.318103)
			(xy 341.275924 -302.290734) (xy 341.27641 -302.263483) (xy 341.284166 -302.209535) (xy 341.299521 -302.15724)
			(xy 341.322163 -302.107663) (xy 341.351629 -302.061813) (xy 341.38732 -302.020622) (xy 341.428511 -301.984931)
			(xy 341.474361 -301.955465) (xy 341.523938 -301.932823) (xy 341.576233 -301.917468) (xy 341.630181 -301.909712)
			(xy 341.684683 -301.909712) (xy 341.738631 -301.917468) (xy 341.790926 -301.932823) (xy 341.840503 -301.955465)
			(xy 341.886353 -301.984931) (xy 341.927544 -302.020622) (xy 341.963235 -302.061813) (xy 341.992701 -302.107663)
			(xy 342.015343 -302.15724) (xy 342.030698 -302.209535) (xy 342.038454 -302.263483) (xy 342.03894 -302.290734)
			(xy 342.038508 -302.318106) (xy 342.030685 -302.372287) (xy 342.015188 -302.424791) (xy 341.992338 -302.474537)
			(xy 341.962605 -302.520502) (xy 341.94496 -302.541432) (xy 341.938864 -302.548544) (xy 341.932514 -302.565562)
			(xy 341.932514 -302.650906) (xy 341.938864 -302.667924) (xy 341.94496 -302.675036) (xy 341.962576 -302.695987)
			(xy 341.992293 -302.741954) (xy 342.015134 -302.791696) (xy 342.03063 -302.844193) (xy 342.038463 -302.898366)
			(xy 342.03894 -302.925734) (xy 342.038888 -302.935722) (xy 342.037874 -302.955671) (xy 342.036908 -302.965612)
			(xy 342.035638 -302.976534) (xy 342.042242 -302.996854) (xy 342.100154 -303.060862) (xy 342.107642 -303.068589)
			(xy 342.12725 -303.077404) (xy 342.138 -303.07788) (xy 345.985084 -303.07788) (xy 345.995809 -303.077314)
			(xy 346.015369 -303.068494) (xy 346.02293 -303.060862) (xy 346.080842 -302.996854) (xy 346.087446 -302.976534)
			(xy 346.086176 -302.965612) (xy 346.085213 -302.955671) (xy 346.084197 -302.935722) (xy 346.084144 -302.925734)
			(xy 346.084619 -302.898364) (xy 346.092433 -302.844185) (xy 346.10792 -302.791681) (xy 346.13076 -302.741934)
			(xy 346.160483 -302.695968) (xy 346.178124 -302.675036) (xy 346.18422 -302.667924) (xy 346.19057 -302.650906)
			(xy 346.19057 -302.565562) (xy 346.18422 -302.548544) (xy 346.178124 -302.541432) (xy 346.16049 -302.520496)
			(xy 346.130777 -302.474524) (xy 346.107939 -302.424778) (xy 346.092447 -302.372278) (xy 346.084618 -302.318103)
			(xy 346.084144 -302.290734) (xy 346.08463 -302.263483) (xy 346.092386 -302.209535) (xy 346.107741 -302.15724)
			(xy 346.130383 -302.107663) (xy 346.159849 -302.061813) (xy 346.19554 -302.020622) (xy 346.236731 -301.984931)
			(xy 346.282581 -301.955465) (xy 346.332158 -301.932823) (xy 346.384453 -301.917468) (xy 346.438401 -301.909712)
			(xy 346.492903 -301.909712) (xy 346.546851 -301.917468) (xy 346.599146 -301.932823) (xy 346.648723 -301.955465)
			(xy 346.694573 -301.984931) (xy 346.735764 -302.020622) (xy 346.771455 -302.061813) (xy 346.800921 -302.107663)
			(xy 346.823563 -302.15724) (xy 346.838918 -302.209535) (xy 346.846674 -302.263483) (xy 346.84716 -302.290734)
			(xy 346.846724 -302.318105) (xy 346.8389 -302.372286) (xy 346.823405 -302.42479) (xy 346.800556 -302.474536)
			(xy 346.770825 -302.520502) (xy 346.75318 -302.541432) (xy 346.747084 -302.548544) (xy 346.740734 -302.565562)
			(xy 346.740734 -302.650906) (xy 346.747084 -302.667924) (xy 346.75318 -302.675036) (xy 346.770799 -302.695984)
			(xy 346.800515 -302.741952) (xy 346.823355 -302.791696) (xy 346.838851 -302.844193) (xy 346.846684 -302.898366)
			(xy 346.84716 -302.925734) (xy 346.847108 -302.935722) (xy 346.846094 -302.955671) (xy 346.845128 -302.965612)
			(xy 346.843858 -302.976534) (xy 346.850462 -302.996854) (xy 346.908374 -303.060862) (xy 346.915854 -303.068598)
			(xy 346.935468 -303.077408) (xy 346.94622 -303.07788) (xy 348.870016 -303.07788) (xy 348.880087 -303.077468)
			(xy 348.898685 -303.069738) (xy 348.906084 -303.062894) (xy 349.096838 -302.871886) (xy 349.118473 -302.851142)
			(xy 349.166987 -302.815951) (xy 349.220407 -302.78878) (xy 349.277418 -302.770295) (xy 349.336619 -302.760952)
			(xy 349.366586 -302.76038) (xy 349.393822 -302.760822) (xy 349.44774 -302.768573) (xy 349.500005 -302.783918)
			(xy 349.549554 -302.806547) (xy 349.595379 -302.835997) (xy 349.636545 -302.871669) (xy 349.672215 -302.912837)
			(xy 349.701663 -302.958663) (xy 349.724289 -303.008214) (xy 349.739632 -303.06048) (xy 349.74738 -303.114398)
			(xy 349.74784 -303.141634) (xy 349.747307 -303.171606) (xy 349.737991 -303.230822) (xy 349.719515 -303.287847)
			(xy 349.692337 -303.341275) (xy 349.657126 -303.389787) (xy 349.636334 -303.411382) (xy 349.433896 -303.61382)
			(xy 349.427092 -303.621153) (xy 349.419448 -303.639627) (xy 349.419458 -303.65962) (xy 349.427119 -303.678087)
			(xy 349.433896 -303.685448) (xy 349.636334 -303.887886) (xy 349.657104 -303.909496) (xy 349.692291 -303.958017)
			(xy 349.719457 -304.011444) (xy 349.737936 -304.06846) (xy 349.747271 -304.127665) (xy 349.74784 -304.157634)
			(xy 349.7474 -304.184869) (xy 349.739644 -304.238783) (xy 349.724294 -304.291044) (xy 349.701663 -304.34059)
			(xy 349.672211 -304.38641) (xy 349.636539 -304.427573) (xy 349.595371 -304.46324) (xy 349.549547 -304.492686)
			(xy 349.499999 -304.51531) (xy 349.447736 -304.530654) (xy 349.393821 -304.538403) (xy 349.366586 -304.538888)
			(xy 349.336612 -304.538392) (xy 349.277396 -304.529065) (xy 349.22037 -304.51058) (xy 349.166943 -304.483393)
			(xy 349.118432 -304.448176) (xy 349.096838 -304.427382) (xy 348.906084 -304.236374) (xy 348.898687 -304.229531)
			(xy 348.880085 -304.221814) (xy 348.870016 -304.221388) (xy 333.181452 -304.221388) (xy 333.15148 -304.22085)
			(xy 333.092265 -304.211533) (xy 333.035241 -304.193058) (xy 332.981813 -304.165881) (xy 332.9333 -304.130672)
			(xy 332.911704 -304.109882) (xy 332.223872 -303.42205) (xy 332.203087 -303.400437) (xy 332.167828 -303.351941)
			(xy 332.140593 -303.298523) (xy 332.122055 -303.241502) (xy 332.112671 -303.182282) (xy 332.112112 -303.152302)
			(xy 332.112112 -297.234102) (xy 332.111739 -297.224057) (xy 332.104154 -297.205459) (xy 332.09738 -297.198034)
			(xy 326.58558 -291.686488) (xy 326.564749 -291.664918) (xy 326.529499 -291.616408) (xy 326.502275 -291.56298)
			(xy 326.483748 -291.505949) (xy 326.474373 -291.446722) (xy 326.47382 -291.41674) (xy 326.208273 -291.41674)
			(xy 326.194566 -291.461274) (xy 326.169894 -291.512627) (xy 326.137859 -291.559738) (xy 326.099172 -291.601561)
			(xy 326.054694 -291.637164) (xy 326.030336 -291.651944) (xy 326.02285 -291.656728) (xy 326.011449 -291.670334)
			(xy 326.005364 -291.687011) (xy 326.004936 -291.695886) (xy 326.004936 -291.74821) (xy 326.005262 -291.757107)
			(xy 326.011333 -291.773833) (xy 326.02277 -291.787463) (xy 326.030336 -291.792152) (xy 326.054707 -291.80691)
			(xy 326.099177 -291.842522) (xy 326.137858 -291.884351) (xy 326.169888 -291.931466) (xy 326.194555 -291.982821)
			(xy 326.211311 -292.037273) (xy 326.219784 -292.093612) (xy 326.220328 -292.122098) (xy 326.2199 -292.147932)
			(xy 326.212933 -292.199129) (xy 326.199125 -292.248919) (xy 326.178729 -292.296391) (xy 326.152118 -292.34068)
			(xy 326.119777 -292.380976) (xy 326.082298 -292.416542) (xy 326.061578 -292.431978) (xy 326.051926 -292.438836)
			(xy 326.041004 -292.459156) (xy 326.03821 -292.52545) (xy 326.038303 -292.53595) (xy 326.045914 -292.555494)
			(xy 326.052942 -292.563296) (xy 331.32395 -297.834304) (xy 331.330801 -297.8417) (xy 331.338542 -297.860299)
			(xy 331.338936 -297.870372) (xy 331.338936 -307.187854) (xy 331.33937 -307.197919) (xy 331.347102 -307.216506)
			(xy 331.353922 -307.223922) (xy 332.963774 -308.833774) (xy 332.972446 -308.841609) (xy 332.99454 -308.84915)
			(xy 333.006192 -308.848252) (xy 333.018143 -308.846832) (xy 333.042164 -308.845304) (xy 333.054198 -308.845204)
			(xy 333.080425 -308.845637) (xy 333.132385 -308.852812) (xy 333.182876 -308.867027) (xy 333.230947 -308.888015)
			(xy 333.275696 -308.915381) (xy 333.316281 -308.948611) (xy 333.351939 -308.98708) (xy 333.382 -309.030065)
			(xy 333.394304 -309.05323) (xy 333.400908 -309.06593) (xy 333.425292 -309.080916) (xy 333.681578 -309.080916)
		)
		(stroke
			(width 0)
			(type solid)
		)
		(fill yes)
		(layer "In9.Cu")
		(net "GND")
	)
	(gr_poly
		(pts
			(xy 140.58138 -417.892738) (xy 140.588987 -417.891228) (xy 140.602828 -417.884249) (xy 140.608558 -417.879022)
			(xy 140.716254 -417.771326) (xy 140.716762 -417.770818) (xy 140.723339 -417.763435) (xy 140.730778 -417.745136)
			(xy 140.73124 -417.735258) (xy 140.73124 -411.01518) (xy 140.730709 -411.005223) (xy 140.723055 -410.986833)
			(xy 140.709009 -410.972708) (xy 140.699998 -410.968444) (xy 140.68552 -410.962348) (xy 140.655548 -410.96819)
			(xy 136.886696 -414.737296) (xy 136.867903 -414.755379) (xy 136.82569 -414.786004) (xy 136.779205 -414.809646)
			(xy 136.729593 -414.825722) (xy 136.678076 -414.833836) (xy 136.652 -414.834324) (xy 118.322598 -414.834324)
			(xy 118.296523 -414.833854) (xy 118.245011 -414.825725) (xy 118.195405 -414.809636) (xy 118.148927 -414.785984)
			(xy 118.106723 -414.75535) (xy 118.087902 -414.737296) (xy 115.934236 -412.583376) (xy 115.915948 -412.575756)
			(xy 115.905788 -412.575756) (xy 115.874175 -412.574967) (xy 115.811547 -412.566203) (xy 115.750587 -412.549384)
			(xy 115.692325 -412.524796) (xy 115.637747 -412.492854) (xy 115.587777 -412.454098) (xy 115.54326 -412.409185)
			(xy 115.504948 -412.358873) (xy 115.473491 -412.304014) (xy 115.44942 -412.245537) (xy 115.433142 -412.18443)
			(xy 115.424934 -412.121727) (xy 115.424458 -412.090108) (xy 115.424955 -412.058309) (xy 115.433255 -411.995256)
			(xy 115.449715 -411.933826) (xy 115.474052 -411.875069) (xy 115.50585 -411.819992) (xy 115.544565 -411.769537)
			(xy 115.589535 -411.724567) (xy 115.63999 -411.685851) (xy 115.695067 -411.654053) (xy 115.753824 -411.629715)
			(xy 115.815254 -411.613256) (xy 115.878307 -411.604955) (xy 115.910106 -411.60446) (xy 115.941723 -411.604969)
			(xy 116.004421 -411.613177) (xy 116.065524 -411.629453) (xy 116.123998 -411.653522) (xy 116.178853 -411.684977)
			(xy 116.229161 -411.723286) (xy 116.274072 -411.767801) (xy 116.312825 -411.817767) (xy 116.344765 -411.872341)
			(xy 116.369352 -411.930599) (xy 116.386169 -411.991556) (xy 116.394932 -412.054179) (xy 116.395754 -412.08579)
			(xy 116.395754 -412.09595) (xy 116.403374 -412.114238) (xy 118.044976 -413.755586) (xy 118.052378 -413.762422)
			(xy 118.070976 -413.770131) (xy 118.081044 -413.770572) (xy 121.398792 -413.770572) (xy 121.408738 -413.770027)
			(xy 121.427098 -413.762352) (xy 121.441185 -413.748297) (xy 121.445528 -413.73933) (xy 121.451624 -413.724852)
			(xy 121.445782 -413.69488) (xy 120.334278 -412.583376) (xy 120.31599 -412.575756) (xy 120.30583 -412.575756)
			(xy 120.274215 -412.57497) (xy 120.211583 -412.56621) (xy 120.150618 -412.549395) (xy 120.092352 -412.524809)
			(xy 120.037769 -412.492868) (xy 119.987794 -412.454113) (xy 119.943273 -412.409199) (xy 119.904957 -412.358886)
			(xy 119.873497 -412.304025) (xy 119.849423 -412.245545) (xy 119.833144 -412.184435) (xy 119.824934 -412.121729)
			(xy 119.8245 -412.090108) (xy 119.824997 -412.05831) (xy 119.833297 -411.995259) (xy 119.849757 -411.933831)
			(xy 119.874095 -411.875077) (xy 119.905894 -411.820002) (xy 119.94461 -411.76955) (xy 119.98958 -411.724583)
			(xy 120.040036 -411.685871) (xy 120.095113 -411.654077) (xy 120.153869 -411.629744) (xy 120.215298 -411.61329)
			(xy 120.27835 -411.604994) (xy 120.310148 -411.60446) (xy 120.341763 -411.604971) (xy 120.404458 -411.613184)
			(xy 120.465556 -411.629464) (xy 120.524025 -411.653535) (xy 120.578875 -411.684992) (xy 120.629179 -411.723301)
			(xy 120.674085 -411.767815) (xy 120.712834 -411.817781) (xy 120.744771 -411.872353) (xy 120.769355 -411.930608)
			(xy 120.78617 -411.991561) (xy 120.794932 -412.054181) (xy 120.795796 -412.08579) (xy 120.795796 -412.09595)
			(xy 120.803416 -412.114238) (xy 122.107198 -413.417766) (xy 122.114595 -413.424616) (xy 122.133193 -413.432357)
			(xy 122.143266 -413.432752) (xy 125.461014 -413.432752) (xy 125.470968 -413.43222) (xy 125.489349 -413.42456)
			(xy 125.503455 -413.410505) (xy 125.50775 -413.40151) (xy 125.513846 -413.387032) (xy 125.508004 -413.35706)
			(xy 124.73432 -412.583376) (xy 124.716032 -412.575756) (xy 124.705872 -412.575756) (xy 124.67426 -412.574966)
			(xy 124.611633 -412.5662) (xy 124.550675 -412.54938) (xy 124.492415 -412.524791) (xy 124.437839 -412.492848)
			(xy 124.387871 -412.454092) (xy 124.343355 -412.409179) (xy 124.305045 -412.358868) (xy 124.273589 -412.30401)
			(xy 124.249519 -412.245534) (xy 124.233242 -412.184428) (xy 124.225033 -412.121726) (xy 124.224542 -412.090108)
			(xy 124.225061 -412.05831) (xy 124.233361 -411.995259) (xy 124.24982 -411.933831) (xy 124.274156 -411.875076)
			(xy 124.305952 -411.820001) (xy 124.344665 -411.769547) (xy 124.389633 -411.724577) (xy 124.440086 -411.685862)
			(xy 124.49516 -411.654063) (xy 124.553914 -411.629726) (xy 124.615342 -411.613265) (xy 124.678392 -411.604963)
			(xy 124.71019 -411.60446) (xy 124.741807 -411.604968) (xy 124.804508 -411.613174) (xy 124.865612 -411.629449)
			(xy 124.924088 -411.653517) (xy 124.978945 -411.684972) (xy 125.029255 -411.72328) (xy 125.074167 -411.767795)
			(xy 125.112922 -411.817762) (xy 125.144863 -411.872337) (xy 125.169451 -411.930596) (xy 125.186268 -411.991554)
			(xy 125.195032 -412.054178) (xy 125.195838 -412.08579) (xy 125.195838 -412.09595) (xy 125.203458 -412.114238)
			(xy 126.16942 -413.079946) (xy 126.176817 -413.086795) (xy 126.195416 -413.094531) (xy 126.205488 -413.094932)
			(xy 129.522982 -413.094932) (xy 129.532932 -413.09439) (xy 129.551302 -413.086722) (xy 129.565407 -413.072674)
			(xy 129.569718 -413.06369) (xy 129.575814 -413.049212) (xy 129.569972 -413.01924) (xy 129.134108 -412.583376)
			(xy 129.11582 -412.575756) (xy 129.10566 -412.575756) (xy 129.074048 -412.574965) (xy 129.011423 -412.566198)
			(xy 128.950466 -412.549377) (xy 128.892207 -412.524787) (xy 128.837633 -412.492844) (xy 128.787666 -412.454088)
			(xy 128.743151 -412.409175) (xy 128.704842 -412.358864) (xy 128.673387 -412.304007) (xy 128.649318 -412.245531)
			(xy 128.633041 -412.184426) (xy 128.624833 -412.121726) (xy 128.62433 -412.090108) (xy 128.624849 -412.05831)
			(xy 128.633149 -411.995258) (xy 128.649608 -411.933829) (xy 128.673943 -411.875074) (xy 128.70574 -411.819998)
			(xy 128.744453 -411.769543) (xy 128.78942 -411.724573) (xy 128.839873 -411.685856) (xy 128.894947 -411.654056)
			(xy 128.953701 -411.629717) (xy 129.015129 -411.613255) (xy 129.07818 -411.604951) (xy 129.109978 -411.60446)
			(xy 129.141596 -411.604967) (xy 129.204297 -411.613172) (xy 129.265403 -411.629446) (xy 129.32388 -411.653513)
			(xy 129.378738 -411.684968) (xy 129.42905 -411.723276) (xy 129.473963 -411.767791) (xy 129.512719 -411.817759)
			(xy 129.544661 -411.872334) (xy 129.56925 -411.930594) (xy 129.586068 -411.991552) (xy 129.594832 -412.054178)
			(xy 129.595626 -412.08579) (xy 129.595626 -412.09595) (xy 129.603246 -412.114238) (xy 130.129788 -412.640526)
			(xy 130.137182 -412.647382) (xy 130.155781 -412.655133) (xy 130.165856 -412.655512) (xy 133.124194 -412.655512)
			(xy 133.134191 -412.655017) (xy 133.152671 -412.647383) (xy 133.166864 -412.633298) (xy 133.171184 -412.62427)
			(xy 133.17728 -412.609792) (xy 133.171184 -412.57982) (xy 133.095746 -412.504382) (xy 133.072835 -412.480805)
			(xy 133.03186 -412.429391) (xy 132.996897 -412.373714) (xy 132.968387 -412.314472) (xy 132.946687 -412.252412)
			(xy 132.93207 -412.188313) (xy 132.924721 -412.12298) (xy 132.924296 -412.090108) (xy 132.924809 -412.054709)
			(xy 132.933342 -411.984428) (xy 132.950284 -411.915688) (xy 132.975389 -411.849492) (xy 133.00829 -411.786804)
			(xy 133.048508 -411.728539) (xy 133.095455 -411.675547) (xy 133.148449 -411.6286) (xy 133.206714 -411.588384)
			(xy 133.269403 -411.555484) (xy 133.3356 -411.530381) (xy 133.40434 -411.513439) (xy 133.474621 -411.504908)
			(xy 133.51002 -411.504384) (xy 133.542894 -411.504813) (xy 133.60823 -411.512147) (xy 133.672333 -411.526753)
			(xy 133.734397 -411.548449) (xy 133.79364 -411.57696) (xy 133.849316 -411.611928) (xy 133.900725 -411.652913)
			(xy 133.924294 -411.675834) (xy 134.195566 -411.947106) (xy 134.202968 -411.953942) (xy 134.221566 -411.961651)
			(xy 134.231634 -411.962092) (xy 135.723884 -411.962092) (xy 135.731715 -411.960977) (xy 135.746202 -411.954646)
			(xy 135.752332 -411.949646) (xy 138.38809 -409.313888) (xy 138.3949 -409.306542) (xy 138.402629 -409.28808)
			(xy 138.403076 -409.278074) (xy 138.403076 -408.294586) (xy 138.402648 -408.284543) (xy 138.394937 -408.265996)
			(xy 138.3807 -408.251827) (xy 138.37158 -408.247596) (xy 138.357102 -408.241754) (xy 138.327384 -408.247596)
			(xy 136.409684 -410.165296) (xy 136.390891 -410.183378) (xy 136.348677 -410.214002) (xy 136.302192 -410.237642)
			(xy 136.25258 -410.253716) (xy 136.201064 -410.261829) (xy 136.174988 -410.262324) (xy 136.169908 -410.262324)
			(xy 136.159887 -410.262743) (xy 136.141372 -410.270412) (xy 136.127203 -410.284585) (xy 136.11954 -410.303103)
			(xy 136.119108 -410.313124) (xy 136.119108 -410.327348) (xy 136.126474 -410.33954) (xy 136.142965 -410.368019)
			(xy 136.168972 -410.428472) (xy 136.186597 -410.491878) (xy 136.195519 -410.55708) (xy 136.19607 -410.589984)
			(xy 136.19607 -410.590238) (xy 136.195562 -410.602684) (xy 136.194254 -410.633924) (xy 136.184601 -410.6957)
			(xy 136.167101 -410.755728) (xy 136.142043 -410.813013) (xy 136.10984 -410.866609) (xy 136.071027 -410.91563)
			(xy 136.026243 -410.959265) (xy 135.976231 -410.996792) (xy 135.921816 -411.027592) (xy 135.863899 -411.051154)
			(xy 135.803438 -411.067089) (xy 135.741431 -411.075134) (xy 135.710168 -411.075632) (xy 135.678373 -411.07511)
			(xy 135.615327 -411.066806) (xy 135.553904 -411.050344) (xy 135.495155 -411.026005) (xy 135.440086 -410.994207)
			(xy 135.389638 -410.955493) (xy 135.344675 -410.910525) (xy 135.305966 -410.860074) (xy 135.274173 -410.805001)
			(xy 135.249841 -410.74625) (xy 135.233385 -410.684826) (xy 135.225087 -410.621779) (xy 135.22452 -410.589984)
			(xy 135.224567 -410.577261) (xy 135.225836 -410.551848) (xy 135.22706 -410.539184) (xy 135.227568 -410.534104)
			(xy 135.232008 -410.500412) (xy 135.249094 -410.434637) (xy 135.261604 -410.40304) (xy 135.266684 -410.391102)
			(xy 135.264398 -410.36621) (xy 135.210296 -410.285184) (xy 135.20278 -410.274997) (xy 135.18052 -410.263008)
			(xy 135.167878 -410.262324) (xy 134.554214 -410.262324) (xy 134.528138 -410.261856) (xy 134.476625 -410.253729)
			(xy 134.427017 -410.237641) (xy 134.380538 -410.21399) (xy 134.338332 -410.183358) (xy 134.319518 -410.165296)
			(xy 133.991096 -409.836874) (xy 133.983754 -409.830056) (xy 133.965291 -409.822314) (xy 133.955282 -409.821888)
			(xy 133.876034 -409.821888) (xy 133.857746 -409.829508) (xy 133.85038 -409.83662) (xy 133.827606 -409.8583)
			(xy 133.77744 -409.896211) (xy 133.7228 -409.927327) (xy 133.6646 -409.95113) (xy 133.603814 -409.967219)
			(xy 133.54146 -409.975327) (xy 133.51002 -409.975812) (xy 133.478222 -409.975316) (xy 133.415169 -409.967017)
			(xy 133.353738 -409.950558) (xy 133.294982 -409.926221) (xy 133.239906 -409.894423) (xy 133.189451 -409.855707)
			(xy 133.144482 -409.810737) (xy 133.105768 -409.760281) (xy 133.073972 -409.705203) (xy 133.049637 -409.646446)
			(xy 133.03318 -409.585016) (xy 133.024883 -409.521962) (xy 133.024372 -409.490164) (xy 133.024905 -409.457504)
			(xy 133.033664 -409.392774) (xy 133.051019 -409.329802) (xy 133.076656 -409.269724) (xy 133.110114 -409.213623)
			(xy 133.150789 -409.162513) (xy 133.197946 -409.117315) (xy 133.250736 -409.078844) (xy 133.308205 -409.047796)
			(xy 133.33857 -409.035758) (xy 133.350247 -409.03057) (xy 133.366912 -409.011243) (xy 133.37032 -408.998928)
			(xy 133.38556 -408.927808) (xy 133.38683 -408.91714) (xy 133.38683 -408.916632) (xy 133.386327 -408.90658)
			(xy 133.378609 -408.888016) (xy 133.371844 -408.880564) (xy 133.095746 -408.604466) (xy 133.072836 -408.580888)
			(xy 133.031862 -408.529474) (xy 132.996901 -408.473797) (xy 132.968392 -408.414555) (xy 132.946694 -408.352495)
			(xy 132.932079 -408.288396) (xy 132.924732 -408.223064) (xy 132.924296 -408.190192) (xy 132.92481 -408.154794)
			(xy 132.933344 -408.084514) (xy 132.950288 -408.015776) (xy 132.975394 -407.949581) (xy 133.008296 -407.886895)
			(xy 133.048513 -407.828632) (xy 133.095461 -407.775641) (xy 133.148454 -407.728696) (xy 133.206719 -407.688481)
			(xy 133.269406 -407.655582) (xy 133.335603 -407.63048) (xy 133.404342 -407.613539) (xy 133.474622 -407.605008)
			(xy 133.51002 -407.604468) (xy 133.542894 -407.604897) (xy 133.60823 -407.61223) (xy 133.672334 -407.626836)
			(xy 133.734398 -407.648531) (xy 133.793642 -407.677042) (xy 133.849319 -407.71201) (xy 133.900728 -407.752994)
			(xy 133.924294 -407.775918) (xy 134.195058 -408.046682) (xy 134.202459 -408.053521) (xy 134.221057 -408.061237)
			(xy 134.231126 -408.061668) (xy 135.993886 -408.061668) (xy 136.000998 -408.06116) (xy 137.29589 -406.766268)
			(xy 137.302697 -406.758921) (xy 137.310419 -406.740459) (xy 137.310876 -406.730454) (xy 137.310876 -405.367998)
			(xy 137.310451 -405.357954) (xy 137.302742 -405.339403) (xy 137.288505 -405.32523) (xy 137.27938 -405.321008)
			(xy 137.264902 -405.315166) (xy 137.235184 -405.321008) (xy 136.302496 -406.253696) (xy 136.286713 -406.268964)
			(xy 136.251826 -406.295632) (xy 136.213726 -406.317465) (xy 136.19353 -406.326086) (xy 136.18337 -406.330404)
			(xy 136.168638 -406.34539) (xy 136.135364 -406.436322) (xy 136.136634 -406.45715) (xy 136.141714 -406.466802)
			(xy 136.154604 -406.492711) (xy 136.174833 -406.54693) (xy 136.188486 -406.603166) (xy 136.195369 -406.660625)
			(xy 136.195816 -406.68956) (xy 136.195816 -406.690068) (xy 136.195296 -406.721865) (xy 136.186995 -406.784915)
			(xy 136.170536 -406.846342) (xy 136.1462 -406.905095) (xy 136.114403 -406.960169) (xy 136.075689 -407.010621)
			(xy 136.030721 -407.055589) (xy 135.980269 -407.094303) (xy 135.925195 -407.1261) (xy 135.866442 -407.150436)
			(xy 135.805015 -407.166895) (xy 135.741965 -407.175196) (xy 135.678371 -407.175196) (xy 135.615321 -407.166895)
			(xy 135.553894 -407.150436) (xy 135.495141 -407.1261) (xy 135.440067 -407.094303) (xy 135.389615 -407.055589)
			(xy 135.344647 -407.010621) (xy 135.305933 -406.960169) (xy 135.274136 -406.905095) (xy 135.2498 -406.846342)
			(xy 135.233341 -406.784915) (xy 135.22504 -406.721865) (xy 135.22452 -406.690068) (xy 135.224568 -406.677345)
			(xy 135.225837 -406.651932) (xy 135.22706 -406.639268) (xy 135.227568 -406.634188) (xy 135.232441 -406.597887)
			(xy 135.251704 -406.527226) (xy 135.265922 -406.493472) (xy 135.271256 -406.481534) (xy 135.269224 -406.456134)
			(xy 135.21563 -406.373838) (xy 135.210772 -406.366898) (xy 135.197438 -406.356464) (xy 135.181424 -406.350967)
			(xy 135.172958 -406.350724) (xy 133.939026 -406.350724) (xy 133.91295 -406.350256) (xy 133.861435 -406.342131)
			(xy 133.811827 -406.326045) (xy 133.765346 -406.302395) (xy 133.723139 -406.271763) (xy 133.70433 -406.253696)
			(xy 133.53415 -406.083262) (xy 133.515862 -406.075642) (xy 133.505702 -406.075642) (xy 133.474089 -406.074854)
			(xy 133.41146 -406.066091) (xy 133.350499 -406.049274) (xy 133.292236 -406.024686) (xy 133.237658 -405.992744)
			(xy 133.187687 -405.953988) (xy 133.14317 -405.909074) (xy 133.104858 -405.858762) (xy 133.073401 -405.803903)
			(xy 133.049331 -405.745424) (xy 133.033054 -405.684317) (xy 133.024847 -405.621613) (xy 133.024372 -405.589994)
			(xy 133.024419 -405.577271) (xy 133.025687 -405.551858) (xy 133.026912 -405.539194) (xy 133.030755 -405.50749)
			(xy 133.045701 -405.445398) (xy 133.068654 -405.385801) (xy 133.099219 -405.329725) (xy 133.13687 -405.278139)
			(xy 133.180955 -405.231931) (xy 133.230716 -405.191899) (xy 133.285294 -405.158734) (xy 133.343747 -405.133006)
			(xy 133.405068 -405.11516) (xy 133.468199 -405.105504) (xy 133.500114 -405.104346) (xy 133.510274 -405.104346)
			(xy 133.5419 -405.104873) (xy 133.604611 -405.11312) (xy 133.665722 -405.129438) (xy 133.724196 -405.153553)
			(xy 133.779045 -405.185055) (xy 133.829341 -405.223411) (xy 133.852158 -405.245316) (xy 133.859524 -405.252682)
			(xy 133.886448 -405.264112) (xy 133.891187 -405.265986) (xy 133.901166 -405.268042) (xy 133.90626 -405.268176)
			(xy 134.793736 -405.268176) (xy 134.819025 -405.268674) (xy 134.868981 -405.276587) (xy 134.917085 -405.292212)
			(xy 134.962155 -405.315166) (xy 135.003082 -405.344884) (xy 135.02132 -405.36241) (xy 135.04672 -405.388064)
			(xy 135.054848 -405.396192) (xy 135.061869 -405.402618) (xy 135.079315 -405.410193) (xy 135.098321 -405.410902)
			(xy 135.107426 -405.40813) (xy 135.193532 -405.377904) (xy 135.201807 -405.374683) (xy 135.215567 -405.363475)
			(xy 135.224631 -405.348218) (xy 135.226552 -405.33955) (xy 135.228076 -405.33193) (xy 135.22833 -405.330406)
			(xy 135.232394 -405.303736) (xy 135.232394 -405.303482) (xy 135.234379 -405.292596) (xy 135.239207 -405.270997)
			(xy 135.242046 -405.260302) (xy 135.245348 -405.248618) (xy 135.240776 -405.225504) (xy 135.184642 -405.15159)
			(xy 135.177049 -405.142603) (xy 135.156004 -405.132144) (xy 135.144256 -405.131524) (xy 134.019798 -405.131524)
			(xy 133.993723 -405.131054) (xy 133.942211 -405.122925) (xy 133.892605 -405.106836) (xy 133.846127 -405.083184)
			(xy 133.803923 -405.05255) (xy 133.785102 -405.034496) (xy 133.53415 -404.78329) (xy 133.515862 -404.77567)
			(xy 133.505702 -404.77567) (xy 133.47409 -404.774882) (xy 133.411465 -404.766119) (xy 133.350508 -404.749301)
			(xy 133.292249 -404.724712) (xy 133.237676 -404.692769) (xy 133.18771 -404.654012) (xy 133.143198 -404.609097)
			(xy 133.104893 -404.558785) (xy 133.073443 -404.503925) (xy 133.049381 -404.445447) (xy 133.033113 -404.384341)
			(xy 133.024914 -404.32164) (xy 133.024372 -404.290022) (xy 133.024868 -404.258223) (xy 133.033167 -404.195169)
			(xy 133.049625 -404.133738) (xy 133.073962 -404.074981) (xy 133.10576 -404.019903) (xy 133.144475 -403.969447)
			(xy 133.189445 -403.924476) (xy 133.239901 -403.885761) (xy 133.294979 -403.853963) (xy 133.353736 -403.829626)
			(xy 133.415167 -403.813167) (xy 133.478221 -403.804868) (xy 133.51002 -403.804374) (xy 133.541638 -403.804883)
			(xy 133.60434 -403.813092) (xy 133.665445 -403.829369) (xy 133.723922 -403.853438) (xy 133.778781 -403.884893)
			(xy 133.829094 -403.9232) (xy 133.87401 -403.967713) (xy 133.912769 -404.017679) (xy 133.944717 -404.072252)
			(xy 133.969312 -404.13051) (xy 133.986138 -404.191466) (xy 133.994912 -404.254091) (xy 133.995668 -404.285704)
			(xy 133.995668 -404.295864) (xy 134.003288 -404.314152) (xy 134.090156 -404.400766) (xy 134.097556 -404.407607)
			(xy 134.116154 -404.415327) (xy 134.126224 -404.415752) (xy 135.824468 -404.415752) (xy 135.833911 -404.415258)
			(xy 135.851493 -404.408344) (xy 135.858758 -404.40229) (xy 136.61009 -403.650704) (xy 136.616902 -403.64336)
			(xy 136.624638 -403.624897) (xy 136.625076 -403.61489) (xy 136.625076 -402.467318) (xy 136.624654 -402.457271)
			(xy 136.616949 -402.438714) (xy 136.602713 -402.424535) (xy 136.59358 -402.420328) (xy 136.579102 -402.414486)
			(xy 136.549384 -402.420328) (xy 136.203436 -402.766022) (xy 136.195816 -402.78431) (xy 136.195816 -402.79447)
			(xy 136.19503 -402.826084) (xy 136.18627 -402.888714) (xy 136.169454 -402.949677) (xy 136.144868 -403.007941)
			(xy 136.112927 -403.062521) (xy 136.074171 -403.112493) (xy 136.029256 -403.157011) (xy 135.978943 -403.195323)
			(xy 135.924082 -403.22678) (xy 135.865602 -403.250849) (xy 135.804493 -403.267124) (xy 135.741788 -403.275328)
			(xy 135.710168 -403.2758) (xy 135.678372 -403.2753) (xy 135.615325 -403.266996) (xy 135.553901 -403.250533)
			(xy 135.495151 -403.226193) (xy 135.440082 -403.194392) (xy 135.389634 -403.155676) (xy 135.344671 -403.110706)
			(xy 135.305963 -403.060252) (xy 135.274172 -403.005177) (xy 135.249842 -402.946423) (xy 135.233389 -402.884997)
			(xy 135.225094 -402.821948) (xy 135.22452 -402.790152) (xy 135.225031 -402.758536) (xy 135.233243 -402.69584)
			(xy 135.249523 -402.634739) (xy 135.273594 -402.576268) (xy 135.30505 -402.521415) (xy 135.343359 -402.471109)
			(xy 135.387872 -402.4262) (xy 135.437838 -402.387447) (xy 135.492409 -402.355506) (xy 135.550665 -402.330918)
			(xy 135.611619 -402.314098) (xy 135.67424 -402.305331) (xy 135.70585 -402.304504) (xy 135.71601 -402.304504)
			(xy 135.734298 -402.296884) (xy 136.12749 -401.903438) (xy 136.134292 -401.89609) (xy 136.142004 -401.877627)
			(xy 136.142476 -401.867624) (xy 136.142476 -401.86737) (xy 136.141983 -401.857368) (xy 136.134317 -401.838891)
			(xy 136.120164 -401.824753) (xy 136.101678 -401.817107) (xy 136.091676 -401.81657) (xy 136.081262 -401.81657)
			(xy 136.06272 -401.824444) (xy 136.055354 -401.83181) (xy 136.032475 -401.8542) (xy 135.981855 -401.893388)
			(xy 135.926525 -401.925585) (xy 135.867445 -401.950234) (xy 135.805638 -401.966906) (xy 135.742176 -401.975313)
			(xy 135.710168 -401.975828) (xy 135.678374 -401.975306) (xy 135.61533 -401.967002) (xy 135.553909 -401.950541)
			(xy 135.495161 -401.926204) (xy 135.440093 -401.894407) (xy 135.389647 -401.855695) (xy 135.344684 -401.810729)
			(xy 135.305975 -401.76028) (xy 135.274182 -401.70521) (xy 135.249849 -401.646461) (xy 135.233391 -401.585039)
			(xy 135.225092 -401.521994) (xy 135.225092 -401.458406) (xy 135.233391 -401.395361) (xy 135.249849 -401.333939)
			(xy 135.274182 -401.27519) (xy 135.305975 -401.22012) (xy 135.344684 -401.169671) (xy 135.389647 -401.124705)
			(xy 135.440093 -401.085993) (xy 135.495161 -401.054196) (xy 135.553909 -401.029859) (xy 135.61533 -401.013398)
			(xy 135.678374 -401.005094) (xy 135.710168 -401.004532) (xy 135.718804 -401.004532) (xy 135.729218 -401.004786)
			(xy 135.748268 -400.997166) (xy 135.791956 -400.953478) (xy 136.12749 -400.61769) (xy 136.1343 -400.610345)
			(xy 136.14203 -400.591882) (xy 136.142476 -400.581876) (xy 136.142476 -399.327878) (xy 136.142056 -399.318299)
			(xy 136.135019 -399.300477) (xy 136.121963 -399.286454) (xy 136.11352 -399.281904) (xy 136.07034 -399.26133)
			(xy 136.069832 -399.26133) (xy 136.056878 -399.25498) (xy 136.026398 -399.25879) (xy 136.015222 -399.268442)
			(xy 136.013698 -399.269458) (xy 136.012174 -399.270728) (xy 136.002776 -399.27784) (xy 135.977405 -399.296374)
			(xy 135.922795 -399.327447) (xy 135.864633 -399.351217) (xy 135.803891 -399.367287) (xy 135.741584 -399.375387)
			(xy 135.710168 -399.375884) (xy 135.70204 -399.375884) (xy 135.670589 -399.374858) (xy 135.608333 -399.365684)
			(xy 135.547783 -399.348548) (xy 135.489952 -399.323735) (xy 135.435811 -399.291663) (xy 135.386264 -399.252867)
			(xy 135.342143 -399.207998) (xy 135.304185 -399.157807) (xy 135.273026 -399.103134) (xy 135.249189 -399.044895)
			(xy 135.233072 -398.984066) (xy 135.224946 -398.921665) (xy 135.224945 -398.858736) (xy 135.233072 -398.796335)
			(xy 135.249188 -398.735506) (xy 135.273026 -398.677267) (xy 135.304184 -398.622594) (xy 135.342142 -398.572403)
			(xy 135.386263 -398.527533) (xy 135.43581 -398.488738) (xy 135.489951 -398.456665) (xy 135.547781 -398.431853)
			(xy 135.608331 -398.414716) (xy 135.670587 -398.405543) (xy 135.70204 -398.404588) (xy 135.710168 -398.404588)
			(xy 135.741585 -398.405081) (xy 135.803894 -398.413179) (xy 135.864638 -398.429245) (xy 135.922804 -398.453011)
			(xy 135.977419 -398.484078) (xy 136.002776 -398.502632) (xy 136.012936 -398.510252) (xy 136.013444 -398.51076)
			(xy 136.017 -398.513554) (xy 136.024658 -398.518925) (xy 136.042574 -398.524247) (xy 136.061204 -398.522761)
			(xy 136.069832 -398.519142) (xy 136.070086 -398.519142) (xy 136.11352 -398.498568) (xy 136.122023 -398.494094)
			(xy 136.135133 -398.480068) (xy 136.142143 -398.462195) (xy 136.142476 -398.452594) (xy 136.142476 -398.027652)
			(xy 136.142069 -398.018065) (xy 136.135048 -398.000223) (xy 136.121994 -397.986177) (xy 136.11352 -397.981678)
			(xy 136.07034 -397.961104) (xy 136.069832 -397.961104) (xy 136.056878 -397.954754) (xy 136.026398 -397.958564)
			(xy 136.015222 -397.968216) (xy 136.013698 -397.969232) (xy 136.012174 -397.970502) (xy 136.002776 -397.977614)
			(xy 135.977404 -397.996145) (xy 135.922793 -398.027214) (xy 135.864631 -398.05098) (xy 135.803889 -398.067047)
			(xy 135.741583 -398.075146) (xy 135.710168 -398.075658) (xy 135.70204 -398.075658) (xy 135.67059 -398.074632)
			(xy 135.608338 -398.065458) (xy 135.547791 -398.048323) (xy 135.489964 -398.023512) (xy 135.435825 -397.991441)
			(xy 135.386281 -397.952648) (xy 135.342162 -397.907781) (xy 135.304206 -397.857592) (xy 135.273049 -397.802922)
			(xy 135.249213 -397.744687) (xy 135.233097 -397.683861) (xy 135.224971 -397.621463) (xy 135.224971 -397.558538)
			(xy 135.233097 -397.49614) (xy 135.249213 -397.435314) (xy 135.273049 -397.377078) (xy 135.304206 -397.322408)
			(xy 135.342162 -397.272219) (xy 135.386281 -397.227353) (xy 135.435825 -397.188559) (xy 135.489964 -397.156488)
			(xy 135.547791 -397.131677) (xy 135.608337 -397.114542) (xy 135.67059 -397.105368) (xy 135.70204 -397.104362)
			(xy 135.710168 -397.104362) (xy 135.741584 -397.104855) (xy 135.803893 -397.112955) (xy 135.864636 -397.129023)
			(xy 135.9228 -397.152791) (xy 135.977412 -397.183862) (xy 136.002776 -397.202406) (xy 136.012936 -397.210026)
			(xy 136.013444 -397.210534) (xy 136.017 -397.213328) (xy 136.024657 -397.218702) (xy 136.042574 -397.224026)
			(xy 136.061205 -397.222539) (xy 136.069832 -397.218916) (xy 136.070086 -397.218916) (xy 136.11352 -397.198342)
			(xy 136.12202 -397.193867) (xy 136.135122 -397.179839) (xy 136.142123 -397.161967) (xy 136.142476 -397.152368)
			(xy 136.142476 -392.836146) (xy 136.142922 -392.811025) (xy 136.150468 -392.761355) (xy 136.165424 -392.713393)
			(xy 136.176004 -392.690604) (xy 136.178544 -392.68527) (xy 136.181084 -392.674348) (xy 136.181084 -392.494516)
			(xy 136.181588 -392.468504) (xy 136.189956 -392.417158) (xy 136.206463 -392.367823) (xy 136.230678 -392.321779)
			(xy 136.261975 -392.280222) (xy 136.280398 -392.261852) (xy 136.281414 -392.26109) (xy 139.916408 -388.626096)
			(xy 139.925713 -388.617028) (xy 139.945547 -388.600241) (xy 139.956032 -388.592568) (xy 139.972288 -388.581646)
			(xy 139.984579 -388.574102) (xy 140.010271 -388.561) (xy 140.023596 -388.555484) (xy 140.033248 -388.55142)
			(xy 140.447522 -388.137146) (xy 140.454919 -388.130298) (xy 140.473518 -388.122564) (xy 140.48359 -388.12216)
			(xy 143.02359 -388.12216) (xy 143.031972 -388.121398) (xy 143.039579 -388.119887) (xy 143.053418 -388.112905)
			(xy 143.05915 -388.107682) (xy 143.078454 -388.088378) (xy 143.243808 -387.92277) (xy 143.262024 -387.905216)
			(xy 143.302948 -387.87548) (xy 143.348021 -387.852515) (xy 143.396133 -387.836889) (xy 143.446099 -387.828986)
			(xy 143.471392 -387.828536) (xy 143.873982 -387.828536) (xy 143.887444 -387.826758) (xy 143.906494 -387.821424)
			(xy 143.911828 -387.818376) (xy 143.933407 -387.806608) (xy 143.97894 -387.788093) (xy 144.026469 -387.775564)
			(xy 144.075212 -387.769227) (xy 144.099788 -387.768846) (xy 144.100296 -387.768846) (xy 144.113034 -387.768924)
			(xy 144.138455 -387.770577) (xy 144.151096 -387.772148) (xy 144.177387 -387.776146) (xy 144.228598 -387.79048)
			(xy 144.277321 -387.811788) (xy 144.322612 -387.839658) (xy 144.363593 -387.873549) (xy 144.399469 -387.912804)
			(xy 144.429544 -387.956661) (xy 144.453236 -388.004271) (xy 144.470085 -388.054711) (xy 144.475454 -388.080758)
			(xy 144.478756 -388.099046) (xy 144.506696 -388.12216) (xy 145.082514 -388.12216) (xy 145.089626 -388.121652)
			(xy 145.206974 -388.004304) (xy 145.225767 -387.986219) (xy 145.267979 -387.95559) (xy 145.314463 -387.931945)
			(xy 145.364076 -387.915864) (xy 145.415593 -387.907745) (xy 145.44167 -387.907276) (xy 146.386042 -387.907276)
			(xy 146.412119 -387.907741) (xy 146.463636 -387.915862) (xy 146.513248 -387.931944) (xy 146.559732 -387.955591)
			(xy 146.601943 -387.986221) (xy 146.620738 -388.004304) (xy 146.723608 -388.107174) (xy 146.731006 -388.114022)
			(xy 146.749604 -388.121758) (xy 146.759676 -388.12216) (xy 146.846544 -388.12216) (xy 146.86534 -388.12216)
			(xy 146.89328 -388.0993) (xy 146.896836 -388.081012) (xy 146.902264 -388.055236) (xy 146.919271 -388.005382)
			(xy 146.942977 -387.958343) (xy 146.972931 -387.915014) (xy 147.008563 -387.87622) (xy 147.049195 -387.842698)
			(xy 147.094053 -387.815088) (xy 147.142285 -387.793913) (xy 147.192971 -387.779577) (xy 147.245148 -387.772354)
			(xy 147.271486 -387.771894) (xy 147.298952 -387.772369) (xy 147.353318 -387.780231) (xy 147.405999 -387.795795)
			(xy 147.455909 -387.818741) (xy 147.50202 -387.848596) (xy 147.543382 -387.884744) (xy 147.579142 -387.926441)
			(xy 147.608565 -387.972829) (xy 147.620228 -387.9977) (xy 147.625979 -388.008621) (xy 147.64535 -388.023858)
			(xy 147.657312 -388.02691) (xy 147.739354 -388.042404) (xy 147.751662 -388.044107) (xy 147.775378 -388.036796)
			(xy 147.784566 -388.028434) (xy 149.016974 -386.796026) (xy 149.017482 -386.795518) (xy 149.024057 -386.788134)
			(xy 149.031492 -386.769835) (xy 149.03196 -386.759958) (xy 149.03196 -385.830826) (xy 149.031642 -385.822071)
			(xy 149.02579 -385.805574) (xy 149.02053 -385.798568) (xy 149.004319 -385.778058) (xy 148.977071 -385.733441)
			(xy 148.956173 -385.685521) (xy 148.942015 -385.635195) (xy 148.934865 -385.583407) (xy 148.934424 -385.557268)
			(xy 148.934865 -385.531269) (xy 148.941925 -385.479752) (xy 148.955911 -385.429669) (xy 148.976562 -385.381948)
			(xy 149.003499 -385.33747) (xy 149.019514 -385.316984) (xy 149.021038 -385.315206) (xy 149.023324 -385.31165)
			(xy 149.027302 -385.305289) (xy 149.031696 -385.290953) (xy 149.03196 -385.283456) (xy 149.03196 -382.797304)
			(xy 149.03182 -382.792007) (xy 149.029641 -382.781638) (xy 149.027642 -382.77673) (xy 149.015196 -382.748536)
			(xy 149.007322 -382.741424) (xy 148.987853 -382.722825) (xy 148.953688 -382.681209) (xy 148.925549 -382.635304)
			(xy 148.903967 -382.585975) (xy 148.889348 -382.534154) (xy 148.88197 -382.480819) (xy 148.88197 -382.426976)
			(xy 148.889349 -382.37364) (xy 148.903969 -382.32182) (xy 148.925552 -382.272492) (xy 148.953691 -382.226587)
			(xy 148.987857 -382.184971) (xy 149.007322 -382.166368) (xy 149.015196 -382.159256) (xy 149.027642 -382.131062)
			(xy 149.029673 -382.126164) (xy 149.031851 -382.115789) (xy 149.03196 -382.110488) (xy 149.03196 -376.728736)
			(xy 149.0319 -376.72513) (xy 149.030886 -376.717989) (xy 149.029928 -376.714512) (xy 143.81607 -358.784398)
			(xy 143.812501 -358.774028) (xy 143.798179 -358.757448) (xy 143.778257 -358.748331) (xy 143.767302 -358.747822)
			(xy 143.75892 -358.747822) (xy 143.731075 -358.747285) (xy 143.676063 -358.73862) (xy 143.623071 -358.721497)
			(xy 143.57339 -358.696333) (xy 143.528232 -358.663743) (xy 143.488697 -358.624521) (xy 143.45575 -358.579623)
			(xy 143.430193 -358.530144) (xy 143.412649 -358.477289) (xy 143.403547 -358.422348) (xy 143.402812 -358.394508)
			(xy 143.402812 -358.39146) (xy 143.40336 -358.363688) (xy 143.412033 -358.308825) (xy 143.420084 -358.28224)
			(xy 143.423132 -358.273096) (xy 143.426155 -358.261536) (xy 143.422439 -358.237963) (xy 143.41602 -358.227884)
			(xy 143.368268 -358.160828) (xy 143.360655 -358.151313) (xy 143.339032 -358.140156) (xy 143.326866 -358.139492)
			(xy 142.697708 -358.139492) (xy 142.671806 -358.139059) (xy 142.620478 -358.13205) (xy 142.570571 -358.118159)
			(xy 142.523003 -358.097643) (xy 142.500604 -358.084628) (xy 142.491779 -358.079766) (xy 142.47187 -358.07677)
			(xy 142.461996 -358.078786) (xy 142.442494 -358.083289) (xy 142.402761 -358.088133) (xy 142.382748 -358.088438)
			(xy 142.356754 -358.087958) (xy 142.305405 -358.079832) (xy 142.255959 -358.063773) (xy 142.209635 -358.040176)
			(xy 142.167574 -358.009621) (xy 142.13081 -357.972863) (xy 142.10025 -357.930806) (xy 142.076645 -357.884485)
			(xy 142.060579 -357.835042) (xy 142.052445 -357.783694) (xy 142.052445 -357.731706) (xy 142.060579 -357.680358)
			(xy 142.076645 -357.630915) (xy 142.10025 -357.584594) (xy 142.13081 -357.542537) (xy 142.167574 -357.505779)
			(xy 142.209635 -357.475224) (xy 142.255959 -357.451627) (xy 142.305405 -357.435568) (xy 142.356754 -357.427442)
			(xy 142.382748 -357.427022) (xy 142.402762 -357.427314) (xy 142.442496 -357.432155) (xy 142.461996 -357.436674)
			(xy 142.47187 -357.438598) (xy 142.491739 -357.435588) (xy 142.500604 -357.430832) (xy 142.523005 -357.417823)
			(xy 142.570574 -357.397309) (xy 142.62048 -357.38342) (xy 142.671807 -357.376411) (xy 142.697708 -357.375968)
			(xy 143.270986 -357.375968) (xy 143.284468 -357.375553) (xy 143.310492 -357.368494) (xy 143.333758 -357.354866)
			(xy 143.352643 -357.335619) (xy 143.365827 -357.312098) (xy 143.37239 -357.285945) (xy 143.371875 -357.258986)
			(xy 143.368522 -357.24592) (xy 142.75943 -355.15042) (xy 142.755863 -355.140051) (xy 142.74154 -355.123475)
			(xy 142.721616 -355.114369) (xy 142.710662 -355.113844) (xy 142.697708 -355.113844) (xy 142.671806 -355.113411)
			(xy 142.620479 -355.106401) (xy 142.570573 -355.092509) (xy 142.523006 -355.07199) (xy 142.500604 -355.05898)
			(xy 142.49178 -355.054114) (xy 142.471869 -355.051115) (xy 142.461996 -355.053138) (xy 142.442494 -355.057641)
			(xy 142.402761 -355.062486) (xy 142.382748 -355.06279) (xy 142.356757 -355.06231) (xy 142.305413 -355.054185)
			(xy 142.255974 -355.038127) (xy 142.209655 -355.014531) (xy 142.167599 -354.98398) (xy 142.13084 -354.947224)
			(xy 142.100284 -354.905171) (xy 142.076685 -354.858854) (xy 142.060622 -354.809416) (xy 142.052492 -354.758073)
			(xy 142.05204 -354.732082) (xy 142.052575 -354.705457) (xy 142.061106 -354.652895) (xy 142.077946 -354.602377)
			(xy 142.10266 -354.555209) (xy 142.13461 -354.512609) (xy 142.17297 -354.475675) (xy 142.194534 -354.460048)
			(xy 142.203424 -354.453952) (xy 142.214346 -354.43668) (xy 142.229078 -354.342954) (xy 142.223998 -354.323142)
			(xy 142.217394 -354.31476) (xy 142.20959 -354.30437) (xy 142.195349 -354.282633) (xy 142.188946 -354.271326)
			(xy 142.18539 -354.264976) (xy 140.482828 -352.562414) (xy 140.47969 -352.559038) (xy 140.474583 -352.551367)
			(xy 140.472668 -352.547174) (xy 140.469112 -352.539046) (xy 140.45946 -352.528632) (xy 140.456158 -352.526092)
			(xy 140.43519 -352.509083) (xy 140.398146 -352.469808) (xy 140.367456 -352.42539) (xy 140.343824 -352.376847)
			(xy 140.327792 -352.325293) (xy 140.319729 -352.271909) (xy 140.319252 -352.244914) (xy 140.319252 -352.239834)
			(xy 140.320169 -352.213408) (xy 140.328843 -352.16125) (xy 140.336524 -352.135948) (xy 140.339572 -352.126804)
			(xy 140.342599 -352.115244) (xy 140.338882 -352.09167) (xy 140.33246 -352.081592) (xy 140.284708 -352.014536)
			(xy 140.277092 -352.00503) (xy 140.255468 -351.993896) (xy 140.243306 -351.9932) (xy 139.614148 -351.9932)
			(xy 139.587234 -351.992722) (xy 139.533944 -351.985133) (xy 139.482246 -351.970139) (xy 139.433164 -351.948038)
			(xy 139.410186 -351.934018) (xy 139.400642 -351.928592) (xy 139.378907 -351.925691) (xy 139.368276 -351.92843)
			(xy 139.345184 -351.934849) (xy 139.297752 -351.941733) (xy 139.273788 -351.942146) (xy 139.247798 -351.941635)
			(xy 139.19646 -351.933502) (xy 139.147025 -351.917439) (xy 139.100712 -351.893839) (xy 139.05866 -351.863286)
			(xy 139.021906 -351.82653) (xy 138.991354 -351.784478) (xy 138.967757 -351.738164) (xy 138.951695 -351.688729)
			(xy 138.943564 -351.63739) (xy 138.943564 -351.58541) (xy 138.951695 -351.534071) (xy 138.967757 -351.484636)
			(xy 138.991354 -351.438322) (xy 139.021906 -351.39627) (xy 139.05866 -351.359514) (xy 139.100712 -351.328961)
			(xy 139.147025 -351.305361) (xy 139.19646 -351.289298) (xy 139.247798 -351.281165) (xy 139.273788 -351.28073)
			(xy 139.297753 -351.281135) (xy 139.345186 -351.288016) (xy 139.368276 -351.294446) (xy 139.378912 -351.297124)
			(xy 139.400635 -351.294247) (xy 139.410186 -351.288858) (xy 139.433171 -351.274846) (xy 139.482244 -351.252721)
			(xy 139.53394 -351.237715) (xy 139.587233 -351.230125) (xy 139.614148 -351.229676) (xy 140.243306 -351.229676)
			(xy 140.255468 -351.228983) (xy 140.277091 -351.217846) (xy 140.284708 -351.20834) (xy 140.330682 -351.14357)
			(xy 140.333222 -351.13976) (xy 140.33373 -351.138998) (xy 140.338258 -351.130883) (xy 140.341782 -351.112653)
			(xy 140.340588 -351.103438) (xy 140.339064 -351.094802) (xy 140.337794 -351.090992) (xy 140.329281 -351.063963)
			(xy 140.31997 -351.008069) (xy 140.319252 -350.97974) (xy 140.319252 -350.97466) (xy 140.319927 -350.948654)
			(xy 140.327895 -350.897247) (xy 140.34326 -350.847547) (xy 140.365697 -350.800614) (xy 140.394726 -350.757446)
			(xy 140.42973 -350.718963) (xy 140.449554 -350.702118) (xy 140.457913 -350.694494) (xy 140.467528 -350.674049)
			(xy 140.468096 -350.662748) (xy 140.468096 -349.53448) (xy 140.467488 -349.523193) (xy 140.457865 -349.502771)
			(xy 140.449554 -349.49511) (xy 140.429527 -349.478079) (xy 140.394217 -349.43913) (xy 140.365017 -349.395414)
			(xy 140.342559 -349.34788) (xy 140.327333 -349.297562) (xy 140.319669 -349.245552) (xy 140.319252 -349.219266)
			(xy 140.319252 -349.216472) (xy 140.320027 -349.189471) (xy 140.328708 -349.136157) (xy 140.336524 -349.1103)
			(xy 140.339572 -349.101156) (xy 140.342611 -349.089594) (xy 140.338913 -349.066006) (xy 140.33246 -349.055944)
			(xy 140.284708 -348.988888) (xy 140.277088 -348.979389) (xy 140.255465 -348.968266) (xy 140.243306 -348.967552)
			(xy 139.614148 -348.967552) (xy 139.587234 -348.967074) (xy 139.533944 -348.959484) (xy 139.482247 -348.944488)
			(xy 139.433167 -348.922385) (xy 139.410186 -348.90837) (xy 139.400641 -348.902948) (xy 139.378907 -348.90005)
			(xy 139.368276 -348.902782) (xy 139.345184 -348.9092) (xy 139.297752 -348.916082) (xy 139.273788 -348.916498)
			(xy 139.247802 -348.915988) (xy 139.196471 -348.907856) (xy 139.147043 -348.891794) (xy 139.100737 -348.868198)
			(xy 139.058692 -348.837649) (xy 139.021943 -348.800899) (xy 138.991395 -348.758853) (xy 138.967801 -348.712546)
			(xy 138.951741 -348.663118) (xy 138.943611 -348.611786) (xy 138.943611 -348.559814) (xy 138.951741 -348.508482)
			(xy 138.967801 -348.459054) (xy 138.991395 -348.412747) (xy 139.021943 -348.370701) (xy 139.058692 -348.333951)
			(xy 139.100737 -348.303402) (xy 139.147043 -348.279806) (xy 139.196471 -348.263744) (xy 139.247802 -348.255612)
			(xy 139.273788 -348.255082) (xy 139.297753 -348.255486) (xy 139.345187 -348.262367) (xy 139.368276 -348.268798)
			(xy 139.378912 -348.271477) (xy 139.400634 -348.268598) (xy 139.410186 -348.26321) (xy 139.433172 -348.2492)
			(xy 139.482245 -348.227077) (xy 139.533941 -348.212073) (xy 139.587233 -348.204485) (xy 139.614148 -348.204028)
			(xy 140.243306 -348.204028) (xy 140.255466 -348.203333) (xy 140.277082 -348.192189) (xy 140.284708 -348.182692)
			(xy 140.330682 -348.117922) (xy 140.333222 -348.114112) (xy 140.33373 -348.11335) (xy 140.33825 -348.105234)
			(xy 140.341757 -348.087006) (xy 140.340588 -348.07779) (xy 140.339064 -348.069154) (xy 140.337794 -348.065344)
			(xy 140.329277 -348.038316) (xy 140.319958 -347.982421) (xy 140.319252 -347.954092) (xy 140.319252 -347.949012)
			(xy 140.31993 -347.923008) (xy 140.327904 -347.871604) (xy 140.343275 -347.821909) (xy 140.365715 -347.774981)
			(xy 140.394747 -347.731818) (xy 140.429752 -347.69334) (xy 140.449554 -347.67647) (xy 140.457922 -347.66885)
			(xy 140.467558 -347.648404) (xy 140.468096 -347.6371) (xy 140.468096 -346.413836) (xy 140.467479 -346.402554)
			(xy 140.457845 -346.382146) (xy 140.449554 -346.374466) (xy 140.42956 -346.357463) (xy 140.394303 -346.318584)
			(xy 140.365134 -346.274951) (xy 140.342684 -346.22751) (xy 140.327441 -346.177288) (xy 140.319734 -346.125372)
			(xy 140.319252 -346.09913) (xy 140.319857 -346.069281) (xy 140.329808 -346.010419) (xy 140.339064 -345.982036)
			(xy 140.342422 -345.970291) (xy 140.338967 -345.946147) (xy 140.33246 -345.935808) (xy 140.284454 -345.868244)
			(xy 140.276842 -345.858729) (xy 140.255218 -345.847574) (xy 140.243052 -345.846908) (xy 139.614148 -345.846908)
			(xy 139.587234 -345.84643) (xy 139.533944 -345.838841) (xy 139.482246 -345.823847) (xy 139.433164 -345.801747)
			(xy 139.410186 -345.787726) (xy 139.400643 -345.7823) (xy 139.378906 -345.779398) (xy 139.368276 -345.782138)
			(xy 139.345184 -345.788557) (xy 139.297752 -345.79544) (xy 139.273788 -345.795854) (xy 139.247798 -345.795343)
			(xy 139.196458 -345.78721) (xy 139.147022 -345.771146) (xy 139.100708 -345.747546) (xy 139.058655 -345.716992)
			(xy 139.0219 -345.680236) (xy 138.991348 -345.638182) (xy 138.967749 -345.591867) (xy 138.951687 -345.542431)
			(xy 138.943556 -345.49109) (xy 138.943556 -345.43911) (xy 138.951687 -345.387769) (xy 138.967749 -345.338333)
			(xy 138.991348 -345.292018) (xy 139.0219 -345.249964) (xy 139.058655 -345.213208) (xy 139.100708 -345.182654)
			(xy 139.147022 -345.159054) (xy 139.196458 -345.14299) (xy 139.247798 -345.134857) (xy 139.273788 -345.134438)
			(xy 139.297753 -345.134842) (xy 139.345187 -345.141722) (xy 139.368276 -345.148154) (xy 139.378912 -345.150832)
			(xy 139.400635 -345.147955) (xy 139.410186 -345.142566) (xy 139.433171 -345.128554) (xy 139.482244 -345.106428)
			(xy 139.53394 -345.091422) (xy 139.587233 -345.083832) (xy 139.614148 -345.083384) (xy 140.237464 -345.083384)
			(xy 140.247116 -345.082368) (xy 140.253974 -345.081098) (xy 140.258387 -345.08017) (xy 140.266818 -345.076976)
			(xy 140.270738 -345.074748) (xy 140.279882 -345.06916) (xy 140.329666 -344.998548) (xy 140.334492 -344.99042)
			(xy 140.33667 -344.985294) (xy 140.338973 -344.974399) (xy 140.339064 -344.96883) (xy 140.339064 -344.956638)
			(xy 140.336524 -344.941144) (xy 140.335508 -344.937842) (xy 140.327915 -344.911958) (xy 140.319749 -344.85864)
			(xy 140.319252 -344.83167) (xy 140.319252 -344.831162) (xy 140.319716 -344.804917) (xy 140.327413 -344.752994)
			(xy 140.34265 -344.702764) (xy 140.365097 -344.655316) (xy 140.394267 -344.611677) (xy 140.429528 -344.572794)
			(xy 140.449554 -344.555826) (xy 140.457915 -344.548203) (xy 140.467533 -344.527757) (xy 140.468096 -344.516456)
			(xy 140.468096 -343.388188) (xy 140.46749 -343.376901) (xy 140.457868 -343.356476) (xy 140.449554 -343.348818)
			(xy 140.429557 -343.331816) (xy 140.394294 -343.292938) (xy 140.365119 -343.249307) (xy 140.342663 -343.201866)
			(xy 140.327412 -343.151643) (xy 140.319697 -343.099726) (xy 140.319252 -343.073482) (xy 140.319861 -343.043634)
			(xy 140.32982 -342.984775) (xy 140.339064 -342.956388) (xy 140.342434 -342.944641) (xy 140.339 -342.920482)
			(xy 140.33246 -342.91016) (xy 140.284454 -342.842596) (xy 140.276838 -342.833088) (xy 140.255215 -342.821944)
			(xy 140.243052 -342.82126) (xy 139.614148 -342.82126) (xy 139.587234 -342.820782) (xy 139.533944 -342.813192)
			(xy 139.482247 -342.798197) (xy 139.433167 -342.776094) (xy 139.410186 -342.762078) (xy 139.400642 -342.756656)
			(xy 139.378907 -342.753757) (xy 139.368276 -342.75649) (xy 139.345184 -342.762908) (xy 139.297752 -342.76979)
			(xy 139.273788 -342.770206) (xy 139.247802 -342.769696) (xy 139.196469 -342.761564) (xy 139.14704 -342.745502)
			(xy 139.100733 -342.721905) (xy 139.058686 -342.691355) (xy 139.021937 -342.654604) (xy 138.991388 -342.612557)
			(xy 138.967794 -342.566249) (xy 138.951734 -342.516819) (xy 138.943603 -342.465486) (xy 138.943603 -342.413514)
			(xy 138.951734 -342.362181) (xy 138.967794 -342.312751) (xy 138.991388 -342.266443) (xy 139.021937 -342.224396)
			(xy 139.058686 -342.187645) (xy 139.100733 -342.157095) (xy 139.14704 -342.133498) (xy 139.196469 -342.117436)
			(xy 139.247802 -342.109304) (xy 139.273788 -342.10879) (xy 139.297753 -342.109194) (xy 139.345186 -342.116075)
			(xy 139.368276 -342.122506) (xy 139.378912 -342.125185) (xy 139.400634 -342.122306) (xy 139.410186 -342.116918)
			(xy 139.433172 -342.102908) (xy 139.482245 -342.080785) (xy 139.533941 -342.06578) (xy 139.587233 -342.058192)
			(xy 139.614148 -342.057736) (xy 140.250672 -342.057736) (xy 140.260546 -342.057267) (xy 140.278834 -342.049814)
			(xy 140.286232 -342.043258) (xy 140.286486 -342.043004) (xy 140.29055 -342.03894) (xy 140.2969 -342.03132)
			(xy 140.346938 -341.957152) (xy 140.350748 -341.93734) (xy 140.348716 -341.92718) (xy 140.347446 -341.92083)
			(xy 140.345668 -341.916512) (xy 140.337316 -341.895106) (xy 140.325567 -341.850685) (xy 140.319634 -341.80512)
			(xy 140.319252 -341.782146) (xy 140.319252 -341.781384) (xy 140.319669 -341.757329) (xy 140.326182 -341.70966)
			(xy 140.339049 -341.663301) (xy 140.358034 -341.619093) (xy 140.370052 -341.59825) (xy 140.373354 -341.592408)
			(xy 140.377926 -341.576914) (xy 140.380084 -341.56831) (xy 140.378899 -341.550622) (xy 140.37564 -341.54237)
			(xy 132.959348 -324.656958) (xy 132.949188 -324.633082) (xy 132.9431 -324.618007) (xy 132.931795 -324.587521)
			(xy 132.926582 -324.572122) (xy 132.917848 -324.54514) (xy 132.90311 -324.490368) (xy 132.897118 -324.462648)
			(xy 132.74167 -323.722492) (xy 132.731803 -323.672337) (xy 132.721235 -323.570659) (xy 132.720588 -323.519546)
			(xy 132.720588 -322.703952) (xy 132.720334 -322.69811) (xy 132.719759 -322.69409) (xy 132.717465 -322.686302)
			(xy 132.715762 -322.682616) (xy 132.711698 -322.673726) (xy 131.801362 -321.76339) (xy 131.79425 -321.756024)
			(xy 131.775454 -321.748404) (xy 116.90604 -321.748404) (xy 116.896014 -321.748817) (xy 116.877484 -321.75648)
			(xy 116.8633 -321.770653) (xy 116.855624 -321.789178) (xy 116.85524 -321.799204) (xy 116.85524 -325.119492)
			(xy 116.854817 -325.129562) (xy 116.847098 -325.148162) (xy 116.840254 -325.15556) (xy 115.926362 -326.069452)
			(xy 115.918964 -326.076298) (xy 115.900365 -326.084026) (xy 115.890294 -326.084438) (xy 104.7496 -326.084438)
			(xy 104.744645 -326.084556) (xy 104.734923 -326.086473) (xy 104.730296 -326.088248) (xy 104.704388 -326.098916)
			(xy 104.69753 -326.105012) (xy 104.676248 -326.124021) (xy 104.629094 -326.156155) (xy 104.57768 -326.180904)
			(xy 104.523151 -326.197717) (xy 104.466727 -326.206218) (xy 104.409665 -326.206218) (xy 104.353241 -326.197717)
			(xy 104.298712 -326.180904) (xy 104.247298 -326.156155) (xy 104.200144 -326.124021) (xy 104.178862 -326.105012)
			(xy 104.172004 -326.098916) (xy 104.146096 -326.088248) (xy 104.141468 -326.086475) (xy 104.131747 -326.084556)
			(xy 104.126792 -326.084438) (xy 99.72548 -326.084438) (xy 99.706684 -326.092058) (xy 99.699572 -326.099424)
			(xy 99.0854 -326.713596) (xy 109.961678 -326.713596) (xy 109.965749 -326.657974) (xy 109.977875 -326.603537)
			(xy 109.997798 -326.551446) (xy 110.025094 -326.502811) (xy 110.05918 -326.458668) (xy 110.099329 -326.419959)
			(xy 110.144687 -326.387508) (xy 110.194287 -326.362007) (xy 110.247071 -326.344) (xy 110.301914 -326.33387)
			(xy 110.357648 -326.331833) (xy 110.413085 -326.337933) (xy 110.467042 -326.352039) (xy 110.518371 -326.373851)
			(xy 110.565977 -326.402905) (xy 110.608845 -326.43858) (xy 110.646062 -326.480117) (xy 110.676835 -326.52663)
			(xy 110.700507 -326.577127) (xy 110.716575 -326.630534) (xy 110.724695 -326.68571) (xy 110.725204 -326.713596)
			(xy 110.724695 -326.741482) (xy 110.716575 -326.796658) (xy 110.700507 -326.850065) (xy 110.676835 -326.900562)
			(xy 110.646062 -326.947075) (xy 110.608845 -326.988612) (xy 110.565977 -327.024287) (xy 110.518371 -327.053341)
			(xy 110.467042 -327.075153) (xy 110.413085 -327.089259) (xy 110.357648 -327.095359) (xy 110.301914 -327.093322)
			(xy 110.247071 -327.083192) (xy 110.194287 -327.065185) (xy 110.144687 -327.039684) (xy 110.099329 -327.007233)
			(xy 110.05918 -326.968524) (xy 110.025094 -326.924381) (xy 109.997798 -326.875746) (xy 109.977875 -326.823655)
			(xy 109.965749 -326.769218) (xy 109.961678 -326.713596) (xy 99.0854 -326.713596) (xy 98.408744 -327.390252)
			(xy 104.653586 -327.390252) (xy 104.657657 -327.33463) (xy 104.669783 -327.280193) (xy 104.689706 -327.228102)
			(xy 104.717002 -327.179467) (xy 104.751088 -327.135324) (xy 104.791237 -327.096615) (xy 104.836595 -327.064164)
			(xy 104.886195 -327.038663) (xy 104.938979 -327.020656) (xy 104.993822 -327.010526) (xy 105.049556 -327.008489)
			(xy 105.104993 -327.014589) (xy 105.15895 -327.028695) (xy 105.210279 -327.050507) (xy 105.257885 -327.079561)
			(xy 105.300753 -327.115236) (xy 105.33797 -327.156773) (xy 105.368743 -327.203286) (xy 105.392415 -327.253783)
			(xy 105.408483 -327.30719) (xy 105.416603 -327.362366) (xy 105.416672 -327.366122) (xy 106.29214 -327.366122)
			(xy 106.296211 -327.3105) (xy 106.308337 -327.256063) (xy 106.32826 -327.203972) (xy 106.355556 -327.155337)
			(xy 106.389642 -327.111194) (xy 106.429791 -327.072485) (xy 106.475149 -327.040034) (xy 106.524749 -327.014533)
			(xy 106.577533 -326.996526) (xy 106.632376 -326.986396) (xy 106.68811 -326.984359) (xy 106.743547 -326.990459)
			(xy 106.797504 -327.004565) (xy 106.848833 -327.026377) (xy 106.896439 -327.055431) (xy 106.939307 -327.091106)
			(xy 106.976524 -327.132643) (xy 107.007297 -327.179156) (xy 107.030969 -327.229653) (xy 107.047037 -327.28306)
			(xy 107.055157 -327.338236) (xy 107.055666 -327.366122) (xy 107.055157 -327.394008) (xy 107.047037 -327.449184)
			(xy 107.044898 -327.456292) (xy 108.97184 -327.456292) (xy 108.975911 -327.40067) (xy 108.988037 -327.346233)
			(xy 109.00796 -327.294142) (xy 109.035256 -327.245507) (xy 109.069342 -327.201364) (xy 109.109491 -327.162655)
			(xy 109.154849 -327.130204) (xy 109.204449 -327.104703) (xy 109.257233 -327.086696) (xy 109.312076 -327.076566)
			(xy 109.36781 -327.074529) (xy 109.423247 -327.080629) (xy 109.477204 -327.094735) (xy 109.528533 -327.116547)
			(xy 109.576139 -327.145601) (xy 109.619007 -327.181276) (xy 109.656224 -327.222813) (xy 109.686997 -327.269326)
			(xy 109.710669 -327.319823) (xy 109.726737 -327.37323) (xy 109.734857 -327.428406) (xy 109.735366 -327.456292)
			(xy 111.608106 -327.456292) (xy 111.612177 -327.40067) (xy 111.624303 -327.346233) (xy 111.644226 -327.294142)
			(xy 111.671522 -327.245507) (xy 111.705608 -327.201364) (xy 111.745757 -327.162655) (xy 111.791115 -327.130204)
			(xy 111.840715 -327.104703) (xy 111.893499 -327.086696) (xy 111.948342 -327.076566) (xy 112.004076 -327.074529)
			(xy 112.059513 -327.080629) (xy 112.11347 -327.094735) (xy 112.164799 -327.116547) (xy 112.212405 -327.145601)
			(xy 112.255273 -327.181276) (xy 112.29249 -327.222813) (xy 112.323263 -327.269326) (xy 112.346935 -327.319823)
			(xy 112.363003 -327.37323) (xy 112.371123 -327.428406) (xy 112.371632 -327.456292) (xy 112.371123 -327.484178)
			(xy 112.363003 -327.539354) (xy 112.346935 -327.592761) (xy 112.323263 -327.643258) (xy 112.29249 -327.689771)
			(xy 112.255273 -327.731308) (xy 112.212405 -327.766983) (xy 112.164799 -327.796037) (xy 112.11347 -327.817849)
			(xy 112.059513 -327.831955) (xy 112.004076 -327.838055) (xy 111.948342 -327.836018) (xy 111.893499 -327.825888)
			(xy 111.840715 -327.807881) (xy 111.791115 -327.78238) (xy 111.745757 -327.749929) (xy 111.705608 -327.71122)
			(xy 111.671522 -327.667077) (xy 111.644226 -327.618442) (xy 111.624303 -327.566351) (xy 111.612177 -327.511914)
			(xy 111.608106 -327.456292) (xy 109.735366 -327.456292) (xy 109.734857 -327.484178) (xy 109.726737 -327.539354)
			(xy 109.710669 -327.592761) (xy 109.686997 -327.643258) (xy 109.656224 -327.689771) (xy 109.619007 -327.731308)
			(xy 109.576139 -327.766983) (xy 109.528533 -327.796037) (xy 109.477204 -327.817849) (xy 109.423247 -327.831955)
			(xy 109.36781 -327.838055) (xy 109.312076 -327.836018) (xy 109.257233 -327.825888) (xy 109.204449 -327.807881)
			(xy 109.154849 -327.78238) (xy 109.109491 -327.749929) (xy 109.069342 -327.71122) (xy 109.035256 -327.667077)
			(xy 109.00796 -327.618442) (xy 108.988037 -327.566351) (xy 108.975911 -327.511914) (xy 108.97184 -327.456292)
			(xy 107.044898 -327.456292) (xy 107.030969 -327.502591) (xy 107.007297 -327.553088) (xy 106.976524 -327.599601)
			(xy 106.939307 -327.641138) (xy 106.896439 -327.676813) (xy 106.848833 -327.705867) (xy 106.797504 -327.727679)
			(xy 106.743547 -327.741785) (xy 106.68811 -327.747885) (xy 106.632376 -327.745848) (xy 106.577533 -327.735718)
			(xy 106.524749 -327.717711) (xy 106.475149 -327.69221) (xy 106.429791 -327.659759) (xy 106.389642 -327.62105)
			(xy 106.355556 -327.576907) (xy 106.32826 -327.528272) (xy 106.308337 -327.476181) (xy 106.296211 -327.421744)
			(xy 106.29214 -327.366122) (xy 105.416672 -327.366122) (xy 105.417112 -327.390252) (xy 105.416603 -327.418138)
			(xy 105.408483 -327.473314) (xy 105.392415 -327.526721) (xy 105.368743 -327.577218) (xy 105.33797 -327.623731)
			(xy 105.300753 -327.665268) (xy 105.257885 -327.700943) (xy 105.210279 -327.729997) (xy 105.15895 -327.751809)
			(xy 105.104993 -327.765915) (xy 105.049556 -327.772015) (xy 104.993822 -327.769978) (xy 104.938979 -327.759848)
			(xy 104.886195 -327.741841) (xy 104.836595 -327.71634) (xy 104.791237 -327.683889) (xy 104.751088 -327.64518)
			(xy 104.717002 -327.601037) (xy 104.689706 -327.552402) (xy 104.669783 -327.500311) (xy 104.657657 -327.445874)
			(xy 104.653586 -327.390252) (xy 98.408744 -327.390252) (xy 97.580704 -328.218292) (xy 103.1908 -328.218292)
			(xy 103.194871 -328.16267) (xy 103.206997 -328.108233) (xy 103.22692 -328.056142) (xy 103.254216 -328.007507)
			(xy 103.288302 -327.963364) (xy 103.328451 -327.924655) (xy 103.373809 -327.892204) (xy 103.423409 -327.866703)
			(xy 103.476193 -327.848696) (xy 103.531036 -327.838566) (xy 103.58677 -327.836529) (xy 103.642207 -327.842629)
			(xy 103.696164 -327.856735) (xy 103.747493 -327.878547) (xy 103.795099 -327.907601) (xy 103.837967 -327.943276)
			(xy 103.875184 -327.984813) (xy 103.905957 -328.031326) (xy 103.929629 -328.081823) (xy 103.945697 -328.13523)
			(xy 103.953817 -328.190406) (xy 103.954326 -328.218292) (xy 103.953817 -328.246178) (xy 103.945697 -328.301354)
			(xy 103.929629 -328.354761) (xy 103.915255 -328.385424) (xy 104.682542 -328.385424) (xy 104.686613 -328.329802)
			(xy 104.698739 -328.275365) (xy 104.718662 -328.223274) (xy 104.745958 -328.174639) (xy 104.780044 -328.130496)
			(xy 104.820193 -328.091787) (xy 104.865551 -328.059336) (xy 104.915151 -328.033835) (xy 104.967935 -328.015828)
			(xy 105.022778 -328.005698) (xy 105.078512 -328.003661) (xy 105.133949 -328.009761) (xy 105.187906 -328.023867)
			(xy 105.239235 -328.045679) (xy 105.286841 -328.074733) (xy 105.329709 -328.110408) (xy 105.366926 -328.151945)
			(xy 105.397699 -328.198458) (xy 105.421371 -328.248955) (xy 105.437439 -328.302362) (xy 105.445559 -328.357538)
			(xy 105.446068 -328.385424) (xy 105.445559 -328.41331) (xy 105.437439 -328.468486) (xy 105.421371 -328.521893)
			(xy 105.397699 -328.57239) (xy 105.366926 -328.618903) (xy 105.329709 -328.66044) (xy 105.286841 -328.696115)
			(xy 105.239235 -328.725169) (xy 105.187906 -328.746981) (xy 105.133949 -328.761087) (xy 105.078512 -328.767187)
			(xy 105.022778 -328.76515) (xy 104.967935 -328.75502) (xy 104.915151 -328.737013) (xy 104.865551 -328.711512)
			(xy 104.820193 -328.679061) (xy 104.780044 -328.640352) (xy 104.745958 -328.596209) (xy 104.718662 -328.547574)
			(xy 104.698739 -328.495483) (xy 104.686613 -328.441046) (xy 104.682542 -328.385424) (xy 103.915255 -328.385424)
			(xy 103.905957 -328.405258) (xy 103.875184 -328.451771) (xy 103.837967 -328.493308) (xy 103.795099 -328.528983)
			(xy 103.747493 -328.558037) (xy 103.696164 -328.579849) (xy 103.642207 -328.593955) (xy 103.58677 -328.600055)
			(xy 103.531036 -328.598018) (xy 103.476193 -328.587888) (xy 103.423409 -328.569881) (xy 103.373809 -328.54438)
			(xy 103.328451 -328.511929) (xy 103.288302 -328.47322) (xy 103.254216 -328.429077) (xy 103.22692 -328.380442)
			(xy 103.206997 -328.328351) (xy 103.194871 -328.273914) (xy 103.1908 -328.218292) (xy 97.580704 -328.218292)
			(xy 96.760792 -329.038204) (xy 102.152194 -329.038204) (xy 102.156265 -328.982582) (xy 102.168391 -328.928145)
			(xy 102.188314 -328.876054) (xy 102.21561 -328.827419) (xy 102.249696 -328.783276) (xy 102.289845 -328.744567)
			(xy 102.335203 -328.712116) (xy 102.384803 -328.686615) (xy 102.437587 -328.668608) (xy 102.49243 -328.658478)
			(xy 102.548164 -328.656441) (xy 102.603601 -328.662541) (xy 102.657558 -328.676647) (xy 102.708887 -328.698459)
			(xy 102.756493 -328.727513) (xy 102.799361 -328.763188) (xy 102.836578 -328.804725) (xy 102.867351 -328.851238)
			(xy 102.891023 -328.901735) (xy 102.907091 -328.955142) (xy 102.915211 -329.010318) (xy 102.91572 -329.038204)
			(xy 102.915211 -329.06609) (xy 102.907091 -329.121266) (xy 102.891023 -329.174673) (xy 102.867351 -329.22517)
			(xy 102.836578 -329.271683) (xy 102.799361 -329.31322) (xy 102.756493 -329.348895) (xy 102.708887 -329.377949)
			(xy 102.657558 -329.399761) (xy 102.603601 -329.413867) (xy 102.548164 -329.419967) (xy 102.49243 -329.41793)
			(xy 102.437587 -329.4078) (xy 102.384803 -329.389793) (xy 102.335203 -329.364292) (xy 102.289845 -329.331841)
			(xy 102.249696 -329.293132) (xy 102.21561 -329.248989) (xy 102.188314 -329.200354) (xy 102.168391 -329.148263)
			(xy 102.156265 -329.093826) (xy 102.152194 -329.038204) (xy 96.760792 -329.038204) (xy 95.97263 -329.826366)
			(xy 95.965264 -329.833478) (xy 95.957644 -329.852274) (xy 95.957644 -330.416662) (xy 97.355152 -330.416662)
			(xy 97.355152 -329.553062) (xy 97.355642 -329.523078) (xy 97.36347 -329.463622) (xy 97.378991 -329.405697)
			(xy 97.40194 -329.350293) (xy 97.431924 -329.298359) (xy 97.46843 -329.250783) (xy 97.510835 -329.208378)
			(xy 97.558411 -329.171872) (xy 97.610345 -329.141888) (xy 97.665749 -329.118939) (xy 97.723674 -329.103418)
			(xy 97.78313 -329.09559) (xy 97.843098 -329.09559) (xy 97.902554 -329.103418) (xy 97.960479 -329.118939)
			(xy 98.015883 -329.141888) (xy 98.067817 -329.171872) (xy 98.115393 -329.208378) (xy 98.157798 -329.250783)
			(xy 98.194304 -329.298359) (xy 98.224288 -329.350293) (xy 98.247237 -329.405697) (xy 98.258955 -329.44943)
			(xy 114.249198 -329.44943) (xy 114.253269 -329.393808) (xy 114.265395 -329.339371) (xy 114.285318 -329.28728)
			(xy 114.312614 -329.238645) (xy 114.3467 -329.194502) (xy 114.386849 -329.155793) (xy 114.432207 -329.123342)
			(xy 114.481807 -329.097841) (xy 114.534591 -329.079834) (xy 114.589434 -329.069704) (xy 114.645168 -329.067667)
			(xy 114.700605 -329.073767) (xy 114.754562 -329.087873) (xy 114.805891 -329.109685) (xy 114.853497 -329.138739)
			(xy 114.896365 -329.174414) (xy 114.933582 -329.215951) (xy 114.964355 -329.262464) (xy 114.988027 -329.312961)
			(xy 115.004095 -329.366368) (xy 115.012215 -329.421544) (xy 115.012678 -329.44689) (xy 116.277642 -329.44689)
			(xy 116.281713 -329.391268) (xy 116.293839 -329.336831) (xy 116.313762 -329.28474) (xy 116.341058 -329.236105)
			(xy 116.375144 -329.191962) (xy 116.415293 -329.153253) (xy 116.460651 -329.120802) (xy 116.510251 -329.095301)
			(xy 116.563035 -329.077294) (xy 116.617878 -329.067164) (xy 116.673612 -329.065127) (xy 116.729049 -329.071227)
			(xy 116.783006 -329.085333) (xy 116.834335 -329.107145) (xy 116.881941 -329.136199) (xy 116.924809 -329.171874)
			(xy 116.962026 -329.213411) (xy 116.992799 -329.259924) (xy 117.016471 -329.310421) (xy 117.032539 -329.363828)
			(xy 117.040659 -329.419004) (xy 117.041168 -329.44689) (xy 117.293642 -329.44689) (xy 117.297713 -329.391268)
			(xy 117.309839 -329.336831) (xy 117.329762 -329.28474) (xy 117.357058 -329.236105) (xy 117.391144 -329.191962)
			(xy 117.431293 -329.153253) (xy 117.476651 -329.120802) (xy 117.526251 -329.095301) (xy 117.579035 -329.077294)
			(xy 117.633878 -329.067164) (xy 117.689612 -329.065127) (xy 117.745049 -329.071227) (xy 117.799006 -329.085333)
			(xy 117.850335 -329.107145) (xy 117.897941 -329.136199) (xy 117.940809 -329.171874) (xy 117.978026 -329.213411)
			(xy 118.008799 -329.259924) (xy 118.032471 -329.310421) (xy 118.048539 -329.363828) (xy 118.056659 -329.419004)
			(xy 118.057168 -329.44689) (xy 118.056659 -329.474776) (xy 118.048539 -329.529952) (xy 118.032471 -329.583359)
			(xy 118.008799 -329.633856) (xy 117.978026 -329.680369) (xy 117.940809 -329.721906) (xy 117.897941 -329.757581)
			(xy 117.850335 -329.786635) (xy 117.799006 -329.808447) (xy 117.745049 -329.822553) (xy 117.689612 -329.828653)
			(xy 117.633878 -329.826616) (xy 117.579035 -329.816486) (xy 117.526251 -329.798479) (xy 117.476651 -329.772978)
			(xy 117.431293 -329.740527) (xy 117.391144 -329.701818) (xy 117.357058 -329.657675) (xy 117.329762 -329.60904)
			(xy 117.309839 -329.556949) (xy 117.297713 -329.502512) (xy 117.293642 -329.44689) (xy 117.041168 -329.44689)
			(xy 117.040659 -329.474776) (xy 117.032539 -329.529952) (xy 117.016471 -329.583359) (xy 116.992799 -329.633856)
			(xy 116.962026 -329.680369) (xy 116.924809 -329.721906) (xy 116.881941 -329.757581) (xy 116.834335 -329.786635)
			(xy 116.783006 -329.808447) (xy 116.729049 -329.822553) (xy 116.673612 -329.828653) (xy 116.617878 -329.826616)
			(xy 116.563035 -329.816486) (xy 116.510251 -329.798479) (xy 116.460651 -329.772978) (xy 116.415293 -329.740527)
			(xy 116.375144 -329.701818) (xy 116.341058 -329.657675) (xy 116.313762 -329.60904) (xy 116.293839 -329.556949)
			(xy 116.281713 -329.502512) (xy 116.277642 -329.44689) (xy 115.012678 -329.44689) (xy 115.012724 -329.44943)
			(xy 115.012215 -329.477316) (xy 115.004095 -329.532492) (xy 114.988027 -329.585899) (xy 114.964355 -329.636396)
			(xy 114.933582 -329.682909) (xy 114.896365 -329.724446) (xy 114.853497 -329.760121) (xy 114.805891 -329.789175)
			(xy 114.754562 -329.810987) (xy 114.700605 -329.825093) (xy 114.645168 -329.831193) (xy 114.589434 -329.829156)
			(xy 114.534591 -329.819026) (xy 114.481807 -329.801019) (xy 114.432207 -329.775518) (xy 114.386849 -329.743067)
			(xy 114.3467 -329.704358) (xy 114.312614 -329.660215) (xy 114.285318 -329.61158) (xy 114.265395 -329.559489)
			(xy 114.253269 -329.505052) (xy 114.249198 -329.44943) (xy 98.258955 -329.44943) (xy 98.262758 -329.463622)
			(xy 98.270586 -329.523078) (xy 98.271076 -329.553062) (xy 98.271076 -330.416662) (xy 98.270586 -330.446646)
			(xy 98.262758 -330.506102) (xy 98.247237 -330.564027) (xy 98.224288 -330.619431) (xy 98.194304 -330.671365)
			(xy 98.157798 -330.718941) (xy 98.115393 -330.761346) (xy 98.067817 -330.797852) (xy 98.015883 -330.827836)
			(xy 97.960479 -330.850785) (xy 97.902554 -330.866306) (xy 97.843098 -330.874134) (xy 97.78313 -330.874134)
			(xy 97.723674 -330.866306) (xy 97.665749 -330.850785) (xy 97.610345 -330.827836) (xy 97.558411 -330.797852)
			(xy 97.510835 -330.761346) (xy 97.46843 -330.718941) (xy 97.431924 -330.671365) (xy 97.40194 -330.619431)
			(xy 97.378991 -330.564027) (xy 97.36347 -330.506102) (xy 97.355642 -330.446646) (xy 97.355152 -330.416662)
			(xy 95.957644 -330.416662) (xy 95.957644 -331.53223) (xy 114.955828 -331.53223) (xy 114.955828 -330.66863)
			(xy 114.956318 -330.638646) (xy 114.964146 -330.57919) (xy 114.979667 -330.521265) (xy 115.002616 -330.465861)
			(xy 115.0326 -330.413927) (xy 115.069106 -330.366351) (xy 115.111511 -330.323946) (xy 115.159087 -330.28744)
			(xy 115.211021 -330.257456) (xy 115.266425 -330.234507) (xy 115.32435 -330.218986) (xy 115.383806 -330.211158)
			(xy 115.443774 -330.211158) (xy 115.50323 -330.218986) (xy 115.561155 -330.234507) (xy 115.616559 -330.257456)
			(xy 115.668493 -330.28744) (xy 115.716069 -330.323946) (xy 115.758474 -330.366351) (xy 115.79498 -330.413927)
			(xy 115.824964 -330.465861) (xy 115.847913 -330.521265) (xy 115.863434 -330.57919) (xy 115.871262 -330.638646)
			(xy 115.871752 -330.66863) (xy 115.871752 -330.760651) (xy 123.469378 -330.760651) (xy 123.469378 -330.706149)
			(xy 123.477134 -330.652201) (xy 123.492489 -330.599906) (xy 123.515131 -330.550329) (xy 123.544597 -330.504479)
			(xy 123.580288 -330.463288) (xy 123.621479 -330.427597) (xy 123.667329 -330.398131) (xy 123.716906 -330.375489)
			(xy 123.769201 -330.360134) (xy 123.823149 -330.352378) (xy 123.8504 -330.351892) (xy 123.87777 -330.35236)
			(xy 123.931949 -330.360178) (xy 123.984452 -330.375666) (xy 124.034199 -330.398508) (xy 124.080166 -330.428231)
			(xy 124.101098 -330.445872) (xy 124.10821 -330.451968) (xy 124.125228 -330.458318) (xy 124.210572 -330.458318)
			(xy 124.22759 -330.451968) (xy 124.234702 -330.445872) (xy 124.255619 -330.428214) (xy 124.301596 -330.398506)
			(xy 124.351348 -330.375674) (xy 124.403852 -330.360187) (xy 124.45803 -330.352364) (xy 124.4854 -330.351892)
			(xy 124.512651 -330.352378) (xy 124.566599 -330.360134) (xy 124.618894 -330.375489) (xy 124.668471 -330.398131)
			(xy 124.714321 -330.427597) (xy 124.755512 -330.463288) (xy 124.791203 -330.504479) (xy 124.820669 -330.550329)
			(xy 124.843311 -330.599906) (xy 124.858666 -330.652201) (xy 124.866422 -330.706149) (xy 124.866422 -330.760651)
			(xy 124.858666 -330.814599) (xy 124.843311 -330.866894) (xy 124.820669 -330.916471) (xy 124.791203 -330.962321)
			(xy 124.755512 -331.003512) (xy 124.714321 -331.039203) (xy 124.668471 -331.068669) (xy 124.618894 -331.091311)
			(xy 124.566599 -331.106666) (xy 124.512651 -331.114422) (xy 124.4854 -331.114908) (xy 124.45803 -331.11444)
			(xy 124.403851 -331.106622) (xy 124.351348 -331.091134) (xy 124.301601 -331.068292) (xy 124.255634 -331.038569)
			(xy 124.234702 -331.020928) (xy 124.22759 -331.014832) (xy 124.210572 -331.008482) (xy 124.125228 -331.008482)
			(xy 124.10821 -331.014832) (xy 124.101098 -331.020928) (xy 124.080181 -331.038586) (xy 124.034204 -331.068294)
			(xy 123.984452 -331.091126) (xy 123.931948 -331.106613) (xy 123.87777 -331.114436) (xy 123.8504 -331.114908)
			(xy 123.823149 -331.114422) (xy 123.769201 -331.106666) (xy 123.716906 -331.091311) (xy 123.667329 -331.068669)
			(xy 123.621479 -331.039203) (xy 123.580288 -331.003512) (xy 123.544597 -330.962321) (xy 123.515131 -330.916471)
			(xy 123.492489 -330.866894) (xy 123.477134 -330.814599) (xy 123.469378 -330.760651) (xy 115.871752 -330.760651)
			(xy 115.871752 -331.53223) (xy 115.871262 -331.562214) (xy 115.863434 -331.62167) (xy 115.847913 -331.679595)
			(xy 115.824964 -331.734999) (xy 115.79498 -331.786933) (xy 115.758474 -331.834509) (xy 115.716069 -331.876914)
			(xy 115.668493 -331.91342) (xy 115.616559 -331.943404) (xy 115.561155 -331.966353) (xy 115.50323 -331.981874)
			(xy 115.443774 -331.989702) (xy 115.383806 -331.989702) (xy 115.32435 -331.981874) (xy 115.266425 -331.966353)
			(xy 115.211021 -331.943404) (xy 115.159087 -331.91342) (xy 115.111511 -331.876914) (xy 115.069106 -331.834509)
			(xy 115.0326 -331.786933) (xy 115.002616 -331.734999) (xy 114.979667 -331.679595) (xy 114.964146 -331.62167)
			(xy 114.956318 -331.562214) (xy 114.955828 -331.53223) (xy 95.957644 -331.53223) (xy 95.957644 -332.043532)
			(xy 101.474776 -332.043532) (xy 101.478847 -331.98791) (xy 101.490973 -331.933473) (xy 101.510896 -331.881382)
			(xy 101.538192 -331.832747) (xy 101.572278 -331.788604) (xy 101.612427 -331.749895) (xy 101.657785 -331.717444)
			(xy 101.707385 -331.691943) (xy 101.760169 -331.673936) (xy 101.815012 -331.663806) (xy 101.870746 -331.661769)
			(xy 101.926183 -331.667869) (xy 101.98014 -331.681975) (xy 102.031469 -331.703787) (xy 102.079075 -331.732841)
			(xy 102.121943 -331.768516) (xy 102.15916 -331.810053) (xy 102.189933 -331.856566) (xy 102.213605 -331.907063)
			(xy 102.229673 -331.96047) (xy 102.237793 -332.015646) (xy 102.238302 -332.043532) (xy 102.237793 -332.071418)
			(xy 102.229673 -332.126594) (xy 102.213605 -332.180001) (xy 102.189933 -332.230498) (xy 102.15916 -332.277011)
			(xy 102.121943 -332.318548) (xy 102.079075 -332.354223) (xy 102.031469 -332.383277) (xy 101.98014 -332.405089)
			(xy 101.926183 -332.419195) (xy 101.870746 -332.425295) (xy 101.815012 -332.423258) (xy 101.760169 -332.413128)
			(xy 101.707385 -332.395121) (xy 101.657785 -332.36962) (xy 101.612427 -332.337169) (xy 101.572278 -332.29846)
			(xy 101.538192 -332.254317) (xy 101.510896 -332.205682) (xy 101.490973 -332.153591) (xy 101.478847 -332.099154)
			(xy 101.474776 -332.043532) (xy 95.957644 -332.043532) (xy 95.957644 -333.614522) (xy 100.858318 -333.614522)
			(xy 100.862389 -333.5589) (xy 100.874515 -333.504463) (xy 100.894438 -333.452372) (xy 100.921734 -333.403737)
			(xy 100.95582 -333.359594) (xy 100.995969 -333.320885) (xy 101.041327 -333.288434) (xy 101.090927 -333.262933)
			(xy 101.143711 -333.244926) (xy 101.198554 -333.234796) (xy 101.254288 -333.232759) (xy 101.309725 -333.238859)
			(xy 101.363682 -333.252965) (xy 101.415011 -333.274777) (xy 101.462617 -333.303831) (xy 101.505485 -333.339506)
			(xy 101.542702 -333.381043) (xy 101.573475 -333.427556) (xy 101.597147 -333.478053) (xy 101.613215 -333.53146)
			(xy 101.621335 -333.586636) (xy 101.621844 -333.614522) (xy 101.621335 -333.642408) (xy 101.613215 -333.697584)
			(xy 101.597147 -333.750991) (xy 101.573475 -333.801488) (xy 101.542702 -333.848001) (xy 101.505485 -333.889538)
			(xy 101.462617 -333.925213) (xy 101.415011 -333.954267) (xy 101.363682 -333.976079) (xy 101.309725 -333.990185)
			(xy 101.254288 -333.996285) (xy 101.198554 -333.994248) (xy 101.143711 -333.984118) (xy 101.090927 -333.966111)
			(xy 101.041327 -333.94061) (xy 100.995969 -333.908159) (xy 100.95582 -333.86945) (xy 100.921734 -333.825307)
			(xy 100.894438 -333.776672) (xy 100.874515 -333.724581) (xy 100.862389 -333.670144) (xy 100.858318 -333.614522)
			(xy 95.957644 -333.614522) (xy 95.957644 -334.297274) (xy 102.382064 -334.297274) (xy 102.386135 -334.241652)
			(xy 102.398261 -334.187215) (xy 102.418184 -334.135124) (xy 102.44548 -334.086489) (xy 102.479566 -334.042346)
			(xy 102.519715 -334.003637) (xy 102.565073 -333.971186) (xy 102.614673 -333.945685) (xy 102.667457 -333.927678)
			(xy 102.7223 -333.917548) (xy 102.778034 -333.915511) (xy 102.833471 -333.921611) (xy 102.887428 -333.935717)
			(xy 102.938757 -333.957529) (xy 102.986363 -333.986583) (xy 103.029231 -334.022258) (xy 103.066448 -334.063795)
			(xy 103.097221 -334.110308) (xy 103.111639 -334.141064) (xy 103.559862 -334.141064) (xy 103.563933 -334.085442)
			(xy 103.576059 -334.031005) (xy 103.595982 -333.978914) (xy 103.623278 -333.930279) (xy 103.657364 -333.886136)
			(xy 103.697513 -333.847427) (xy 103.742871 -333.814976) (xy 103.792471 -333.789475) (xy 103.845255 -333.771468)
			(xy 103.900098 -333.761338) (xy 103.955832 -333.759301) (xy 104.011269 -333.765401) (xy 104.065226 -333.779507)
			(xy 104.116555 -333.801319) (xy 104.164161 -333.830373) (xy 104.207029 -333.866048) (xy 104.244246 -333.907585)
			(xy 104.275019 -333.954098) (xy 104.298691 -334.004595) (xy 104.314759 -334.058002) (xy 104.322879 -334.113178)
			(xy 104.323388 -334.141064) (xy 104.322879 -334.16895) (xy 104.320254 -334.186784) (xy 109.31271 -334.186784)
			(xy 109.313221 -334.158045) (xy 109.321847 -334.101217) (xy 109.338899 -334.046326) (xy 109.363994 -333.994614)
			(xy 109.396562 -333.947252) (xy 109.415834 -333.925926) (xy 109.422438 -333.918814) (xy 109.42955 -333.901288)
			(xy 109.430058 -333.812896) (xy 109.4232 -333.79537) (xy 109.41685 -333.788004) (xy 109.398255 -333.76681)
			(xy 109.366816 -333.720007) (xy 109.342606 -333.669088) (xy 109.326152 -333.615161) (xy 109.317811 -333.5594)
			(xy 109.317282 -333.53121) (xy 109.317768 -333.503959) (xy 109.325524 -333.450011) (xy 109.340879 -333.397716)
			(xy 109.363521 -333.348139) (xy 109.392987 -333.302289) (xy 109.428678 -333.261098) (xy 109.469869 -333.225407)
			(xy 109.515719 -333.195941) (xy 109.565296 -333.173299) (xy 109.617591 -333.157944) (xy 109.671539 -333.150188)
			(xy 109.726041 -333.150188) (xy 109.779989 -333.157944) (xy 109.832284 -333.173299) (xy 109.881861 -333.195941)
			(xy 109.927711 -333.225407) (xy 109.968902 -333.261098) (xy 110.004593 -333.302289) (xy 110.034059 -333.348139)
			(xy 110.056701 -333.397716) (xy 110.072056 -333.450011) (xy 110.079812 -333.503959) (xy 110.080298 -333.53121)
			(xy 110.079781 -333.559949) (xy 110.071157 -333.616777) (xy 110.054105 -333.671668) (xy 110.029012 -333.723379)
			(xy 109.996445 -333.770741) (xy 109.977174 -333.792068) (xy 109.97057 -333.79918) (xy 109.963458 -333.816706)
			(xy 109.963236 -333.855314) (xy 112.467134 -333.855314) (xy 112.471205 -333.799692) (xy 112.483331 -333.745255)
			(xy 112.503254 -333.693164) (xy 112.53055 -333.644529) (xy 112.564636 -333.600386) (xy 112.604785 -333.561677)
			(xy 112.650143 -333.529226) (xy 112.699743 -333.503725) (xy 112.752527 -333.485718) (xy 112.80737 -333.475588)
			(xy 112.863104 -333.473551) (xy 112.918541 -333.479651) (xy 112.972498 -333.493757) (xy 113.023827 -333.515569)
			(xy 113.071433 -333.544623) (xy 113.114301 -333.580298) (xy 113.151518 -333.621835) (xy 113.182291 -333.668348)
			(xy 113.205963 -333.718845) (xy 113.222031 -333.772252) (xy 113.230151 -333.827428) (xy 113.23066 -333.855314)
			(xy 113.230151 -333.8832) (xy 113.222031 -333.938376) (xy 113.205963 -333.991783) (xy 113.182291 -334.04228)
			(xy 113.151518 -334.088793) (xy 113.114301 -334.13033) (xy 113.071433 -334.166005) (xy 113.023827 -334.195059)
			(xy 112.972498 -334.216871) (xy 112.918541 -334.230977) (xy 112.863104 -334.237077) (xy 112.80737 -334.23504)
			(xy 112.752527 -334.22491) (xy 112.699743 -334.206903) (xy 112.650143 -334.181402) (xy 112.604785 -334.148951)
			(xy 112.564636 -334.110242) (xy 112.53055 -334.066099) (xy 112.503254 -334.017464) (xy 112.483331 -333.965373)
			(xy 112.471205 -333.910936) (xy 112.467134 -333.855314) (xy 109.963236 -333.855314) (xy 109.96295 -333.905098)
			(xy 109.969808 -333.922624) (xy 109.976158 -333.92999) (xy 109.994752 -333.951186) (xy 110.02619 -333.997988)
			(xy 110.0504 -334.048907) (xy 110.066855 -334.102833) (xy 110.075196 -334.158594) (xy 110.075726 -334.186784)
			(xy 110.07524 -334.214035) (xy 110.067484 -334.267983) (xy 110.052129 -334.320278) (xy 110.029487 -334.369855)
			(xy 110.000021 -334.415705) (xy 109.96433 -334.456896) (xy 109.923139 -334.492587) (xy 109.877289 -334.522053)
			(xy 109.827712 -334.544695) (xy 109.775417 -334.56005) (xy 109.721469 -334.567806) (xy 109.666967 -334.567806)
			(xy 109.613019 -334.56005) (xy 109.560724 -334.544695) (xy 109.511147 -334.522053) (xy 109.465297 -334.492587)
			(xy 109.424106 -334.456896) (xy 109.388415 -334.415705) (xy 109.358949 -334.369855) (xy 109.336307 -334.320278)
			(xy 109.320952 -334.267983) (xy 109.313196 -334.214035) (xy 109.31271 -334.186784) (xy 104.320254 -334.186784)
			(xy 104.314759 -334.224126) (xy 104.298691 -334.277533) (xy 104.275019 -334.32803) (xy 104.244246 -334.374543)
			(xy 104.207029 -334.41608) (xy 104.164161 -334.451755) (xy 104.116555 -334.480809) (xy 104.065226 -334.502621)
			(xy 104.011269 -334.516727) (xy 103.955832 -334.522827) (xy 103.900098 -334.52079) (xy 103.845255 -334.51066)
			(xy 103.792471 -334.492653) (xy 103.742871 -334.467152) (xy 103.697513 -334.434701) (xy 103.657364 -334.395992)
			(xy 103.623278 -334.351849) (xy 103.595982 -334.303214) (xy 103.576059 -334.251123) (xy 103.563933 -334.196686)
			(xy 103.559862 -334.141064) (xy 103.111639 -334.141064) (xy 103.120893 -334.160805) (xy 103.136961 -334.214212)
			(xy 103.145081 -334.269388) (xy 103.14559 -334.297274) (xy 103.145081 -334.32516) (xy 103.136961 -334.380336)
			(xy 103.120893 -334.433743) (xy 103.097221 -334.48424) (xy 103.066448 -334.530753) (xy 103.029231 -334.57229)
			(xy 102.986363 -334.607965) (xy 102.938757 -334.637019) (xy 102.887428 -334.658831) (xy 102.833471 -334.672937)
			(xy 102.778034 -334.679037) (xy 102.7223 -334.677) (xy 102.667457 -334.66687) (xy 102.614673 -334.648863)
			(xy 102.565073 -334.623362) (xy 102.519715 -334.590911) (xy 102.479566 -334.552202) (xy 102.44548 -334.508059)
			(xy 102.418184 -334.459424) (xy 102.398261 -334.407333) (xy 102.386135 -334.352896) (xy 102.382064 -334.297274)
			(xy 95.957644 -334.297274) (xy 95.957644 -334.774794) (xy 104.55224 -334.774794) (xy 104.556311 -334.719172)
			(xy 104.568437 -334.664735) (xy 104.58836 -334.612644) (xy 104.615656 -334.564009) (xy 104.649742 -334.519866)
			(xy 104.689891 -334.481157) (xy 104.735249 -334.448706) (xy 104.784849 -334.423205) (xy 104.837633 -334.405198)
			(xy 104.892476 -334.395068) (xy 104.94821 -334.393031) (xy 105.003647 -334.399131) (xy 105.057604 -334.413237)
			(xy 105.108933 -334.435049) (xy 105.156539 -334.464103) (xy 105.199407 -334.499778) (xy 105.236624 -334.541315)
			(xy 105.267397 -334.587828) (xy 105.291069 -334.638325) (xy 105.307137 -334.691732) (xy 105.308558 -334.701388)
			(xy 106.182412 -334.701388) (xy 106.186483 -334.645766) (xy 106.198609 -334.591329) (xy 106.218532 -334.539238)
			(xy 106.245828 -334.490603) (xy 106.279914 -334.44646) (xy 106.320063 -334.407751) (xy 106.365421 -334.3753)
			(xy 106.415021 -334.349799) (xy 106.467805 -334.331792) (xy 106.522648 -334.321662) (xy 106.578382 -334.319625)
			(xy 106.633819 -334.325725) (xy 106.687776 -334.339831) (xy 106.739105 -334.361643) (xy 106.786711 -334.390697)
			(xy 106.829579 -334.426372) (xy 106.866796 -334.467909) (xy 106.897569 -334.514422) (xy 106.921241 -334.564919)
			(xy 106.937309 -334.618326) (xy 106.945429 -334.673502) (xy 106.945938 -334.701388) (xy 106.945429 -334.729274)
			(xy 106.937309 -334.78445) (xy 106.921241 -334.837857) (xy 106.897569 -334.888354) (xy 106.866796 -334.934867)
			(xy 106.829579 -334.976404) (xy 106.786711 -335.012079) (xy 106.739105 -335.041133) (xy 106.687776 -335.062945)
			(xy 106.633819 -335.077051) (xy 106.578382 -335.083151) (xy 106.522648 -335.081114) (xy 106.467805 -335.070984)
			(xy 106.415021 -335.052977) (xy 106.365421 -335.027476) (xy 106.320063 -334.995025) (xy 106.279914 -334.956316)
			(xy 106.245828 -334.912173) (xy 106.218532 -334.863538) (xy 106.198609 -334.811447) (xy 106.186483 -334.75701)
			(xy 106.182412 -334.701388) (xy 105.308558 -334.701388) (xy 105.315257 -334.746908) (xy 105.315766 -334.774794)
			(xy 105.315257 -334.80268) (xy 105.307137 -334.857856) (xy 105.291069 -334.911263) (xy 105.267397 -334.96176)
			(xy 105.236624 -335.008273) (xy 105.199407 -335.04981) (xy 105.156539 -335.085485) (xy 105.108933 -335.114539)
			(xy 105.057604 -335.136351) (xy 105.003647 -335.150457) (xy 104.94821 -335.156557) (xy 104.892476 -335.15452)
			(xy 104.837633 -335.14439) (xy 104.784849 -335.126383) (xy 104.735249 -335.100882) (xy 104.689891 -335.068431)
			(xy 104.649742 -335.029722) (xy 104.615656 -334.985579) (xy 104.58836 -334.936944) (xy 104.568437 -334.884853)
			(xy 104.556311 -334.830416) (xy 104.55224 -334.774794) (xy 95.957644 -334.774794) (xy 95.957644 -335.205754)
			(xy 101.972536 -335.205754) (xy 101.980293 -335.1518) (xy 101.995649 -335.099498) (xy 102.018292 -335.049914)
			(xy 102.047761 -335.004058) (xy 102.083457 -334.962862) (xy 102.124652 -334.927166) (xy 102.170507 -334.897696)
			(xy 102.220091 -334.875052) (xy 102.272392 -334.859694) (xy 102.326346 -334.851937) (xy 102.380855 -334.851937)
			(xy 102.43481 -334.859695) (xy 102.487111 -334.875052) (xy 102.536694 -334.897696) (xy 102.58255 -334.927167)
			(xy 102.623744 -334.962863) (xy 102.65944 -335.004059) (xy 102.688909 -335.049916) (xy 102.711552 -335.099499)
			(xy 102.726908 -335.151801) (xy 102.734664 -335.205755) (xy 102.735126 -335.23301) (xy 102.734618 -335.253584)
			(xy 102.733856 -335.264506) (xy 102.741222 -335.284064) (xy 102.808786 -335.353152) (xy 102.82809 -335.361026)
			(xy 102.839012 -335.360772) (xy 102.849934 -335.360518) (xy 102.877182 -335.361015) (xy 102.931122 -335.368775)
			(xy 102.983409 -335.384132) (xy 103.032979 -335.406774) (xy 103.078821 -335.43624) (xy 103.120004 -335.47193)
			(xy 103.155689 -335.513117) (xy 103.185149 -335.558963) (xy 103.207785 -335.608536) (xy 103.223136 -335.660825)
			(xy 103.230889 -335.714766) (xy 103.230888 -335.73593) (xy 103.44988 -335.73593) (xy 103.453951 -335.680308)
			(xy 103.466077 -335.625871) (xy 103.486 -335.57378) (xy 103.513296 -335.525145) (xy 103.547382 -335.481002)
			(xy 103.587531 -335.442293) (xy 103.632889 -335.409842) (xy 103.682489 -335.384341) (xy 103.735273 -335.366334)
			(xy 103.790116 -335.356204) (xy 103.84585 -335.354167) (xy 103.901287 -335.360267) (xy 103.955244 -335.374373)
			(xy 104.006573 -335.396185) (xy 104.054179 -335.425239) (xy 104.097047 -335.460914) (xy 104.134264 -335.502451)
			(xy 104.165037 -335.548964) (xy 104.188709 -335.599461) (xy 104.204777 -335.652868) (xy 104.212897 -335.708044)
			(xy 104.213406 -335.73593) (xy 104.212897 -335.763816) (xy 104.204777 -335.818992) (xy 104.188709 -335.872399)
			(xy 104.184337 -335.881726) (xy 111.234218 -335.881726) (xy 111.238289 -335.826104) (xy 111.250415 -335.771667)
			(xy 111.270338 -335.719576) (xy 111.297634 -335.670941) (xy 111.33172 -335.626798) (xy 111.371869 -335.588089)
			(xy 111.417227 -335.555638) (xy 111.466827 -335.530137) (xy 111.519611 -335.51213) (xy 111.574454 -335.502)
			(xy 111.630188 -335.499963) (xy 111.685625 -335.506063) (xy 111.739582 -335.520169) (xy 111.790911 -335.541981)
			(xy 111.838517 -335.571035) (xy 111.881385 -335.60671) (xy 111.918602 -335.648247) (xy 111.949375 -335.69476)
			(xy 111.973047 -335.745257) (xy 111.989115 -335.798664) (xy 111.997235 -335.85384) (xy 111.997744 -335.881726)
			(xy 111.997235 -335.909612) (xy 111.989115 -335.964788) (xy 111.973047 -336.018195) (xy 111.949375 -336.068692)
			(xy 111.918602 -336.115205) (xy 111.881385 -336.156742) (xy 111.838517 -336.192417) (xy 111.790911 -336.221471)
			(xy 111.739582 -336.243283) (xy 111.685625 -336.257389) (xy 111.630188 -336.263489) (xy 111.574454 -336.261452)
			(xy 111.519611 -336.251322) (xy 111.466827 -336.233315) (xy 111.417227 -336.207814) (xy 111.371869 -336.175363)
			(xy 111.33172 -336.136654) (xy 111.297634 -336.092511) (xy 111.270338 -336.043876) (xy 111.250415 -335.991785)
			(xy 111.238289 -335.937348) (xy 111.234218 -335.881726) (xy 104.184337 -335.881726) (xy 104.165037 -335.922896)
			(xy 104.134264 -335.969409) (xy 104.097047 -336.010946) (xy 104.054179 -336.046621) (xy 104.006573 -336.075675)
			(xy 103.955244 -336.097487) (xy 103.901287 -336.111593) (xy 103.84585 -336.117693) (xy 103.790116 -336.115656)
			(xy 103.735273 -336.105526) (xy 103.682489 -336.087519) (xy 103.632889 -336.062018) (xy 103.587531 -336.029567)
			(xy 103.547382 -335.990858) (xy 103.513296 -335.946715) (xy 103.486 -335.89808) (xy 103.466077 -335.845989)
			(xy 103.453951 -335.791552) (xy 103.44988 -335.73593) (xy 103.230888 -335.73593) (xy 103.230887 -335.769262)
			(xy 103.22313 -335.823203) (xy 103.207775 -335.875491) (xy 103.185135 -335.925061) (xy 103.155672 -335.970905)
			(xy 103.119984 -336.01209) (xy 103.078799 -336.047777) (xy 103.032954 -336.077239) (xy 102.983383 -336.099878)
			(xy 102.931095 -336.115231) (xy 102.877154 -336.122987) (xy 102.822658 -336.122988) (xy 102.768717 -336.115234)
			(xy 102.716428 -336.099882) (xy 102.666856 -336.077245) (xy 102.621011 -336.047784) (xy 102.579824 -336.012099)
			(xy 102.544135 -335.970915) (xy 102.51467 -335.925072) (xy 102.492029 -335.875502) (xy 102.476673 -335.823214)
			(xy 102.468914 -335.769274) (xy 102.468426 -335.742026) (xy 102.468934 -335.721452) (xy 102.469696 -335.71053)
			(xy 102.46233 -335.690972) (xy 102.394766 -335.621884) (xy 102.375462 -335.61401) (xy 102.36454 -335.614264)
			(xy 102.353618 -335.614518) (xy 102.326363 -335.614064) (xy 102.272409 -335.606309) (xy 102.220107 -335.590955)
			(xy 102.170523 -335.568313) (xy 102.124665 -335.538844) (xy 102.083469 -335.50315) (xy 102.047772 -335.461956)
			(xy 102.0183 -335.416101) (xy 101.995655 -335.366518) (xy 101.980296 -335.314217) (xy 101.972538 -335.260263)
			(xy 101.972536 -335.205754) (xy 95.957644 -335.205754) (xy 95.957644 -335.69783) (xy 97.767392 -335.69783)
			(xy 97.771463 -335.642208) (xy 97.783589 -335.587771) (xy 97.803512 -335.53568) (xy 97.830808 -335.487045)
			(xy 97.864894 -335.442902) (xy 97.905043 -335.404193) (xy 97.950401 -335.371742) (xy 98.000001 -335.346241)
			(xy 98.052785 -335.328234) (xy 98.107628 -335.318104) (xy 98.163362 -335.316067) (xy 98.218799 -335.322167)
			(xy 98.272756 -335.336273) (xy 98.324085 -335.358085) (xy 98.371691 -335.387139) (xy 98.414559 -335.422814)
			(xy 98.451776 -335.464351) (xy 98.482549 -335.510864) (xy 98.506221 -335.561361) (xy 98.522289 -335.614768)
			(xy 98.530409 -335.669944) (xy 98.530918 -335.69783) (xy 98.530409 -335.725716) (xy 98.522289 -335.780892)
			(xy 98.506221 -335.834299) (xy 98.482549 -335.884796) (xy 98.451776 -335.931309) (xy 98.414559 -335.972846)
			(xy 98.371691 -336.008521) (xy 98.324085 -336.037575) (xy 98.272756 -336.059387) (xy 98.218799 -336.073493)
			(xy 98.163362 -336.079593) (xy 98.107628 -336.077556) (xy 98.052785 -336.067426) (xy 98.000001 -336.049419)
			(xy 97.950401 -336.023918) (xy 97.905043 -335.991467) (xy 97.864894 -335.952758) (xy 97.830808 -335.908615)
			(xy 97.803512 -335.85998) (xy 97.783589 -335.807889) (xy 97.771463 -335.753452) (xy 97.767392 -335.69783)
			(xy 95.957644 -335.69783) (xy 95.957644 -336.562954) (xy 108.718602 -336.562954) (xy 108.722673 -336.507332)
			(xy 108.734799 -336.452895) (xy 108.754722 -336.400804) (xy 108.782018 -336.352169) (xy 108.816104 -336.308026)
			(xy 108.856253 -336.269317) (xy 108.901611 -336.236866) (xy 108.951211 -336.211365) (xy 109.003995 -336.193358)
			(xy 109.058838 -336.183228) (xy 109.114572 -336.181191) (xy 109.170009 -336.187291) (xy 109.223966 -336.201397)
			(xy 109.275295 -336.223209) (xy 109.322901 -336.252263) (xy 109.365769 -336.287938) (xy 109.402986 -336.329475)
			(xy 109.433759 -336.375988) (xy 109.457431 -336.426485) (xy 109.473499 -336.479892) (xy 109.481619 -336.535068)
			(xy 109.482128 -336.562954) (xy 109.481619 -336.59084) (xy 109.473499 -336.646016) (xy 109.457431 -336.699423)
			(xy 109.433759 -336.74992) (xy 109.402986 -336.796433) (xy 109.365769 -336.83797) (xy 109.322901 -336.873645)
			(xy 109.275295 -336.902699) (xy 109.223966 -336.924511) (xy 109.170009 -336.938617) (xy 109.114572 -336.944717)
			(xy 109.058838 -336.94268) (xy 109.003995 -336.93255) (xy 108.951211 -336.914543) (xy 108.901611 -336.889042)
			(xy 108.856253 -336.856591) (xy 108.816104 -336.817882) (xy 108.782018 -336.773739) (xy 108.754722 -336.725104)
			(xy 108.734799 -336.673013) (xy 108.722673 -336.618576) (xy 108.718602 -336.562954) (xy 95.957644 -336.562954)
			(xy 95.957644 -336.98561) (xy 99.107496 -336.98561) (xy 99.111567 -336.929988) (xy 99.123693 -336.875551)
			(xy 99.143616 -336.82346) (xy 99.170912 -336.774825) (xy 99.204998 -336.730682) (xy 99.245147 -336.691973)
			(xy 99.290505 -336.659522) (xy 99.340105 -336.634021) (xy 99.392889 -336.616014) (xy 99.447732 -336.605884)
			(xy 99.503466 -336.603847) (xy 99.558903 -336.609947) (xy 99.61286 -336.624053) (xy 99.664189 -336.645865)
			(xy 99.711795 -336.674919) (xy 99.754663 -336.710594) (xy 99.79188 -336.752131) (xy 99.822653 -336.798644)
			(xy 99.846325 -336.849141) (xy 99.862393 -336.902548) (xy 99.870513 -336.957724) (xy 99.871022 -336.98561)
			(xy 99.870513 -337.013496) (xy 99.862393 -337.068672) (xy 99.846325 -337.122079) (xy 99.822653 -337.172576)
			(xy 99.79188 -337.219089) (xy 99.754663 -337.260626) (xy 99.711795 -337.296301) (xy 99.664189 -337.325355)
			(xy 99.61286 -337.347167) (xy 99.558903 -337.361273) (xy 99.503466 -337.367373) (xy 99.447732 -337.365336)
			(xy 99.392889 -337.355206) (xy 99.340105 -337.337199) (xy 99.290505 -337.311698) (xy 99.245147 -337.279247)
			(xy 99.204998 -337.240538) (xy 99.170912 -337.196395) (xy 99.143616 -337.14776) (xy 99.123693 -337.095669)
			(xy 99.111567 -337.041232) (xy 99.107496 -336.98561) (xy 95.957644 -336.98561) (xy 95.957644 -337.247992)
			(xy 95.958116 -337.257864) (xy 95.965572 -337.276149) (xy 95.972122 -337.283552) (xy 95.972376 -337.283806)
			(xy 100.457254 -341.768684) (xy 100.464092 -341.776085) (xy 100.471803 -341.794684) (xy 100.47224 -341.804752)
			(xy 100.47224 -342.317324) (xy 100.472748 -342.325452) (xy 100.47478 -342.33739) (xy 100.475796 -342.3412)
			(xy 100.476304 -342.343232) (xy 100.476558 -342.344502) (xy 100.482942 -342.366898) (xy 100.490081 -342.412918)
			(xy 100.490782 -342.436196) (xy 100.490782 -342.439498) (xy 100.490284 -342.46533) (xy 100.482247 -342.516364)
			(xy 100.47478 -342.541098) (xy 100.47224 -342.548972) (xy 100.47224 -342.694268) (xy 102.35157 -342.694268)
			(xy 102.35157 -342.634332) (xy 102.359393 -342.574909) (xy 102.374905 -342.517016) (xy 102.397841 -342.461642)
			(xy 102.427809 -342.409736) (xy 102.464294 -342.362185) (xy 102.506675 -342.319804) (xy 102.554224 -342.283316)
			(xy 102.60613 -342.253347) (xy 102.661502 -342.23041) (xy 102.719395 -342.214896) (xy 102.778818 -342.207071)
			(xy 102.808786 -342.20658) (xy 103.672386 -342.20658) (xy 103.702355 -342.207072) (xy 103.76178 -342.214894)
			(xy 103.819676 -342.230405) (xy 103.875051 -342.253341) (xy 103.926959 -342.283309) (xy 103.974512 -342.319796)
			(xy 104.016895 -342.362178) (xy 104.053383 -342.409729) (xy 104.083352 -342.461636) (xy 104.085479 -342.466772)
			(xy 111.4808 -342.466772) (xy 111.4808 -342.412228) (xy 111.488562 -342.358241) (xy 111.503929 -342.305907)
			(xy 111.526587 -342.256293) (xy 111.556075 -342.210409) (xy 111.591794 -342.169188) (xy 111.633015 -342.133471)
			(xy 111.6789 -342.103983) (xy 111.728515 -342.081326) (xy 111.780848 -342.06596) (xy 111.834836 -342.058199)
			(xy 111.862108 -342.057736) (xy 112.725708 -342.057736) (xy 112.752977 -342.058227) (xy 112.806959 -342.06599)
			(xy 112.859288 -342.081355) (xy 112.908897 -342.104012) (xy 112.954776 -342.133498) (xy 112.995993 -342.169213)
			(xy 113.031707 -342.21043) (xy 113.061192 -342.256311) (xy 113.083847 -342.30592) (xy 113.099212 -342.358249)
			(xy 113.106974 -342.412231) (xy 113.106974 -342.466768) (xy 114.589822 -342.466768) (xy 114.589822 -342.412232)
			(xy 114.597583 -342.358251) (xy 114.612947 -342.305924) (xy 114.635601 -342.256315) (xy 114.665084 -342.210436)
			(xy 114.700796 -342.169219) (xy 114.74201 -342.133503) (xy 114.787887 -342.104016) (xy 114.837494 -342.081358)
			(xy 114.88982 -342.06599) (xy 114.9438 -342.058225) (xy 114.971068 -342.057736) (xy 115.834668 -342.057736)
			(xy 115.86194 -342.058201) (xy 115.91593 -342.06596) (xy 115.968267 -342.081323) (xy 116.017884 -342.103979)
			(xy 116.063771 -342.133465) (xy 116.104995 -342.169183) (xy 116.140715 -342.210403) (xy 116.170206 -342.256288)
			(xy 116.192866 -342.305903) (xy 116.208233 -342.358238) (xy 116.215996 -342.412228) (xy 116.215996 -342.466772)
			(xy 117.6987 -342.466772) (xy 117.6987 -342.412228) (xy 117.706462 -342.358238) (xy 117.72183 -342.305903)
			(xy 117.74449 -342.256288) (xy 117.77398 -342.210402) (xy 117.809701 -342.169181) (xy 117.850925 -342.133464)
			(xy 117.896812 -342.103977) (xy 117.946429 -342.08132) (xy 117.998765 -342.065957) (xy 118.052756 -342.058198)
			(xy 118.080028 -342.057736) (xy 118.943628 -342.057736) (xy 118.970896 -342.058228) (xy 119.024876 -342.065993)
			(xy 119.077202 -342.081361) (xy 119.126809 -342.104019) (xy 119.172686 -342.133505) (xy 119.2139 -342.16922)
			(xy 119.249612 -342.210437) (xy 119.279095 -342.256316) (xy 119.301749 -342.305924) (xy 119.317113 -342.358251)
			(xy 119.324874 -342.412232) (xy 119.324874 -342.466768) (xy 119.324874 -342.466769) (xy 120.807722 -342.466769)
			(xy 120.807722 -342.412231) (xy 120.815484 -342.358248) (xy 120.830849 -342.305919) (xy 120.853504 -342.25631)
			(xy 120.882989 -342.210429) (xy 120.918703 -342.169212) (xy 120.95992 -342.133496) (xy 121.005799 -342.10401)
			(xy 121.055408 -342.081353) (xy 121.107736 -342.065986) (xy 121.161719 -342.058223) (xy 121.188988 -342.057736)
			(xy 122.052588 -342.057736) (xy 122.079859 -342.058203) (xy 122.133847 -342.065963) (xy 122.186181 -342.081329)
			(xy 122.235796 -342.103985) (xy 122.28168 -342.133472) (xy 122.322902 -342.16919) (xy 122.35862 -342.21041)
			(xy 122.388109 -342.256294) (xy 122.410767 -342.305908) (xy 122.426134 -342.358241) (xy 122.433896 -342.412229)
			(xy 122.433896 -342.466771) (xy 122.433896 -342.466773) (xy 123.9166 -342.466773) (xy 123.9166 -342.412227)
			(xy 123.924363 -342.358235) (xy 123.939732 -342.305899) (xy 123.962393 -342.256282) (xy 123.991885 -342.210396)
			(xy 124.027608 -342.169174) (xy 124.068834 -342.133456) (xy 124.114724 -342.10397) (xy 124.164344 -342.081315)
			(xy 124.216682 -342.065953) (xy 124.270675 -342.058196) (xy 124.297948 -342.057736) (xy 125.161548 -342.057736)
			(xy 125.188815 -342.05823) (xy 125.242793 -342.065997) (xy 125.295117 -342.081366) (xy 125.34472 -342.104025)
			(xy 125.390595 -342.133512) (xy 125.431807 -342.169227) (xy 125.467517 -342.210443) (xy 125.496998 -342.256322)
			(xy 125.519651 -342.305928) (xy 125.535013 -342.358254) (xy 125.542774 -342.412233) (xy 125.542774 -342.466767)
			(xy 125.542773 -342.466772) (xy 127.0256 -342.466772) (xy 127.0256 -342.412228) (xy 127.033362 -342.358241)
			(xy 127.048729 -342.305907) (xy 127.071387 -342.256293) (xy 127.100875 -342.210409) (xy 127.136594 -342.169188)
			(xy 127.177815 -342.133471) (xy 127.2237 -342.103983) (xy 127.273315 -342.081326) (xy 127.325648 -342.06596)
			(xy 127.379636 -342.058199) (xy 127.406908 -342.057736) (xy 128.270508 -342.057736) (xy 128.297777 -342.058227)
			(xy 128.351759 -342.06599) (xy 128.404088 -342.081355) (xy 128.453697 -342.104012) (xy 128.499576 -342.133498)
			(xy 128.540793 -342.169213) (xy 128.576507 -342.21043) (xy 128.605992 -342.256311) (xy 128.628647 -342.30592)
			(xy 128.644012 -342.358249) (xy 128.651774 -342.412231) (xy 128.651774 -342.466768) (xy 130.134622 -342.466768)
			(xy 130.134622 -342.412232) (xy 130.142383 -342.358251) (xy 130.157747 -342.305924) (xy 130.180401 -342.256315)
			(xy 130.209884 -342.210436) (xy 130.245596 -342.169219) (xy 130.28681 -342.133503) (xy 130.332687 -342.104016)
			(xy 130.382294 -342.081358) (xy 130.43462 -342.06599) (xy 130.4886 -342.058225) (xy 130.515868 -342.057736)
			(xy 131.379468 -342.057736) (xy 131.40674 -342.058201) (xy 131.46073 -342.06596) (xy 131.513067 -342.081323)
			(xy 131.562684 -342.103979) (xy 131.608571 -342.133465) (xy 131.649795 -342.169183) (xy 131.685515 -342.210403)
			(xy 131.715006 -342.256288) (xy 131.737666 -342.305903) (xy 131.753033 -342.358238) (xy 131.760796 -342.412228)
			(xy 131.760796 -342.466772) (xy 133.2435 -342.466772) (xy 133.2435 -342.412228) (xy 133.251262 -342.358238)
			(xy 133.26663 -342.305903) (xy 133.28929 -342.256288) (xy 133.31878 -342.210402) (xy 133.354501 -342.169181)
			(xy 133.395725 -342.133464) (xy 133.441612 -342.103977) (xy 133.491229 -342.08132) (xy 133.543565 -342.065957)
			(xy 133.597556 -342.058198) (xy 133.624828 -342.057736) (xy 134.488428 -342.057736) (xy 134.515696 -342.058228)
			(xy 134.569676 -342.065993) (xy 134.622002 -342.081361) (xy 134.671609 -342.104019) (xy 134.717486 -342.133505)
			(xy 134.7587 -342.16922) (xy 134.794412 -342.210437) (xy 134.823895 -342.256316) (xy 134.846549 -342.305924)
			(xy 134.861913 -342.358251) (xy 134.869674 -342.412232) (xy 134.869674 -342.466768) (xy 134.869674 -342.466769)
			(xy 136.352522 -342.466769) (xy 136.352522 -342.412231) (xy 136.360284 -342.358248) (xy 136.375649 -342.305919)
			(xy 136.398304 -342.25631) (xy 136.427789 -342.210429) (xy 136.463503 -342.169212) (xy 136.50472 -342.133496)
			(xy 136.550599 -342.10401) (xy 136.600208 -342.081353) (xy 136.652536 -342.065986) (xy 136.706519 -342.058223)
			(xy 136.733788 -342.057736) (xy 137.597388 -342.057736) (xy 137.624659 -342.058203) (xy 137.678647 -342.065963)
			(xy 137.730981 -342.081329) (xy 137.780596 -342.103985) (xy 137.82648 -342.133472) (xy 137.867702 -342.16919)
			(xy 137.90342 -342.21041) (xy 137.932909 -342.256294) (xy 137.955567 -342.305908) (xy 137.970934 -342.358241)
			(xy 137.978696 -342.412229) (xy 137.978696 -342.466771) (xy 137.970934 -342.520759) (xy 137.955567 -342.573092)
			(xy 137.932909 -342.622706) (xy 137.90342 -342.66859) (xy 137.867702 -342.70981) (xy 137.82648 -342.745528)
			(xy 137.780596 -342.775015) (xy 137.730981 -342.797671) (xy 137.678647 -342.813037) (xy 137.624659 -342.820797)
			(xy 137.597388 -342.82126) (xy 136.733788 -342.82126) (xy 136.706519 -342.820777) (xy 136.652536 -342.813014)
			(xy 136.600208 -342.797647) (xy 136.550599 -342.77499) (xy 136.50472 -342.745504) (xy 136.463503 -342.709788)
			(xy 136.427789 -342.668571) (xy 136.398304 -342.62269) (xy 136.375649 -342.573081) (xy 136.360284 -342.520752)
			(xy 136.352522 -342.466769) (xy 134.869674 -342.466769) (xy 134.861913 -342.520749) (xy 134.846549 -342.573076)
			(xy 134.823895 -342.622684) (xy 134.794412 -342.668563) (xy 134.7587 -342.70978) (xy 134.717486 -342.745495)
			(xy 134.671609 -342.774981) (xy 134.622002 -342.797639) (xy 134.569676 -342.813007) (xy 134.515696 -342.820772)
			(xy 134.488428 -342.82126) (xy 133.624828 -342.82126) (xy 133.597556 -342.820802) (xy 133.543565 -342.813043)
			(xy 133.491229 -342.79768) (xy 133.441612 -342.775023) (xy 133.395725 -342.745536) (xy 133.354501 -342.709819)
			(xy 133.31878 -342.668598) (xy 133.28929 -342.622712) (xy 133.26663 -342.573097) (xy 133.251262 -342.520762)
			(xy 133.2435 -342.466772) (xy 131.760796 -342.466772) (xy 131.753033 -342.520762) (xy 131.737666 -342.573097)
			(xy 131.715006 -342.622712) (xy 131.685515 -342.668597) (xy 131.649795 -342.709817) (xy 131.608571 -342.745535)
			(xy 131.562684 -342.775021) (xy 131.513067 -342.797677) (xy 131.46073 -342.81304) (xy 131.40674 -342.820799)
			(xy 131.379468 -342.82126) (xy 130.515868 -342.82126) (xy 130.4886 -342.820775) (xy 130.43462 -342.81301)
			(xy 130.382294 -342.797642) (xy 130.332687 -342.774984) (xy 130.28681 -342.745497) (xy 130.245596 -342.709781)
			(xy 130.209884 -342.668564) (xy 130.180401 -342.622685) (xy 130.157747 -342.573076) (xy 130.142383 -342.520749)
			(xy 130.134622 -342.466768) (xy 128.651774 -342.466768) (xy 128.651774 -342.466769) (xy 128.644012 -342.520751)
			(xy 128.628647 -342.57308) (xy 128.605992 -342.622689) (xy 128.576507 -342.66857) (xy 128.540793 -342.709787)
			(xy 128.499576 -342.745502) (xy 128.453697 -342.774988) (xy 128.404088 -342.797645) (xy 128.351759 -342.81301)
			(xy 128.297777 -342.820773) (xy 128.270508 -342.82126) (xy 127.406908 -342.82126) (xy 127.379636 -342.820801)
			(xy 127.325648 -342.81304) (xy 127.273315 -342.797674) (xy 127.2237 -342.775017) (xy 127.177815 -342.745529)
			(xy 127.136594 -342.709812) (xy 127.100875 -342.668591) (xy 127.071387 -342.622707) (xy 127.048729 -342.573093)
			(xy 127.033362 -342.520759) (xy 127.0256 -342.466772) (xy 125.542773 -342.466772) (xy 125.535013 -342.520746)
			(xy 125.519651 -342.573072) (xy 125.496998 -342.622678) (xy 125.467517 -342.668557) (xy 125.431807 -342.709773)
			(xy 125.390595 -342.745488) (xy 125.34472 -342.774975) (xy 125.295117 -342.797634) (xy 125.242793 -342.813003)
			(xy 125.188815 -342.82077) (xy 125.161548 -342.82126) (xy 124.297948 -342.82126) (xy 124.270675 -342.820804)
			(xy 124.216682 -342.813047) (xy 124.164344 -342.797685) (xy 124.114724 -342.77503) (xy 124.068834 -342.745544)
			(xy 124.027608 -342.709826) (xy 123.991885 -342.668604) (xy 123.962393 -342.622718) (xy 123.939732 -342.573101)
			(xy 123.924363 -342.520765) (xy 123.9166 -342.466773) (xy 122.433896 -342.466773) (xy 122.426134 -342.520759)
			(xy 122.410767 -342.573092) (xy 122.388109 -342.622706) (xy 122.35862 -342.66859) (xy 122.322902 -342.70981)
			(xy 122.28168 -342.745528) (xy 122.235796 -342.775015) (xy 122.186181 -342.797671) (xy 122.133847 -342.813037)
			(xy 122.079859 -342.820797) (xy 122.052588 -342.82126) (xy 121.188988 -342.82126) (xy 121.161719 -342.820777)
			(xy 121.107736 -342.813014) (xy 121.055408 -342.797647) (xy 121.005799 -342.77499) (xy 120.95992 -342.745504)
			(xy 120.918703 -342.709788) (xy 120.882989 -342.668571) (xy 120.853504 -342.62269) (xy 120.830849 -342.573081)
			(xy 120.815484 -342.520752) (xy 120.807722 -342.466769) (xy 119.324874 -342.466769) (xy 119.317113 -342.520749)
			(xy 119.301749 -342.573076) (xy 119.279095 -342.622684) (xy 119.249612 -342.668563) (xy 119.2139 -342.70978)
			(xy 119.172686 -342.745495) (xy 119.126809 -342.774981) (xy 119.077202 -342.797639) (xy 119.024876 -342.813007)
			(xy 118.970896 -342.820772) (xy 118.943628 -342.82126) (xy 118.080028 -342.82126) (xy 118.052756 -342.820802)
			(xy 117.998765 -342.813043) (xy 117.946429 -342.79768) (xy 117.896812 -342.775023) (xy 117.850925 -342.745536)
			(xy 117.809701 -342.709819) (xy 117.77398 -342.668598) (xy 117.74449 -342.622712) (xy 117.72183 -342.573097)
			(xy 117.706462 -342.520762) (xy 117.6987 -342.466772) (xy 116.215996 -342.466772) (xy 116.208233 -342.520762)
			(xy 116.192866 -342.573097) (xy 116.170206 -342.622712) (xy 116.140715 -342.668597) (xy 116.104995 -342.709817)
			(xy 116.063771 -342.745535) (xy 116.017884 -342.775021) (xy 115.968267 -342.797677) (xy 115.91593 -342.81304)
			(xy 115.86194 -342.820799) (xy 115.834668 -342.82126) (xy 114.971068 -342.82126) (xy 114.9438 -342.820775)
			(xy 114.88982 -342.81301) (xy 114.837494 -342.797642) (xy 114.787887 -342.774984) (xy 114.74201 -342.745497)
			(xy 114.700796 -342.709781) (xy 114.665084 -342.668564) (xy 114.635601 -342.622685) (xy 114.612947 -342.573076)
			(xy 114.597583 -342.520749) (xy 114.589822 -342.466768) (xy 113.106974 -342.466768) (xy 113.106974 -342.466769)
			(xy 113.099212 -342.520751) (xy 113.083847 -342.57308) (xy 113.061192 -342.622689) (xy 113.031707 -342.66857)
			(xy 112.995993 -342.709787) (xy 112.954776 -342.745502) (xy 112.908897 -342.774988) (xy 112.859288 -342.797645)
			(xy 112.806959 -342.81301) (xy 112.752977 -342.820773) (xy 112.725708 -342.82126) (xy 111.862108 -342.82126)
			(xy 111.834836 -342.820801) (xy 111.780848 -342.81304) (xy 111.728515 -342.797674) (xy 111.6789 -342.775017)
			(xy 111.633015 -342.745529) (xy 111.591794 -342.709812) (xy 111.556075 -342.668591) (xy 111.526587 -342.622707)
			(xy 111.503929 -342.573093) (xy 111.488562 -342.520759) (xy 111.4808 -342.466772) (xy 104.085479 -342.466772)
			(xy 104.10629 -342.517011) (xy 104.121803 -342.574906) (xy 104.129627 -342.634331) (xy 104.129627 -342.694269)
			(xy 104.121803 -342.753694) (xy 104.10629 -342.811589) (xy 104.083352 -342.866964) (xy 104.053383 -342.918871)
			(xy 104.016895 -342.966422) (xy 103.974512 -343.008804) (xy 103.926959 -343.045291) (xy 103.875051 -343.075259)
			(xy 103.819676 -343.098195) (xy 103.76178 -343.113706) (xy 103.702355 -343.121528) (xy 103.672386 -343.121996)
			(xy 102.808786 -343.121996) (xy 102.778818 -343.121529) (xy 102.719395 -343.113704) (xy 102.661502 -343.09819)
			(xy 102.60613 -343.075253) (xy 102.554224 -343.045284) (xy 102.506675 -343.008796) (xy 102.464294 -342.966415)
			(xy 102.427809 -342.918864) (xy 102.397841 -342.866958) (xy 102.374905 -342.811584) (xy 102.359393 -342.753691)
			(xy 102.35157 -342.694268) (xy 100.47224 -342.694268) (xy 100.47224 -343.446862) (xy 101.207568 -343.446862)
			(xy 101.211639 -343.39124) (xy 101.223765 -343.336803) (xy 101.243688 -343.284712) (xy 101.270984 -343.236077)
			(xy 101.30507 -343.191934) (xy 101.345219 -343.153225) (xy 101.390577 -343.120774) (xy 101.440177 -343.095273)
			(xy 101.492961 -343.077266) (xy 101.547804 -343.067136) (xy 101.603538 -343.065099) (xy 101.658975 -343.071199)
			(xy 101.712932 -343.085305) (xy 101.764261 -343.107117) (xy 101.811867 -343.136171) (xy 101.854735 -343.171846)
			(xy 101.891952 -343.213383) (xy 101.922725 -343.259896) (xy 101.946397 -343.310393) (xy 101.962465 -343.3638)
			(xy 101.970585 -343.418976) (xy 101.971094 -343.446862) (xy 101.970585 -343.474748) (xy 101.962465 -343.529924)
			(xy 101.946397 -343.583331) (xy 101.922725 -343.633828) (xy 101.891952 -343.680341) (xy 101.854735 -343.721878)
			(xy 101.811867 -343.757553) (xy 101.764261 -343.786607) (xy 101.712932 -343.808419) (xy 101.658975 -343.822525)
			(xy 101.603538 -343.828625) (xy 101.547804 -343.826588) (xy 101.492961 -343.816458) (xy 101.440177 -343.798451)
			(xy 101.390577 -343.77295) (xy 101.345219 -343.740499) (xy 101.30507 -343.70179) (xy 101.270984 -343.657647)
			(xy 101.243688 -343.609012) (xy 101.223765 -343.556921) (xy 101.211639 -343.502484) (xy 101.207568 -343.446862)
			(xy 100.47224 -343.446862) (xy 100.47224 -345.228926) (xy 105.613452 -345.228926) (xy 105.617523 -345.173304)
			(xy 105.629649 -345.118867) (xy 105.649572 -345.066776) (xy 105.676868 -345.018141) (xy 105.710954 -344.973998)
			(xy 105.751103 -344.935289) (xy 105.796461 -344.902838) (xy 105.846061 -344.877337) (xy 105.898845 -344.85933)
			(xy 105.953688 -344.8492) (xy 106.009422 -344.847163) (xy 106.064859 -344.853263) (xy 106.118816 -344.867369)
			(xy 106.170145 -344.889181) (xy 106.217751 -344.918235) (xy 106.260619 -344.95391) (xy 106.297836 -344.995447)
			(xy 106.328609 -345.04196) (xy 106.352281 -345.092457) (xy 106.368349 -345.145864) (xy 106.376469 -345.20104)
			(xy 106.376978 -345.228926) (xy 106.376469 -345.256812) (xy 106.368349 -345.311988) (xy 106.352281 -345.365395)
			(xy 106.328609 -345.415892) (xy 106.297836 -345.462405) (xy 106.260619 -345.503942) (xy 106.217751 -345.539617)
			(xy 106.174964 -345.56573) (xy 107.785662 -345.56573) (xy 107.786148 -345.539579) (xy 107.793301 -345.487769)
			(xy 107.807463 -345.437422) (xy 107.828368 -345.38948) (xy 107.855624 -345.344842) (xy 107.888722 -345.304345)
			(xy 107.927041 -345.268749) (xy 107.969862 -345.238719) (xy 107.992926 -345.226386) (xy 108.004967 -345.21971)
			(xy 108.025252 -345.201113) (xy 108.039828 -345.177771) (xy 108.047635 -345.151382) (xy 108.048105 -345.123867)
			(xy 108.041203 -345.097227) (xy 108.027431 -345.073401) (xy 108.007792 -345.054123) (xy 107.995974 -345.047062)
			(xy 107.970936 -345.032486) (xy 107.925169 -344.996967) (xy 107.885299 -344.954935) (xy 107.852244 -344.907358)
			(xy 107.826763 -344.85533) (xy 107.809442 -344.800047) (xy 107.800679 -344.74278) (xy 107.80014 -344.713814)
			(xy 107.800626 -344.686563) (xy 107.808382 -344.632615) (xy 107.823737 -344.58032) (xy 107.846379 -344.530743)
			(xy 107.875845 -344.484893) (xy 107.911536 -344.443702) (xy 107.952727 -344.408011) (xy 107.998577 -344.378545)
			(xy 108.048154 -344.355903) (xy 108.100449 -344.340548) (xy 108.154397 -344.332792) (xy 108.208899 -344.332792)
			(xy 108.262847 -344.340548) (xy 108.315142 -344.355903) (xy 108.364719 -344.378545) (xy 108.410569 -344.408011)
			(xy 108.45176 -344.443702) (xy 108.487451 -344.484893) (xy 108.516917 -344.530743) (xy 108.539559 -344.58032)
			(xy 108.554914 -344.632615) (xy 108.56267 -344.686563) (xy 108.563156 -344.713814) (xy 108.562696 -344.739965)
			(xy 108.555538 -344.791776) (xy 108.541371 -344.842124) (xy 108.520462 -344.890066) (xy 108.493202 -344.934703)
			(xy 108.460101 -344.975199) (xy 108.42178 -345.010796) (xy 108.378957 -345.040825) (xy 108.355892 -345.053158)
			(xy 108.343811 -345.059769) (xy 108.323518 -345.078376) (xy 108.308939 -345.10173) (xy 108.301132 -345.128132)
			(xy 108.300668 -345.155659) (xy 108.30758 -345.182309) (xy 108.321364 -345.206141) (xy 108.341018 -345.225421)
			(xy 108.352844 -345.232482) (xy 108.377882 -345.247058) (xy 108.423653 -345.282574) (xy 108.463526 -345.324604)
			(xy 108.496584 -345.372181) (xy 108.522065 -345.42421) (xy 108.539383 -345.479495) (xy 108.541352 -345.492368)
			(xy 111.480847 -345.492368) (xy 111.480847 -345.437832) (xy 111.488609 -345.383851) (xy 111.503974 -345.331524)
			(xy 111.526629 -345.281916) (xy 111.556114 -345.236038) (xy 111.591828 -345.194822) (xy 111.633044 -345.159109)
			(xy 111.678923 -345.129625) (xy 111.728531 -345.106971) (xy 111.780859 -345.091607) (xy 111.83484 -345.083847)
			(xy 111.862108 -345.083384) (xy 112.725708 -345.083384) (xy 112.75298 -345.083779) (xy 112.80697 -345.091543)
			(xy 112.859304 -345.106911) (xy 112.90892 -345.12957) (xy 112.954805 -345.15906) (xy 112.996027 -345.194779)
			(xy 113.031745 -345.236001) (xy 113.061234 -345.281888) (xy 113.083892 -345.331503) (xy 113.099259 -345.383838)
			(xy 113.107021 -345.437828) (xy 113.107021 -345.492365) (xy 114.58987 -345.492365) (xy 114.58987 -345.437835)
			(xy 114.59763 -345.383861) (xy 114.612992 -345.33154) (xy 114.635643 -345.281938) (xy 114.665122 -345.236064)
			(xy 114.70083 -345.194853) (xy 114.742039 -345.159142) (xy 114.78791 -345.129658) (xy 114.83751 -345.107003)
			(xy 114.88983 -345.091637) (xy 114.943803 -345.083872) (xy 114.971068 -345.083384) (xy 115.834668 -345.083384)
			(xy 115.861944 -345.083753) (xy 115.915941 -345.091513) (xy 115.968283 -345.106878) (xy 116.017907 -345.129537)
			(xy 116.0638 -345.159027) (xy 116.105029 -345.194749) (xy 116.140754 -345.235975) (xy 116.170248 -345.281865)
			(xy 116.192911 -345.331487) (xy 116.20828 -345.383828) (xy 116.216044 -345.437824) (xy 116.216044 -345.492369)
			(xy 117.698747 -345.492369) (xy 117.698747 -345.437831) (xy 117.706509 -345.383848) (xy 117.721875 -345.33152)
			(xy 117.744532 -345.281911) (xy 117.774019 -345.236031) (xy 117.809735 -345.194815) (xy 117.850953 -345.159102)
			(xy 117.896835 -345.129619) (xy 117.946446 -345.106965) (xy 117.998776 -345.091603) (xy 118.052759 -345.083845)
			(xy 118.080028 -345.083384) (xy 118.943628 -345.083384) (xy 118.970899 -345.08378) (xy 119.024886 -345.091546)
			(xy 119.077219 -345.106916) (xy 119.126832 -345.129576) (xy 119.172714 -345.159067) (xy 119.213934 -345.194786)
			(xy 119.24965 -345.236008) (xy 119.279137 -345.281893) (xy 119.301794 -345.331507) (xy 119.31716 -345.383841)
			(xy 119.324922 -345.437829) (xy 119.324922 -345.492366) (xy 120.80777 -345.492366) (xy 120.80777 -345.437834)
			(xy 120.815531 -345.383858) (xy 120.830894 -345.331536) (xy 120.853546 -345.281933) (xy 120.883027 -345.236058)
			(xy 120.918737 -345.194846) (xy 120.959948 -345.159135) (xy 121.005822 -345.129652) (xy 121.055425 -345.106998)
			(xy 121.107747 -345.091633) (xy 121.161722 -345.083871) (xy 121.188988 -345.083384) (xy 122.052588 -345.083384)
			(xy 122.079863 -345.083755) (xy 122.133857 -345.091516) (xy 122.186198 -345.106884) (xy 122.235819 -345.129543)
			(xy 122.281709 -345.159034) (xy 122.322936 -345.194756) (xy 122.358659 -345.235981) (xy 122.388151 -345.281871)
			(xy 122.410812 -345.331491) (xy 122.426181 -345.383831) (xy 122.433944 -345.437825) (xy 122.433944 -345.49237)
			(xy 123.916648 -345.49237) (xy 123.916648 -345.43783) (xy 123.92441 -345.383846) (xy 123.939777 -345.331515)
			(xy 123.962435 -345.281905) (xy 123.991924 -345.236024) (xy 124.027642 -345.194808) (xy 124.068863 -345.159095)
			(xy 124.114747 -345.129612) (xy 124.16436 -345.10696) (xy 124.216692 -345.0916) (xy 124.270678 -345.083844)
			(xy 124.297948 -345.083384) (xy 125.161548 -345.083384) (xy 125.188818 -345.083782) (xy 125.242803 -345.09155)
			(xy 125.295133 -345.106921) (xy 125.344744 -345.129583) (xy 125.390624 -345.159074) (xy 125.431841 -345.194793)
			(xy 125.467555 -345.236015) (xy 125.49704 -345.281899) (xy 125.519695 -345.331512) (xy 125.53506 -345.383844)
			(xy 125.542822 -345.43783) (xy 125.542822 -345.492368) (xy 127.025647 -345.492368) (xy 127.025647 -345.437832)
			(xy 127.033409 -345.383851) (xy 127.048774 -345.331524) (xy 127.071429 -345.281916) (xy 127.100914 -345.236038)
			(xy 127.136628 -345.194822) (xy 127.177844 -345.159109) (xy 127.223723 -345.129625) (xy 127.273331 -345.106971)
			(xy 127.325659 -345.091607) (xy 127.37964 -345.083847) (xy 127.406908 -345.083384) (xy 128.270508 -345.083384)
			(xy 128.29778 -345.083779) (xy 128.35177 -345.091543) (xy 128.404104 -345.106911) (xy 128.45372 -345.12957)
			(xy 128.499605 -345.15906) (xy 128.540827 -345.194779) (xy 128.576545 -345.236001) (xy 128.606034 -345.281888)
			(xy 128.628692 -345.331503) (xy 128.644059 -345.383838) (xy 128.651821 -345.437828) (xy 128.651821 -345.492365)
			(xy 130.13467 -345.492365) (xy 130.13467 -345.437835) (xy 130.14243 -345.383861) (xy 130.157792 -345.33154)
			(xy 130.180443 -345.281938) (xy 130.209922 -345.236064) (xy 130.24563 -345.194853) (xy 130.286839 -345.159142)
			(xy 130.33271 -345.129658) (xy 130.38231 -345.107003) (xy 130.43463 -345.091637) (xy 130.488603 -345.083872)
			(xy 130.515868 -345.083384) (xy 131.379468 -345.083384) (xy 131.406744 -345.083753) (xy 131.460741 -345.091513)
			(xy 131.513083 -345.106878) (xy 131.562707 -345.129537) (xy 131.6086 -345.159027) (xy 131.649829 -345.194749)
			(xy 131.685554 -345.235975) (xy 131.715048 -345.281865) (xy 131.737711 -345.331487) (xy 131.75308 -345.383828)
			(xy 131.760844 -345.437824) (xy 131.760844 -345.492369) (xy 133.243547 -345.492369) (xy 133.243547 -345.437831)
			(xy 133.251309 -345.383848) (xy 133.266675 -345.33152) (xy 133.289332 -345.281911) (xy 133.318819 -345.236031)
			(xy 133.354535 -345.194815) (xy 133.395753 -345.159102) (xy 133.441635 -345.129619) (xy 133.491246 -345.106965)
			(xy 133.543576 -345.091603) (xy 133.597559 -345.083845) (xy 133.624828 -345.083384) (xy 134.488428 -345.083384)
			(xy 134.515699 -345.08378) (xy 134.569686 -345.091546) (xy 134.622019 -345.106916) (xy 134.671632 -345.129576)
			(xy 134.717514 -345.159067) (xy 134.758734 -345.194786) (xy 134.79445 -345.236008) (xy 134.823937 -345.281893)
			(xy 134.846594 -345.331507) (xy 134.86196 -345.383841) (xy 134.869722 -345.437829) (xy 134.869722 -345.492366)
			(xy 136.35257 -345.492366) (xy 136.35257 -345.437834) (xy 136.360331 -345.383858) (xy 136.375694 -345.331536)
			(xy 136.398346 -345.281933) (xy 136.427827 -345.236058) (xy 136.463537 -345.194846) (xy 136.504748 -345.159135)
			(xy 136.550622 -345.129652) (xy 136.600225 -345.106998) (xy 136.652547 -345.091633) (xy 136.706522 -345.083871)
			(xy 136.733788 -345.083384) (xy 137.597388 -345.083384) (xy 137.624663 -345.083755) (xy 137.678657 -345.091516)
			(xy 137.730998 -345.106884) (xy 137.780619 -345.129543) (xy 137.826509 -345.159034) (xy 137.867736 -345.194756)
			(xy 137.903459 -345.235981) (xy 137.932951 -345.281871) (xy 137.955612 -345.331491) (xy 137.970981 -345.383831)
			(xy 137.978744 -345.437825) (xy 137.978744 -345.492375) (xy 137.970981 -345.546369) (xy 137.955612 -345.598709)
			(xy 137.932951 -345.648329) (xy 137.903459 -345.694219) (xy 137.867736 -345.735444) (xy 137.826509 -345.771166)
			(xy 137.780619 -345.800657) (xy 137.730998 -345.823316) (xy 137.678658 -345.838684) (xy 137.624663 -345.846445)
			(xy 137.597388 -345.846908) (xy 136.733788 -345.846908) (xy 136.706522 -345.846329) (xy 136.652547 -345.838567)
			(xy 136.600225 -345.823202) (xy 136.550622 -345.800548) (xy 136.504748 -345.771065) (xy 136.463537 -345.735354)
			(xy 136.427827 -345.694142) (xy 136.398346 -345.648267) (xy 136.375694 -345.598664) (xy 136.360331 -345.546342)
			(xy 136.35257 -345.492366) (xy 134.869722 -345.492366) (xy 134.869722 -345.492371) (xy 134.86196 -345.546359)
			(xy 134.846594 -345.598693) (xy 134.823937 -345.648307) (xy 134.79445 -345.694192) (xy 134.758734 -345.735414)
			(xy 134.717514 -345.771133) (xy 134.671632 -345.800624) (xy 134.622019 -345.823284) (xy 134.569686 -345.838654)
			(xy 134.515699 -345.84642) (xy 134.488428 -345.846908) (xy 133.624828 -345.846908) (xy 133.597559 -345.846355)
			(xy 133.543576 -345.838597) (xy 133.491246 -345.823235) (xy 133.441635 -345.800581) (xy 133.395753 -345.771098)
			(xy 133.354535 -345.735385) (xy 133.318819 -345.694169) (xy 133.289332 -345.648289) (xy 133.266675 -345.59868)
			(xy 133.251309 -345.546352) (xy 133.243547 -345.492369) (xy 131.760844 -345.492369) (xy 131.760844 -345.492376)
			(xy 131.75308 -345.546372) (xy 131.737711 -345.598713) (xy 131.715048 -345.648335) (xy 131.685554 -345.694225)
			(xy 131.649829 -345.735451) (xy 131.6086 -345.771173) (xy 131.562707 -345.800663) (xy 131.513083 -345.823322)
			(xy 131.460741 -345.838687) (xy 131.406744 -345.846447) (xy 131.379468 -345.846908) (xy 130.515868 -345.846908)
			(xy 130.488603 -345.846328) (xy 130.43463 -345.838563) (xy 130.38231 -345.823197) (xy 130.33271 -345.800542)
			(xy 130.286839 -345.771058) (xy 130.24563 -345.735347) (xy 130.209922 -345.694136) (xy 130.180443 -345.648262)
			(xy 130.157792 -345.59866) (xy 130.14243 -345.546339) (xy 130.13467 -345.492365) (xy 128.651821 -345.492365)
			(xy 128.651821 -345.492372) (xy 128.644059 -345.546362) (xy 128.628692 -345.598697) (xy 128.606034 -345.648312)
			(xy 128.576545 -345.694199) (xy 128.540827 -345.735421) (xy 128.499605 -345.77114) (xy 128.45372 -345.80063)
			(xy 128.404104 -345.82329) (xy 128.35177 -345.838657) (xy 128.29778 -345.846421) (xy 128.270508 -345.846908)
			(xy 127.406908 -345.846908) (xy 127.37964 -345.846353) (xy 127.325659 -345.838593) (xy 127.273331 -345.823229)
			(xy 127.223723 -345.800575) (xy 127.177844 -345.771091) (xy 127.136628 -345.735378) (xy 127.100914 -345.694162)
			(xy 127.071429 -345.648284) (xy 127.048774 -345.598676) (xy 127.033409 -345.546349) (xy 127.025647 -345.492368)
			(xy 125.542822 -345.492368) (xy 125.542822 -345.49237) (xy 125.53506 -345.546356) (xy 125.519695 -345.598688)
			(xy 125.49704 -345.648301) (xy 125.467555 -345.694185) (xy 125.431841 -345.735407) (xy 125.390624 -345.771126)
			(xy 125.344743 -345.800617) (xy 125.295133 -345.823279) (xy 125.242803 -345.83865) (xy 125.188818 -345.846418)
			(xy 125.161548 -345.846908) (xy 124.297948 -345.846908) (xy 124.270678 -345.846356) (xy 124.216692 -345.8386)
			(xy 124.16436 -345.82324) (xy 124.114747 -345.800588) (xy 124.068863 -345.771105) (xy 124.027642 -345.735392)
			(xy 123.991924 -345.694176) (xy 123.962435 -345.648295) (xy 123.939777 -345.598685) (xy 123.92441 -345.546354)
			(xy 123.916648 -345.49237) (xy 122.433944 -345.49237) (xy 122.433944 -345.492375) (xy 122.426181 -345.546369)
			(xy 122.410812 -345.598709) (xy 122.388151 -345.648329) (xy 122.358659 -345.694219) (xy 122.322936 -345.735444)
			(xy 122.281709 -345.771166) (xy 122.235819 -345.800657) (xy 122.186198 -345.823316) (xy 122.133858 -345.838684)
			(xy 122.079863 -345.846445) (xy 122.052588 -345.846908) (xy 121.188988 -345.846908) (xy 121.161722 -345.846329)
			(xy 121.107747 -345.838567) (xy 121.055425 -345.823202) (xy 121.005822 -345.800548) (xy 120.959948 -345.771065)
			(xy 120.918737 -345.735354) (xy 120.883027 -345.694142) (xy 120.853546 -345.648267) (xy 120.830894 -345.598664)
			(xy 120.815531 -345.546342) (xy 120.80777 -345.492366) (xy 119.324922 -345.492366) (xy 119.324922 -345.492371)
			(xy 119.31716 -345.546359) (xy 119.301794 -345.598693) (xy 119.279137 -345.648307) (xy 119.24965 -345.694192)
			(xy 119.213934 -345.735414) (xy 119.172714 -345.771133) (xy 119.126832 -345.800624) (xy 119.077219 -345.823284)
			(xy 119.024886 -345.838654) (xy 118.970899 -345.84642) (xy 118.943628 -345.846908) (xy 118.080028 -345.846908)
			(xy 118.052759 -345.846355) (xy 117.998776 -345.838597) (xy 117.946446 -345.823235) (xy 117.896835 -345.800581)
			(xy 117.850953 -345.771098) (xy 117.809735 -345.735385) (xy 117.774019 -345.694169) (xy 117.744532 -345.648289)
			(xy 117.721875 -345.59868) (xy 117.706509 -345.546352) (xy 117.698747 -345.492369) (xy 116.216044 -345.492369)
			(xy 116.216044 -345.492376) (xy 116.20828 -345.546372) (xy 116.192911 -345.598713) (xy 116.170248 -345.648335)
			(xy 116.140754 -345.694225) (xy 116.105029 -345.735451) (xy 116.0638 -345.771173) (xy 116.017907 -345.800663)
			(xy 115.968283 -345.823322) (xy 115.915941 -345.838687) (xy 115.861944 -345.846447) (xy 115.834668 -345.846908)
			(xy 114.971068 -345.846908) (xy 114.943803 -345.846328) (xy 114.88983 -345.838563) (xy 114.83751 -345.823197)
			(xy 114.78791 -345.800542) (xy 114.742039 -345.771058) (xy 114.70083 -345.735347) (xy 114.665122 -345.694136)
			(xy 114.635643 -345.648262) (xy 114.612992 -345.59866) (xy 114.59763 -345.546339) (xy 114.58987 -345.492365)
			(xy 113.107021 -345.492365) (xy 113.107021 -345.492372) (xy 113.099259 -345.546362) (xy 113.083892 -345.598697)
			(xy 113.061234 -345.648312) (xy 113.031745 -345.694199) (xy 112.996027 -345.735421) (xy 112.954805 -345.77114)
			(xy 112.90892 -345.80063) (xy 112.859304 -345.82329) (xy 112.80697 -345.838657) (xy 112.75298 -345.846421)
			(xy 112.725708 -345.846908) (xy 111.862108 -345.846908) (xy 111.83484 -345.846353) (xy 111.780859 -345.838593)
			(xy 111.728531 -345.823229) (xy 111.678923 -345.800575) (xy 111.633044 -345.771091) (xy 111.591828 -345.735378)
			(xy 111.556114 -345.694162) (xy 111.526629 -345.648284) (xy 111.503974 -345.598676) (xy 111.488609 -345.546349)
			(xy 111.480847 -345.492368) (xy 108.541352 -345.492368) (xy 108.548141 -345.536763) (xy 108.548678 -345.56573)
			(xy 108.548192 -345.592981) (xy 108.540436 -345.646929) (xy 108.525081 -345.699224) (xy 108.502439 -345.748801)
			(xy 108.472973 -345.794651) (xy 108.437282 -345.835842) (xy 108.396091 -345.871533) (xy 108.350241 -345.900999)
			(xy 108.300664 -345.923641) (xy 108.248369 -345.938996) (xy 108.194421 -345.946752) (xy 108.139919 -345.946752)
			(xy 108.085971 -345.938996) (xy 108.033676 -345.923641) (xy 107.984099 -345.900999) (xy 107.938249 -345.871533)
			(xy 107.897058 -345.835842) (xy 107.861367 -345.794651) (xy 107.831901 -345.748801) (xy 107.809259 -345.699224)
			(xy 107.793904 -345.646929) (xy 107.786148 -345.592981) (xy 107.785662 -345.56573) (xy 106.174964 -345.56573)
			(xy 106.170145 -345.568671) (xy 106.118816 -345.590483) (xy 106.064859 -345.604589) (xy 106.009422 -345.610689)
			(xy 105.953688 -345.608652) (xy 105.898845 -345.598522) (xy 105.846061 -345.580515) (xy 105.796461 -345.555014)
			(xy 105.751103 -345.522563) (xy 105.710954 -345.483854) (xy 105.676868 -345.439711) (xy 105.649572 -345.391076)
			(xy 105.629649 -345.338985) (xy 105.617523 -345.284548) (xy 105.613452 -345.228926) (xy 100.47224 -345.228926)
			(xy 100.47224 -345.342972) (xy 100.472748 -345.3511) (xy 100.47478 -345.363038) (xy 100.475796 -345.366848)
			(xy 100.476304 -345.36888) (xy 100.476558 -345.37015) (xy 100.482939 -345.392547) (xy 100.490071 -345.438567)
			(xy 100.490782 -345.461844) (xy 100.490782 -345.465146) (xy 100.49028 -345.490977) (xy 100.482237 -345.542009)
			(xy 100.47478 -345.566746) (xy 100.47224 -345.57462) (xy 100.47224 -346.461842) (xy 107.639864 -346.461842)
			(xy 107.643935 -346.40622) (xy 107.656061 -346.351783) (xy 107.675984 -346.299692) (xy 107.70328 -346.251057)
			(xy 107.737366 -346.206914) (xy 107.777515 -346.168205) (xy 107.822873 -346.135754) (xy 107.872473 -346.110253)
			(xy 107.925257 -346.092246) (xy 107.9801 -346.082116) (xy 108.035834 -346.080079) (xy 108.091271 -346.086179)
			(xy 108.145228 -346.100285) (xy 108.196557 -346.122097) (xy 108.244163 -346.151151) (xy 108.287031 -346.186826)
			(xy 108.324248 -346.228363) (xy 108.355021 -346.274876) (xy 108.378693 -346.325373) (xy 108.394761 -346.37878)
			(xy 108.402881 -346.433956) (xy 108.40339 -346.461842) (xy 108.402881 -346.489728) (xy 108.394761 -346.544904)
			(xy 108.378693 -346.598311) (xy 108.355021 -346.648808) (xy 108.324248 -346.695321) (xy 108.287031 -346.736858)
			(xy 108.244163 -346.772533) (xy 108.196557 -346.801587) (xy 108.145228 -346.823399) (xy 108.091271 -346.837505)
			(xy 108.035834 -346.843605) (xy 107.9801 -346.841568) (xy 107.925257 -346.831438) (xy 107.872473 -346.813431)
			(xy 107.822873 -346.78793) (xy 107.777515 -346.755479) (xy 107.737366 -346.71677) (xy 107.70328 -346.672627)
			(xy 107.675984 -346.623992) (xy 107.656061 -346.571901) (xy 107.643935 -346.517464) (xy 107.639864 -346.461842)
			(xy 100.47224 -346.461842) (xy 100.47224 -348.153228) (xy 100.472665 -348.163243) (xy 100.480341 -348.181743)
			(xy 100.494514 -348.195897) (xy 100.513025 -348.203548) (xy 100.52304 -348.204028) (xy 100.937314 -348.204028)
			(xy 100.964583 -348.204515) (xy 101.018567 -348.212279) (xy 101.070896 -348.227646) (xy 101.120506 -348.250303)
			(xy 101.166386 -348.27979) (xy 101.207603 -348.315507) (xy 101.243318 -348.356725) (xy 101.272803 -348.402606)
			(xy 101.274605 -348.406551) (xy 105.290366 -348.406551) (xy 105.290366 -348.352049) (xy 105.298122 -348.298103)
			(xy 105.313475 -348.245809) (xy 105.336115 -348.196233) (xy 105.365579 -348.150383) (xy 105.401268 -348.109192)
			(xy 105.442455 -348.073499) (xy 105.488303 -348.044031) (xy 105.537877 -348.021387) (xy 105.59017 -348.006029)
			(xy 105.644115 -347.998268) (xy 105.671366 -347.99778) (xy 105.700106 -347.998269) (xy 105.756935 -348.006901)
			(xy 105.811826 -348.023959) (xy 105.863537 -348.049058) (xy 105.910898 -348.08163) (xy 105.932224 -348.100904)
			(xy 105.939336 -348.107508) (xy 105.956862 -348.11462) (xy 106.045254 -348.115128) (xy 106.06278 -348.10827)
			(xy 106.070146 -348.10192) (xy 106.091316 -348.083296) (xy 106.138126 -348.051863) (xy 106.189051 -348.027659)
			(xy 106.242983 -348.011211) (xy 106.298748 -348.002877) (xy 106.32694 -348.002352) (xy 106.354186 -348.002921)
			(xy 106.408124 -348.010681) (xy 106.460409 -348.026038) (xy 106.509976 -348.048679) (xy 106.555816 -348.078143)
			(xy 106.596997 -348.113831) (xy 106.632681 -348.155016) (xy 106.66214 -348.20086) (xy 106.684776 -348.250429)
			(xy 106.700127 -348.302715) (xy 106.707882 -348.356653) (xy 106.707882 -348.411147) (xy 106.700127 -348.465085)
			(xy 106.684776 -348.517371) (xy 106.66214 -348.56694) (xy 106.632681 -348.612784) (xy 106.632431 -348.613072)
			(xy 111.480792 -348.613072) (xy 111.480792 -348.558528) (xy 111.488554 -348.504539) (xy 111.503921 -348.452204)
			(xy 111.52658 -348.402589) (xy 111.556069 -348.356704) (xy 111.591788 -348.315483) (xy 111.63301 -348.279764)
			(xy 111.678896 -348.250276) (xy 111.728512 -348.227618) (xy 111.780847 -348.212252) (xy 111.834836 -348.204491)
			(xy 111.862108 -348.204028) (xy 112.725708 -348.204028) (xy 112.752976 -348.204535) (xy 112.806958 -348.212297)
			(xy 112.859285 -348.227663) (xy 112.908893 -348.250319) (xy 112.954771 -348.279804) (xy 112.995987 -348.315519)
			(xy 113.0317 -348.356735) (xy 113.061185 -348.402614) (xy 113.08384 -348.452223) (xy 113.099204 -348.50455)
			(xy 113.106966 -348.558532) (xy 113.106966 -348.613068) (xy 113.106966 -348.613069) (xy 114.589814 -348.613069)
			(xy 114.589814 -348.558531) (xy 114.597575 -348.504549) (xy 114.61294 -348.452221) (xy 114.635594 -348.402611)
			(xy 114.665078 -348.356731) (xy 114.70079 -348.315513) (xy 114.742005 -348.279797) (xy 114.787883 -348.250309)
			(xy 114.837491 -348.227651) (xy 114.889818 -348.212282) (xy 114.943799 -348.204517) (xy 114.971068 -348.204028)
			(xy 115.834668 -348.204028) (xy 115.86194 -348.204509) (xy 115.915929 -348.212268) (xy 115.968264 -348.227631)
			(xy 116.01788 -348.250286) (xy 116.063766 -348.279772) (xy 116.104989 -348.315488) (xy 116.140709 -348.356708)
			(xy 116.170199 -348.402592) (xy 116.192858 -348.452206) (xy 116.208226 -348.50454) (xy 116.215988 -348.558528)
			(xy 116.215988 -348.613072) (xy 116.215988 -348.613073) (xy 117.698692 -348.613073) (xy 117.698692 -348.558527)
			(xy 117.706455 -348.504536) (xy 117.721823 -348.4522) (xy 117.744483 -348.402584) (xy 117.773974 -348.356697)
			(xy 117.809695 -348.315476) (xy 117.85092 -348.279757) (xy 117.896808 -348.25027) (xy 117.946426 -348.227613)
			(xy 117.998764 -348.212249) (xy 118.052755 -348.20449) (xy 118.080028 -348.204028) (xy 118.943628 -348.204028)
			(xy 118.970895 -348.204536) (xy 119.024875 -348.212301) (xy 119.077199 -348.227668) (xy 119.126805 -348.250326)
			(xy 119.172681 -348.279811) (xy 119.213894 -348.315526) (xy 119.249605 -348.356742) (xy 119.279088 -348.40262)
			(xy 119.301741 -348.452227) (xy 119.317105 -348.504553) (xy 119.324866 -348.558533) (xy 119.324866 -348.613067)
			(xy 119.324866 -348.61307) (xy 120.807714 -348.61307) (xy 120.807714 -348.55853) (xy 120.815476 -348.504546)
			(xy 120.830841 -348.452217) (xy 120.853497 -348.402606) (xy 120.882983 -348.356724) (xy 120.918697 -348.315506)
			(xy 120.959915 -348.27979) (xy 121.005795 -348.250303) (xy 121.055405 -348.227645) (xy 121.107735 -348.212279)
			(xy 121.161718 -348.204515) (xy 121.188988 -348.204028) (xy 122.052588 -348.204028) (xy 122.079859 -348.204511)
			(xy 122.133846 -348.212271) (xy 122.186178 -348.227636) (xy 122.235792 -348.250292) (xy 122.281676 -348.279779)
			(xy 122.322896 -348.315495) (xy 122.358614 -348.356715) (xy 122.388102 -348.402598) (xy 122.41076 -348.45221)
			(xy 122.426126 -348.504543) (xy 122.433889 -348.558529) (xy 122.433889 -348.613071) (xy 122.433889 -348.613074)
			(xy 123.916592 -348.613074) (xy 123.916592 -348.558526) (xy 123.924355 -348.504534) (xy 123.939724 -348.452196)
			(xy 123.962386 -348.402578) (xy 123.991879 -348.356691) (xy 124.027602 -348.315468) (xy 124.068829 -348.27975)
			(xy 124.11472 -348.250263) (xy 124.164341 -348.227608) (xy 124.216681 -348.212245) (xy 124.270674 -348.204488)
			(xy 124.297948 -348.204028) (xy 125.161548 -348.204028) (xy 125.188814 -348.204538) (xy 125.242791 -348.212305)
			(xy 125.295114 -348.227674) (xy 125.344717 -348.250332) (xy 125.39059 -348.279819) (xy 125.431801 -348.315533)
			(xy 125.46751 -348.356748) (xy 125.496991 -348.402626) (xy 125.519643 -348.452231) (xy 125.535006 -348.504556)
			(xy 125.542766 -348.558534) (xy 125.542766 -348.613066) (xy 125.542765 -348.613072) (xy 127.025592 -348.613072)
			(xy 127.025592 -348.558528) (xy 127.033354 -348.504539) (xy 127.048721 -348.452204) (xy 127.07138 -348.402589)
			(xy 127.100869 -348.356704) (xy 127.136588 -348.315483) (xy 127.17781 -348.279764) (xy 127.223696 -348.250276)
			(xy 127.273312 -348.227618) (xy 127.325647 -348.212252) (xy 127.379636 -348.204491) (xy 127.406908 -348.204028)
			(xy 128.270508 -348.204028) (xy 128.297776 -348.204535) (xy 128.351758 -348.212297) (xy 128.404085 -348.227663)
			(xy 128.453693 -348.250319) (xy 128.499571 -348.279804) (xy 128.540787 -348.315519) (xy 128.5765 -348.356735)
			(xy 128.605985 -348.402614) (xy 128.62864 -348.452223) (xy 128.644004 -348.50455) (xy 128.651766 -348.558532)
			(xy 128.651766 -348.613068) (xy 128.651766 -348.613069) (xy 130.134614 -348.613069) (xy 130.134614 -348.558531)
			(xy 130.142375 -348.504549) (xy 130.15774 -348.452221) (xy 130.180394 -348.402611) (xy 130.209878 -348.356731)
			(xy 130.24559 -348.315513) (xy 130.286805 -348.279797) (xy 130.332683 -348.250309) (xy 130.382291 -348.227651)
			(xy 130.434618 -348.212282) (xy 130.488599 -348.204517) (xy 130.515868 -348.204028) (xy 131.379468 -348.204028)
			(xy 131.40674 -348.204509) (xy 131.460729 -348.212268) (xy 131.513064 -348.227631) (xy 131.56268 -348.250286)
			(xy 131.608566 -348.279772) (xy 131.649789 -348.315488) (xy 131.685509 -348.356708) (xy 131.714999 -348.402592)
			(xy 131.737658 -348.452206) (xy 131.753026 -348.50454) (xy 131.760788 -348.558528) (xy 131.760788 -348.613072)
			(xy 131.760788 -348.613073) (xy 133.243492 -348.613073) (xy 133.243492 -348.558527) (xy 133.251255 -348.504536)
			(xy 133.266623 -348.4522) (xy 133.289283 -348.402584) (xy 133.318774 -348.356697) (xy 133.354495 -348.315476)
			(xy 133.39572 -348.279757) (xy 133.441608 -348.25027) (xy 133.491226 -348.227613) (xy 133.543564 -348.212249)
			(xy 133.597555 -348.20449) (xy 133.624828 -348.204028) (xy 134.488428 -348.204028) (xy 134.515695 -348.204536)
			(xy 134.569675 -348.212301) (xy 134.621999 -348.227668) (xy 134.671605 -348.250326) (xy 134.717481 -348.279811)
			(xy 134.758694 -348.315526) (xy 134.794405 -348.356742) (xy 134.823888 -348.40262) (xy 134.846541 -348.452227)
			(xy 134.861905 -348.504553) (xy 134.869666 -348.558533) (xy 134.869666 -348.613067) (xy 134.869666 -348.61307)
			(xy 136.352514 -348.61307) (xy 136.352514 -348.55853) (xy 136.360276 -348.504546) (xy 136.375641 -348.452217)
			(xy 136.398297 -348.402606) (xy 136.427783 -348.356724) (xy 136.463497 -348.315506) (xy 136.504715 -348.27979)
			(xy 136.550595 -348.250303) (xy 136.600205 -348.227645) (xy 136.652535 -348.212279) (xy 136.706518 -348.204515)
			(xy 136.733788 -348.204028) (xy 137.597388 -348.204028) (xy 137.624659 -348.204511) (xy 137.678646 -348.212271)
			(xy 137.730978 -348.227636) (xy 137.780592 -348.250292) (xy 137.826476 -348.279779) (xy 137.867696 -348.315495)
			(xy 137.903414 -348.356715) (xy 137.932902 -348.402598) (xy 137.95556 -348.45221) (xy 137.970926 -348.504543)
			(xy 137.978689 -348.558529) (xy 137.978689 -348.613071) (xy 137.970926 -348.667057) (xy 137.95556 -348.71939)
			(xy 137.932902 -348.769002) (xy 137.903414 -348.814885) (xy 137.867696 -348.856105) (xy 137.826476 -348.891821)
			(xy 137.780592 -348.921308) (xy 137.730978 -348.943964) (xy 137.678646 -348.959329) (xy 137.624659 -348.967089)
			(xy 137.597388 -348.967552) (xy 136.733788 -348.967552) (xy 136.706518 -348.967085) (xy 136.652535 -348.959321)
			(xy 136.600205 -348.943955) (xy 136.550595 -348.921297) (xy 136.504715 -348.89181) (xy 136.463497 -348.856094)
			(xy 136.427783 -348.814876) (xy 136.398297 -348.768994) (xy 136.375641 -348.719383) (xy 136.360276 -348.667053)
			(xy 136.352514 -348.61307) (xy 134.869666 -348.61307) (xy 134.861905 -348.667047) (xy 134.846541 -348.719373)
			(xy 134.823888 -348.76898) (xy 134.794405 -348.814858) (xy 134.758694 -348.856074) (xy 134.717481 -348.891789)
			(xy 134.671605 -348.921274) (xy 134.621999 -348.943932) (xy 134.569675 -348.959299) (xy 134.515695 -348.967064)
			(xy 134.488428 -348.967552) (xy 133.624828 -348.967552) (xy 133.597555 -348.96711) (xy 133.543564 -348.959351)
			(xy 133.491226 -348.943987) (xy 133.441608 -348.92133) (xy 133.39572 -348.891843) (xy 133.354495 -348.856124)
			(xy 133.318774 -348.814903) (xy 133.289283 -348.769016) (xy 133.266623 -348.7194) (xy 133.251255 -348.667064)
			(xy 133.243492 -348.613073) (xy 131.760788 -348.613073) (xy 131.753026 -348.66706) (xy 131.737658 -348.719394)
			(xy 131.714999 -348.769008) (xy 131.685509 -348.814892) (xy 131.649789 -348.856112) (xy 131.608566 -348.891828)
			(xy 131.56268 -348.921314) (xy 131.513064 -348.943969) (xy 131.460729 -348.959332) (xy 131.40674 -348.967091)
			(xy 131.379468 -348.967552) (xy 130.515868 -348.967552) (xy 130.488599 -348.967083) (xy 130.434618 -348.959318)
			(xy 130.382291 -348.943949) (xy 130.332683 -348.921291) (xy 130.286805 -348.891803) (xy 130.24559 -348.856087)
			(xy 130.209878 -348.814869) (xy 130.180394 -348.768989) (xy 130.15774 -348.719379) (xy 130.142375 -348.667051)
			(xy 130.134614 -348.613069) (xy 128.651766 -348.613069) (xy 128.644004 -348.66705) (xy 128.62864 -348.719377)
			(xy 128.605985 -348.768986) (xy 128.5765 -348.814865) (xy 128.540787 -348.856081) (xy 128.499571 -348.891796)
			(xy 128.453693 -348.921281) (xy 128.404085 -348.943937) (xy 128.351758 -348.959303) (xy 128.297776 -348.967065)
			(xy 128.270508 -348.967552) (xy 127.406908 -348.967552) (xy 127.379636 -348.967109) (xy 127.325647 -348.959348)
			(xy 127.273312 -348.943982) (xy 127.223696 -348.921324) (xy 127.17781 -348.891836) (xy 127.136588 -348.856117)
			(xy 127.100869 -348.814896) (xy 127.07138 -348.769011) (xy 127.048721 -348.719396) (xy 127.033354 -348.667061)
			(xy 127.025592 -348.613072) (xy 125.542765 -348.613072) (xy 125.535006 -348.667044) (xy 125.519643 -348.719369)
			(xy 125.496991 -348.768974) (xy 125.46751 -348.814852) (xy 125.431801 -348.856067) (xy 125.39059 -348.891781)
			(xy 125.344717 -348.921268) (xy 125.295114 -348.943926) (xy 125.242791 -348.959295) (xy 125.188814 -348.967062)
			(xy 125.161548 -348.967552) (xy 124.297948 -348.967552) (xy 124.270674 -348.967112) (xy 124.216681 -348.959355)
			(xy 124.164341 -348.943992) (xy 124.11472 -348.921337) (xy 124.068829 -348.89185) (xy 124.027602 -348.856132)
			(xy 123.991879 -348.814909) (xy 123.962386 -348.769022) (xy 123.939724 -348.719404) (xy 123.924355 -348.667066)
			(xy 123.916592 -348.613074) (xy 122.433889 -348.613074) (xy 122.426126 -348.667057) (xy 122.41076 -348.71939)
			(xy 122.388102 -348.769002) (xy 122.358614 -348.814885) (xy 122.322896 -348.856105) (xy 122.281676 -348.891821)
			(xy 122.235792 -348.921308) (xy 122.186178 -348.943964) (xy 122.133846 -348.959329) (xy 122.079859 -348.967089)
			(xy 122.052588 -348.967552) (xy 121.188988 -348.967552) (xy 121.161718 -348.967085) (xy 121.107735 -348.959321)
			(xy 121.055405 -348.943955) (xy 121.005795 -348.921297) (xy 120.959915 -348.89181) (xy 120.918697 -348.856094)
			(xy 120.882983 -348.814876) (xy 120.853497 -348.768994) (xy 120.830841 -348.719383) (xy 120.815476 -348.667053)
			(xy 120.807714 -348.61307) (xy 119.324866 -348.61307) (xy 119.317105 -348.667047) (xy 119.301741 -348.719373)
			(xy 119.279088 -348.76898) (xy 119.249605 -348.814858) (xy 119.213894 -348.856074) (xy 119.172681 -348.891789)
			(xy 119.126805 -348.921274) (xy 119.077199 -348.943932) (xy 119.024875 -348.959299) (xy 118.970895 -348.967064)
			(xy 118.943628 -348.967552) (xy 118.080028 -348.967552) (xy 118.052755 -348.96711) (xy 117.998764 -348.959351)
			(xy 117.946426 -348.943987) (xy 117.896808 -348.92133) (xy 117.85092 -348.891843) (xy 117.809695 -348.856124)
			(xy 117.773974 -348.814903) (xy 117.744483 -348.769016) (xy 117.721823 -348.7194) (xy 117.706455 -348.667064)
			(xy 117.698692 -348.613073) (xy 116.215988 -348.613073) (xy 116.208226 -348.66706) (xy 116.192858 -348.719394)
			(xy 116.170199 -348.769008) (xy 116.140709 -348.814892) (xy 116.104989 -348.856112) (xy 116.063766 -348.891828)
			(xy 116.01788 -348.921314) (xy 115.968264 -348.943969) (xy 115.915929 -348.959332) (xy 115.86194 -348.967091)
			(xy 115.834668 -348.967552) (xy 114.971068 -348.967552) (xy 114.943799 -348.967083) (xy 114.889818 -348.959318)
			(xy 114.837491 -348.943949) (xy 114.787883 -348.921291) (xy 114.742005 -348.891803) (xy 114.70079 -348.856087)
			(xy 114.665078 -348.814869) (xy 114.635594 -348.768989) (xy 114.61294 -348.719379) (xy 114.597575 -348.667051)
			(xy 114.589814 -348.613069) (xy 113.106966 -348.613069) (xy 113.099204 -348.66705) (xy 113.08384 -348.719377)
			(xy 113.061185 -348.768986) (xy 113.0317 -348.814865) (xy 112.995987 -348.856081) (xy 112.954771 -348.891796)
			(xy 112.908893 -348.921281) (xy 112.859285 -348.943937) (xy 112.806958 -348.959303) (xy 112.752976 -348.967065)
			(xy 112.725708 -348.967552) (xy 111.862108 -348.967552) (xy 111.834836 -348.967109) (xy 111.780847 -348.959348)
			(xy 111.728512 -348.943982) (xy 111.678896 -348.921324) (xy 111.63301 -348.891836) (xy 111.591788 -348.856117)
			(xy 111.556069 -348.814896) (xy 111.52658 -348.769011) (xy 111.503921 -348.719396) (xy 111.488554 -348.667061)
			(xy 111.480792 -348.613072) (xy 106.632431 -348.613072) (xy 106.596997 -348.653969) (xy 106.555816 -348.689657)
			(xy 106.509976 -348.719121) (xy 106.460409 -348.741762) (xy 106.408124 -348.757119) (xy 106.354186 -348.764879)
			(xy 106.32694 -348.765368) (xy 106.298201 -348.764863) (xy 106.241373 -348.756233) (xy 106.186483 -348.739177)
			(xy 106.134772 -348.714082) (xy 106.087409 -348.681515) (xy 106.066082 -348.662244) (xy 106.05897 -348.65564)
			(xy 106.041444 -348.648528) (xy 105.953052 -348.64802) (xy 105.935526 -348.654878) (xy 105.92816 -348.661228)
			(xy 105.906994 -348.679857) (xy 105.860182 -348.711288) (xy 105.809256 -348.73549) (xy 105.755323 -348.751936)
			(xy 105.699558 -348.76027) (xy 105.671366 -348.760796) (xy 105.644115 -348.760332) (xy 105.59017 -348.752571)
			(xy 105.537877 -348.737213) (xy 105.488303 -348.714569) (xy 105.442455 -348.685101) (xy 105.401268 -348.649408)
			(xy 105.365579 -348.608217) (xy 105.336115 -348.562367) (xy 105.313475 -348.512791) (xy 105.298122 -348.460497)
			(xy 105.290366 -348.406551) (xy 101.274605 -348.406551) (xy 101.295459 -348.452217) (xy 101.310824 -348.504547)
			(xy 101.318586 -348.558531) (xy 101.318586 -348.613069) (xy 101.310824 -348.667053) (xy 101.295459 -348.719383)
			(xy 101.272803 -348.768994) (xy 101.243318 -348.814875) (xy 101.207603 -348.856093) (xy 101.166386 -348.89181)
			(xy 101.120506 -348.921297) (xy 101.070896 -348.943954) (xy 101.018567 -348.959321) (xy 100.964583 -348.967085)
			(xy 100.937314 -348.967552) (xy 100.52304 -348.967552) (xy 100.513024 -348.968033) (xy 100.49451 -348.975683)
			(xy 100.480333 -348.989836) (xy 100.47265 -349.008336) (xy 100.47224 -349.018352) (xy 100.47224 -349.651066)
			(xy 100.472772 -349.662089) (xy 100.481975 -349.682123) (xy 100.49002 -349.689674) (xy 100.510693 -349.70788)
			(xy 100.547096 -349.749223) (xy 100.577171 -349.795374) (xy 100.600291 -349.845372) (xy 100.615976 -349.898177)
			(xy 100.623898 -349.95269) (xy 100.623893 -350.007775) (xy 100.615962 -350.062286) (xy 100.600268 -350.115089)
			(xy 100.577139 -350.165083) (xy 100.547057 -350.211229) (xy 100.510647 -350.252565) (xy 100.49002 -350.270826)
			(xy 100.481998 -350.278398) (xy 100.472784 -350.298416) (xy 100.47224 -350.309434) (xy 100.47224 -351.178876)
			(xy 100.472656 -351.188898) (xy 100.480323 -351.207416) (xy 100.494498 -351.221586) (xy 100.513018 -351.229247)
			(xy 100.52304 -351.229676) (xy 100.937314 -351.229676) (xy 100.96458 -351.230163) (xy 101.018557 -351.237926)
			(xy 101.070879 -351.253291) (xy 101.120483 -351.275946) (xy 101.166357 -351.305429) (xy 101.207569 -351.341141)
			(xy 101.24328 -351.382354) (xy 101.272761 -351.428229) (xy 101.295414 -351.477834) (xy 101.30593 -351.513648)
			(xy 106.459526 -351.513648) (xy 106.463597 -351.458026) (xy 106.475723 -351.403589) (xy 106.495646 -351.351498)
			(xy 106.522942 -351.302863) (xy 106.557028 -351.25872) (xy 106.597177 -351.220011) (xy 106.642535 -351.18756)
			(xy 106.692135 -351.162059) (xy 106.744919 -351.144052) (xy 106.799762 -351.133922) (xy 106.855496 -351.131885)
			(xy 106.910933 -351.137985) (xy 106.96489 -351.152091) (xy 107.016219 -351.173903) (xy 107.063825 -351.202957)
			(xy 107.106693 -351.238632) (xy 107.14391 -351.280169) (xy 107.174683 -351.326682) (xy 107.198355 -351.377179)
			(xy 107.214423 -351.430586) (xy 107.222543 -351.485762) (xy 107.223052 -351.513648) (xy 107.222543 -351.541534)
			(xy 107.214423 -351.59671) (xy 107.201799 -351.638669) (xy 111.480839 -351.638669) (xy 111.480839 -351.584131)
			(xy 111.488601 -351.530149) (xy 111.503966 -351.477821) (xy 111.526622 -351.428212) (xy 111.556107 -351.382333)
			(xy 111.591822 -351.341117) (xy 111.633039 -351.305403) (xy 111.678919 -351.275918) (xy 111.728529 -351.253263)
			(xy 111.780857 -351.237899) (xy 111.834839 -351.230139) (xy 111.862108 -351.229676) (xy 112.725708 -351.229676)
			(xy 112.75298 -351.230087) (xy 112.806968 -351.23785) (xy 112.859302 -351.253218) (xy 112.908916 -351.275877)
			(xy 112.9548 -351.305366) (xy 112.996021 -351.341085) (xy 113.031739 -351.382306) (xy 113.061227 -351.428191)
			(xy 113.083885 -351.477806) (xy 113.099251 -351.53014) (xy 113.107014 -351.584128) (xy 113.107014 -351.638665)
			(xy 114.589862 -351.638665) (xy 114.589862 -351.584135) (xy 114.597622 -351.530159) (xy 114.612984 -351.477838)
			(xy 114.635636 -351.428234) (xy 114.665116 -351.38236) (xy 114.700824 -351.341147) (xy 114.742034 -351.305435)
			(xy 114.787906 -351.275951) (xy 114.837508 -351.253296) (xy 114.889828 -351.237929) (xy 114.943803 -351.230165)
			(xy 114.971068 -351.229676) (xy 115.834668 -351.229676) (xy 115.861943 -351.230061) (xy 115.915939 -351.237821)
			(xy 115.968281 -351.253186) (xy 116.017903 -351.275844) (xy 116.063795 -351.305333) (xy 116.105023 -351.341054)
			(xy 116.140747 -351.382279) (xy 116.170241 -351.428169) (xy 116.192903 -351.477789) (xy 116.208273 -351.53013)
			(xy 116.216036 -351.584125) (xy 116.216036 -351.63867) (xy 117.698739 -351.63867) (xy 117.698739 -351.58413)
			(xy 117.706502 -351.530146) (xy 117.721868 -351.477817) (xy 117.744525 -351.428207) (xy 117.774012 -351.382326)
			(xy 117.809729 -351.341109) (xy 117.850949 -351.305396) (xy 117.896831 -351.275912) (xy 117.946443 -351.253258)
			(xy 117.998774 -351.237896) (xy 118.052758 -351.230137) (xy 118.080028 -351.229676) (xy 118.943628 -351.229676)
			(xy 118.970899 -351.230088) (xy 119.024885 -351.237854) (xy 119.077216 -351.253223) (xy 119.126828 -351.275883)
			(xy 119.17271 -351.305373) (xy 119.213928 -351.341092) (xy 119.249644 -351.382313) (xy 119.27913 -351.428197)
			(xy 119.301786 -351.47781) (xy 119.317152 -351.530143) (xy 119.324914 -351.584129) (xy 119.324914 -351.638666)
			(xy 120.807762 -351.638666) (xy 120.807762 -351.584134) (xy 120.815523 -351.530157) (xy 120.830886 -351.477833)
			(xy 120.853539 -351.428229) (xy 120.883021 -351.382353) (xy 120.918731 -351.34114) (xy 120.959943 -351.305428)
			(xy 121.005818 -351.275945) (xy 121.055422 -351.25329) (xy 121.107745 -351.237925) (xy 121.161722 -351.230163)
			(xy 121.188988 -351.229676) (xy 122.052588 -351.229676) (xy 122.079862 -351.230063) (xy 122.133856 -351.237824)
			(xy 122.186195 -351.253191) (xy 122.235815 -351.27585) (xy 122.281704 -351.30534) (xy 122.32293 -351.341061)
			(xy 122.358652 -351.382286) (xy 122.388144 -351.428175) (xy 122.410805 -351.477794) (xy 122.426173 -351.530132)
			(xy 122.433936 -351.584126) (xy 122.433936 -351.63867) (xy 123.91664 -351.63867) (xy 123.91664 -351.58413)
			(xy 123.924402 -351.530144) (xy 123.939769 -351.477812) (xy 123.962428 -351.428201) (xy 123.991917 -351.38232)
			(xy 124.027636 -351.341102) (xy 124.068858 -351.305388) (xy 124.114743 -351.275905) (xy 124.164358 -351.253253)
			(xy 124.216691 -351.237892) (xy 124.270677 -351.230136) (xy 124.297948 -351.229676) (xy 125.161548 -351.229676)
			(xy 125.188818 -351.23009) (xy 125.242802 -351.237858) (xy 125.295131 -351.253229) (xy 125.34474 -351.27589)
			(xy 125.390619 -351.30538) (xy 125.431835 -351.341099) (xy 125.467549 -351.382319) (xy 125.497033 -351.428203)
			(xy 125.519688 -351.477814) (xy 125.535052 -351.530145) (xy 125.542814 -351.58413) (xy 125.542814 -351.638669)
			(xy 127.025639 -351.638669) (xy 127.025639 -351.584131) (xy 127.033401 -351.530149) (xy 127.048766 -351.477821)
			(xy 127.071422 -351.428212) (xy 127.100907 -351.382333) (xy 127.136622 -351.341117) (xy 127.177839 -351.305403)
			(xy 127.223719 -351.275918) (xy 127.273329 -351.253263) (xy 127.325657 -351.237899) (xy 127.379639 -351.230139)
			(xy 127.406908 -351.229676) (xy 128.270508 -351.229676) (xy 128.29778 -351.230087) (xy 128.351768 -351.23785)
			(xy 128.404102 -351.253218) (xy 128.453716 -351.275877) (xy 128.4996 -351.305366) (xy 128.540821 -351.341085)
			(xy 128.576539 -351.382306) (xy 128.606027 -351.428191) (xy 128.628685 -351.477806) (xy 128.644051 -351.53014)
			(xy 128.651814 -351.584128) (xy 128.651814 -351.638665) (xy 130.134662 -351.638665) (xy 130.134662 -351.584135)
			(xy 130.142422 -351.530159) (xy 130.157784 -351.477838) (xy 130.180436 -351.428234) (xy 130.209916 -351.38236)
			(xy 130.245624 -351.341147) (xy 130.286834 -351.305435) (xy 130.332706 -351.275951) (xy 130.382308 -351.253296)
			(xy 130.434628 -351.237929) (xy 130.488603 -351.230165) (xy 130.515868 -351.229676) (xy 131.379468 -351.229676)
			(xy 131.406743 -351.230061) (xy 131.460739 -351.237821) (xy 131.513081 -351.253186) (xy 131.562703 -351.275844)
			(xy 131.608595 -351.305333) (xy 131.649823 -351.341054) (xy 131.685547 -351.382279) (xy 131.715041 -351.428169)
			(xy 131.737703 -351.477789) (xy 131.753073 -351.53013) (xy 131.760836 -351.584125) (xy 131.760836 -351.63867)
			(xy 133.243539 -351.63867) (xy 133.243539 -351.58413) (xy 133.251302 -351.530146) (xy 133.266668 -351.477817)
			(xy 133.289325 -351.428207) (xy 133.318812 -351.382326) (xy 133.354529 -351.341109) (xy 133.395749 -351.305396)
			(xy 133.441631 -351.275912) (xy 133.491243 -351.253258) (xy 133.543574 -351.237896) (xy 133.597558 -351.230137)
			(xy 133.624828 -351.229676) (xy 134.488428 -351.229676) (xy 134.515699 -351.230088) (xy 134.569685 -351.237854)
			(xy 134.622016 -351.253223) (xy 134.671628 -351.275883) (xy 134.71751 -351.305373) (xy 134.758728 -351.341092)
			(xy 134.794444 -351.382313) (xy 134.82393 -351.428197) (xy 134.846586 -351.47781) (xy 134.861952 -351.530143)
			(xy 134.869714 -351.584129) (xy 134.869714 -351.638666) (xy 136.352562 -351.638666) (xy 136.352562 -351.584134)
			(xy 136.360323 -351.530157) (xy 136.375686 -351.477833) (xy 136.398339 -351.428229) (xy 136.427821 -351.382353)
			(xy 136.463531 -351.34114) (xy 136.504743 -351.305428) (xy 136.550618 -351.275945) (xy 136.600222 -351.25329)
			(xy 136.652545 -351.237925) (xy 136.706522 -351.230163) (xy 136.733788 -351.229676) (xy 137.597388 -351.229676)
			(xy 137.624662 -351.230063) (xy 137.678656 -351.237824) (xy 137.730995 -351.253191) (xy 137.780615 -351.27585)
			(xy 137.826504 -351.30534) (xy 137.86773 -351.341061) (xy 137.903452 -351.382286) (xy 137.932944 -351.428175)
			(xy 137.955605 -351.477794) (xy 137.970973 -351.530132) (xy 137.978736 -351.584126) (xy 137.978736 -351.638674)
			(xy 137.970973 -351.692668) (xy 137.955605 -351.745006) (xy 137.932944 -351.794625) (xy 137.903452 -351.840514)
			(xy 137.86773 -351.881739) (xy 137.826504 -351.91746) (xy 137.780615 -351.94695) (xy 137.730995 -351.969609)
			(xy 137.678656 -351.984976) (xy 137.624662 -351.992737) (xy 137.597388 -351.9932) (xy 136.733788 -351.9932)
			(xy 136.706522 -351.992637) (xy 136.652545 -351.984875) (xy 136.600222 -351.96951) (xy 136.550618 -351.946855)
			(xy 136.504744 -351.917372) (xy 136.463531 -351.88166) (xy 136.427821 -351.840447) (xy 136.398339 -351.794571)
			(xy 136.375686 -351.744967) (xy 136.360323 -351.692643) (xy 136.352562 -351.638666) (xy 134.869714 -351.638666)
			(xy 134.869714 -351.638671) (xy 134.861952 -351.692657) (xy 134.846586 -351.74499) (xy 134.82393 -351.794603)
			(xy 134.794444 -351.840487) (xy 134.758728 -351.881708) (xy 134.71751 -351.917427) (xy 134.671628 -351.946917)
			(xy 134.622016 -351.969577) (xy 134.569685 -351.984946) (xy 134.515699 -351.992712) (xy 134.488428 -351.9932)
			(xy 133.624828 -351.9932) (xy 133.597558 -351.992663) (xy 133.543574 -351.984904) (xy 133.491243 -351.969542)
			(xy 133.441631 -351.946888) (xy 133.395749 -351.917404) (xy 133.354529 -351.881691) (xy 133.318812 -351.840474)
			(xy 133.289325 -351.794593) (xy 133.266668 -351.744983) (xy 133.251302 -351.692654) (xy 133.243539 -351.63867)
			(xy 131.760836 -351.63867) (xy 131.760836 -351.638675) (xy 131.753073 -351.69267) (xy 131.737703 -351.745011)
			(xy 131.715041 -351.794631) (xy 131.685547 -351.840521) (xy 131.649823 -351.881746) (xy 131.608595 -351.917467)
			(xy 131.562703 -351.946956) (xy 131.513081 -351.969614) (xy 131.460739 -351.984979) (xy 131.406743 -351.992739)
			(xy 131.379468 -351.9932) (xy 130.515868 -351.9932) (xy 130.488603 -351.992635) (xy 130.434628 -351.984871)
			(xy 130.382308 -351.969504) (xy 130.332706 -351.946849) (xy 130.286834 -351.917365) (xy 130.245624 -351.881653)
			(xy 130.209916 -351.84044) (xy 130.180436 -351.794566) (xy 130.157784 -351.744962) (xy 130.142422 -351.692641)
			(xy 130.134662 -351.638665) (xy 128.651814 -351.638665) (xy 128.651814 -351.638672) (xy 128.644051 -351.69266)
			(xy 128.628685 -351.744994) (xy 128.606027 -351.794609) (xy 128.576539 -351.840494) (xy 128.540821 -351.881715)
			(xy 128.4996 -351.917434) (xy 128.453716 -351.946923) (xy 128.404102 -351.969582) (xy 128.351768 -351.98495)
			(xy 128.29778 -351.992713) (xy 128.270508 -351.9932) (xy 127.406908 -351.9932) (xy 127.379639 -351.992661)
			(xy 127.325657 -351.984901) (xy 127.273329 -351.969537) (xy 127.223719 -351.946882) (xy 127.177839 -351.917397)
			(xy 127.136622 -351.881683) (xy 127.100907 -351.840467) (xy 127.071422 -351.794588) (xy 127.048766 -351.744979)
			(xy 127.033401 -351.692651) (xy 127.025639 -351.638669) (xy 125.542814 -351.638669) (xy 125.542814 -351.63867)
			(xy 125.535052 -351.692655) (xy 125.519688 -351.744986) (xy 125.497033 -351.794597) (xy 125.467549 -351.840481)
			(xy 125.431835 -351.881701) (xy 125.390619 -351.91742) (xy 125.34474 -351.94691) (xy 125.295131 -351.969571)
			(xy 125.242802 -351.984942) (xy 125.188818 -351.99271) (xy 125.161548 -351.9932) (xy 124.297948 -351.9932)
			(xy 124.270677 -351.992664) (xy 124.216691 -351.984908) (xy 124.164358 -351.969547) (xy 124.114743 -351.946895)
			(xy 124.068858 -351.917411) (xy 124.027636 -351.881698) (xy 123.991917 -351.84048) (xy 123.962428 -351.794599)
			(xy 123.939769 -351.744987) (xy 123.924402 -351.692656) (xy 123.91664 -351.63867) (xy 122.433936 -351.63867)
			(xy 122.433936 -351.638674) (xy 122.426173 -351.692668) (xy 122.410805 -351.745006) (xy 122.388144 -351.794625)
			(xy 122.358652 -351.840514) (xy 122.32293 -351.881739) (xy 122.281704 -351.91746) (xy 122.235815 -351.94695)
			(xy 122.186195 -351.969609) (xy 122.133856 -351.984976) (xy 122.079862 -351.992737) (xy 122.052588 -351.9932)
			(xy 121.188988 -351.9932) (xy 121.161722 -351.992637) (xy 121.107745 -351.984875) (xy 121.055422 -351.96951)
			(xy 121.005818 -351.946855) (xy 120.959944 -351.917372) (xy 120.918731 -351.88166) (xy 120.883021 -351.840447)
			(xy 120.853539 -351.794571) (xy 120.830886 -351.744967) (xy 120.815523 -351.692643) (xy 120.807762 -351.638666)
			(xy 119.324914 -351.638666) (xy 119.324914 -351.638671) (xy 119.317152 -351.692657) (xy 119.301786 -351.74499)
			(xy 119.27913 -351.794603) (xy 119.249644 -351.840487) (xy 119.213928 -351.881708) (xy 119.17271 -351.917427)
			(xy 119.126828 -351.946917) (xy 119.077216 -351.969577) (xy 119.024885 -351.984946) (xy 118.970899 -351.992712)
			(xy 118.943628 -351.9932) (xy 118.080028 -351.9932) (xy 118.052758 -351.992663) (xy 117.998774 -351.984904)
			(xy 117.946443 -351.969542) (xy 117.896831 -351.946888) (xy 117.850949 -351.917404) (xy 117.809729 -351.881691)
			(xy 117.774012 -351.840474) (xy 117.744525 -351.794593) (xy 117.721868 -351.744983) (xy 117.706502 -351.692654)
			(xy 117.698739 -351.63867) (xy 116.216036 -351.63867) (xy 116.216036 -351.638675) (xy 116.208273 -351.69267)
			(xy 116.192903 -351.745011) (xy 116.170241 -351.794631) (xy 116.140747 -351.840521) (xy 116.105023 -351.881746)
			(xy 116.063795 -351.917467) (xy 116.017903 -351.946956) (xy 115.968281 -351.969614) (xy 115.915939 -351.984979)
			(xy 115.861943 -351.992739) (xy 115.834668 -351.9932) (xy 114.971068 -351.9932) (xy 114.943803 -351.992635)
			(xy 114.889828 -351.984871) (xy 114.837508 -351.969504) (xy 114.787906 -351.946849) (xy 114.742034 -351.917365)
			(xy 114.700824 -351.881653) (xy 114.665116 -351.84044) (xy 114.635636 -351.794566) (xy 114.612984 -351.744962)
			(xy 114.597622 -351.692641) (xy 114.589862 -351.638665) (xy 113.107014 -351.638665) (xy 113.107014 -351.638672)
			(xy 113.099251 -351.69266) (xy 113.083885 -351.744994) (xy 113.061227 -351.794609) (xy 113.031739 -351.840494)
			(xy 112.996021 -351.881715) (xy 112.9548 -351.917434) (xy 112.908916 -351.946923) (xy 112.859302 -351.969582)
			(xy 112.806968 -351.98495) (xy 112.75298 -351.992713) (xy 112.725708 -351.9932) (xy 111.862108 -351.9932)
			(xy 111.834839 -351.992661) (xy 111.780857 -351.984901) (xy 111.728529 -351.969537) (xy 111.678919 -351.946882)
			(xy 111.633039 -351.917397) (xy 111.591822 -351.881683) (xy 111.556107 -351.840467) (xy 111.526622 -351.794588)
			(xy 111.503966 -351.744979) (xy 111.488601 -351.692651) (xy 111.480839 -351.638669) (xy 107.201799 -351.638669)
			(xy 107.198355 -351.650117) (xy 107.174683 -351.700614) (xy 107.14391 -351.747127) (xy 107.106693 -351.788664)
			(xy 107.063825 -351.824339) (xy 107.016219 -351.853393) (xy 106.96489 -351.875205) (xy 106.910933 -351.889311)
			(xy 106.855496 -351.895411) (xy 106.799762 -351.893374) (xy 106.744919 -351.883244) (xy 106.692135 -351.865237)
			(xy 106.642535 -351.839736) (xy 106.597177 -351.807285) (xy 106.557028 -351.768576) (xy 106.522942 -351.724433)
			(xy 106.495646 -351.675798) (xy 106.475723 -351.623707) (xy 106.463597 -351.56927) (xy 106.459526 -351.513648)
			(xy 101.30593 -351.513648) (xy 101.310777 -351.530157) (xy 101.318538 -351.584134) (xy 101.318538 -351.638666)
			(xy 101.310777 -351.692643) (xy 101.295414 -351.744966) (xy 101.272761 -351.794571) (xy 101.24328 -351.840446)
			(xy 101.207569 -351.881659) (xy 101.166357 -351.917371) (xy 101.120483 -351.946854) (xy 101.070879 -351.969509)
			(xy 101.018557 -351.984874) (xy 100.96458 -351.992637) (xy 100.937314 -351.9932) (xy 100.52304 -351.9932)
			(xy 100.513013 -351.993613) (xy 100.494483 -352.001275) (xy 100.480298 -352.015449) (xy 100.47262 -352.033974)
			(xy 100.47224 -352.044) (xy 100.47224 -352.560128) (xy 100.472687 -352.570284) (xy 100.480548 -352.589014)
			(xy 100.48748 -352.59645) (xy 100.515928 -352.62439) (xy 100.532946 -352.631756) (xy 100.542598 -352.632264)
			(xy 100.569024 -352.633922) (xy 100.621078 -352.643619) (xy 100.671292 -352.660416) (xy 100.718704 -352.68399)
			(xy 100.762403 -352.713889) (xy 100.801553 -352.749539) (xy 100.835401 -352.790256) (xy 100.863299 -352.835259)
			(xy 100.884711 -352.883686) (xy 100.899227 -352.934606) (xy 100.906568 -352.987044) (xy 100.907088 -353.013518)
			(xy 100.906627 -353.040006) (xy 100.899284 -353.09247) (xy 100.884757 -353.143415) (xy 100.884578 -353.14382)
			(xy 106.532932 -353.14382) (xy 106.537003 -353.088198) (xy 106.549129 -353.033761) (xy 106.569052 -352.98167)
			(xy 106.596348 -352.933035) (xy 106.630434 -352.888892) (xy 106.670583 -352.850183) (xy 106.715941 -352.817732)
			(xy 106.765541 -352.792231) (xy 106.818325 -352.774224) (xy 106.873168 -352.764094) (xy 106.928902 -352.762057)
			(xy 106.984339 -352.768157) (xy 107.038296 -352.782263) (xy 107.089625 -352.804075) (xy 107.137231 -352.833129)
			(xy 107.180099 -352.868804) (xy 107.217316 -352.910341) (xy 107.248089 -352.956854) (xy 107.271761 -353.007351)
			(xy 107.287829 -353.060758) (xy 107.295949 -353.115934) (xy 107.296458 -353.14382) (xy 107.295949 -353.171706)
			(xy 107.287829 -353.226882) (xy 107.271761 -353.280289) (xy 107.248089 -353.330786) (xy 107.217316 -353.377299)
			(xy 107.180099 -353.418836) (xy 107.137231 -353.454511) (xy 107.089625 -353.483565) (xy 107.038296 -353.505377)
			(xy 106.984339 -353.519483) (xy 106.928902 -353.525583) (xy 106.873168 -353.523546) (xy 106.818325 -353.513416)
			(xy 106.765541 -353.495409) (xy 106.715941 -353.469908) (xy 106.670583 -353.437457) (xy 106.630434 -353.398748)
			(xy 106.596348 -353.354605) (xy 106.569052 -353.30597) (xy 106.549129 -353.253879) (xy 106.537003 -353.199442)
			(xy 106.532932 -353.14382) (xy 100.884578 -353.14382) (xy 100.863325 -353.191862) (xy 100.835398 -353.236879)
			(xy 100.801515 -353.277601) (xy 100.762325 -353.313247) (xy 100.718583 -353.34313) (xy 100.671128 -353.366678)
			(xy 100.620873 -353.383436) (xy 100.568783 -353.393084) (xy 100.542344 -353.394772) (xy 100.532692 -353.39528)
			(xy 100.515674 -353.402646) (xy 100.487226 -353.43084) (xy 100.480383 -353.438239) (xy 100.472659 -353.456838)
			(xy 100.47224 -353.466908) (xy 100.47224 -354.10521) (xy 100.472677 -354.114633) (xy 100.479445 -354.132224)
			(xy 100.482724 -354.136198) (xy 105.899202 -354.136198) (xy 105.903273 -354.080576) (xy 105.915399 -354.026139)
			(xy 105.935322 -353.974048) (xy 105.962618 -353.925413) (xy 105.996704 -353.88127) (xy 106.036853 -353.842561)
			(xy 106.082211 -353.81011) (xy 106.131811 -353.784609) (xy 106.184595 -353.766602) (xy 106.239438 -353.756472)
			(xy 106.295172 -353.754435) (xy 106.350609 -353.760535) (xy 106.404566 -353.774641) (xy 106.455895 -353.796453)
			(xy 106.503501 -353.825507) (xy 106.546369 -353.861182) (xy 106.583586 -353.902719) (xy 106.614359 -353.949232)
			(xy 106.638031 -353.999729) (xy 106.654099 -354.053136) (xy 106.662219 -354.108312) (xy 106.662728 -354.136198)
			(xy 106.662219 -354.164084) (xy 106.654099 -354.21926) (xy 106.638031 -354.272667) (xy 106.614359 -354.323164)
			(xy 106.583586 -354.369677) (xy 106.546369 -354.411214) (xy 106.503501 -354.446889) (xy 106.455895 -354.475943)
			(xy 106.404566 -354.497755) (xy 106.350609 -354.511861) (xy 106.295172 -354.517961) (xy 106.239438 -354.515924)
			(xy 106.184595 -354.505794) (xy 106.131811 -354.487787) (xy 106.082211 -354.462286) (xy 106.036853 -354.429835)
			(xy 105.996704 -354.391126) (xy 105.962618 -354.346983) (xy 105.935322 -354.298348) (xy 105.915399 -354.246257)
			(xy 105.903273 -354.19182) (xy 105.899202 -354.136198) (xy 100.482724 -354.136198) (xy 100.485448 -354.1395)
			(xy 100.493322 -354.148136) (xy 100.50399 -354.152454) (xy 100.529825 -354.163655) (xy 100.578159 -354.192541)
			(xy 100.621723 -354.228218) (xy 100.659571 -354.269909) (xy 100.690881 -354.31671) (xy 100.714973 -354.367604)
			(xy 100.731324 -354.421486) (xy 100.739579 -354.477186) (xy 100.739558 -354.533494) (xy 100.731262 -354.589188)
			(xy 100.714872 -354.643058) (xy 100.690742 -354.693934) (xy 100.659398 -354.740712) (xy 100.62152 -354.782376)
			(xy 100.577929 -354.81802) (xy 100.529574 -354.846871) (xy 100.503736 -354.858066) (xy 100.489512 -354.863908)
			(xy 100.47224 -354.889562) (xy 100.47224 -355.543866) (xy 100.796342 -355.543866) (xy 100.800413 -355.488244)
			(xy 100.812539 -355.433807) (xy 100.832462 -355.381716) (xy 100.859758 -355.333081) (xy 100.893844 -355.288938)
			(xy 100.933993 -355.250229) (xy 100.979351 -355.217778) (xy 101.028951 -355.192277) (xy 101.081735 -355.17427)
			(xy 101.136578 -355.16414) (xy 101.192312 -355.162103) (xy 101.247749 -355.168203) (xy 101.301706 -355.182309)
			(xy 101.353035 -355.204121) (xy 101.400641 -355.233175) (xy 101.443509 -355.26885) (xy 101.480726 -355.310387)
			(xy 101.483114 -355.313996) (xy 106.055922 -355.313996) (xy 106.056408 -355.286745) (xy 106.064164 -355.232797)
			(xy 106.079519 -355.180502) (xy 106.102161 -355.130925) (xy 106.131627 -355.085075) (xy 106.167318 -355.043884)
			(xy 106.208509 -355.008193) (xy 106.254359 -354.978727) (xy 106.303936 -354.956085) (xy 106.356231 -354.94073)
			(xy 106.410179 -354.932974) (xy 106.464681 -354.932974) (xy 106.518629 -354.94073) (xy 106.570924 -354.956085)
			(xy 106.620501 -354.978727) (xy 106.666351 -355.008193) (xy 106.707542 -355.043884) (xy 106.743233 -355.085075)
			(xy 106.772699 -355.130925) (xy 106.795341 -355.180502) (xy 106.810696 -355.232797) (xy 106.818452 -355.286745)
			(xy 106.818938 -355.313996) (xy 106.818455 -355.342566) (xy 106.809941 -355.399069) (xy 106.793088 -355.453667)
			(xy 106.768274 -355.505138) (xy 106.736054 -355.552329) (xy 106.697152 -355.594181) (xy 106.652438 -355.629757)
			(xy 106.62793 -355.64445) (xy 106.616417 -355.651599) (xy 106.59736 -355.670853) (xy 106.58403 -355.694437)
			(xy 106.577363 -355.720694) (xy 106.577428 -355.72446) (xy 106.991658 -355.72446) (xy 106.992258 -355.695119)
			(xy 107.001235 -355.637129) (xy 107.018987 -355.581197) (xy 107.045094 -355.528644) (xy 107.078941 -355.480708)
			(xy 107.11973 -355.438521) (xy 107.166498 -355.403077) (xy 107.192064 -355.388672) (xy 107.202732 -355.38283)
			(xy 107.216448 -355.363526) (xy 107.232704 -355.260148) (xy 107.225592 -355.237542) (xy 107.21721 -355.228906)
			(xy 107.197458 -355.207456) (xy 107.164022 -355.159689) (xy 107.13824 -355.107392) (xy 107.120711 -355.051782)
			(xy 107.111844 -354.994153) (xy 107.111292 -354.965) (xy 107.111733 -354.93833) (xy 107.119151 -354.885508)
			(xy 107.133856 -354.834235) (xy 107.155563 -354.785511) (xy 107.183846 -354.740286) (xy 107.218155 -354.699444)
			(xy 107.257819 -354.66378) (xy 107.279694 -354.648516) (xy 107.2896 -354.641912) (xy 107.301284 -354.621846)
			(xy 107.308142 -354.517706) (xy 107.299252 -354.49637) (xy 107.290362 -354.488242) (xy 107.270564 -354.470073)
			(xy 107.235771 -354.429123) (xy 107.207072 -354.383695) (xy 107.185034 -354.334687) (xy 107.170096 -354.28307)
			(xy 107.162552 -354.229867) (xy 107.162092 -354.203) (xy 107.162578 -354.175749) (xy 107.170334 -354.121801)
			(xy 107.185689 -354.069506) (xy 107.208331 -354.019929) (xy 107.237797 -353.974079) (xy 107.273488 -353.932888)
			(xy 107.314679 -353.897197) (xy 107.360529 -353.867731) (xy 107.410106 -353.845089) (xy 107.462401 -353.829734)
			(xy 107.516349 -353.821978) (xy 107.570851 -353.821978) (xy 107.624799 -353.829734) (xy 107.677094 -353.845089)
			(xy 107.726671 -353.867731) (xy 107.772521 -353.897197) (xy 107.813712 -353.932888) (xy 107.849403 -353.974079)
			(xy 107.878869 -354.019929) (xy 107.901511 -354.069506) (xy 107.916866 -354.121801) (xy 107.924622 -354.175749)
			(xy 107.925108 -354.203) (xy 107.924667 -354.22967) (xy 107.917249 -354.282492) (xy 107.902544 -354.333765)
			(xy 107.880837 -354.382489) (xy 107.852554 -354.427714) (xy 107.818245 -354.468556) (xy 107.778581 -354.50422)
			(xy 107.756706 -354.519484) (xy 107.7468 -354.526088) (xy 107.735116 -354.546154) (xy 107.728258 -354.650294)
			(xy 107.737148 -354.67163) (xy 107.746038 -354.679758) (xy 107.765836 -354.697927) (xy 107.800629 -354.738877)
			(xy 107.813575 -354.759369) (xy 114.589806 -354.759369) (xy 114.589806 -354.704831) (xy 114.597568 -354.650847)
			(xy 114.612932 -354.598518) (xy 114.635587 -354.548908) (xy 114.665071 -354.503026) (xy 114.700785 -354.461807)
			(xy 114.742 -354.42609) (xy 114.78788 -354.396602) (xy 114.837488 -354.373943) (xy 114.889816 -354.358574)
			(xy 114.943799 -354.350809) (xy 114.971068 -354.35032) (xy 115.834668 -354.35032) (xy 115.861939 -354.350817)
			(xy 115.915927 -354.358575) (xy 115.968261 -354.373938) (xy 116.017876 -354.396593) (xy 116.063761 -354.426078)
			(xy 116.104983 -354.461794) (xy 116.140703 -354.503013) (xy 116.170192 -354.548896) (xy 116.192851 -354.598509)
			(xy 116.208218 -354.650842) (xy 116.21598 -354.704829) (xy 116.21598 -354.759371) (xy 116.21598 -354.759374)
			(xy 117.698684 -354.759374) (xy 117.698684 -354.704826) (xy 117.706447 -354.650835) (xy 117.721815 -354.598497)
			(xy 117.744476 -354.54888) (xy 117.773968 -354.502993) (xy 117.80969 -354.46177) (xy 117.850915 -354.426051)
			(xy 117.896804 -354.396562) (xy 117.946423 -354.373905) (xy 117.998762 -354.358541) (xy 118.052754 -354.350782)
			(xy 118.080028 -354.35032) (xy 118.943628 -354.35032) (xy 118.970895 -354.350844) (xy 119.024873 -354.358609)
			(xy 119.077197 -354.373976) (xy 119.126801 -354.396633) (xy 119.172676 -354.426118) (xy 119.213888 -354.461831)
			(xy 119.249599 -354.503046) (xy 119.279081 -354.548924) (xy 119.301734 -354.59853) (xy 119.317097 -354.650855)
			(xy 119.324858 -354.704833) (xy 119.324858 -354.759367) (xy 119.324858 -354.75937) (xy 120.807706 -354.75937)
			(xy 120.807706 -354.70483) (xy 120.815468 -354.650845) (xy 120.830834 -354.598514) (xy 120.85349 -354.548902)
			(xy 120.882976 -354.50302) (xy 120.918692 -354.4618) (xy 120.95991 -354.426083) (xy 121.005791 -354.396596)
			(xy 121.055403 -354.373938) (xy 121.107733 -354.358571) (xy 121.161718 -354.350807) (xy 121.188988 -354.35032)
			(xy 122.052588 -354.35032) (xy 122.079858 -354.350819) (xy 122.133844 -354.358579) (xy 122.186176 -354.373944)
			(xy 122.235788 -354.396599) (xy 122.281671 -354.426085) (xy 122.322891 -354.461801) (xy 122.358608 -354.503019)
			(xy 122.388095 -354.548902) (xy 122.410752 -354.598513) (xy 122.426118 -354.650844) (xy 122.433881 -354.70483)
			(xy 122.433881 -354.75937) (xy 122.43388 -354.759374) (xy 123.916584 -354.759374) (xy 123.916584 -354.704826)
			(xy 123.924347 -354.650832) (xy 123.939717 -354.598493) (xy 123.962379 -354.548874) (xy 123.991872 -354.502986)
			(xy 124.027597 -354.461763) (xy 124.068825 -354.426044) (xy 124.114716 -354.396556) (xy 124.164338 -354.3739)
			(xy 124.216679 -354.358537) (xy 124.270673 -354.35078) (xy 124.297948 -354.35032) (xy 125.161548 -354.35032)
			(xy 125.188814 -354.350846) (xy 125.24279 -354.358613) (xy 125.295111 -354.373981) (xy 125.344713 -354.396639)
			(xy 125.390586 -354.426125) (xy 125.431795 -354.461839) (xy 125.467504 -354.503053) (xy 125.496984 -354.548929)
			(xy 125.519636 -354.598534) (xy 125.534998 -354.650857) (xy 125.542758 -354.704834) (xy 125.542758 -354.759366)
			(xy 125.542757 -354.759373) (xy 127.025584 -354.759373) (xy 127.025584 -354.704827) (xy 127.033346 -354.650837)
			(xy 127.048714 -354.598501) (xy 127.071373 -354.548885) (xy 127.100863 -354.502999) (xy 127.136583 -354.461777)
			(xy 127.177806 -354.426058) (xy 127.223692 -354.396569) (xy 127.273309 -354.373911) (xy 127.325645 -354.358545)
			(xy 127.379635 -354.350783) (xy 127.406908 -354.35032) (xy 128.270508 -354.35032) (xy 128.297776 -354.350843)
			(xy 128.351756 -354.358605) (xy 128.404082 -354.37397) (xy 128.453689 -354.396626) (xy 128.499567 -354.426111)
			(xy 128.540781 -354.461824) (xy 128.576494 -354.50304) (xy 128.605978 -354.548918) (xy 128.628632 -354.598525)
			(xy 128.643997 -354.650852) (xy 128.651758 -354.704832) (xy 128.651758 -354.759368) (xy 128.651758 -354.759369)
			(xy 130.134606 -354.759369) (xy 130.134606 -354.704831) (xy 130.142368 -354.650847) (xy 130.157732 -354.598518)
			(xy 130.180387 -354.548908) (xy 130.209871 -354.503026) (xy 130.245585 -354.461807) (xy 130.2868 -354.42609)
			(xy 130.33268 -354.396602) (xy 130.382288 -354.373943) (xy 130.434616 -354.358574) (xy 130.488599 -354.350809)
			(xy 130.515868 -354.35032) (xy 131.379468 -354.35032) (xy 131.406739 -354.350817) (xy 131.460727 -354.358575)
			(xy 131.513061 -354.373938) (xy 131.562676 -354.396593) (xy 131.608561 -354.426078) (xy 131.649783 -354.461794)
			(xy 131.685503 -354.503013) (xy 131.714992 -354.548896) (xy 131.737651 -354.598509) (xy 131.753018 -354.650842)
			(xy 131.76078 -354.704829) (xy 131.76078 -354.759371) (xy 131.76078 -354.759374) (xy 133.243484 -354.759374)
			(xy 133.243484 -354.704826) (xy 133.251247 -354.650835) (xy 133.266615 -354.598497) (xy 133.289276 -354.54888)
			(xy 133.318768 -354.502993) (xy 133.35449 -354.46177) (xy 133.395715 -354.426051) (xy 133.441604 -354.396562)
			(xy 133.491223 -354.373905) (xy 133.543562 -354.358541) (xy 133.597554 -354.350782) (xy 133.624828 -354.35032)
			(xy 134.488428 -354.35032) (xy 134.515695 -354.350844) (xy 134.569673 -354.358609) (xy 134.621997 -354.373976)
			(xy 134.671601 -354.396633) (xy 134.717476 -354.426118) (xy 134.758688 -354.461831) (xy 134.794399 -354.503046)
			(xy 134.823881 -354.548924) (xy 134.846534 -354.59853) (xy 134.861897 -354.650855) (xy 134.869658 -354.704833)
			(xy 134.869658 -354.759367) (xy 134.869658 -354.75937) (xy 136.352506 -354.75937) (xy 136.352506 -354.70483)
			(xy 136.360268 -354.650845) (xy 136.375634 -354.598514) (xy 136.39829 -354.548902) (xy 136.427776 -354.50302)
			(xy 136.463492 -354.4618) (xy 136.50471 -354.426083) (xy 136.550591 -354.396596) (xy 136.600203 -354.373938)
			(xy 136.652533 -354.358571) (xy 136.706518 -354.350807) (xy 136.733788 -354.35032) (xy 137.597388 -354.35032)
			(xy 137.624658 -354.350819) (xy 137.678644 -354.358579) (xy 137.730976 -354.373944) (xy 137.780588 -354.396599)
			(xy 137.826471 -354.426085) (xy 137.867691 -354.461801) (xy 137.903408 -354.503019) (xy 137.932895 -354.548902)
			(xy 137.955552 -354.598513) (xy 137.970918 -354.650844) (xy 137.978681 -354.70483) (xy 137.978681 -354.75937)
			(xy 137.97868 -354.759374) (xy 139.461384 -354.759374) (xy 139.461384 -354.704826) (xy 139.469147 -354.650832)
			(xy 139.484517 -354.598493) (xy 139.507179 -354.548874) (xy 139.536672 -354.502986) (xy 139.572397 -354.461763)
			(xy 139.613625 -354.426044) (xy 139.659516 -354.396556) (xy 139.709138 -354.3739) (xy 139.761479 -354.358537)
			(xy 139.815473 -354.35078) (xy 139.842748 -354.35032) (xy 140.706348 -354.35032) (xy 140.733614 -354.350846)
			(xy 140.78759 -354.358613) (xy 140.839911 -354.373981) (xy 140.889513 -354.396639) (xy 140.935386 -354.426125)
			(xy 140.976595 -354.461839) (xy 141.012304 -354.503053) (xy 141.041784 -354.548929) (xy 141.064436 -354.598534)
			(xy 141.079798 -354.650857) (xy 141.087558 -354.704834) (xy 141.087558 -354.759366) (xy 141.079798 -354.813343)
			(xy 141.064436 -354.865666) (xy 141.041784 -354.915271) (xy 141.012304 -354.961147) (xy 140.976595 -355.002361)
			(xy 140.935386 -355.038075) (xy 140.889513 -355.067561) (xy 140.839911 -355.090219) (xy 140.78759 -355.105587)
			(xy 140.733614 -355.113354) (xy 140.706348 -355.113844) (xy 139.842748 -355.113844) (xy 139.815473 -355.11342)
			(xy 139.761479 -355.105663) (xy 139.709138 -355.0903) (xy 139.659516 -355.067644) (xy 139.613625 -355.038156)
			(xy 139.572397 -355.002437) (xy 139.536672 -354.961214) (xy 139.507179 -354.915326) (xy 139.484517 -354.865707)
			(xy 139.469147 -354.813368) (xy 139.461384 -354.759374) (xy 137.97868 -354.759374) (xy 137.970918 -354.813356)
			(xy 137.955552 -354.865687) (xy 137.932895 -354.915298) (xy 137.903408 -354.961181) (xy 137.867691 -355.002399)
			(xy 137.826471 -355.038115) (xy 137.780588 -355.067601) (xy 137.730976 -355.090256) (xy 137.678644 -355.105621)
			(xy 137.624658 -355.113381) (xy 137.597388 -355.113844) (xy 136.733788 -355.113844) (xy 136.706518 -355.113393)
			(xy 136.652533 -355.105629) (xy 136.600203 -355.090262) (xy 136.550591 -355.067604) (xy 136.50471 -355.038117)
			(xy 136.463492 -355.0024) (xy 136.427776 -354.96118) (xy 136.39829 -354.915298) (xy 136.375634 -354.865686)
			(xy 136.360268 -354.813355) (xy 136.352506 -354.75937) (xy 134.869658 -354.75937) (xy 134.861897 -354.813345)
			(xy 134.846534 -354.86567) (xy 134.823881 -354.915276) (xy 134.794399 -354.961154) (xy 134.758688 -355.002369)
			(xy 134.717476 -355.038082) (xy 134.671601 -355.067567) (xy 134.621997 -355.090224) (xy 134.569673 -355.105591)
			(xy 134.515695 -355.113356) (xy 134.488428 -355.113844) (xy 133.624828 -355.113844) (xy 133.597554 -355.113418)
			(xy 133.543562 -355.105659) (xy 133.491223 -355.090295) (xy 133.441604 -355.067638) (xy 133.395715 -355.038149)
			(xy 133.35449 -355.00243) (xy 133.318768 -354.961207) (xy 133.289276 -354.91532) (xy 133.266615 -354.865703)
			(xy 133.251247 -354.813365) (xy 133.243484 -354.759374) (xy 131.76078 -354.759374) (xy 131.753018 -354.813358)
			(xy 131.737651 -354.865691) (xy 131.714992 -354.915304) (xy 131.685503 -354.961187) (xy 131.649783 -355.002406)
			(xy 131.608561 -355.038122) (xy 131.562676 -355.067607) (xy 131.513061 -355.090262) (xy 131.460727 -355.105625)
			(xy 131.406739 -355.113383) (xy 131.379468 -355.113844) (xy 130.515868 -355.113844) (xy 130.488599 -355.113391)
			(xy 130.434616 -355.105626) (xy 130.382288 -355.090257) (xy 130.33268 -355.067598) (xy 130.2868 -355.03811)
			(xy 130.245585 -355.002393) (xy 130.209871 -354.961174) (xy 130.180387 -354.915292) (xy 130.157732 -354.865682)
			(xy 130.142368 -354.813353) (xy 130.134606 -354.759369) (xy 128.651758 -354.759369) (xy 128.643997 -354.813348)
			(xy 128.628632 -354.865675) (xy 128.605978 -354.915282) (xy 128.576494 -354.96116) (xy 128.540781 -355.002376)
			(xy 128.499567 -355.038089) (xy 128.453689 -355.067574) (xy 128.404082 -355.09023) (xy 128.351756 -355.105595)
			(xy 128.297776 -355.113357) (xy 128.270508 -355.113844) (xy 127.406908 -355.113844) (xy 127.379635 -355.113417)
			(xy 127.325645 -355.105655) (xy 127.273309 -355.090289) (xy 127.223692 -355.067631) (xy 127.177806 -355.038142)
			(xy 127.136583 -355.002423) (xy 127.100863 -354.961201) (xy 127.071373 -354.915315) (xy 127.048714 -354.865699)
			(xy 127.033346 -354.813363) (xy 127.025584 -354.759373) (xy 125.542757 -354.759373) (xy 125.534998 -354.813343)
			(xy 125.519636 -354.865666) (xy 125.496984 -354.915271) (xy 125.467504 -354.961147) (xy 125.431795 -355.002361)
			(xy 125.390586 -355.038075) (xy 125.344713 -355.067561) (xy 125.295111 -355.090219) (xy 125.24279 -355.105587)
			(xy 125.188814 -355.113354) (xy 125.161548 -355.113844) (xy 124.297948 -355.113844) (xy 124.270673 -355.11342)
			(xy 124.216679 -355.105663) (xy 124.164338 -355.0903) (xy 124.114716 -355.067644) (xy 124.068825 -355.038156)
			(xy 124.027597 -355.002437) (xy 123.991872 -354.961214) (xy 123.962379 -354.915326) (xy 123.939717 -354.865707)
			(xy 123.924347 -354.813368) (xy 123.916584 -354.759374) (xy 122.43388 -354.759374) (xy 122.426118 -354.813356)
			(xy 122.410752 -354.865687) (xy 122.388095 -354.915298) (xy 122.358608 -354.961181) (xy 122.322891 -355.002399)
			(xy 122.281671 -355.038115) (xy 122.235788 -355.067601) (xy 122.186176 -355.090256) (xy 122.133844 -355.105621)
			(xy 122.079858 -355.113381) (xy 122.052588 -355.113844) (xy 121.188988 -355.113844) (xy 121.161718 -355.113393)
			(xy 121.107733 -355.105629) (xy 121.055403 -355.090262) (xy 121.005791 -355.067604) (xy 120.95991 -355.038117)
			(xy 120.918692 -355.0024) (xy 120.882976 -354.96118) (xy 120.85349 -354.915298) (xy 120.830834 -354.865686)
			(xy 120.815468 -354.813355) (xy 120.807706 -354.75937) (xy 119.324858 -354.75937) (xy 119.317097 -354.813345)
			(xy 119.301734 -354.86567) (xy 119.279081 -354.915276) (xy 119.249599 -354.961154) (xy 119.213888 -355.002369)
			(xy 119.172676 -355.038082) (xy 119.126801 -355.067567) (xy 119.077197 -355.090224) (xy 119.024873 -355.105591)
			(xy 118.970895 -355.113356) (xy 118.943628 -355.113844) (xy 118.080028 -355.113844) (xy 118.052754 -355.113418)
			(xy 117.998762 -355.105659) (xy 117.946423 -355.090295) (xy 117.896804 -355.067638) (xy 117.850915 -355.038149)
			(xy 117.80969 -355.00243) (xy 117.773968 -354.961207) (xy 117.744476 -354.91532) (xy 117.721815 -354.865703)
			(xy 117.706447 -354.813365) (xy 117.698684 -354.759374) (xy 116.21598 -354.759374) (xy 116.208218 -354.813358)
			(xy 116.192851 -354.865691) (xy 116.170192 -354.915304) (xy 116.140703 -354.961187) (xy 116.104983 -355.002406)
			(xy 116.063761 -355.038122) (xy 116.017876 -355.067607) (xy 115.968261 -355.090262) (xy 115.915927 -355.105625)
			(xy 115.861939 -355.113383) (xy 115.834668 -355.113844) (xy 114.971068 -355.113844) (xy 114.943799 -355.113391)
			(xy 114.889816 -355.105626) (xy 114.837488 -355.090257) (xy 114.78788 -355.067598) (xy 114.742 -355.03811)
			(xy 114.700785 -355.002393) (xy 114.665071 -354.961174) (xy 114.635587 -354.915292) (xy 114.612932 -354.865682)
			(xy 114.597568 -354.813353) (xy 114.589806 -354.759369) (xy 107.813575 -354.759369) (xy 107.829328 -354.784305)
			(xy 107.851366 -354.833313) (xy 107.866304 -354.88493) (xy 107.873848 -354.938133) (xy 107.874308 -354.965)
			(xy 107.873774 -354.994343) (xy 107.864787 -355.052338) (xy 107.847025 -355.108272) (xy 107.820907 -355.160826)
			(xy 107.787049 -355.208761) (xy 107.746251 -355.250946) (xy 107.699473 -355.286385) (xy 107.673902 -355.300788)
			(xy 107.663234 -355.30663) (xy 107.649518 -355.325934) (xy 107.633262 -355.429312) (xy 107.640374 -355.451918)
			(xy 107.648756 -355.460554) (xy 107.668531 -355.481984) (xy 107.701965 -355.529756) (xy 107.727743 -355.582058)
			(xy 107.745266 -355.637672) (xy 107.754127 -355.695305) (xy 107.754674 -355.72446) (xy 107.754188 -355.751711)
			(xy 107.746432 -355.805659) (xy 107.731077 -355.857954) (xy 107.708435 -355.907531) (xy 107.678969 -355.953381)
			(xy 107.643278 -355.994572) (xy 107.602087 -356.030263) (xy 107.556237 -356.059729) (xy 107.50666 -356.082371)
			(xy 107.454365 -356.097726) (xy 107.400417 -356.105482) (xy 107.345915 -356.105482) (xy 107.291967 -356.097726)
			(xy 107.239672 -356.082371) (xy 107.190095 -356.059729) (xy 107.144245 -356.030263) (xy 107.103054 -355.994572)
			(xy 107.067363 -355.953381) (xy 107.037897 -355.907531) (xy 107.015255 -355.857954) (xy 106.9999 -355.805659)
			(xy 106.992144 -355.751711) (xy 106.991658 -355.72446) (xy 106.577428 -355.72446) (xy 106.577827 -355.747781)
			(xy 106.585391 -355.773795) (xy 106.599522 -355.796908) (xy 106.619228 -355.815497) (xy 106.630978 -355.82225)
			(xy 106.65669 -355.836645) (xy 106.703806 -355.872029) (xy 106.744919 -355.914239) (xy 106.779048 -355.962272)
			(xy 106.805383 -356.014982) (xy 106.823295 -356.071117) (xy 106.832359 -356.129338) (xy 106.832908 -356.1588)
			(xy 106.832422 -356.186051) (xy 106.824666 -356.239999) (xy 106.809311 -356.292294) (xy 106.786669 -356.341871)
			(xy 106.757203 -356.387721) (xy 106.721512 -356.428912) (xy 106.680321 -356.464603) (xy 106.634471 -356.494069)
			(xy 106.584894 -356.516711) (xy 106.532599 -356.532066) (xy 106.478651 -356.539822) (xy 106.424149 -356.539822)
			(xy 106.370201 -356.532066) (xy 106.317906 -356.516711) (xy 106.268329 -356.494069) (xy 106.222479 -356.464603)
			(xy 106.181288 -356.428912) (xy 106.145597 -356.387721) (xy 106.116131 -356.341871) (xy 106.093489 -356.292294)
			(xy 106.078134 -356.239999) (xy 106.070378 -356.186051) (xy 106.069892 -356.1588) (xy 106.070357 -356.130229)
			(xy 106.078872 -356.073725) (xy 106.095727 -356.019125) (xy 106.120544 -355.967654) (xy 106.152767 -355.920463)
			(xy 106.191673 -355.878612) (xy 106.236391 -355.843038) (xy 106.2609 -355.828346) (xy 106.272424 -355.821209)
			(xy 106.291495 -355.801958) (xy 106.304835 -355.778371) (xy 106.311507 -355.752107) (xy 106.311041 -355.725013)
			(xy 106.303471 -355.698994) (xy 106.289329 -355.67588) (xy 106.269608 -355.657295) (xy 106.257852 -355.650546)
			(xy 106.232122 -355.636182) (xy 106.185009 -355.60079) (xy 106.1439 -355.558573) (xy 106.109774 -355.510535)
			(xy 106.083443 -355.45782) (xy 106.065533 -355.401683) (xy 106.05647 -355.343459) (xy 106.055922 -355.313996)
			(xy 101.483114 -355.313996) (xy 101.511499 -355.3569) (xy 101.535171 -355.407397) (xy 101.551239 -355.460804)
			(xy 101.559359 -355.51598) (xy 101.559868 -355.543866) (xy 101.559359 -355.571752) (xy 101.551239 -355.626928)
			(xy 101.535171 -355.680335) (xy 101.511499 -355.730832) (xy 101.480726 -355.777345) (xy 101.443509 -355.818882)
			(xy 101.400641 -355.854557) (xy 101.353035 -355.883611) (xy 101.301706 -355.905423) (xy 101.247749 -355.919529)
			(xy 101.192312 -355.925629) (xy 101.136578 -355.923592) (xy 101.081735 -355.913462) (xy 101.028951 -355.895455)
			(xy 100.979351 -355.869954) (xy 100.933993 -355.837503) (xy 100.893844 -355.798794) (xy 100.859758 -355.754651)
			(xy 100.832462 -355.706016) (xy 100.812539 -355.653925) (xy 100.800413 -355.599488) (xy 100.796342 -355.543866)
			(xy 100.47224 -355.543866) (xy 100.47224 -356.160578) (xy 100.47224 -356.163626) (xy 100.475952 -356.221284)
			(xy 103.80167 -356.221284) (xy 103.805741 -356.165662) (xy 103.817867 -356.111225) (xy 103.83779 -356.059134)
			(xy 103.865086 -356.010499) (xy 103.899172 -355.966356) (xy 103.939321 -355.927647) (xy 103.984679 -355.895196)
			(xy 104.034279 -355.869695) (xy 104.087063 -355.851688) (xy 104.141906 -355.841558) (xy 104.19764 -355.839521)
			(xy 104.253077 -355.845621) (xy 104.307034 -355.859727) (xy 104.358363 -355.881539) (xy 104.405969 -355.910593)
			(xy 104.448837 -355.946268) (xy 104.486054 -355.987805) (xy 104.516827 -356.034318) (xy 104.540499 -356.084815)
			(xy 104.556567 -356.138222) (xy 104.564687 -356.193398) (xy 104.565196 -356.221284) (xy 104.564687 -356.24917)
			(xy 104.556567 -356.304346) (xy 104.540499 -356.357753) (xy 104.516827 -356.40825) (xy 104.486054 -356.454763)
			(xy 104.448837 -356.4963) (xy 104.405969 -356.531975) (xy 104.358363 -356.561029) (xy 104.307034 -356.582841)
			(xy 104.253077 -356.596947) (xy 104.19764 -356.603047) (xy 104.141906 -356.60101) (xy 104.087063 -356.59088)
			(xy 104.034279 -356.572873) (xy 103.984679 -356.547372) (xy 103.939321 -356.514921) (xy 103.899172 -356.476212)
			(xy 103.865086 -356.432069) (xy 103.83779 -356.383434) (xy 103.817867 -356.331343) (xy 103.805741 -356.276906)
			(xy 103.80167 -356.221284) (xy 100.475952 -356.221284) (xy 100.576623 -357.784966) (xy 114.589854 -357.784966)
			(xy 114.589854 -357.730434) (xy 114.597614 -357.676458) (xy 114.612977 -357.624135) (xy 114.635629 -357.574531)
			(xy 114.66511 -357.528655) (xy 114.700819 -357.487441) (xy 114.742029 -357.451729) (xy 114.787903 -357.422244)
			(xy 114.837505 -357.399588) (xy 114.889826 -357.384221) (xy 114.943802 -357.376457) (xy 114.971068 -357.375968)
			(xy 115.834668 -357.375968) (xy 115.861943 -357.376369) (xy 115.915937 -357.384128) (xy 115.968278 -357.399493)
			(xy 116.017899 -357.422151) (xy 116.06379 -357.45164) (xy 116.105017 -357.48736) (xy 116.140741 -357.528584)
			(xy 116.170234 -357.574473) (xy 116.192896 -357.624092) (xy 116.208265 -357.676431) (xy 116.216028 -357.730425)
			(xy 116.216028 -357.78497) (xy 117.698731 -357.78497) (xy 117.698732 -357.73043) (xy 117.706494 -357.676445)
			(xy 117.72186 -357.624114) (xy 117.744518 -357.574503) (xy 117.774006 -357.528621) (xy 117.809724 -357.487404)
			(xy 117.850944 -357.451689) (xy 117.896827 -357.422205) (xy 117.94644 -357.39955) (xy 117.998772 -357.384188)
			(xy 118.052758 -357.37643) (xy 118.080028 -357.375968) (xy 118.943628 -357.375968) (xy 118.970898 -357.376396)
			(xy 119.024883 -357.384162) (xy 119.077213 -357.399531) (xy 119.126824 -357.42219) (xy 119.172705 -357.451679)
			(xy 119.213922 -357.487397) (xy 119.249637 -357.528618) (xy 119.279123 -357.574501) (xy 119.301779 -357.624113)
			(xy 119.317144 -357.676444) (xy 119.324906 -357.73043) (xy 119.324906 -357.784967) (xy 120.807754 -357.784967)
			(xy 120.807754 -357.730433) (xy 120.815515 -357.676455) (xy 120.830879 -357.624131) (xy 120.853532 -357.574525)
			(xy 120.883015 -357.528648) (xy 120.918726 -357.487434) (xy 120.959939 -357.451722) (xy 121.005815 -357.422238)
			(xy 121.055419 -357.399583) (xy 121.107743 -357.384218) (xy 121.161721 -357.376455) (xy 121.188988 -357.375968)
			(xy 122.052588 -357.375968) (xy 122.079862 -357.376371) (xy 122.133854 -357.384132) (xy 122.186192 -357.399499)
			(xy 122.235811 -357.422157) (xy 122.2817 -357.451647) (xy 122.322924 -357.487367) (xy 122.358646 -357.528591)
			(xy 122.388137 -357.574479) (xy 122.410797 -357.624096) (xy 122.426165 -357.676434) (xy 122.433928 -357.730426)
			(xy 122.433928 -357.784971) (xy 123.916632 -357.784971) (xy 123.916632 -357.730429) (xy 123.924394 -357.676442)
			(xy 123.939762 -357.62411) (xy 123.962421 -357.574497) (xy 123.991911 -357.528615) (xy 124.027631 -357.487397)
			(xy 124.068853 -357.451682) (xy 124.114739 -357.422198) (xy 124.164355 -357.399545) (xy 124.216689 -357.384184)
			(xy 124.270677 -357.376428) (xy 124.297948 -357.375968) (xy 125.161548 -357.375968) (xy 125.188817 -357.376398)
			(xy 125.2428 -357.384166) (xy 125.295128 -357.399536) (xy 125.344736 -357.422197) (xy 125.390614 -357.451687)
			(xy 125.431829 -357.487405) (xy 125.467542 -357.528624) (xy 125.497026 -357.574506) (xy 125.51968 -357.624117)
			(xy 125.535045 -357.676447) (xy 125.542806 -357.730431) (xy 125.542806 -357.784969) (xy 127.025631 -357.784969)
			(xy 127.025631 -357.730431) (xy 127.033393 -357.676447) (xy 127.048759 -357.624118) (xy 127.071415 -357.574508)
			(xy 127.100901 -357.528628) (xy 127.136617 -357.487411) (xy 127.177834 -357.451696) (xy 127.223715 -357.422211)
			(xy 127.273326 -357.399556) (xy 127.325655 -357.384191) (xy 127.379639 -357.376431) (xy 127.406908 -357.375968)
			(xy 128.270508 -357.375968) (xy 128.297779 -357.376395) (xy 128.351766 -357.384158) (xy 128.404099 -357.399525)
			(xy 128.453712 -357.422184) (xy 128.499595 -357.451672) (xy 128.540815 -357.48739) (xy 128.576532 -357.528611)
			(xy 128.60602 -357.574495) (xy 128.628677 -357.624109) (xy 128.644043 -357.676442) (xy 128.651806 -357.730429)
			(xy 128.651806 -357.784966) (xy 130.134654 -357.784966) (xy 130.134654 -357.730434) (xy 130.142414 -357.676458)
			(xy 130.157777 -357.624135) (xy 130.180429 -357.574531) (xy 130.20991 -357.528655) (xy 130.245619 -357.487441)
			(xy 130.286829 -357.451729) (xy 130.332703 -357.422244) (xy 130.382305 -357.399588) (xy 130.434626 -357.384221)
			(xy 130.488602 -357.376457) (xy 130.515868 -357.375968) (xy 131.379468 -357.375968) (xy 131.406743 -357.376369)
			(xy 131.460737 -357.384128) (xy 131.513078 -357.399493) (xy 131.562699 -357.422151) (xy 131.60859 -357.45164)
			(xy 131.649817 -357.48736) (xy 131.685541 -357.528584) (xy 131.715034 -357.574473) (xy 131.737696 -357.624092)
			(xy 131.753065 -357.676431) (xy 131.760828 -357.730425) (xy 131.760828 -357.78497) (xy 133.243531 -357.78497)
			(xy 133.243532 -357.73043) (xy 133.251294 -357.676445) (xy 133.26666 -357.624114) (xy 133.289318 -357.574503)
			(xy 133.318806 -357.528621) (xy 133.354524 -357.487404) (xy 133.395744 -357.451689) (xy 133.441627 -357.422205)
			(xy 133.49124 -357.39955) (xy 133.543572 -357.384188) (xy 133.597558 -357.37643) (xy 133.624828 -357.375968)
			(xy 134.488428 -357.375968) (xy 134.515698 -357.376396) (xy 134.569683 -357.384162) (xy 134.622013 -357.399531)
			(xy 134.671624 -357.42219) (xy 134.717505 -357.451679) (xy 134.758722 -357.487397) (xy 134.794437 -357.528618)
			(xy 134.823923 -357.574501) (xy 134.846579 -357.624113) (xy 134.861944 -357.676444) (xy 134.869706 -357.73043)
			(xy 134.869706 -357.784967) (xy 136.352554 -357.784967) (xy 136.352554 -357.730433) (xy 136.360315 -357.676455)
			(xy 136.375679 -357.624131) (xy 136.398332 -357.574525) (xy 136.427815 -357.528648) (xy 136.463526 -357.487434)
			(xy 136.504739 -357.451722) (xy 136.550615 -357.422238) (xy 136.600219 -357.399583) (xy 136.652543 -357.384218)
			(xy 136.706521 -357.376455) (xy 136.733788 -357.375968) (xy 137.597388 -357.375968) (xy 137.624662 -357.376371)
			(xy 137.678654 -357.384132) (xy 137.730992 -357.399499) (xy 137.780611 -357.422157) (xy 137.8265 -357.451647)
			(xy 137.867724 -357.487367) (xy 137.903446 -357.528591) (xy 137.932937 -357.574479) (xy 137.955597 -357.624096)
			(xy 137.970965 -357.676434) (xy 137.978728 -357.730426) (xy 137.978728 -357.784971) (xy 139.461432 -357.784971)
			(xy 139.461432 -357.730429) (xy 139.469194 -357.676442) (xy 139.484562 -357.62411) (xy 139.507221 -357.574497)
			(xy 139.536711 -357.528615) (xy 139.572431 -357.487397) (xy 139.613653 -357.451682) (xy 139.659539 -357.422198)
			(xy 139.709155 -357.399545) (xy 139.761489 -357.384184) (xy 139.815477 -357.376428) (xy 139.842748 -357.375968)
			(xy 140.706348 -357.375968) (xy 140.733617 -357.376398) (xy 140.7876 -357.384166) (xy 140.839928 -357.399536)
			(xy 140.889536 -357.422197) (xy 140.935414 -357.451687) (xy 140.976629 -357.487405) (xy 141.012342 -357.528624)
			(xy 141.041826 -357.574506) (xy 141.06448 -357.624117) (xy 141.079845 -357.676447) (xy 141.087606 -357.730431)
			(xy 141.087606 -357.784969) (xy 141.079845 -357.838953) (xy 141.06448 -357.891283) (xy 141.041826 -357.940894)
			(xy 141.012342 -357.986776) (xy 140.976629 -358.027995) (xy 140.935414 -358.063713) (xy 140.889536 -358.093203)
			(xy 140.839928 -358.115864) (xy 140.7876 -358.131234) (xy 140.733617 -358.139002) (xy 140.706348 -358.139492)
			(xy 139.842748 -358.139492) (xy 139.815477 -358.138972) (xy 139.761489 -358.131216) (xy 139.709155 -358.115855)
			(xy 139.659539 -358.093202) (xy 139.613653 -358.063718) (xy 139.572431 -358.028003) (xy 139.536711 -357.986785)
			(xy 139.507221 -357.940903) (xy 139.484562 -357.89129) (xy 139.469194 -357.838958) (xy 139.461432 -357.784971)
			(xy 137.978728 -357.784971) (xy 137.978728 -357.784974) (xy 137.970965 -357.838966) (xy 137.955597 -357.891304)
			(xy 137.932937 -357.940921) (xy 137.903446 -357.986809) (xy 137.867724 -358.028033) (xy 137.8265 -358.063753)
			(xy 137.780611 -358.093243) (xy 137.730992 -358.115901) (xy 137.678654 -358.131268) (xy 137.624662 -358.139029)
			(xy 137.597388 -358.139492) (xy 136.733788 -358.139492) (xy 136.706521 -358.138945) (xy 136.652543 -358.131182)
			(xy 136.600219 -358.115817) (xy 136.550615 -358.093162) (xy 136.504739 -358.063678) (xy 136.463526 -358.027966)
			(xy 136.427815 -357.986752) (xy 136.398332 -357.940875) (xy 136.375679 -357.891269) (xy 136.360315 -357.838945)
			(xy 136.352554 -357.784967) (xy 134.869706 -357.784967) (xy 134.869706 -357.78497) (xy 134.861944 -357.838956)
			(xy 134.846579 -357.891287) (xy 134.823923 -357.940899) (xy 134.794437 -357.986782) (xy 134.758722 -358.028003)
			(xy 134.717505 -358.063721) (xy 134.671624 -358.09321) (xy 134.622013 -358.115869) (xy 134.569683 -358.131238)
			(xy 134.515698 -358.139004) (xy 134.488428 -358.139492) (xy 133.624828 -358.139492) (xy 133.597558 -358.13897)
			(xy 133.543572 -358.131212) (xy 133.49124 -358.11585) (xy 133.441627 -358.093195) (xy 133.395744 -358.063711)
			(xy 133.354524 -358.027996) (xy 133.318806 -357.986779) (xy 133.289318 -357.940897) (xy 133.26666 -357.891286)
			(xy 133.251294 -357.838955) (xy 133.243531 -357.78497) (xy 131.760828 -357.78497) (xy 131.760828 -357.784975)
			(xy 131.753065 -357.838969) (xy 131.737696 -357.891308) (xy 131.715034 -357.940927) (xy 131.685541 -357.986816)
			(xy 131.649817 -358.02804) (xy 131.60859 -358.06376) (xy 131.562699 -358.093249) (xy 131.513078 -358.115907)
			(xy 131.460737 -358.131272) (xy 131.406743 -358.139031) (xy 131.379468 -358.139492) (xy 130.515868 -358.139492)
			(xy 130.488602 -358.138943) (xy 130.434626 -358.131179) (xy 130.382305 -358.115812) (xy 130.332703 -358.093156)
			(xy 130.286829 -358.063671) (xy 130.245619 -358.027959) (xy 130.20991 -357.986745) (xy 130.180429 -357.940869)
			(xy 130.157777 -357.891265) (xy 130.142414 -357.838942) (xy 130.134654 -357.784966) (xy 128.651806 -357.784966)
			(xy 128.651806 -357.784971) (xy 128.644043 -357.838958) (xy 128.628677 -357.891291) (xy 128.60602 -357.940905)
			(xy 128.576532 -357.986789) (xy 128.540815 -358.02801) (xy 128.499595 -358.063728) (xy 128.453712 -358.093216)
			(xy 128.404099 -358.115875) (xy 128.351766 -358.131242) (xy 128.297779 -358.139005) (xy 128.270508 -358.139492)
			(xy 127.406908 -358.139492) (xy 127.379639 -358.138969) (xy 127.325655 -358.131209) (xy 127.273326 -358.115844)
			(xy 127.223715 -358.093189) (xy 127.177834 -358.063704) (xy 127.136617 -358.027989) (xy 127.100901 -357.986772)
			(xy 127.071415 -357.940892) (xy 127.048759 -357.891282) (xy 127.033393 -357.838953) (xy 127.025631 -357.784969)
			(xy 125.542806 -357.784969) (xy 125.535045 -357.838953) (xy 125.51968 -357.891283) (xy 125.497026 -357.940894)
			(xy 125.467542 -357.986776) (xy 125.431829 -358.027995) (xy 125.390614 -358.063713) (xy 125.344736 -358.093203)
			(xy 125.295128 -358.115864) (xy 125.2428 -358.131234) (xy 125.188817 -358.139002) (xy 125.161548 -358.139492)
			(xy 124.297948 -358.139492) (xy 124.270677 -358.138972) (xy 124.216689 -358.131216) (xy 124.164355 -358.115855)
			(xy 124.114739 -358.093202) (xy 124.068853 -358.063718) (xy 124.027631 -358.028003) (xy 123.991911 -357.986785)
			(xy 123.962421 -357.940903) (xy 123.939762 -357.89129) (xy 123.924394 -357.838958) (xy 123.916632 -357.784971)
			(xy 122.433928 -357.784971) (xy 122.433928 -357.784974) (xy 122.426165 -357.838966) (xy 122.410797 -357.891304)
			(xy 122.388137 -357.940921) (xy 122.358646 -357.986809) (xy 122.322924 -358.028033) (xy 122.2817 -358.063753)
			(xy 122.235811 -358.093243) (xy 122.186192 -358.115901) (xy 122.133854 -358.131268) (xy 122.079862 -358.139029)
			(xy 122.052588 -358.139492) (xy 121.188988 -358.139492) (xy 121.161721 -358.138945) (xy 121.107743 -358.131182)
			(xy 121.055419 -358.115817) (xy 121.005815 -358.093162) (xy 120.959939 -358.063678) (xy 120.918726 -358.027966)
			(xy 120.883015 -357.986752) (xy 120.853532 -357.940875) (xy 120.830879 -357.891269) (xy 120.815515 -357.838945)
			(xy 120.807754 -357.784967) (xy 119.324906 -357.784967) (xy 119.324906 -357.78497) (xy 119.317144 -357.838956)
			(xy 119.301779 -357.891287) (xy 119.279123 -357.940899) (xy 119.249637 -357.986782) (xy 119.213922 -358.028003)
			(xy 119.172705 -358.063721) (xy 119.126824 -358.09321) (xy 119.077213 -358.115869) (xy 119.024883 -358.131238)
			(xy 118.970898 -358.139004) (xy 118.943628 -358.139492) (xy 118.080028 -358.139492) (xy 118.052758 -358.13897)
			(xy 117.998772 -358.131212) (xy 117.94644 -358.11585) (xy 117.896827 -358.093195) (xy 117.850944 -358.063711)
			(xy 117.809724 -358.027996) (xy 117.774006 -357.986779) (xy 117.744518 -357.940897) (xy 117.72186 -357.891286)
			(xy 117.706494 -357.838955) (xy 117.698731 -357.78497) (xy 116.216028 -357.78497) (xy 116.216028 -357.784975)
			(xy 116.208265 -357.838969) (xy 116.192896 -357.891308) (xy 116.170234 -357.940927) (xy 116.140741 -357.986816)
			(xy 116.105017 -358.02804) (xy 116.06379 -358.06376) (xy 116.017899 -358.093249) (xy 115.968278 -358.115907)
			(xy 115.915937 -358.131272) (xy 115.861943 -358.139031) (xy 115.834668 -358.139492) (xy 114.971068 -358.139492)
			(xy 114.943802 -358.138943) (xy 114.889826 -358.131179) (xy 114.837505 -358.115812) (xy 114.787903 -358.093156)
			(xy 114.742029 -358.063671) (xy 114.700819 -358.027959) (xy 114.66511 -357.986745) (xy 114.635629 -357.940869)
			(xy 114.612977 -357.891265) (xy 114.597614 -357.838942) (xy 114.589854 -357.784966) (xy 100.576623 -357.784966)
			(xy 100.639626 -358.76357) (xy 100.694236 -359.611422) (xy 100.696268 -359.674414) (xy 100.696268 -359.674922)
			(xy 100.696014 -359.690162) (xy 100.696014 -359.69448) (xy 100.69576 -359.699814) (xy 100.687658 -360.017783)
			(xy 101.774757 -360.017783) (xy 101.774757 -359.957817) (xy 101.782584 -359.898365) (xy 101.798104 -359.840443)
			(xy 101.821052 -359.785042) (xy 101.851035 -359.733111) (xy 101.88754 -359.685538) (xy 101.929942 -359.643136)
			(xy 101.977516 -359.606632) (xy 102.029448 -359.57665) (xy 102.084849 -359.553703) (xy 102.142771 -359.538183)
			(xy 102.202223 -359.530357) (xy 102.232206 -359.529888) (xy 103.095806 -359.529888) (xy 103.125793 -359.530279)
			(xy 103.185255 -359.538108) (xy 103.243186 -359.553631) (xy 103.298595 -359.576583) (xy 103.350534 -359.60657)
			(xy 103.398115 -359.643081) (xy 103.440523 -359.68549) (xy 103.477033 -359.733071) (xy 103.50702 -359.785011)
			(xy 103.529971 -359.84042) (xy 103.545494 -359.898351) (xy 103.553322 -359.957813) (xy 103.553322 -360.017787)
			(xy 103.545494 -360.077249) (xy 103.529971 -360.13518) (xy 103.525241 -360.1466) (xy 106.603292 -360.1466)
			(xy 106.603805 -360.117682) (xy 106.612541 -360.060509) (xy 106.629813 -360.005313) (xy 106.655224 -359.953358)
			(xy 106.688191 -359.905838) (xy 106.707686 -359.884472) (xy 106.714036 -359.877614) (xy 106.721148 -359.86085)
			(xy 106.724704 -359.775252) (xy 106.718862 -359.758234) (xy 106.71302 -359.750868) (xy 106.69712 -359.730454)
			(xy 106.670426 -359.686126) (xy 106.649966 -359.638599) (xy 106.636113 -359.588743) (xy 106.629123 -359.537472)
			(xy 106.628692 -359.5116) (xy 106.629178 -359.484349) (xy 106.636934 -359.430401) (xy 106.652289 -359.378106)
			(xy 106.674931 -359.328529) (xy 106.704397 -359.282679) (xy 106.740088 -359.241488) (xy 106.781279 -359.205797)
			(xy 106.827129 -359.176331) (xy 106.876706 -359.153689) (xy 106.929001 -359.138334) (xy 106.982949 -359.130578)
			(xy 107.037451 -359.130578) (xy 107.091399 -359.138334) (xy 107.143694 -359.153689) (xy 107.193271 -359.176331)
			(xy 107.239121 -359.205797) (xy 107.280312 -359.241488) (xy 107.316003 -359.282679) (xy 107.345469 -359.328529)
			(xy 107.368111 -359.378106) (xy 107.383466 -359.430401) (xy 107.391222 -359.484349) (xy 107.391708 -359.5116)
			(xy 107.391195 -359.540518) (xy 107.382459 -359.597691) (xy 107.365187 -359.652887) (xy 107.339776 -359.704842)
			(xy 107.306809 -359.752362) (xy 107.287314 -359.773728) (xy 107.280964 -359.780586) (xy 107.273852 -359.79735)
			(xy 107.270296 -359.882948) (xy 107.276138 -359.899966) (xy 107.28198 -359.907332) (xy 107.29788 -359.927746)
			(xy 107.324574 -359.972074) (xy 107.345034 -360.019601) (xy 107.358887 -360.069457) (xy 107.365877 -360.120728)
			(xy 107.366308 -360.1466) (xy 107.365822 -360.173851) (xy 107.358066 -360.227799) (xy 107.342711 -360.280094)
			(xy 107.320069 -360.329671) (xy 107.290603 -360.375521) (xy 107.254912 -360.416712) (xy 107.213721 -360.452403)
			(xy 107.167871 -360.481869) (xy 107.118294 -360.504511) (xy 107.065999 -360.519866) (xy 107.012051 -360.527622)
			(xy 106.957549 -360.527622) (xy 106.903601 -360.519866) (xy 106.851306 -360.504511) (xy 106.801729 -360.481869)
			(xy 106.755879 -360.452403) (xy 106.714688 -360.416712) (xy 106.678997 -360.375521) (xy 106.649531 -360.329671)
			(xy 106.626889 -360.280094) (xy 106.611534 -360.227799) (xy 106.603778 -360.173851) (xy 106.603292 -360.1466)
			(xy 103.525241 -360.1466) (xy 103.50702 -360.190589) (xy 103.477033 -360.242529) (xy 103.440523 -360.29011)
			(xy 103.398115 -360.332519) (xy 103.350534 -360.36903) (xy 103.298595 -360.399017) (xy 103.243186 -360.421969)
			(xy 103.185255 -360.437492) (xy 103.125793 -360.445321) (xy 103.095806 -360.445812) (xy 102.232206 -360.445812)
			(xy 102.202223 -360.445243) (xy 102.142771 -360.437417) (xy 102.084849 -360.421897) (xy 102.029448 -360.39895)
			(xy 101.977516 -360.368968) (xy 101.929942 -360.332464) (xy 101.88754 -360.290062) (xy 101.851035 -360.242489)
			(xy 101.821052 -360.190558) (xy 101.798104 -360.135157) (xy 101.782584 -360.077235) (xy 101.774757 -360.017783)
			(xy 100.687658 -360.017783) (xy 100.657152 -361.214924) (xy 100.657318 -361.224221) (xy 100.663521 -361.241732)
			(xy 100.675604 -361.255842) (xy 100.683568 -361.260644) (xy 100.688648 -361.263438) (xy 100.691188 -361.264454)
			(xy 100.715454 -361.274828) (xy 100.760878 -361.301688) (xy 100.80184 -361.334958) (xy 100.837442 -361.373911)
			(xy 100.866904 -361.417692) (xy 100.88958 -361.465343) (xy 100.904975 -361.515819) (xy 100.91275 -361.568014)
			(xy 100.913184 -361.5944) (xy 100.91266 -361.622081) (xy 100.904102 -361.676778) (xy 100.88719 -361.729494)
			(xy 100.862332 -361.778962) (xy 100.830126 -361.823992) (xy 100.791345 -361.863502) (xy 100.746922 -361.896541)
			(xy 100.697926 -361.922316) (xy 100.671884 -361.931712) (xy 100.656644 -361.936792) (xy 100.638102 -361.962446)
			(xy 100.48748 -367.872264) (xy 100.487714 -367.882417) (xy 100.49517 -367.901288) (xy 100.501958 -367.90884)
			(xy 100.50907 -367.916206) (xy 100.527612 -367.92408) (xy 100.542598 -367.92408) (xy 100.555044 -367.923826)
			(xy 100.555552 -367.923826) (xy 100.582826 -367.924286) (xy 100.636818 -367.932043) (xy 100.689157 -367.947405)
			(xy 100.738777 -367.970059) (xy 100.784668 -367.999546) (xy 100.825895 -368.035263) (xy 100.861618 -368.076484)
			(xy 100.891112 -368.12237) (xy 100.913774 -368.171986) (xy 100.929145 -368.224323) (xy 100.934859 -368.264054)
			(xy 103.243332 -368.264054) (xy 103.243332 -368.209546) (xy 103.251089 -368.155594) (xy 103.266445 -368.103294)
			(xy 103.289087 -368.053713) (xy 103.318555 -368.007858) (xy 103.354249 -367.966663) (xy 103.395442 -367.930967)
			(xy 103.441295 -367.901497) (xy 103.490876 -367.878852) (xy 103.543174 -367.863493) (xy 103.597126 -367.855733)
			(xy 103.62438 -367.855246) (xy 103.651658 -367.855674) (xy 103.705657 -367.863443) (xy 103.757999 -367.878824)
			(xy 103.807616 -367.901505) (xy 103.853496 -367.931023) (xy 103.894704 -367.966775) (xy 103.930398 -368.008032)
			(xy 103.959852 -368.053954) (xy 103.982463 -368.103603) (xy 103.997771 -368.155966) (xy 104.002078 -368.182906)
			(xy 104.004785 -368.197766) (xy 104.017581 -368.225105) (xy 104.037808 -368.247511) (xy 104.063699 -368.263029)
			(xy 104.092995 -368.270304) (xy 104.123138 -368.268701) (xy 104.151497 -368.25836) (xy 104.163876 -368.249708)
			(xy 104.188882 -368.23155) (xy 104.243532 -368.202707) (xy 104.302116 -368.183048) (xy 104.363103 -368.173089)
			(xy 104.394 -368.172492) (xy 104.421251 -368.172978) (xy 104.475199 -368.180734) (xy 104.527494 -368.196089)
			(xy 104.577071 -368.218731) (xy 104.622921 -368.248197) (xy 104.664112 -368.283888) (xy 104.699803 -368.325079)
			(xy 104.729269 -368.370929) (xy 104.751911 -368.420506) (xy 104.767266 -368.472801) (xy 104.775022 -368.526749)
			(xy 104.775022 -368.581251) (xy 104.767266 -368.635199) (xy 104.751911 -368.687494) (xy 104.729269 -368.737071)
			(xy 104.699803 -368.782921) (xy 104.664112 -368.824112) (xy 104.622921 -368.859803) (xy 104.577071 -368.889269)
			(xy 104.527494 -368.911911) (xy 104.475199 -368.927266) (xy 104.421251 -368.935022) (xy 104.394 -368.935508)
			(xy 104.366724 -368.935053) (xy 104.312728 -368.927283) (xy 104.260389 -368.911901) (xy 104.210775 -368.889222)
			(xy 104.164896 -368.859707) (xy 104.12369 -368.823958) (xy 104.087995 -368.782705) (xy 104.05854 -368.736788)
			(xy 104.035925 -368.687144) (xy 104.020612 -368.634786) (xy 104.016302 -368.607848) (xy 104.013597 -368.592985)
			(xy 104.000809 -368.565637) (xy 103.980584 -368.543223) (xy 103.95469 -368.5277) (xy 103.925389 -368.520426)
			(xy 103.895241 -368.522035) (xy 103.866881 -368.532388) (xy 103.854504 -368.541046) (xy 103.829509 -368.55922)
			(xy 103.774855 -368.588058) (xy 103.716267 -368.607711) (xy 103.655278 -368.617667) (xy 103.62438 -368.618262)
			(xy 103.597126 -368.617867) (xy 103.543174 -368.610107) (xy 103.490876 -368.594748) (xy 103.441295 -368.572103)
			(xy 103.395442 -368.542633) (xy 103.354249 -368.506937) (xy 103.318555 -368.465742) (xy 103.289087 -368.419887)
			(xy 103.266445 -368.370306) (xy 103.251089 -368.318006) (xy 103.243332 -368.264054) (xy 100.934859 -368.264054)
			(xy 100.93691 -368.278315) (xy 100.937314 -368.305588) (xy 100.936883 -368.33187) (xy 100.929688 -368.38394)
			(xy 100.915418 -368.434531) (xy 100.894343 -368.482685) (xy 100.866861 -368.527494) (xy 100.833492 -368.568109)
			(xy 100.794868 -368.603762) (xy 100.751718 -368.63378) (xy 100.704858 -368.657595) (xy 100.655173 -368.674757)
			(xy 100.629466 -368.680238) (xy 100.61976 -368.682672) (xy 100.603146 -368.693788) (xy 100.59205 -368.710415)
			(xy 100.588159 -368.730022) (xy 100.589588 -368.739928) (xy 100.628358 -368.935) (xy 102.360982 -368.935)
			(xy 102.365053 -368.879378) (xy 102.377179 -368.824941) (xy 102.397102 -368.77285) (xy 102.424398 -368.724215)
			(xy 102.458484 -368.680072) (xy 102.498633 -368.641363) (xy 102.543991 -368.608912) (xy 102.593591 -368.583411)
			(xy 102.646375 -368.565404) (xy 102.701218 -368.555274) (xy 102.756952 -368.553237) (xy 102.812389 -368.559337)
			(xy 102.866346 -368.573443) (xy 102.917675 -368.595255) (xy 102.965281 -368.624309) (xy 103.008149 -368.659984)
			(xy 103.045366 -368.701521) (xy 103.076139 -368.748034) (xy 103.099811 -368.798531) (xy 103.115879 -368.851938)
			(xy 103.123999 -368.907114) (xy 103.124508 -368.935) (xy 103.123999 -368.962886) (xy 103.119991 -368.990118)
			(xy 117.624352 -368.990118) (xy 117.624858 -368.9585) (xy 117.633063 -368.895798) (xy 117.649338 -368.834692)
			(xy 117.673405 -368.776215) (xy 117.70486 -368.721357) (xy 117.743168 -368.671045) (xy 117.787683 -368.626131)
			(xy 117.837651 -368.587375) (xy 117.892226 -368.555432) (xy 117.950486 -368.530843) (xy 118.011444 -368.514024)
			(xy 118.07407 -368.505259) (xy 118.105682 -368.50447) (xy 118.115842 -368.50447) (xy 118.13413 -368.49685)
			(xy 120.165622 -366.465104) (xy 120.184434 -366.44704) (xy 120.226641 -366.416408) (xy 120.27312 -366.392757)
			(xy 120.322728 -366.37667) (xy 120.374242 -366.368544) (xy 120.400318 -366.368076) (xy 136.423654 -366.368076)
			(xy 136.449732 -366.36853) (xy 136.50125 -366.376653) (xy 136.550862 -366.392737) (xy 136.597347 -366.416386)
			(xy 136.639558 -366.447018) (xy 136.65835 -366.465104) (xy 148.012658 -377.819412) (xy 148.030773 -377.838191)
			(xy 148.061457 -377.880389) (xy 148.085157 -377.926871) (xy 148.101288 -377.976489) (xy 148.109454 -378.028021)
			(xy 148.10994 -378.054108) (xy 148.10994 -379.201426) (xy 148.112734 -379.213364) (xy 148.115528 -379.218952)
			(xy 148.129353 -379.246484) (xy 148.148921 -379.304898) (xy 148.158858 -379.365696) (xy 148.15947 -379.396498)
			(xy 148.159043 -379.423753) (xy 148.151285 -379.477707) (xy 148.135927 -379.530008) (xy 148.113282 -379.57959)
			(xy 148.083811 -379.625445) (xy 148.048113 -379.666639) (xy 148.006916 -379.702333) (xy 147.961059 -379.7318)
			(xy 147.911474 -379.75444) (xy 147.859171 -379.769793) (xy 147.805217 -379.777545) (xy 147.777962 -379.778006)
			(xy 147.750934 -379.777556) (xy 147.69742 -379.769915) (xy 147.645518 -379.754805) (xy 147.596265 -379.732527)
			(xy 147.550646 -379.703527) (xy 147.529804 -379.686312) (xy 147.518374 -379.676406) (xy 147.489164 -379.672342)
			(xy 147.391628 -379.7173) (xy 147.383041 -379.721725) (xy 147.369732 -379.735701) (xy 147.362578 -379.753624)
			(xy 147.362164 -379.763274) (xy 147.362164 -380.23546) (xy 147.364958 -380.247398) (xy 147.367752 -380.252986)
			(xy 147.381583 -380.280515) (xy 147.40115 -380.33893) (xy 147.411084 -380.39973) (xy 147.411694 -380.430532)
			(xy 147.411261 -380.457501) (xy 147.403648 -380.5109) (xy 147.388591 -380.562695) (xy 147.366392 -380.611854)
			(xy 147.337493 -380.657398) (xy 147.302468 -380.698418) (xy 147.262017 -380.734099) (xy 147.239736 -380.749302)
			(xy 147.230084 -380.755652) (xy 147.2184 -380.774956) (xy 147.209256 -380.864872) (xy 147.208665 -380.876196)
			(xy 147.216185 -380.897558) (xy 147.223734 -380.90602) (xy 147.399756 -381.081788) (xy 147.407169 -381.088465)
			(xy 147.425604 -381.096041) (xy 147.43557 -381.09652) (xy 147.552156 -381.09652) (xy 147.578243 -381.097014)
			(xy 147.629775 -381.105176) (xy 147.679393 -381.121306) (xy 147.725874 -381.145005) (xy 147.768072 -381.175689)
			(xy 147.786852 -381.193802) (xy 147.931632 -381.338582) (xy 147.9423 -381.344932) (xy 147.948142 -381.346964)
			(xy 147.973725 -381.355337) (xy 148.022374 -381.37838) (xy 148.0673 -381.408035) (xy 148.107609 -381.443713)
			(xy 148.142501 -381.484704) (xy 148.171281 -381.530195) (xy 148.193379 -381.579281) (xy 148.208355 -381.630987)
			(xy 148.21591 -381.684285) (xy 148.216366 -381.7112) (xy 148.215945 -381.738455) (xy 148.208186 -381.792409)
			(xy 148.192828 -381.844711) (xy 148.170183 -381.894293) (xy 148.140711 -381.940149) (xy 148.105013 -381.981342)
			(xy 148.063815 -382.017036) (xy 148.017957 -382.046503) (xy 147.968371 -382.069143) (xy 147.916068 -382.084495)
			(xy 147.862113 -382.092248) (xy 147.834858 -382.092708) (xy 147.807948 -382.09224) (xy 147.754664 -382.084658)
			(xy 147.702974 -382.069665) (xy 147.653903 -382.047557) (xy 147.608425 -382.018774) (xy 147.567443 -381.983887)
			(xy 147.531769 -381.943588) (xy 147.502111 -381.898676) (xy 147.479058 -381.850042) (xy 147.470622 -381.824484)
			(xy 147.46859 -381.818642) (xy 147.46224 -381.807974) (xy 147.429474 -381.775208) (xy 147.422051 -381.768544)
			(xy 147.403623 -381.76096) (xy 147.39366 -381.760476) (xy 147.277074 -381.760476) (xy 147.266693 -381.760343)
			(xy 147.245977 -381.758943) (xy 147.235672 -381.757682) (xy 147.223734 -381.756158) (xy 147.201382 -381.764032)
			(xy 147.127976 -381.83947) (xy 147.12061 -381.862076) (xy 147.122388 -381.874014) (xy 147.124227 -381.886443)
			(xy 147.126264 -381.911489) (xy 147.126452 -381.924052) (xy 147.126452 -382.249426) (xy 147.129246 -382.261364)
			(xy 147.13204 -382.266952) (xy 147.145866 -382.294483) (xy 147.165433 -382.352898) (xy 147.17537 -382.413696)
			(xy 147.175982 -382.444498) (xy 147.175483 -382.472007) (xy 147.167562 -382.526451) (xy 147.151896 -382.579192)
			(xy 147.128814 -382.629133) (xy 147.098792 -382.675238) (xy 147.080986 -382.696212) (xy 147.075173 -382.703478)
			(xy 147.0688 -382.720945) (xy 147.06854 -382.730248) (xy 147.068794 -382.760474) (xy 147.069273 -382.77038)
			(xy 147.076869 -382.788681) (xy 147.083526 -382.796034) (xy 147.14728 -382.859788) (xy 147.154685 -382.866475)
			(xy 147.173126 -382.874045) (xy 147.183094 -382.87452) (xy 147.777962 -382.87452) (xy 147.812065 -382.874999)
			(xy 147.87981 -382.882913) (xy 147.946178 -382.898638) (xy 148.010272 -382.921963) (xy 148.071224 -382.952571)
			(xy 148.12821 -382.990048) (xy 148.180461 -383.033888) (xy 148.227268 -383.083498) (xy 148.267999 -383.138206)
			(xy 148.302103 -383.197273) (xy 148.329119 -383.2599) (xy 148.348681 -383.32524) (xy 148.360526 -383.39241)
			(xy 148.364492 -383.4605) (xy 148.360526 -383.52859) (xy 148.348681 -383.59576) (xy 148.329119 -383.6611)
			(xy 148.302103 -383.723727) (xy 148.267999 -383.782794) (xy 148.227268 -383.837502) (xy 148.180461 -383.887112)
			(xy 148.12821 -383.930952) (xy 148.071224 -383.968429) (xy 148.010272 -383.999037) (xy 147.946178 -384.022362)
			(xy 147.87981 -384.038087) (xy 147.812065 -384.046001) (xy 147.777962 -384.046476) (xy 146.919442 -384.046476)
			(xy 146.886561 -384.046016) (xy 146.821214 -384.038653) (xy 146.757103 -384.024015) (xy 146.695035 -384.002286)
			(xy 146.635793 -383.973741) (xy 146.580122 -383.938738) (xy 146.528722 -383.897718) (xy 146.505168 -383.874772)
			(xy 144.908524 -382.278128) (xy 144.885603 -382.254553) (xy 144.844609 -382.203141) (xy 144.809623 -382.147467)
			(xy 144.781084 -382.088228) (xy 144.75935 -382.026169) (xy 144.744694 -381.962069) (xy 144.737299 -381.896731)
			(xy 144.73682 -381.863854) (xy 144.73682 -378.8664) (xy 144.736365 -378.856431) (xy 144.728776 -378.837994)
			(xy 144.722088 -378.830586) (xy 135.295894 -369.404392) (xy 135.272965 -369.380831) (xy 135.231981 -369.32942)
			(xy 135.197015 -369.273742) (xy 135.168505 -369.214498) (xy 135.146811 -369.152433) (xy 135.132206 -369.088329)
			(xy 135.124872 -369.022992) (xy 135.124444 -368.990118) (xy 135.124977 -368.954385) (xy 135.133676 -368.88345)
			(xy 135.150934 -368.814099) (xy 135.176497 -368.747361) (xy 135.19277 -368.715544) (xy 135.198866 -368.703606)
			(xy 135.198358 -368.67719) (xy 135.146542 -368.59083) (xy 135.141683 -368.583534) (xy 135.128105 -368.572468)
			(xy 135.111611 -368.566569) (xy 135.102854 -368.566192) (xy 132.224272 -368.566192) (xy 132.214266 -368.566644)
			(xy 132.195802 -368.574368) (xy 132.188458 -368.581178) (xy 131.803394 -368.965988) (xy 131.795774 -368.984276)
			(xy 131.795774 -368.994436) (xy 131.794956 -369.026047) (xy 131.78619 -369.088669) (xy 131.769371 -369.149624)
			(xy 131.744783 -369.207881) (xy 131.712842 -369.262454) (xy 131.674088 -369.31242) (xy 131.629178 -369.356934)
			(xy 131.57887 -369.395243) (xy 131.524015 -369.426698) (xy 131.465543 -369.450768) (xy 131.404441 -369.467046)
			(xy 131.341743 -369.475256) (xy 131.310126 -369.475766) (xy 131.278329 -369.475226) (xy 131.215278 -369.466929)
			(xy 131.15385 -369.450473) (xy 131.095096 -369.426139) (xy 131.04002 -369.394345) (xy 130.989566 -369.355633)
			(xy 130.944596 -369.310667) (xy 130.90588 -369.260217) (xy 130.87408 -369.205144) (xy 130.849742 -369.146391)
			(xy 130.83328 -369.084965) (xy 130.824977 -369.021915) (xy 130.824478 -368.990118) (xy 130.824958 -368.958499)
			(xy 130.833164 -368.895795) (xy 130.849439 -368.834687) (xy 130.873509 -368.776209) (xy 130.904965 -368.721349)
			(xy 130.943276 -368.671036) (xy 130.987794 -368.626122) (xy 131.037764 -368.587366) (xy 131.092342 -368.555424)
			(xy 131.150605 -368.530837) (xy 131.211566 -368.51402) (xy 131.274195 -368.505258) (xy 131.305808 -368.50447)
			(xy 131.315968 -368.50447) (xy 131.334256 -368.49685) (xy 131.729988 -368.100864) (xy 131.73583 -368.071146)
			(xy 131.729988 -368.056668) (xy 131.725791 -368.047531) (xy 131.711604 -368.033299) (xy 131.693045 -368.025595)
			(xy 131.682998 -368.025172) (xy 128.36525 -368.025172) (xy 128.355244 -368.025618) (xy 128.33678 -368.033347)
			(xy 128.329436 -368.040158) (xy 127.403352 -368.965988) (xy 127.395732 -368.984276) (xy 127.395732 -368.994436)
			(xy 127.394956 -369.026049) (xy 127.386189 -369.088675) (xy 127.369368 -369.149633) (xy 127.344777 -369.207893)
			(xy 127.312833 -369.262468) (xy 127.274075 -369.312435) (xy 127.22916 -369.356949) (xy 127.178848 -369.395257)
			(xy 127.123989 -369.426711) (xy 127.065511 -369.450779) (xy 127.004404 -369.467053) (xy 126.941702 -369.475259)
			(xy 126.910084 -369.475766) (xy 126.878287 -369.475243) (xy 126.815238 -369.466941) (xy 126.753813 -369.45048)
			(xy 126.69506 -369.426143) (xy 126.639987 -369.394346) (xy 126.589536 -369.355633) (xy 126.544568 -369.310666)
			(xy 126.505855 -369.260214) (xy 126.474058 -369.205141) (xy 126.44972 -369.146389) (xy 126.43326 -369.084963)
			(xy 126.424957 -369.021915) (xy 126.424436 -368.990118) (xy 126.424958 -368.958501) (xy 126.433163 -368.8958)
			(xy 126.449436 -368.834695) (xy 126.473503 -368.776219) (xy 126.504956 -368.721362) (xy 126.543263 -368.671051)
			(xy 126.587776 -368.626137) (xy 126.637742 -368.587381) (xy 126.692316 -368.555437) (xy 126.750574 -368.530847)
			(xy 126.81153 -368.514027) (xy 126.874154 -368.50526) (xy 126.905766 -368.50447) (xy 126.915926 -368.50447)
			(xy 126.934214 -368.49685) (xy 127.794766 -367.636044) (xy 127.800608 -367.606326) (xy 127.794766 -367.591848)
			(xy 127.790593 -367.582698) (xy 127.776395 -367.568469) (xy 127.757827 -367.560771) (xy 127.747776 -367.560352)
			(xy 124.430028 -367.560352) (xy 124.420021 -367.560792) (xy 124.401558 -367.568525) (xy 124.394214 -367.575338)
			(xy 123.00331 -368.965988) (xy 122.99569 -368.984276) (xy 122.99569 -368.994436) (xy 122.994856 -369.026046)
			(xy 122.986091 -369.088667) (xy 122.969272 -369.149621) (xy 122.944685 -369.207877) (xy 122.912745 -369.262449)
			(xy 122.873993 -369.312415) (xy 122.829084 -369.356928) (xy 122.778778 -369.395237) (xy 122.723926 -369.426693)
			(xy 122.665455 -369.450764) (xy 122.604354 -369.467043) (xy 122.541658 -369.475255) (xy 122.510042 -369.475766)
			(xy 122.478245 -369.475211) (xy 122.415195 -369.466916) (xy 122.353767 -369.450462) (xy 122.295013 -369.42613)
			(xy 122.239937 -369.394337) (xy 122.189483 -369.355627) (xy 122.144513 -369.310662) (xy 122.105796 -369.260213)
			(xy 122.073997 -369.205141) (xy 122.049658 -369.146389) (xy 122.033196 -369.084964) (xy 122.024893 -369.021915)
			(xy 122.024394 -368.990118) (xy 122.024858 -368.958498) (xy 122.033065 -368.895793) (xy 122.049341 -368.834684)
			(xy 122.073411 -368.776205) (xy 122.104869 -368.721344) (xy 122.143181 -368.671031) (xy 122.1877 -368.626117)
			(xy 122.237673 -368.587361) (xy 122.292253 -368.555419) (xy 122.350517 -368.530833) (xy 122.41148 -368.514017)
			(xy 122.47411 -368.505257) (xy 122.505724 -368.50447) (xy 122.515884 -368.50447) (xy 122.534172 -368.49685)
			(xy 123.923552 -367.107216) (xy 123.929394 -367.077498) (xy 123.923552 -367.06302) (xy 123.919359 -367.053879)
			(xy 123.905174 -367.039643) (xy 123.886611 -367.031942) (xy 123.876562 -367.031524) (xy 120.558814 -367.031524)
			(xy 120.548807 -367.031965) (xy 120.530345 -367.039699) (xy 120.523 -367.04651) (xy 118.603268 -368.965988)
			(xy 118.595648 -368.984276) (xy 118.595648 -368.994436) (xy 118.594856 -369.026048) (xy 118.58609 -369.088673)
			(xy 118.569269 -369.14963) (xy 118.544679 -369.207888) (xy 118.512736 -369.262463) (xy 118.47398 -369.312429)
			(xy 118.429067 -369.356943) (xy 118.378756 -369.395252) (xy 118.323899 -369.426706) (xy 118.265423 -369.450775)
			(xy 118.204318 -369.467051) (xy 118.141618 -369.475258) (xy 118.11 -369.475766) (xy 118.078204 -369.475228)
			(xy 118.015155 -369.466928) (xy 117.95373 -369.450469) (xy 117.894978 -369.426134) (xy 117.839905 -369.394339)
			(xy 117.789453 -369.355627) (xy 117.744485 -369.310661) (xy 117.705772 -369.26021) (xy 117.673974 -369.205138)
			(xy 117.649637 -369.146387) (xy 117.633176 -369.084962) (xy 117.624873 -369.021914) (xy 117.624352 -368.990118)
			(xy 103.119991 -368.990118) (xy 103.115879 -369.018062) (xy 103.099811 -369.071469) (xy 103.076139 -369.121966)
			(xy 103.045366 -369.168479) (xy 103.008149 -369.210016) (xy 102.965281 -369.245691) (xy 102.917675 -369.274745)
			(xy 102.866346 -369.296557) (xy 102.812389 -369.310663) (xy 102.756952 -369.316763) (xy 102.701218 -369.314726)
			(xy 102.646375 -369.304596) (xy 102.593591 -369.286589) (xy 102.543991 -369.261088) (xy 102.498633 -369.228637)
			(xy 102.458484 -369.189928) (xy 102.424398 -369.145785) (xy 102.397102 -369.09715) (xy 102.377179 -369.045059)
			(xy 102.365053 -368.990622) (xy 102.360982 -368.935) (xy 100.628358 -368.935) (xy 100.726494 -369.428776)
			(xy 100.730304 -369.448334) (xy 100.730304 -369.448842) (xy 100.744528 -369.52047) (xy 100.745544 -369.530376)
			(xy 100.745544 -369.607846) (xy 100.745544 -370.967) (xy 104.011992 -370.967) (xy 104.015722 -370.913749)
			(xy 104.026838 -370.861537) (xy 104.045124 -370.811385) (xy 104.070223 -370.764271) (xy 104.101645 -370.721117)
			(xy 104.138775 -370.682763) (xy 104.159558 -370.66601) (xy 104.168321 -370.658449) (xy 104.178501 -370.637689)
			(xy 104.179116 -370.626132) (xy 104.179116 -370.545868) (xy 104.178501 -370.534306) (xy 104.168337 -370.513535)
			(xy 104.159558 -370.50599) (xy 104.138775 -370.489237) (xy 104.101645 -370.450883) (xy 104.070223 -370.407729)
			(xy 104.045124 -370.360615) (xy 104.026838 -370.310463) (xy 104.015722 -370.258251) (xy 104.011992 -370.205)
			(xy 104.015722 -370.151749) (xy 104.026838 -370.099537) (xy 104.045124 -370.049385) (xy 104.070223 -370.002271)
			(xy 104.101645 -369.959117) (xy 104.138775 -369.920763) (xy 104.159558 -369.90401) (xy 104.168321 -369.896449)
			(xy 104.178501 -369.875689) (xy 104.179116 -369.864132) (xy 104.179116 -369.783868) (xy 104.178501 -369.772306)
			(xy 104.168337 -369.751535) (xy 104.159558 -369.74399) (xy 104.137061 -369.725815) (xy 104.097329 -369.683791)
			(xy 104.064392 -369.636252) (xy 104.039007 -369.584288) (xy 104.021753 -369.529088) (xy 104.013026 -369.471917)
			(xy 104.012492 -369.443) (xy 104.012978 -369.415749) (xy 104.020734 -369.361801) (xy 104.036089 -369.309506)
			(xy 104.058731 -369.259929) (xy 104.088197 -369.214079) (xy 104.123888 -369.172888) (xy 104.165079 -369.137197)
			(xy 104.210929 -369.107731) (xy 104.260506 -369.085089) (xy 104.312801 -369.069734) (xy 104.366749 -369.061978)
			(xy 104.421251 -369.061978) (xy 104.475199 -369.069734) (xy 104.527494 -369.085089) (xy 104.577071 -369.107731)
			(xy 104.622921 -369.137197) (xy 104.664112 -369.172888) (xy 104.699803 -369.214079) (xy 104.729269 -369.259929)
			(xy 104.751911 -369.309506) (xy 104.767266 -369.361801) (xy 104.775022 -369.415749) (xy 104.775508 -369.443)
			(xy 104.775025 -369.471919) (xy 104.766293 -369.529093) (xy 104.749031 -369.584294) (xy 104.723633 -369.636256)
			(xy 104.690681 -369.683789) (xy 104.650932 -369.725803) (xy 104.628442 -369.74399) (xy 104.619679 -369.751551)
			(xy 104.609499 -369.772311) (xy 104.608884 -369.783868) (xy 104.608884 -369.864132) (xy 104.609499 -369.875694)
			(xy 104.619663 -369.896465) (xy 104.628442 -369.90401) (xy 104.649225 -369.920763) (xy 104.686355 -369.959117)
			(xy 104.717777 -370.002271) (xy 104.742876 -370.049385) (xy 104.761162 -370.099537) (xy 104.772278 -370.151749)
			(xy 104.776008 -370.205) (xy 104.772278 -370.258251) (xy 104.761162 -370.310463) (xy 104.742876 -370.360615)
			(xy 104.717777 -370.407729) (xy 104.686355 -370.450883) (xy 104.649225 -370.489237) (xy 104.628442 -370.50599)
			(xy 104.619679 -370.513551) (xy 104.615187 -370.522712) (xy 115.424977 -370.522712) (xy 115.424979 -370.457267)
			(xy 115.433774 -370.392417) (xy 115.451204 -370.329336) (xy 115.476952 -370.26917) (xy 115.493292 -370.240814)
			(xy 115.496601 -370.234787) (xy 115.50021 -370.221525) (xy 115.500404 -370.214652) (xy 115.500404 -369.928902)
			(xy 115.500934 -369.918749) (xy 115.508702 -369.899986) (xy 115.523056 -369.885622) (xy 115.541813 -369.877841)
			(xy 115.551966 -369.87734) (xy 116.268246 -369.87734) (xy 116.278407 -369.877796) (xy 116.297177 -369.885586)
			(xy 116.311541 -369.899963) (xy 116.319314 -369.918741) (xy 116.319808 -369.928902) (xy 116.319808 -370.214652)
			(xy 116.320017 -370.221524) (xy 116.323614 -370.234787) (xy 116.32692 -370.240814) (xy 116.343248 -370.269175)
			(xy 116.368995 -370.32934) (xy 116.386425 -370.392419) (xy 116.39522 -370.457268) (xy 116.395221 -370.522711)
			(xy 116.395221 -370.522712) (xy 119.825027 -370.522712) (xy 119.825029 -370.457268) (xy 119.833823 -370.392418)
			(xy 119.851251 -370.329337) (xy 119.876996 -370.26917) (xy 119.893334 -370.240814) (xy 119.896692 -370.234796)
			(xy 119.900431 -370.221538) (xy 119.9007 -370.214652) (xy 119.9007 -369.928902) (xy 119.901227 -369.91878)
			(xy 119.908947 -369.900067) (xy 119.92322 -369.885712) (xy 119.941889 -369.877886) (xy 119.952008 -369.87734)
			(xy 120.668288 -369.87734) (xy 120.678446 -369.877732) (xy 120.697206 -369.885531) (xy 120.711531 -369.899938)
			(xy 120.719224 -369.918741) (xy 120.719596 -369.928902) (xy 120.719596 -370.214652) (xy 120.719848 -370.221542)
			(xy 120.723578 -370.234808) (xy 120.726962 -370.240814) (xy 120.743289 -370.269176) (xy 120.769034 -370.329341)
			(xy 120.786461 -370.39242) (xy 120.795256 -370.457269) (xy 120.795257 -370.522711) (xy 120.795257 -370.522712)
			(xy 124.225063 -370.522712) (xy 124.225065 -370.457268) (xy 124.23386 -370.392417) (xy 124.251289 -370.329336)
			(xy 124.277037 -370.26917) (xy 124.293376 -370.240814) (xy 124.296684 -370.234786) (xy 124.300294 -370.221525)
			(xy 124.300488 -370.214652) (xy 124.300488 -369.928902) (xy 124.300867 -369.918724) (xy 124.30866 -369.89992)
			(xy 124.32306 -369.885533) (xy 124.341872 -369.877757) (xy 124.35205 -369.87734) (xy 125.06833 -369.87734)
			(xy 125.07849 -369.877809) (xy 125.09726 -369.885593) (xy 125.111625 -369.899967) (xy 125.119398 -369.918742)
			(xy 125.119892 -369.928902) (xy 125.119892 -370.214652) (xy 125.120104 -370.221524) (xy 125.123699 -370.234786)
			(xy 125.127004 -370.240814) (xy 125.14333 -370.269176) (xy 125.169072 -370.329342) (xy 125.186498 -370.392421)
			(xy 125.195292 -370.457269) (xy 125.195293 -370.522711) (xy 125.195293 -370.522712) (xy 128.624853 -370.522712)
			(xy 128.624854 -370.457268) (xy 128.633649 -370.392417) (xy 128.651078 -370.329337) (xy 128.676825 -370.26917)
			(xy 128.693164 -370.240814) (xy 128.696471 -370.234785) (xy 128.700082 -370.221525) (xy 128.700276 -370.214652)
			(xy 128.700276 -369.928902) (xy 128.700666 -369.918726) (xy 128.708458 -369.899924) (xy 128.722854 -369.885538)
			(xy 128.741661 -369.877759) (xy 128.751838 -369.87734) (xy 129.468118 -369.87734) (xy 129.478277 -369.877818)
			(xy 129.497047 -369.885599) (xy 129.511412 -369.89997) (xy 129.519185 -369.918743) (xy 129.51968 -369.928902)
			(xy 129.51968 -370.214652) (xy 129.519893 -370.221524) (xy 129.523487 -370.234786) (xy 129.526792 -370.240814)
			(xy 129.543118 -370.269176) (xy 129.568861 -370.329342) (xy 129.586288 -370.392421) (xy 129.595081 -370.457269)
			(xy 129.595082 -370.489988) (xy 133.023872 -370.489988) (xy 133.027863 -370.427821) (xy 133.039772 -370.366674)
			(xy 133.059401 -370.307553) (xy 133.08643 -370.251427) (xy 133.120414 -370.199218) (xy 133.160796 -370.151783)
			(xy 133.206912 -370.109902) (xy 133.258004 -370.074262) (xy 133.313235 -370.045448) (xy 133.371697 -370.023934)
			(xy 133.432431 -370.010072) (xy 133.494438 -370.00409) (xy 133.556701 -370.006086) (xy 133.618198 -370.016029)
			(xy 133.677919 -370.033753) (xy 133.734882 -370.05897) (xy 133.788153 -370.091263) (xy 133.836858 -370.130103)
			(xy 133.880195 -370.174853) (xy 133.917455 -370.224777) (xy 133.948024 -370.279056) (xy 133.971402 -370.336799)
			(xy 133.987203 -370.397057) (xy 133.995169 -370.45884) (xy 133.995668 -370.489988) (xy 133.995169 -370.521136)
			(xy 133.987203 -370.582919) (xy 133.971402 -370.643177) (xy 133.948024 -370.70092) (xy 133.917455 -370.755199)
			(xy 133.880195 -370.805123) (xy 133.836858 -370.849873) (xy 133.788153 -370.888713) (xy 133.734882 -370.921006)
			(xy 133.677919 -370.946223) (xy 133.618198 -370.963947) (xy 133.556701 -370.97389) (xy 133.494438 -370.975886)
			(xy 133.432431 -370.969904) (xy 133.371697 -370.956042) (xy 133.313235 -370.934528) (xy 133.258004 -370.905714)
			(xy 133.206912 -370.870074) (xy 133.160796 -370.828193) (xy 133.120414 -370.780758) (xy 133.08643 -370.728549)
			(xy 133.059401 -370.672423) (xy 133.039772 -370.613302) (xy 133.027863 -370.552155) (xy 133.023872 -370.489988)
			(xy 129.595082 -370.489988) (xy 129.595083 -370.522711) (xy 129.586292 -370.587559) (xy 129.568868 -370.650639)
			(xy 129.543128 -370.710806) (xy 129.526792 -370.739162) (xy 129.52349 -370.745193) (xy 129.519877 -370.758452)
			(xy 129.51968 -370.765324) (xy 129.51968 -371.514878) (xy 129.519883 -371.52175) (xy 129.523484 -371.535013)
			(xy 129.526792 -371.54104) (xy 129.54314 -371.56939) (xy 129.565986 -371.62279) (xy 130.824993 -371.62279)
			(xy 130.824998 -371.557345) (xy 130.833795 -371.492494) (xy 130.851225 -371.429412) (xy 130.876973 -371.369245)
			(xy 130.893312 -371.340888) (xy 130.896632 -371.334866) (xy 130.900234 -371.3216) (xy 130.900424 -371.314726)
			(xy 130.900424 -371.028722) (xy 130.900882 -371.018554) (xy 130.908657 -370.999762) (xy 130.923032 -370.985377)
			(xy 130.941818 -370.977589) (xy 130.951986 -370.97716) (xy 131.668266 -370.97716) (xy 131.678438 -370.977592)
			(xy 131.697236 -370.98537) (xy 131.711623 -370.999754) (xy 131.719405 -371.01855) (xy 131.719828 -371.028722)
			(xy 131.719828 -371.314726) (xy 131.720007 -371.3216) (xy 131.723624 -371.334863) (xy 131.72694 -371.340888)
			(xy 131.743246 -371.369262) (xy 131.768994 -371.429424) (xy 131.786425 -371.492501) (xy 131.795222 -371.557347)
			(xy 131.795226 -371.622788) (xy 131.786438 -371.687635) (xy 131.769015 -371.750714) (xy 131.752116 -371.790214)
			(xy 133.023872 -371.790214) (xy 133.027863 -371.728047) (xy 133.039772 -371.6669) (xy 133.059401 -371.607779)
			(xy 133.08643 -371.551653) (xy 133.120414 -371.499444) (xy 133.160796 -371.452009) (xy 133.206912 -371.410128)
			(xy 133.258004 -371.374488) (xy 133.313235 -371.345674) (xy 133.371697 -371.32416) (xy 133.432431 -371.310298)
			(xy 133.494438 -371.304316) (xy 133.556701 -371.306312) (xy 133.618198 -371.316255) (xy 133.677919 -371.333979)
			(xy 133.734882 -371.359196) (xy 133.788153 -371.391489) (xy 133.836858 -371.430329) (xy 133.880195 -371.475079)
			(xy 133.917455 -371.525003) (xy 133.948024 -371.579282) (xy 133.952388 -371.590062) (xy 135.22402 -371.590062)
			(xy 135.228011 -371.527895) (xy 135.23992 -371.466748) (xy 135.259549 -371.407627) (xy 135.286578 -371.351501)
			(xy 135.320562 -371.299292) (xy 135.360944 -371.251857) (xy 135.40706 -371.209976) (xy 135.458152 -371.174336)
			(xy 135.513383 -371.145522) (xy 135.571845 -371.124008) (xy 135.632579 -371.110146) (xy 135.694586 -371.104164)
			(xy 135.756849 -371.10616) (xy 135.818346 -371.116103) (xy 135.878067 -371.133827) (xy 135.93503 -371.159044)
			(xy 135.988301 -371.191337) (xy 136.037006 -371.230177) (xy 136.080343 -371.274927) (xy 136.117603 -371.324851)
			(xy 136.148172 -371.37913) (xy 136.17155 -371.436873) (xy 136.187351 -371.497131) (xy 136.195317 -371.558914)
			(xy 136.195816 -371.590062) (xy 136.195317 -371.62121) (xy 136.187351 -371.682993) (xy 136.17155 -371.743251)
			(xy 136.148172 -371.800994) (xy 136.117603 -371.855273) (xy 136.080343 -371.905197) (xy 136.037006 -371.949947)
			(xy 135.988301 -371.988787) (xy 135.93503 -372.02108) (xy 135.878067 -372.046297) (xy 135.818346 -372.064021)
			(xy 135.756849 -372.073964) (xy 135.694586 -372.07596) (xy 135.632579 -372.069978) (xy 135.571845 -372.056116)
			(xy 135.513383 -372.034602) (xy 135.458152 -372.005788) (xy 135.40706 -371.970148) (xy 135.360944 -371.928267)
			(xy 135.320562 -371.880832) (xy 135.286578 -371.828623) (xy 135.259549 -371.772497) (xy 135.23992 -371.713376)
			(xy 135.228011 -371.652229) (xy 135.22402 -371.590062) (xy 133.952388 -371.590062) (xy 133.971402 -371.637025)
			(xy 133.987203 -371.697283) (xy 133.995169 -371.759066) (xy 133.995668 -371.790214) (xy 133.995169 -371.821362)
			(xy 133.987203 -371.883145) (xy 133.971402 -371.943403) (xy 133.948024 -372.001146) (xy 133.917455 -372.055425)
			(xy 133.880195 -372.105349) (xy 133.836858 -372.150099) (xy 133.788153 -372.188939) (xy 133.734882 -372.221232)
			(xy 133.677919 -372.246449) (xy 133.618198 -372.264173) (xy 133.556701 -372.274116) (xy 133.494438 -372.276112)
			(xy 133.432431 -372.27013) (xy 133.371697 -372.256268) (xy 133.313235 -372.234754) (xy 133.258004 -372.20594)
			(xy 133.206912 -372.1703) (xy 133.160796 -372.128419) (xy 133.120414 -372.080984) (xy 133.08643 -372.028775)
			(xy 133.059401 -371.972649) (xy 133.039772 -371.913528) (xy 133.027863 -371.852381) (xy 133.023872 -371.790214)
			(xy 131.752116 -371.790214) (xy 131.743275 -371.81088) (xy 131.72694 -371.839236) (xy 131.723616 -371.845256)
			(xy 131.720016 -371.858523) (xy 131.719828 -371.865398) (xy 131.719828 -372.614698) (xy 131.720017 -372.621571)
			(xy 131.723627 -372.634834) (xy 131.72694 -372.64086) (xy 131.743307 -372.6692) (xy 131.769049 -372.72937)
			(xy 131.786473 -372.792454) (xy 131.795263 -372.857306) (xy 131.795261 -372.890034) (xy 135.22402 -372.890034)
			(xy 135.228011 -372.827867) (xy 135.23992 -372.76672) (xy 135.259549 -372.707599) (xy 135.286578 -372.651473)
			(xy 135.320562 -372.599264) (xy 135.360944 -372.551829) (xy 135.40706 -372.509948) (xy 135.458152 -372.474308)
			(xy 135.513383 -372.445494) (xy 135.571845 -372.42398) (xy 135.632579 -372.410118) (xy 135.694586 -372.404136)
			(xy 135.756849 -372.406132) (xy 135.818346 -372.416075) (xy 135.878067 -372.433799) (xy 135.93503 -372.459016)
			(xy 135.988301 -372.491309) (xy 136.037006 -372.530149) (xy 136.080343 -372.574899) (xy 136.117603 -372.624823)
			(xy 136.148172 -372.679102) (xy 136.17155 -372.736845) (xy 136.187351 -372.797103) (xy 136.195317 -372.858886)
			(xy 136.195816 -372.890034) (xy 136.195317 -372.921182) (xy 136.187351 -372.982965) (xy 136.17155 -373.043223)
			(xy 136.148172 -373.100966) (xy 136.117603 -373.155245) (xy 136.080343 -373.205169) (xy 136.037006 -373.249919)
			(xy 135.988301 -373.288759) (xy 135.93503 -373.321052) (xy 135.878067 -373.346269) (xy 135.818346 -373.363993)
			(xy 135.756849 -373.373936) (xy 135.694586 -373.375932) (xy 135.632579 -373.36995) (xy 135.571845 -373.356088)
			(xy 135.513383 -373.334574) (xy 135.458152 -373.30576) (xy 135.40706 -373.27012) (xy 135.360944 -373.228239)
			(xy 135.320562 -373.180804) (xy 135.286578 -373.128595) (xy 135.259549 -373.072469) (xy 135.23992 -373.013348)
			(xy 135.228011 -372.952201) (xy 135.22402 -372.890034) (xy 131.795261 -372.890034) (xy 131.795259 -372.922752)
			(xy 131.786461 -372.987603) (xy 131.76903 -373.050685) (xy 131.74328 -373.110852) (xy 131.72694 -373.139208)
			(xy 131.723626 -373.145233) (xy 131.720019 -373.158496) (xy 131.719828 -373.16537) (xy 131.719828 -373.451374)
			(xy 131.719414 -373.461548) (xy 131.711631 -373.480349) (xy 131.697242 -373.494736) (xy 131.67844 -373.502515)
			(xy 131.668266 -373.502936) (xy 130.951986 -373.502936) (xy 130.94181 -373.502547) (xy 130.92301 -373.494752)
			(xy 130.908625 -373.480356) (xy 130.900845 -373.46155) (xy 130.900424 -373.451374) (xy 130.900424 -373.16537)
			(xy 130.90024 -373.158496) (xy 130.896626 -373.145234) (xy 130.893312 -373.139208) (xy 130.877004 -373.110836)
			(xy 130.851259 -373.050672) (xy 130.833831 -372.987596) (xy 130.825034 -372.922749) (xy 130.825031 -372.857309)
			(xy 130.833819 -372.792462) (xy 130.85124 -372.729383) (xy 130.876978 -372.669216) (xy 130.893312 -372.64086)
			(xy 130.896642 -372.634843) (xy 130.900238 -372.621573) (xy 130.900424 -372.614698) (xy 130.900424 -371.865398)
			(xy 130.90023 -371.858525) (xy 130.896623 -371.845262) (xy 130.893312 -371.839236) (xy 130.876943 -371.810897)
			(xy 130.851204 -371.750726) (xy 130.833782 -371.687643) (xy 130.824993 -371.62279) (xy 129.565986 -371.62279)
			(xy 129.568881 -371.629558) (xy 129.586305 -371.69264) (xy 129.595096 -371.75749) (xy 129.595095 -371.822934)
			(xy 129.586301 -371.887784) (xy 129.568873 -371.950864) (xy 129.543129 -372.011031) (xy 129.526792 -372.039388)
			(xy 129.523481 -372.045414) (xy 129.519873 -372.058677) (xy 129.51968 -372.06555) (xy 129.51968 -372.351554)
			(xy 129.519199 -372.36172) (xy 129.511432 -372.380511) (xy 129.497064 -372.394896) (xy 129.478284 -372.402686)
			(xy 129.468118 -372.403116) (xy 128.751838 -372.403116) (xy 128.741663 -372.402704) (xy 128.722861 -372.394923)
			(xy 128.708473 -372.380533) (xy 128.700695 -372.361729) (xy 128.700276 -372.351554) (xy 128.700276 -372.06555)
			(xy 128.700068 -372.058678) (xy 128.696471 -372.045415) (xy 128.693164 -372.039388) (xy 128.676838 -372.011026)
			(xy 128.651091 -371.950861) (xy 128.633663 -371.887782) (xy 128.624868 -371.822933) (xy 128.624866 -371.757491)
			(xy 128.633658 -371.692642) (xy 128.651083 -371.629562) (xy 128.676827 -371.569396) (xy 128.693164 -371.54104)
			(xy 128.696462 -371.535007) (xy 128.700078 -371.52175) (xy 128.700276 -371.514878) (xy 128.700276 -370.765324)
			(xy 128.700078 -370.758451) (xy 128.696474 -370.745188) (xy 128.693164 -370.739162) (xy 128.676816 -370.710812)
			(xy 128.651071 -370.650644) (xy 128.633645 -370.587563) (xy 128.624853 -370.522712) (xy 125.195293 -370.522712)
			(xy 125.186503 -370.587559) (xy 125.169079 -370.650639) (xy 125.143339 -370.710805) (xy 125.127004 -370.739162)
			(xy 125.123703 -370.745193) (xy 125.120089 -370.758452) (xy 125.119892 -370.765324) (xy 125.119892 -371.514878)
			(xy 125.120093 -371.521751) (xy 125.123695 -371.535013) (xy 125.127004 -371.54104) (xy 125.143352 -371.56939)
			(xy 125.166196 -371.62279) (xy 126.424943 -371.62279) (xy 126.424948 -371.557344) (xy 126.433746 -371.492493)
			(xy 126.451179 -371.429411) (xy 126.476929 -371.369244) (xy 126.49327 -371.340888) (xy 126.49664 -371.334876)
			(xy 126.500372 -371.321613) (xy 126.500636 -371.314726) (xy 126.500636 -371.028722) (xy 126.501144 -371.018597)
			(xy 126.508864 -370.999877) (xy 126.523144 -370.98552) (xy 126.541822 -370.9777) (xy 126.551944 -370.97716)
			(xy 127.268224 -370.97716) (xy 127.278375 -370.977601) (xy 127.29712 -370.985397) (xy 127.311441 -370.999787)
			(xy 127.319147 -371.018569) (xy 127.319532 -371.028722) (xy 127.319532 -371.314726) (xy 127.319768 -371.321619)
			(xy 127.323494 -371.334891) (xy 127.326898 -371.340888) (xy 127.343202 -371.369262) (xy 127.368947 -371.429425)
			(xy 127.386376 -371.492502) (xy 127.395172 -371.557347) (xy 127.395176 -371.622787) (xy 127.386389 -371.687635)
			(xy 127.368969 -371.750713) (xy 127.343232 -371.810879) (xy 127.326898 -371.839236) (xy 127.323525 -371.845247)
			(xy 127.319794 -371.85851) (xy 127.319532 -371.865398) (xy 127.319532 -372.614698) (xy 127.319762 -372.62159)
			(xy 127.323506 -372.634856) (xy 127.326898 -372.64086) (xy 127.343263 -372.669201) (xy 127.369002 -372.729371)
			(xy 127.386424 -372.792455) (xy 127.395213 -372.857307) (xy 127.395209 -372.922752) (xy 127.386412 -372.987603)
			(xy 127.368983 -373.050684) (xy 127.343236 -373.110851) (xy 127.326898 -373.139208) (xy 127.323535 -373.145224)
			(xy 127.319798 -373.158483) (xy 127.319532 -373.16537) (xy 127.319532 -373.451374) (xy 127.319051 -373.461503)
			(xy 127.311327 -373.480228) (xy 127.297038 -373.494587) (xy 127.27835 -373.502402) (xy 127.268224 -373.502936)
			(xy 126.551944 -373.502936) (xy 126.541797 -373.502443) (xy 126.523053 -373.494669) (xy 126.508729 -373.480294)
			(xy 126.501021 -373.461522) (xy 126.500636 -373.451374) (xy 126.500636 -373.16537) (xy 126.500406 -373.158477)
			(xy 126.496675 -373.145205) (xy 126.49327 -373.139208) (xy 126.47696 -373.110836) (xy 126.451212 -373.050674)
			(xy 126.433782 -372.987597) (xy 126.424984 -372.92275) (xy 126.42498 -372.857309) (xy 126.43377 -372.792461)
			(xy 126.451193 -372.729382) (xy 126.476934 -372.669216) (xy 126.49327 -372.64086) (xy 126.49665 -372.634853)
			(xy 126.500375 -372.621586) (xy 126.500636 -372.614698) (xy 126.500636 -371.865398) (xy 126.500434 -371.858503)
			(xy 126.496685 -371.845231) (xy 126.49327 -371.839236) (xy 126.476899 -371.810898) (xy 126.451157 -371.750727)
			(xy 126.433733 -371.687643) (xy 126.424943 -371.62279) (xy 125.166196 -371.62279) (xy 125.169092 -371.629559)
			(xy 125.186516 -371.69264) (xy 125.195307 -371.75749) (xy 125.195305 -371.822934) (xy 125.186511 -371.887784)
			(xy 125.169084 -371.950864) (xy 125.143341 -372.011031) (xy 125.127004 -372.039388) (xy 125.123694 -372.045415)
			(xy 125.120085 -372.058677) (xy 125.119892 -372.06555) (xy 125.119892 -372.351554) (xy 125.119399 -372.361719)
			(xy 125.111635 -372.380507) (xy 125.097271 -372.394892) (xy 125.078494 -372.402684) (xy 125.06833 -372.403116)
			(xy 124.35205 -372.403116) (xy 124.341876 -372.402694) (xy 124.323073 -372.394917) (xy 124.308685 -372.38053)
			(xy 124.300907 -372.361728) (xy 124.300488 -372.351554) (xy 124.300488 -372.06555) (xy 124.300278 -372.058678)
			(xy 124.296682 -372.045415) (xy 124.293376 -372.039388) (xy 124.277049 -372.011026) (xy 124.251302 -371.950861)
			(xy 124.233873 -371.887782) (xy 124.225078 -371.822933) (xy 124.225077 -371.757491) (xy 124.233868 -371.692642)
			(xy 124.251294 -371.629562) (xy 124.277038 -371.569396) (xy 124.293376 -371.54104) (xy 124.296675 -371.535008)
			(xy 124.300291 -371.52175) (xy 124.300488 -371.514878) (xy 124.300488 -370.765324) (xy 124.300288 -370.758451)
			(xy 124.296685 -370.745189) (xy 124.293376 -370.739162) (xy 124.277027 -370.710812) (xy 124.251282 -370.650644)
			(xy 124.233856 -370.587563) (xy 124.225063 -370.522712) (xy 120.795257 -370.522712) (xy 120.786466 -370.58756)
			(xy 120.769041 -370.650639) (xy 120.743299 -370.710806) (xy 120.726962 -370.739162) (xy 120.723577 -370.745167)
			(xy 120.719855 -370.758435) (xy 120.719596 -370.765324) (xy 120.719596 -371.514878) (xy 120.719838 -371.521769)
			(xy 120.723575 -371.535035) (xy 120.726962 -371.54104) (xy 120.743311 -371.56939) (xy 120.766158 -371.62279)
			(xy 122.024907 -371.62279) (xy 122.024912 -371.557345) (xy 122.033709 -371.492493) (xy 122.05114 -371.429412)
			(xy 122.076888 -371.369244) (xy 122.093228 -371.340888) (xy 122.096549 -371.334866) (xy 122.10015 -371.3216)
			(xy 122.10034 -371.314726) (xy 122.10034 -371.028722) (xy 122.100782 -371.018552) (xy 122.10856 -370.999757)
			(xy 122.12294 -370.985371) (xy 122.141732 -370.977586) (xy 122.151902 -370.97716) (xy 122.868182 -370.97716)
			(xy 122.878355 -370.977579) (xy 122.897154 -370.985362) (xy 122.91154 -370.99975) (xy 122.919322 -371.018549)
			(xy 122.919744 -371.028722) (xy 122.919744 -371.314726) (xy 122.919921 -371.3216) (xy 122.923539 -371.334863)
			(xy 122.926856 -371.340888) (xy 122.943161 -371.369262) (xy 122.968908 -371.429424) (xy 122.986339 -371.492501)
			(xy 122.995136 -371.557347) (xy 122.99514 -371.622788) (xy 122.986352 -371.687635) (xy 122.96893 -371.750714)
			(xy 122.943191 -371.81088) (xy 122.926856 -371.839236) (xy 122.923533 -371.845257) (xy 122.919932 -371.858523)
			(xy 122.919744 -371.865398) (xy 122.919744 -372.614698) (xy 122.919931 -372.621572) (xy 122.923542 -372.634835)
			(xy 122.926856 -372.64086) (xy 122.943222 -372.6692) (xy 122.968964 -372.729371) (xy 122.986387 -372.792454)
			(xy 122.995177 -372.857306) (xy 122.995173 -372.922752) (xy 122.986376 -372.987603) (xy 122.968944 -373.050685)
			(xy 122.943196 -373.110852) (xy 122.926856 -373.139208) (xy 122.923543 -373.145233) (xy 122.919935 -373.158496)
			(xy 122.919744 -373.16537) (xy 122.919744 -373.451374) (xy 122.919314 -373.461546) (xy 122.911534 -373.480344)
			(xy 122.89715 -373.49473) (xy 122.878354 -373.502513) (xy 122.868182 -373.502936) (xy 122.151902 -373.502936)
			(xy 122.141727 -373.502534) (xy 122.122928 -373.494745) (xy 122.108542 -373.480352) (xy 122.100761 -373.461549)
			(xy 122.10034 -373.451374) (xy 122.10034 -373.16537) (xy 122.100154 -373.158496) (xy 122.096541 -373.145234)
			(xy 122.093228 -373.139208) (xy 122.07692 -373.110836) (xy 122.051174 -373.050673) (xy 122.033745 -372.987596)
			(xy 122.024948 -372.922749) (xy 122.024944 -372.857309) (xy 122.033733 -372.792461) (xy 122.051154 -372.729382)
			(xy 122.076893 -372.669216) (xy 122.093228 -372.64086) (xy 122.096559 -372.634843) (xy 122.100154 -372.621573)
			(xy 122.10034 -372.614698) (xy 122.10034 -371.865398) (xy 122.100144 -371.858525) (xy 122.096538 -371.845263)
			(xy 122.093228 -371.839236) (xy 122.076859 -371.810897) (xy 122.051118 -371.750727) (xy 122.033696 -371.687643)
			(xy 122.024907 -371.62279) (xy 120.766158 -371.62279) (xy 120.769054 -371.629558) (xy 120.786479 -371.692639)
			(xy 120.79527 -371.75749) (xy 120.795269 -371.822934) (xy 120.786474 -371.887784) (xy 120.769046 -371.950865)
			(xy 120.7433 -372.011032) (xy 120.726962 -372.039388) (xy 120.723603 -372.045406) (xy 120.719864 -372.058664)
			(xy 120.719596 -372.06555) (xy 120.719596 -372.351554) (xy 120.719037 -372.361673) (xy 120.711331 -372.380387)
			(xy 120.697067 -372.394743) (xy 120.678404 -372.40257) (xy 120.668288 -372.403116) (xy 119.952008 -372.403116)
			(xy 119.941856 -372.402672) (xy 119.923107 -372.394882) (xy 119.908784 -372.380493) (xy 119.901081 -372.361707)
			(xy 119.9007 -372.351554) (xy 119.9007 -372.06555) (xy 119.900448 -372.05866) (xy 119.896718 -372.045394)
			(xy 119.893334 -372.039388) (xy 119.877009 -372.011025) (xy 119.851264 -371.95086) (xy 119.833836 -371.887781)
			(xy 119.825042 -371.822933) (xy 119.82504 -371.757491) (xy 119.833832 -371.692642) (xy 119.851256 -371.629563)
			(xy 119.876998 -371.569396) (xy 119.893334 -371.54104) (xy 119.896718 -371.535035) (xy 119.900441 -371.521767)
			(xy 119.9007 -371.514878) (xy 119.9007 -370.765324) (xy 119.900457 -370.758433) (xy 119.896721 -370.745167)
			(xy 119.893334 -370.739162) (xy 119.876987 -370.710811) (xy 119.851244 -370.650643) (xy 119.833819 -370.587562)
			(xy 119.825027 -370.522712) (xy 116.395221 -370.522712) (xy 116.386429 -370.58756) (xy 116.369002 -370.65064)
			(xy 116.343258 -370.710806) (xy 116.32692 -370.739162) (xy 116.32362 -370.745194) (xy 116.320005 -370.758452)
			(xy 116.319808 -370.765324) (xy 116.319808 -371.514878) (xy 116.320008 -371.521751) (xy 116.323611 -371.535013)
			(xy 116.32692 -371.54104) (xy 116.343271 -371.569389) (xy 116.36612 -371.622791) (xy 117.624857 -371.622791)
			(xy 117.624862 -371.557344) (xy 117.63366 -371.492492) (xy 117.651093 -371.429411) (xy 117.676845 -371.369244)
			(xy 117.693186 -371.340888) (xy 117.696549 -371.334872) (xy 117.700286 -371.321613) (xy 117.700552 -371.314726)
			(xy 117.700552 -371.028722) (xy 117.701045 -371.018595) (xy 117.708768 -370.999872) (xy 117.723052 -370.985515)
			(xy 117.741736 -370.977697) (xy 117.75186 -370.97716) (xy 118.46814 -370.97716) (xy 118.478292 -370.977588)
			(xy 118.497037 -370.985389) (xy 118.511358 -370.999783) (xy 118.519063 -371.018568) (xy 118.519448 -371.028722)
			(xy 118.519448 -371.314726) (xy 118.519681 -371.321619) (xy 118.523409 -371.334891) (xy 118.526814 -371.340888)
			(xy 118.543121 -371.369261) (xy 118.56887 -371.429424) (xy 118.586302 -371.4925) (xy 118.5951 -371.557347)
			(xy 118.595104 -371.622788) (xy 118.586315 -371.687636) (xy 118.568892 -371.750715) (xy 118.54315 -371.81088)
			(xy 118.526814 -371.839236) (xy 118.523442 -371.845247) (xy 118.51971 -371.85851) (xy 118.519448 -371.865398)
			(xy 118.519448 -372.614698) (xy 118.519654 -372.621593) (xy 118.523401 -372.634865) (xy 118.526814 -372.64086)
			(xy 118.543182 -372.6692) (xy 118.568925 -372.72937) (xy 118.58635 -372.792453) (xy 118.595141 -372.857306)
			(xy 118.595137 -372.922752) (xy 118.586339 -372.987604) (xy 118.568906 -373.050685) (xy 118.543155 -373.110852)
			(xy 118.526814 -373.139208) (xy 118.523452 -373.145224) (xy 118.519714 -373.158484) (xy 118.519448 -373.16537)
			(xy 118.519448 -373.451374) (xy 118.518952 -373.461501) (xy 118.51123 -373.480223) (xy 118.496947 -373.494581)
			(xy 118.478264 -373.502399) (xy 118.46814 -373.502936) (xy 117.75186 -373.502936) (xy 117.741708 -373.502512)
			(xy 117.722961 -373.49471) (xy 117.708641 -373.480315) (xy 117.700936 -373.461528) (xy 117.700552 -373.451374)
			(xy 117.700552 -373.16537) (xy 117.70032 -373.158477) (xy 117.696591 -373.145205) (xy 117.693186 -373.139208)
			(xy 117.676876 -373.110836) (xy 117.651127 -373.050674) (xy 117.633696 -372.987597) (xy 117.624898 -372.92275)
			(xy 117.624894 -372.857309) (xy 117.633684 -372.79246) (xy 117.651108 -372.729381) (xy 117.676849 -372.669216)
			(xy 117.693186 -372.64086) (xy 117.696559 -372.634849) (xy 117.70029 -372.621586) (xy 117.700552 -372.614698)
			(xy 117.700552 -371.865398) (xy 117.700348 -371.858503) (xy 117.6966 -371.845231) (xy 117.693186 -371.839236)
			(xy 117.676815 -371.810898) (xy 117.651072 -371.750728) (xy 117.633647 -371.687644) (xy 117.624857 -371.622791)
			(xy 116.36612 -371.622791) (xy 116.369015 -371.629557) (xy 116.386442 -371.692639) (xy 116.395234 -371.75749)
			(xy 116.395233 -371.822934) (xy 116.386437 -371.887785) (xy 116.369008 -371.950866) (xy 116.34326 -372.011032)
			(xy 116.32692 -372.039388) (xy 116.323611 -372.045415) (xy 116.320001 -372.058677) (xy 116.319808 -372.06555)
			(xy 116.319808 -372.351554) (xy 116.31923 -372.361703) (xy 116.311479 -372.380462) (xy 116.29714 -372.394828)
			(xy 116.278394 -372.402612) (xy 116.268246 -372.403116) (xy 115.551966 -372.403116) (xy 115.541786 -372.402763)
			(xy 115.522982 -372.394958) (xy 115.508597 -372.380551) (xy 115.500821 -372.361734) (xy 115.500404 -372.351554)
			(xy 115.500404 -372.06555) (xy 115.500192 -372.058678) (xy 115.496597 -372.045416) (xy 115.493292 -372.039388)
			(xy 115.476965 -372.011026) (xy 115.451217 -371.950861) (xy 115.433787 -371.887782) (xy 115.424992 -371.822933)
			(xy 115.42499 -371.757491) (xy 115.433783 -371.692641) (xy 115.451209 -371.629562) (xy 115.476954 -371.569396)
			(xy 115.493292 -371.54104) (xy 115.496592 -371.535008) (xy 115.500207 -371.52175) (xy 115.500404 -371.514878)
			(xy 115.500404 -370.765324) (xy 115.500203 -370.758451) (xy 115.496601 -370.745189) (xy 115.493292 -370.739162)
			(xy 115.476943 -370.710812) (xy 115.451197 -370.650644) (xy 115.43377 -370.587563) (xy 115.424977 -370.522712)
			(xy 104.615187 -370.522712) (xy 104.609499 -370.534311) (xy 104.608884 -370.545868) (xy 104.608884 -370.626132)
			(xy 104.609499 -370.637694) (xy 104.619663 -370.658465) (xy 104.628442 -370.66601) (xy 104.649225 -370.682763)
			(xy 104.686355 -370.721117) (xy 104.717777 -370.764271) (xy 104.742876 -370.811385) (xy 104.761162 -370.861537)
			(xy 104.772278 -370.913749) (xy 104.776008 -370.967) (xy 104.772278 -371.020251) (xy 104.761162 -371.072463)
			(xy 104.742876 -371.122615) (xy 104.717777 -371.169729) (xy 104.686355 -371.212883) (xy 104.649225 -371.251237)
			(xy 104.628442 -371.26799) (xy 104.619679 -371.275551) (xy 104.609499 -371.296311) (xy 104.608884 -371.307868)
			(xy 104.608884 -371.388132) (xy 104.609499 -371.399694) (xy 104.619663 -371.420465) (xy 104.628442 -371.42801)
			(xy 104.650939 -371.446185) (xy 104.690671 -371.488209) (xy 104.723608 -371.535748) (xy 104.748993 -371.587712)
			(xy 104.766247 -371.642912) (xy 104.774974 -371.700083) (xy 104.775508 -371.729) (xy 104.775022 -371.756251)
			(xy 104.767266 -371.810199) (xy 104.751911 -371.862494) (xy 104.729269 -371.912071) (xy 104.699803 -371.957921)
			(xy 104.664112 -371.999112) (xy 104.622921 -372.034803) (xy 104.577071 -372.064269) (xy 104.527494 -372.086911)
			(xy 104.475199 -372.102266) (xy 104.421251 -372.110022) (xy 104.366749 -372.110022) (xy 104.312801 -372.102266)
			(xy 104.260506 -372.086911) (xy 104.210929 -372.064269) (xy 104.165079 -372.034803) (xy 104.123888 -371.999112)
			(xy 104.088197 -371.957921) (xy 104.058731 -371.912071) (xy 104.036089 -371.862494) (xy 104.020734 -371.810199)
			(xy 104.012978 -371.756251) (xy 104.012492 -371.729) (xy 104.012975 -371.700081) (xy 104.021707 -371.642907)
			(xy 104.038969 -371.587706) (xy 104.064367 -371.535744) (xy 104.097319 -371.488211) (xy 104.137068 -371.446197)
			(xy 104.159558 -371.42801) (xy 104.168321 -371.420449) (xy 104.178501 -371.399689) (xy 104.179116 -371.388132)
			(xy 104.179116 -371.307868) (xy 104.178501 -371.296306) (xy 104.168337 -371.275535) (xy 104.159558 -371.26799)
			(xy 104.138775 -371.251237) (xy 104.101645 -371.212883) (xy 104.070223 -371.169729) (xy 104.045124 -371.122615)
			(xy 104.026838 -371.072463) (xy 104.015722 -371.020251) (xy 104.011992 -370.967) (xy 100.745544 -370.967)
			(xy 100.745544 -371.094) (xy 100.745544 -371.116352) (xy 100.671476 -374.422887) (xy 115.42496 -374.422887)
			(xy 115.424965 -374.357441) (xy 115.433764 -374.292588) (xy 115.451198 -374.229507) (xy 115.47695 -374.16934)
			(xy 115.493292 -374.140984) (xy 115.496612 -374.134962) (xy 115.500214 -374.121696) (xy 115.500404 -374.114822)
			(xy 115.500404 -373.828818) (xy 115.500947 -373.818666) (xy 115.508709 -373.799903) (xy 115.52306 -373.785539)
			(xy 115.541814 -373.777757) (xy 115.551966 -373.777256) (xy 116.268246 -373.777256) (xy 116.278409 -373.777696)
			(xy 116.297183 -373.785489) (xy 116.311547 -373.799871) (xy 116.319316 -373.818654) (xy 116.319808 -373.828818)
			(xy 116.319808 -374.114822) (xy 116.31999 -374.121696) (xy 116.323605 -374.134959) (xy 116.32692 -374.140984)
			(xy 116.343223 -374.169359) (xy 116.368972 -374.229521) (xy 116.386404 -374.292597) (xy 116.395202 -374.357444)
			(xy 116.395207 -374.422884) (xy 116.395207 -374.422887) (xy 119.82501 -374.422887) (xy 119.825015 -374.357441)
			(xy 119.833813 -374.292589) (xy 119.851245 -374.229508) (xy 119.876994 -374.16934) (xy 119.893334 -374.140984)
			(xy 119.896702 -374.134971) (xy 119.900435 -374.121709) (xy 119.9007 -374.114822) (xy 119.9007 -373.828818)
			(xy 119.90124 -373.818697) (xy 119.908955 -373.799984) (xy 119.923224 -373.785629) (xy 119.94189 -373.777802)
			(xy 119.952008 -373.777256) (xy 120.668288 -373.777256) (xy 120.678436 -373.777731) (xy 120.69718 -373.785514)
			(xy 120.711502 -373.799894) (xy 120.71921 -373.818669) (xy 120.719596 -373.828818) (xy 120.719596 -374.114822)
			(xy 120.71986 -374.121711) (xy 120.723581 -374.134977) (xy 120.726962 -374.140984) (xy 120.743264 -374.16936)
			(xy 120.769011 -374.229522) (xy 120.786441 -374.292598) (xy 120.795239 -374.357444) (xy 120.795243 -374.422884)
			(xy 120.795243 -374.422887) (xy 124.225046 -374.422887) (xy 124.225051 -374.357441) (xy 124.23385 -374.292589)
			(xy 124.251283 -374.229507) (xy 124.277035 -374.16934) (xy 124.293376 -374.140984) (xy 124.296695 -374.134961)
			(xy 124.300298 -374.121696) (xy 124.300488 -374.114822) (xy 124.300488 -373.828818) (xy 124.30088 -373.818641)
			(xy 124.308668 -373.799837) (xy 124.323064 -373.78545) (xy 124.341873 -373.777673) (xy 124.35205 -373.777256)
			(xy 125.06833 -373.777256) (xy 125.078492 -373.777709) (xy 125.097265 -373.785497) (xy 125.11163 -373.799875)
			(xy 125.1194 -373.818656) (xy 125.119892 -373.828818) (xy 125.119892 -374.114822) (xy 125.120076 -374.121696)
			(xy 125.12369 -374.134959) (xy 125.127004 -374.140984) (xy 125.143304 -374.16936) (xy 125.169049 -374.229523)
			(xy 125.186478 -374.292599) (xy 125.195275 -374.357444) (xy 125.19528 -374.422884) (xy 125.19528 -374.422887)
			(xy 128.624836 -374.422887) (xy 128.624841 -374.357441) (xy 128.633639 -374.292589) (xy 128.651072 -374.229507)
			(xy 128.676823 -374.16934) (xy 128.693164 -374.140984) (xy 128.696481 -374.134961) (xy 128.700086 -374.121696)
			(xy 128.700276 -374.114822) (xy 128.700276 -373.828818) (xy 128.700679 -373.818643) (xy 128.708465 -373.799841)
			(xy 128.722858 -373.785454) (xy 128.741663 -373.777675) (xy 128.751838 -373.777256) (xy 129.468118 -373.777256)
			(xy 129.478279 -373.777719) (xy 129.497052 -373.785503) (xy 129.511418 -373.799878) (xy 129.519188 -373.818656)
			(xy 129.51968 -373.828818) (xy 129.51968 -374.114822) (xy 129.519866 -374.121696) (xy 129.523479 -374.134958)
			(xy 129.526792 -374.140984) (xy 129.543093 -374.16936) (xy 129.568838 -374.229523) (xy 129.586268 -374.292598)
			(xy 129.595064 -374.357444) (xy 129.595066 -374.390158) (xy 133.023872 -374.390158) (xy 133.027863 -374.327991)
			(xy 133.039772 -374.266844) (xy 133.059401 -374.207723) (xy 133.08643 -374.151597) (xy 133.120414 -374.099388)
			(xy 133.160796 -374.051953) (xy 133.206912 -374.010072) (xy 133.258004 -373.974432) (xy 133.313235 -373.945618)
			(xy 133.371697 -373.924104) (xy 133.432431 -373.910242) (xy 133.494438 -373.90426) (xy 133.556701 -373.906256)
			(xy 133.618198 -373.916199) (xy 133.677919 -373.933923) (xy 133.734882 -373.95914) (xy 133.788153 -373.991433)
			(xy 133.836858 -374.030273) (xy 133.880195 -374.075023) (xy 133.917455 -374.124947) (xy 133.948024 -374.179226)
			(xy 133.971402 -374.236969) (xy 133.987203 -374.297227) (xy 133.995169 -374.35901) (xy 133.995668 -374.390158)
			(xy 133.995169 -374.421306) (xy 133.987203 -374.483089) (xy 133.971402 -374.543347) (xy 133.948024 -374.60109)
			(xy 133.917455 -374.655369) (xy 133.880195 -374.705293) (xy 133.836858 -374.750043) (xy 133.788153 -374.788883)
			(xy 133.734882 -374.821176) (xy 133.677919 -374.846393) (xy 133.618198 -374.864117) (xy 133.556701 -374.87406)
			(xy 133.494438 -374.876056) (xy 133.432431 -374.870074) (xy 133.371697 -374.856212) (xy 133.313235 -374.834698)
			(xy 133.258004 -374.805884) (xy 133.206912 -374.770244) (xy 133.160796 -374.728363) (xy 133.120414 -374.680928)
			(xy 133.08643 -374.628719) (xy 133.059401 -374.572593) (xy 133.039772 -374.513472) (xy 133.027863 -374.452325)
			(xy 133.023872 -374.390158) (xy 129.595066 -374.390158) (xy 129.595069 -374.422884) (xy 129.586282 -374.487731)
			(xy 129.568862 -374.550809) (xy 129.543126 -374.610976) (xy 129.526792 -374.639332) (xy 129.523465 -374.645351)
			(xy 129.519867 -374.658619) (xy 129.51968 -374.665494) (xy 129.51968 -375.414794) (xy 129.519877 -375.421667)
			(xy 129.523482 -375.43493) (xy 129.526792 -375.440956) (xy 129.543154 -375.469298) (xy 129.568894 -375.529469)
			(xy 129.586316 -375.592552) (xy 129.595105 -375.657403) (xy 129.595102 -375.722848) (xy 129.586306 -375.787699)
			(xy 129.568877 -375.85078) (xy 129.54313 -375.910947) (xy 129.526792 -375.939304) (xy 129.523475 -375.945328)
			(xy 129.519871 -375.958592) (xy 129.51968 -375.965466) (xy 129.51968 -376.25147) (xy 129.519212 -376.261637)
			(xy 129.51144 -376.280428) (xy 129.497068 -376.294813) (xy 129.478285 -376.302602) (xy 129.468118 -376.303032)
			(xy 128.751838 -376.303032) (xy 128.741665 -376.302604) (xy 128.722866 -376.294826) (xy 128.708478 -376.280441)
			(xy 128.700697 -376.261643) (xy 128.700276 -376.25147) (xy 128.700276 -375.965466) (xy 128.7001 -375.958592)
			(xy 128.696481 -375.945329) (xy 128.693164 -375.939304) (xy 128.676851 -375.910934) (xy 128.651104 -375.850771)
			(xy 128.633674 -375.787694) (xy 128.624877 -375.722846) (xy 128.624873 -375.657405) (xy 128.633663 -375.592557)
			(xy 128.651087 -375.529478) (xy 128.676828 -375.469312) (xy 128.693164 -375.440956) (xy 128.696491 -375.434938)
			(xy 128.700089 -375.421669) (xy 128.700276 -375.414794) (xy 128.700276 -374.665494) (xy 128.700089 -374.65862)
			(xy 128.696478 -374.645358) (xy 128.693164 -374.639332) (xy 128.67679 -374.610996) (xy 128.651048 -374.550825)
			(xy 128.633625 -374.48774) (xy 128.624836 -374.422887) (xy 125.19528 -374.422887) (xy 125.186493 -374.487731)
			(xy 125.169073 -374.550809) (xy 125.143337 -374.610975) (xy 125.127004 -374.639332) (xy 125.123678 -374.645351)
			(xy 125.120079 -374.658619) (xy 125.119892 -374.665494) (xy 125.119892 -375.414794) (xy 125.120087 -375.421667)
			(xy 125.123693 -375.43493) (xy 125.127004 -375.440956) (xy 125.143365 -375.469299) (xy 125.169105 -375.529469)
			(xy 125.186527 -375.592552) (xy 125.195316 -375.657403) (xy 125.195312 -375.722848) (xy 125.186516 -375.787699)
			(xy 125.169088 -375.85078) (xy 125.143342 -375.910947) (xy 125.127004 -375.939304) (xy 125.123688 -375.945328)
			(xy 125.120083 -375.958592) (xy 125.119892 -375.965466) (xy 125.119892 -376.25147) (xy 125.119343 -376.261622)
			(xy 125.111584 -376.280385) (xy 125.097235 -376.29475) (xy 125.078482 -376.302531) (xy 125.06833 -376.303032)
			(xy 124.35205 -376.303032) (xy 124.341878 -376.302595) (xy 124.323079 -376.29482) (xy 124.308691 -376.280438)
			(xy 124.300909 -376.261642) (xy 124.300488 -376.25147) (xy 124.300488 -375.965466) (xy 124.300311 -375.958592)
			(xy 124.296693 -375.945329) (xy 124.293376 -375.939304) (xy 124.277063 -375.910934) (xy 124.251315 -375.850771)
			(xy 124.233884 -375.787694) (xy 124.225087 -375.722846) (xy 124.225084 -375.657405) (xy 124.233874 -375.592557)
			(xy 124.251298 -375.529478) (xy 124.277039 -375.469312) (xy 124.293376 -375.440956) (xy 124.296705 -375.434938)
			(xy 124.300302 -375.421669) (xy 124.300488 -375.414794) (xy 124.300488 -374.665494) (xy 124.3003 -374.65862)
			(xy 124.296689 -374.645358) (xy 124.293376 -374.639332) (xy 124.277002 -374.610996) (xy 124.251259 -374.550825)
			(xy 124.233835 -374.487741) (xy 124.225046 -374.422887) (xy 120.795243 -374.422887) (xy 120.786456 -374.487731)
			(xy 120.769035 -374.55081) (xy 120.743297 -374.610976) (xy 120.726962 -374.639332) (xy 120.723588 -374.645342)
			(xy 120.719859 -374.658606) (xy 120.719596 -374.665494) (xy 120.719596 -375.414794) (xy 120.719832 -375.421685)
			(xy 120.723573 -375.434951) (xy 120.726962 -375.440956) (xy 120.743325 -375.469298) (xy 120.769066 -375.529468)
			(xy 120.78649 -375.592551) (xy 120.79528 -375.657403) (xy 120.795276 -375.722848) (xy 120.786479 -375.787699)
			(xy 120.769049 -375.850781) (xy 120.743301 -375.910948) (xy 120.726962 -375.939304) (xy 120.723598 -375.945319)
			(xy 120.719862 -375.958579) (xy 120.719596 -375.965466) (xy 120.719596 -376.25147) (xy 120.71905 -376.26159)
			(xy 120.711339 -376.280304) (xy 120.697071 -376.29466) (xy 120.678405 -376.302487) (xy 120.668288 -376.303032)
			(xy 119.952008 -376.303032) (xy 119.941858 -376.302572) (xy 119.923112 -376.294786) (xy 119.90879 -376.280401)
			(xy 119.901084 -376.261621) (xy 119.9007 -376.25147) (xy 119.9007 -375.965466) (xy 119.900441 -375.958577)
			(xy 119.896716 -375.945311) (xy 119.893334 -375.939304) (xy 119.877022 -375.910934) (xy 119.851276 -375.85077)
			(xy 119.833847 -375.787693) (xy 119.825051 -375.722846) (xy 119.825048 -375.657405) (xy 119.833837 -375.592557)
			(xy 119.851259 -375.529478) (xy 119.876999 -375.469312) (xy 119.893334 -375.440956) (xy 119.896712 -375.434948)
			(xy 119.900439 -375.421682) (xy 119.9007 -375.414794) (xy 119.9007 -374.665494) (xy 119.900469 -374.658602)
			(xy 119.896725 -374.645337) (xy 119.893334 -374.639332) (xy 119.876961 -374.610995) (xy 119.851221 -374.550824)
			(xy 119.833799 -374.48774) (xy 119.82501 -374.422887) (xy 116.395207 -374.422887) (xy 116.386419 -374.487732)
			(xy 116.368996 -374.550811) (xy 116.343256 -374.610976) (xy 116.32692 -374.639332) (xy 116.323595 -374.645352)
			(xy 116.319996 -374.658619) (xy 116.319808 -374.665494) (xy 116.319808 -375.414794) (xy 116.320002 -375.421667)
			(xy 116.323609 -375.43493) (xy 116.32692 -375.440956) (xy 116.343284 -375.469298) (xy 116.369028 -375.529467)
			(xy 116.386453 -375.59255) (xy 116.395243 -375.657403) (xy 116.39524 -375.722848) (xy 116.386443 -375.7877)
			(xy 116.369011 -375.850781) (xy 116.343261 -375.910948) (xy 116.32692 -375.939304) (xy 116.323605 -375.945329)
			(xy 116.319999 -375.958592) (xy 116.319808 -375.965466) (xy 116.319808 -376.25147) (xy 116.319243 -376.26162)
			(xy 116.311487 -376.28038) (xy 116.297144 -376.294745) (xy 116.278395 -376.302528) (xy 116.268246 -376.303032)
			(xy 115.551966 -376.303032) (xy 115.541802 -376.302594) (xy 115.523027 -376.294803) (xy 115.508662 -376.28042)
			(xy 115.500894 -376.261634) (xy 115.500404 -376.25147) (xy 115.500404 -375.965466) (xy 115.500225 -375.958592)
			(xy 115.496608 -375.945329) (xy 115.493292 -375.939304) (xy 115.476978 -375.910934) (xy 115.451229 -375.850771)
			(xy 115.433798 -375.787694) (xy 115.425001 -375.722846) (xy 115.424998 -375.657405) (xy 115.433788 -375.592556)
			(xy 115.451212 -375.529477) (xy 115.476955 -375.469312) (xy 115.493292 -375.440956) (xy 115.496622 -375.434939)
			(xy 115.500218 -375.421669) (xy 115.500404 -375.414794) (xy 115.500404 -374.665494) (xy 115.500214 -374.658621)
			(xy 115.496604 -374.645358) (xy 115.493292 -374.639332) (xy 115.476917 -374.610996) (xy 115.451174 -374.550825)
			(xy 115.43375 -374.487741) (xy 115.42496 -374.422887) (xy 100.671476 -374.422887) (xy 100.653769 -375.213371)
			(xy 104.681961 -375.213371) (xy 104.681961 -375.153429) (xy 104.689785 -375.094001) (xy 104.7053 -375.036103)
			(xy 104.72824 -374.980725) (xy 104.758212 -374.928815) (xy 104.794703 -374.881262) (xy 104.837089 -374.838879)
			(xy 104.884645 -374.802391) (xy 104.936557 -374.772424) (xy 104.991937 -374.749489) (xy 105.049837 -374.733978)
			(xy 105.109265 -374.726159) (xy 105.139236 -374.725692) (xy 106.002836 -374.725692) (xy 106.032802 -374.726184)
			(xy 106.092221 -374.734011) (xy 106.15011 -374.749527) (xy 106.205479 -374.772465) (xy 106.25738 -374.802434)
			(xy 106.304926 -374.838921) (xy 106.347303 -374.881301) (xy 106.383786 -374.92885) (xy 106.413751 -374.980753)
			(xy 106.436685 -375.036124) (xy 106.452196 -375.094014) (xy 106.460018 -375.153434) (xy 106.460018 -375.213366)
			(xy 106.452196 -375.272786) (xy 106.436685 -375.330676) (xy 106.413751 -375.386047) (xy 106.383786 -375.43795)
			(xy 106.347303 -375.485499) (xy 106.304926 -375.527879) (xy 106.25738 -375.564366) (xy 106.205479 -375.594335)
			(xy 106.15011 -375.617273) (xy 106.092221 -375.632789) (xy 106.032802 -375.640616) (xy 106.002836 -375.641108)
			(xy 105.139236 -375.641108) (xy 105.109265 -375.640641) (xy 105.049837 -375.632822) (xy 104.991937 -375.617311)
			(xy 104.936557 -375.594376) (xy 104.884645 -375.564409) (xy 104.837089 -375.527921) (xy 104.794703 -375.485538)
			(xy 104.758212 -375.437985) (xy 104.72824 -375.386075) (xy 104.7053 -375.330697) (xy 104.689785 -375.272799)
			(xy 104.681961 -375.213371) (xy 100.653769 -375.213371) (xy 100.632006 -376.184922) (xy 100.63988 -376.204226)
			(xy 100.6475 -376.211846) (xy 100.667458 -376.232109) (xy 100.701755 -376.277475) (xy 100.728943 -376.327428)
			(xy 100.748419 -376.380861) (xy 100.759753 -376.436592) (xy 100.762693 -376.493388) (xy 100.757175 -376.549992)
			(xy 100.743321 -376.60515) (xy 100.721436 -376.657643) (xy 100.692007 -376.706309) (xy 100.655683 -376.75007)
			(xy 100.6348 -376.769376) (xy 100.626926 -376.776234) (xy 100.61829 -376.795284) (xy 100.617654 -376.822925)
			(xy 117.624881 -376.822925) (xy 117.624881 -376.757482) (xy 117.633674 -376.692632) (xy 117.651102 -376.629552)
			(xy 117.676847 -376.569386) (xy 117.693186 -376.54103) (xy 117.696535 -376.535007) (xy 117.700281 -376.521753)
			(xy 117.700552 -376.514868) (xy 117.700552 -375.765568) (xy 117.700321 -375.758675) (xy 117.696591 -375.745403)
			(xy 117.693186 -375.739406) (xy 117.676874 -375.711035) (xy 117.651125 -375.650873) (xy 117.633694 -375.587795)
			(xy 117.624897 -375.522948) (xy 117.624893 -375.457507) (xy 117.633683 -375.392658) (xy 117.651107 -375.329579)
			(xy 117.676849 -375.269414) (xy 117.693186 -375.241058) (xy 117.69656 -375.235048) (xy 117.70029 -375.221784)
			(xy 117.700552 -375.214896) (xy 117.700552 -374.928638) (xy 117.701058 -374.918512) (xy 117.708776 -374.89979)
			(xy 117.723056 -374.885432) (xy 117.741737 -374.877613) (xy 117.75186 -374.877076) (xy 118.46814 -374.877076)
			(xy 118.478294 -374.877488) (xy 118.497042 -374.885293) (xy 118.511363 -374.899691) (xy 118.519066 -374.918482)
			(xy 118.519448 -374.928638) (xy 118.519448 -375.214896) (xy 118.519655 -375.221791) (xy 118.523401 -375.235063)
			(xy 118.526814 -375.241058) (xy 118.54318 -375.269399) (xy 118.568924 -375.329568) (xy 118.586349 -375.392652)
			(xy 118.595139 -375.457505) (xy 118.595136 -375.52295) (xy 118.586338 -375.587802) (xy 118.568906 -375.650883)
			(xy 118.543155 -375.71105) (xy 118.526814 -375.739406) (xy 118.523453 -375.745423) (xy 118.519714 -375.758682)
			(xy 118.519448 -375.765568) (xy 118.519448 -376.514868) (xy 118.519665 -376.521762) (xy 118.523404 -376.535034)
			(xy 118.526814 -376.54103) (xy 118.543156 -376.569384) (xy 118.568902 -376.629551) (xy 118.58633 -376.692631)
			(xy 118.595123 -376.757482) (xy 118.595123 -376.822925) (xy 122.024931 -376.822925) (xy 122.024931 -376.757482)
			(xy 122.033723 -376.692633) (xy 122.051148 -376.629553) (xy 122.076891 -376.569386) (xy 122.093228 -376.54103)
			(xy 122.096534 -376.535001) (xy 122.100145 -376.521741) (xy 122.10034 -376.514868) (xy 122.10034 -375.765568)
			(xy 122.100155 -375.758694) (xy 122.096541 -375.745432) (xy 122.093228 -375.739406) (xy 122.076918 -375.711035)
			(xy 122.051172 -375.650871) (xy 122.033743 -375.587794) (xy 122.024947 -375.522948) (xy 122.024943 -375.457507)
			(xy 122.033732 -375.392659) (xy 122.051154 -375.32958) (xy 122.076893 -375.269414) (xy 122.093228 -375.241058)
			(xy 122.09656 -375.235042) (xy 122.100154 -375.221771) (xy 122.10034 -375.214896) (xy 122.10034 -374.928638)
			(xy 122.100795 -374.918469) (xy 122.108568 -374.899674) (xy 122.122944 -374.885288) (xy 122.141733 -374.877502)
			(xy 122.151902 -374.877076) (xy 122.868182 -374.877076) (xy 122.878357 -374.877479) (xy 122.897159 -374.885265)
			(xy 122.911546 -374.899658) (xy 122.919325 -374.918463) (xy 122.919744 -374.928638) (xy 122.919744 -375.214896)
			(xy 122.919932 -375.22177) (xy 122.923542 -375.235033) (xy 122.926856 -375.241058) (xy 122.943221 -375.269399)
			(xy 122.968962 -375.329569) (xy 122.986386 -375.392653) (xy 122.995176 -375.457505) (xy 122.995172 -375.52295)
			(xy 122.986375 -375.587801) (xy 122.968944 -375.650883) (xy 122.943196 -375.71105) (xy 122.926856 -375.739406)
			(xy 122.923544 -375.745432) (xy 122.919936 -375.758695) (xy 122.919744 -375.765568) (xy 122.919744 -376.514868)
			(xy 122.919943 -376.521741) (xy 122.923546 -376.535004) (xy 122.926856 -376.54103) (xy 122.943197 -376.569384)
			(xy 122.968941 -376.629551) (xy 122.986367 -376.692632) (xy 122.99516 -376.757482) (xy 122.995159 -376.822925)
			(xy 126.424967 -376.822925) (xy 126.424967 -376.757482) (xy 126.43376 -376.692632) (xy 126.451187 -376.629552)
			(xy 126.476932 -376.569386) (xy 126.49327 -376.54103) (xy 126.496625 -376.535011) (xy 126.500366 -376.521754)
			(xy 126.500636 -376.514868) (xy 126.500636 -375.765568) (xy 126.500407 -375.758675) (xy 126.496676 -375.745403)
			(xy 126.49327 -375.739406) (xy 126.476959 -375.711035) (xy 126.451211 -375.650872) (xy 126.43378 -375.587795)
			(xy 126.424983 -375.522948) (xy 126.42498 -375.457507) (xy 126.433769 -375.392659) (xy 126.451193 -375.32958)
			(xy 126.476934 -375.269414) (xy 126.49327 -375.241058) (xy 126.496651 -375.235051) (xy 126.500376 -375.221784)
			(xy 126.500636 -375.214896) (xy 126.500636 -374.928638) (xy 126.501158 -374.918514) (xy 126.508872 -374.899795)
			(xy 126.523148 -374.885437) (xy 126.541823 -374.877616) (xy 126.551944 -374.877076) (xy 127.268224 -374.877076)
			(xy 127.278377 -374.877501) (xy 127.297125 -374.8853) (xy 127.311447 -374.899695) (xy 127.31915 -374.918483)
			(xy 127.319532 -374.928638) (xy 127.319532 -375.214896) (xy 127.319763 -375.221788) (xy 127.323506 -375.235054)
			(xy 127.326898 -375.241058) (xy 127.343261 -375.2694) (xy 127.369001 -375.32957) (xy 127.386423 -375.392653)
			(xy 127.395212 -375.457505) (xy 127.395208 -375.52295) (xy 127.386412 -375.587801) (xy 127.368983 -375.650882)
			(xy 127.343236 -375.711049) (xy 127.326898 -375.739406) (xy 127.323535 -375.745422) (xy 127.319798 -375.758681)
			(xy 127.319532 -375.765568) (xy 127.319532 -376.514868) (xy 127.319751 -376.521762) (xy 127.323489 -376.535034)
			(xy 127.326898 -376.54103) (xy 127.343238 -376.569385) (xy 127.368979 -376.629552) (xy 127.386404 -376.692633)
			(xy 127.395196 -376.757482) (xy 127.395195 -376.822925) (xy 130.825017 -376.822925) (xy 130.825017 -376.757482)
			(xy 130.833809 -376.692633) (xy 130.851234 -376.629553) (xy 130.876976 -376.569386) (xy 130.893312 -376.54103)
			(xy 130.896617 -376.535001) (xy 130.900229 -376.521741) (xy 130.900424 -376.514868) (xy 130.900424 -375.765568)
			(xy 130.900241 -375.758694) (xy 130.896626 -375.745431) (xy 130.893312 -375.739406) (xy 130.877003 -375.711035)
			(xy 130.851258 -375.650871) (xy 130.833829 -375.587794) (xy 130.825033 -375.522948) (xy 130.82503 -375.457507)
			(xy 130.833818 -375.39266) (xy 130.851239 -375.329581) (xy 130.876978 -375.269414) (xy 130.893312 -375.241058)
			(xy 130.896643 -375.235041) (xy 130.900238 -375.221771) (xy 130.900424 -375.214896) (xy 130.900424 -374.928638)
			(xy 130.900895 -374.918471) (xy 130.908665 -374.899679) (xy 130.923036 -374.885294) (xy 130.941819 -374.877505)
			(xy 130.951986 -374.877076) (xy 131.668266 -374.877076) (xy 131.67844 -374.877493) (xy 131.697241 -374.885274)
			(xy 131.711629 -374.899662) (xy 131.719408 -374.918464) (xy 131.719828 -374.928638) (xy 131.719828 -375.214896)
			(xy 131.720018 -375.221769) (xy 131.723627 -375.235032) (xy 131.72694 -375.241058) (xy 131.743305 -375.269399)
			(xy 131.769048 -375.329569) (xy 131.786472 -375.392652) (xy 131.795262 -375.457505) (xy 131.795258 -375.52295)
			(xy 131.786461 -375.587802) (xy 131.769029 -375.650883) (xy 131.752233 -375.69013) (xy 133.023872 -375.69013)
			(xy 133.027863 -375.627963) (xy 133.039772 -375.566816) (xy 133.059401 -375.507695) (xy 133.08643 -375.451569)
			(xy 133.120414 -375.39936) (xy 133.160796 -375.351925) (xy 133.206912 -375.310044) (xy 133.258004 -375.274404)
			(xy 133.313235 -375.24559) (xy 133.371697 -375.224076) (xy 133.432431 -375.210214) (xy 133.494438 -375.204232)
			(xy 133.556701 -375.206228) (xy 133.618198 -375.216171) (xy 133.677919 -375.233895) (xy 133.734882 -375.259112)
			(xy 133.788153 -375.291405) (xy 133.836858 -375.330245) (xy 133.880195 -375.374995) (xy 133.917455 -375.424919)
			(xy 133.948024 -375.479198) (xy 133.952491 -375.490232) (xy 135.22402 -375.490232) (xy 135.228011 -375.428065)
			(xy 135.23992 -375.366918) (xy 135.259549 -375.307797) (xy 135.286578 -375.251671) (xy 135.320562 -375.199462)
			(xy 135.360944 -375.152027) (xy 135.40706 -375.110146) (xy 135.458152 -375.074506) (xy 135.513383 -375.045692)
			(xy 135.571845 -375.024178) (xy 135.632579 -375.010316) (xy 135.694586 -375.004334) (xy 135.756849 -375.00633)
			(xy 135.818346 -375.016273) (xy 135.878067 -375.033997) (xy 135.93503 -375.059214) (xy 135.988301 -375.091507)
			(xy 136.037006 -375.130347) (xy 136.080343 -375.175097) (xy 136.117603 -375.225021) (xy 136.148172 -375.2793)
			(xy 136.17155 -375.337043) (xy 136.187351 -375.397301) (xy 136.195317 -375.459084) (xy 136.195816 -375.490232)
			(xy 136.195317 -375.52138) (xy 136.187351 -375.583163) (xy 136.17155 -375.643421) (xy 136.148172 -375.701164)
			(xy 136.117603 -375.755443) (xy 136.080343 -375.805367) (xy 136.037006 -375.850117) (xy 135.988301 -375.888957)
			(xy 135.93503 -375.92125) (xy 135.878067 -375.946467) (xy 135.818346 -375.964191) (xy 135.756849 -375.974134)
			(xy 135.694586 -375.97613) (xy 135.632579 -375.970148) (xy 135.571845 -375.956286) (xy 135.513383 -375.934772)
			(xy 135.458152 -375.905958) (xy 135.40706 -375.870318) (xy 135.360944 -375.828437) (xy 135.320562 -375.781002)
			(xy 135.286578 -375.728793) (xy 135.259549 -375.672667) (xy 135.23992 -375.613546) (xy 135.228011 -375.552399)
			(xy 135.22402 -375.490232) (xy 133.952491 -375.490232) (xy 133.971402 -375.536941) (xy 133.987203 -375.597199)
			(xy 133.995169 -375.658982) (xy 133.995668 -375.69013) (xy 133.995169 -375.721278) (xy 133.987203 -375.783061)
			(xy 133.971402 -375.843319) (xy 133.948024 -375.901062) (xy 133.917455 -375.955341) (xy 133.880195 -376.005265)
			(xy 133.836858 -376.050015) (xy 133.788153 -376.088855) (xy 133.734882 -376.121148) (xy 133.677919 -376.146365)
			(xy 133.618198 -376.164089) (xy 133.556701 -376.174032) (xy 133.494438 -376.176028) (xy 133.432431 -376.170046)
			(xy 133.371697 -376.156184) (xy 133.313235 -376.13467) (xy 133.258004 -376.105856) (xy 133.206912 -376.070216)
			(xy 133.160796 -376.028335) (xy 133.120414 -375.9809) (xy 133.08643 -375.928691) (xy 133.059401 -375.872565)
			(xy 133.039772 -375.813444) (xy 133.027863 -375.752297) (xy 133.023872 -375.69013) (xy 131.752233 -375.69013)
			(xy 131.74328 -375.71105) (xy 131.72694 -375.739406) (xy 131.723626 -375.745431) (xy 131.72002 -375.758694)
			(xy 131.719828 -375.765568) (xy 131.719828 -376.514868) (xy 131.720029 -376.521741) (xy 131.723631 -376.535004)
			(xy 131.72694 -376.54103) (xy 131.743281 -376.569384) (xy 131.769026 -376.629551) (xy 131.786453 -376.692632)
			(xy 131.795246 -376.757482) (xy 131.795245 -376.790204) (xy 135.22402 -376.790204) (xy 135.228011 -376.728037)
			(xy 135.23992 -376.66689) (xy 135.259549 -376.607769) (xy 135.286578 -376.551643) (xy 135.320562 -376.499434)
			(xy 135.360944 -376.451999) (xy 135.40706 -376.410118) (xy 135.458152 -376.374478) (xy 135.513383 -376.345664)
			(xy 135.571845 -376.32415) (xy 135.632579 -376.310288) (xy 135.694586 -376.304306) (xy 135.756849 -376.306302)
			(xy 135.818346 -376.316245) (xy 135.878067 -376.333969) (xy 135.93503 -376.359186) (xy 135.988301 -376.391479)
			(xy 136.037006 -376.430319) (xy 136.080343 -376.475069) (xy 136.117603 -376.524993) (xy 136.148172 -376.579272)
			(xy 136.17155 -376.637015) (xy 136.187351 -376.697273) (xy 136.195317 -376.759056) (xy 136.195816 -376.790204)
			(xy 136.195317 -376.821352) (xy 136.187351 -376.883135) (xy 136.17155 -376.943393) (xy 136.148172 -377.001136)
			(xy 136.117603 -377.055415) (xy 136.080343 -377.105339) (xy 136.037006 -377.150089) (xy 135.988301 -377.188929)
			(xy 135.93503 -377.221222) (xy 135.878067 -377.246439) (xy 135.818346 -377.264163) (xy 135.756849 -377.274106)
			(xy 135.694586 -377.276102) (xy 135.632579 -377.27012) (xy 135.571845 -377.256258) (xy 135.513383 -377.234744)
			(xy 135.458152 -377.20593) (xy 135.40706 -377.17029) (xy 135.360944 -377.128409) (xy 135.320562 -377.080974)
			(xy 135.286578 -377.028765) (xy 135.259549 -376.972639) (xy 135.23992 -376.913518) (xy 135.228011 -376.852371)
			(xy 135.22402 -376.790204) (xy 131.795245 -376.790204) (xy 131.795245 -376.822925) (xy 131.786452 -376.887775)
			(xy 131.769024 -376.950855) (xy 131.743278 -377.011022) (xy 131.72694 -377.039378) (xy 131.723636 -377.045408)
			(xy 131.720023 -377.058668) (xy 131.719828 -377.06554) (xy 131.719828 -377.35129) (xy 131.719427 -377.361465)
			(xy 131.711639 -377.380266) (xy 131.697246 -377.394653) (xy 131.678441 -377.402432) (xy 131.668266 -377.402852)
			(xy 130.951986 -377.402852) (xy 130.941826 -377.402378) (xy 130.923055 -377.394597) (xy 130.90869 -377.380225)
			(xy 130.900918 -377.36145) (xy 130.900424 -377.35129) (xy 130.900424 -377.06554) (xy 130.900214 -377.058668)
			(xy 130.896618 -377.045405) (xy 130.893312 -377.039378) (xy 130.876979 -377.01102) (xy 130.851236 -376.950853)
			(xy 130.83381 -376.887774) (xy 130.825017 -376.822925) (xy 127.395195 -376.822925) (xy 127.386403 -376.887774)
			(xy 127.368977 -376.950854) (xy 127.343234 -377.011021) (xy 127.326898 -377.039378) (xy 127.323545 -377.045399)
			(xy 127.319802 -377.058655) (xy 127.319532 -377.06554) (xy 127.319532 -377.35129) (xy 127.319064 -377.36142)
			(xy 127.311335 -377.380146) (xy 127.297042 -377.394503) (xy 127.278351 -377.402318) (xy 127.268224 -377.402852)
			(xy 126.551944 -377.402852) (xy 126.541799 -377.402343) (xy 126.523058 -377.394572) (xy 126.508735 -377.380202)
			(xy 126.501024 -377.361436) (xy 126.500636 -377.35129) (xy 126.500636 -377.06554) (xy 126.500418 -377.058646)
			(xy 126.49668 -377.045374) (xy 126.49327 -377.039378) (xy 126.476935 -377.01102) (xy 126.451189 -376.950854)
			(xy 126.433761 -376.887774) (xy 126.424967 -376.822925) (xy 122.995159 -376.822925) (xy 122.986366 -376.887775)
			(xy 122.968938 -376.950855) (xy 122.943194 -377.011022) (xy 122.926856 -377.039378) (xy 122.923553 -377.045409)
			(xy 122.919939 -377.058668) (xy 122.919744 -377.06554) (xy 122.919744 -377.35129) (xy 122.919328 -377.361463)
			(xy 122.911543 -377.380261) (xy 122.897154 -377.394647) (xy 122.878355 -377.402429) (xy 122.868182 -377.402852)
			(xy 122.151902 -377.402852) (xy 122.141729 -377.402434) (xy 122.122933 -377.394648) (xy 122.108547 -377.380261)
			(xy 122.100764 -377.361463) (xy 122.10034 -377.35129) (xy 122.10034 -377.06554) (xy 122.100128 -377.058668)
			(xy 122.096533 -377.045406) (xy 122.093228 -377.039378) (xy 122.076894 -377.01102) (xy 122.051151 -376.950853)
			(xy 122.033724 -376.887774) (xy 122.024931 -376.822925) (xy 118.595123 -376.822925) (xy 118.586329 -376.887776)
			(xy 118.5689 -376.950856) (xy 118.543153 -377.011022) (xy 118.526814 -377.039378) (xy 118.523462 -377.045399)
			(xy 118.519718 -377.058655) (xy 118.519448 -377.06554) (xy 118.519448 -377.35129) (xy 118.518965 -377.361418)
			(xy 118.511238 -377.380141) (xy 118.496951 -377.394498) (xy 118.478265 -377.402315) (xy 118.46814 -377.402852)
			(xy 117.75186 -377.402852) (xy 117.74171 -377.402412) (xy 117.722967 -377.394613) (xy 117.708647 -377.380223)
			(xy 117.700939 -377.361442) (xy 117.700552 -377.35129) (xy 117.700552 -377.06554) (xy 117.700332 -377.058646)
			(xy 117.696595 -377.045374) (xy 117.693186 -377.039378) (xy 117.676851 -377.01102) (xy 117.651104 -376.950855)
			(xy 117.633675 -376.887775) (xy 117.624881 -376.822925) (xy 100.617654 -376.822925) (xy 100.612702 -377.038108)
			(xy 100.624894 -377.061222) (xy 100.63607 -377.068334) (xy 100.658916 -377.083897) (xy 100.700293 -377.120553)
			(xy 100.735952 -377.162792) (xy 100.765149 -377.209731) (xy 100.787272 -377.260389) (xy 100.801861 -377.313708)
			(xy 100.808609 -377.368573) (xy 100.807377 -377.423837) (xy 100.798189 -377.478347) (xy 100.781237 -377.530962)
			(xy 100.756877 -377.580583) (xy 100.725616 -377.626173) (xy 100.688109 -377.66678) (xy 100.645139 -377.701555)
			(xy 100.621592 -377.716034) (xy 100.610162 -377.722638) (xy 100.596954 -377.745244) (xy 100.583999 -378.3228)
			(xy 115.424969 -378.3228) (xy 115.424972 -378.257355) (xy 115.433769 -378.192504) (xy 115.451201 -378.129422)
			(xy 115.476951 -378.069256) (xy 115.493292 -378.0409) (xy 115.496606 -378.034875) (xy 115.500212 -378.021612)
			(xy 115.500404 -378.014738) (xy 115.500404 -377.728734) (xy 115.500961 -377.718583) (xy 115.508717 -377.699821)
			(xy 115.523064 -377.685456) (xy 115.541815 -377.677674) (xy 115.551966 -377.677172) (xy 116.268246 -377.677172)
			(xy 116.278411 -377.677597) (xy 116.297188 -377.685393) (xy 116.311552 -377.69978) (xy 116.319319 -377.718568)
			(xy 116.319808 -377.728734) (xy 116.319808 -378.014738) (xy 116.320023 -378.02161) (xy 116.323615 -378.034872)
			(xy 116.32692 -378.0409) (xy 116.343237 -378.069268) (xy 116.368985 -378.129431) (xy 116.386415 -378.192509)
			(xy 116.395212 -378.257357) (xy 116.395215 -378.322799) (xy 116.395215 -378.3228) (xy 119.825019 -378.3228)
			(xy 119.825022 -378.257355) (xy 119.833818 -378.192504) (xy 119.851248 -378.129423) (xy 119.876995 -378.069256)
			(xy 119.893334 -378.0409) (xy 119.896697 -378.034884) (xy 119.900433 -378.021624) (xy 119.9007 -378.014738)
			(xy 119.9007 -377.728734) (xy 119.901253 -377.718614) (xy 119.908963 -377.699902) (xy 119.923228 -377.685546)
			(xy 119.941892 -377.677718) (xy 119.952008 -377.677172) (xy 120.668288 -377.677172) (xy 120.678438 -377.677631)
			(xy 120.697185 -377.685417) (xy 120.711507 -377.699802) (xy 120.719213 -377.718582) (xy 120.719596 -377.728734)
			(xy 120.719596 -378.014738) (xy 120.719854 -378.021627) (xy 120.723579 -378.034893) (xy 120.726962 -378.0409)
			(xy 120.743277 -378.069268) (xy 120.769023 -378.129432) (xy 120.786452 -378.19251) (xy 120.795248 -378.257357)
			(xy 120.795251 -378.322798) (xy 120.795251 -378.3228) (xy 124.225055 -378.3228) (xy 124.225058 -378.257355)
			(xy 124.233855 -378.192504) (xy 124.251286 -378.129423) (xy 124.277036 -378.069256) (xy 124.293376 -378.0409)
			(xy 124.296689 -378.034874) (xy 124.300296 -378.021611) (xy 124.300488 -378.014738) (xy 124.300488 -377.728734)
			(xy 124.300893 -377.718558) (xy 124.308676 -377.699755) (xy 124.323068 -377.685367) (xy 124.341874 -377.67759)
			(xy 124.35205 -377.677172) (xy 125.06833 -377.677172) (xy 125.078508 -377.67754) (xy 125.09731 -377.685341)
			(xy 125.111695 -377.699744) (xy 125.119473 -377.718556) (xy 125.119892 -377.728734) (xy 125.119892 -378.014738)
			(xy 125.120109 -378.021609) (xy 125.1237 -378.034872) (xy 125.127004 -378.0409) (xy 125.143318 -378.069269)
			(xy 125.169062 -378.129433) (xy 125.186489 -378.19251) (xy 125.195284 -378.257357) (xy 125.195287 -378.322798)
			(xy 125.195287 -378.3228) (xy 128.624845 -378.3228) (xy 128.624848 -378.257355) (xy 128.633645 -378.192504)
			(xy 128.651075 -378.129423) (xy 128.676824 -378.069256) (xy 128.693164 -378.0409) (xy 128.696476 -378.034874)
			(xy 128.700084 -378.021611) (xy 128.700276 -378.014738) (xy 128.700276 -377.728734) (xy 128.700693 -377.71856)
			(xy 128.708474 -377.699759) (xy 128.722862 -377.685371) (xy 128.741664 -377.677592) (xy 128.751838 -377.677172)
			(xy 129.468118 -377.677172) (xy 129.478295 -377.67755) (xy 129.497097 -377.685347) (xy 129.511482 -377.699747)
			(xy 129.51926 -377.718557) (xy 129.51968 -377.728734) (xy 129.51968 -378.014738) (xy 129.519898 -378.021609)
			(xy 129.523489 -378.034872) (xy 129.526792 -378.0409) (xy 129.543106 -378.069269) (xy 129.568851 -378.129433)
			(xy 129.586278 -378.19251) (xy 129.595074 -378.257357) (xy 129.595075 -378.290074) (xy 133.023872 -378.290074)
			(xy 133.027863 -378.227907) (xy 133.039772 -378.16676) (xy 133.059401 -378.107639) (xy 133.08643 -378.051513)
			(xy 133.120414 -377.999304) (xy 133.160796 -377.951869) (xy 133.206912 -377.909988) (xy 133.258004 -377.874348)
			(xy 133.313235 -377.845534) (xy 133.371697 -377.82402) (xy 133.432431 -377.810158) (xy 133.494438 -377.804176)
			(xy 133.556701 -377.806172) (xy 133.618198 -377.816115) (xy 133.677919 -377.833839) (xy 133.734882 -377.859056)
			(xy 133.788153 -377.891349) (xy 133.836858 -377.930189) (xy 133.880195 -377.974939) (xy 133.917455 -378.024863)
			(xy 133.948024 -378.079142) (xy 133.971402 -378.136885) (xy 133.987203 -378.197143) (xy 133.995169 -378.258926)
			(xy 133.995668 -378.290074) (xy 133.995169 -378.321222) (xy 133.987203 -378.383005) (xy 133.971402 -378.443263)
			(xy 133.948024 -378.501006) (xy 133.917455 -378.555285) (xy 133.880195 -378.605209) (xy 133.836858 -378.649959)
			(xy 133.788153 -378.688799) (xy 133.734882 -378.721092) (xy 133.677919 -378.746309) (xy 133.618198 -378.764033)
			(xy 133.556701 -378.773976) (xy 133.494438 -378.775972) (xy 133.432431 -378.76999) (xy 133.371697 -378.756128)
			(xy 133.313235 -378.734614) (xy 133.258004 -378.7058) (xy 133.206912 -378.67016) (xy 133.160796 -378.628279)
			(xy 133.120414 -378.580844) (xy 133.08643 -378.528635) (xy 133.059401 -378.472509) (xy 133.039772 -378.413388)
			(xy 133.027863 -378.352241) (xy 133.023872 -378.290074) (xy 129.595075 -378.290074) (xy 129.595077 -378.322798)
			(xy 129.586287 -378.387646) (xy 129.568865 -378.450725) (xy 129.543127 -378.510892) (xy 129.526792 -378.539248)
			(xy 129.52346 -378.545264) (xy 129.519865 -378.558534) (xy 129.51968 -378.56541) (xy 129.51968 -379.31471)
			(xy 129.519871 -379.321583) (xy 129.52348 -379.334846) (xy 129.526792 -379.340872) (xy 129.543167 -379.369207)
			(xy 129.568906 -379.429379) (xy 129.586327 -379.492463) (xy 129.595115 -379.557317) (xy 129.595109 -379.622762)
			(xy 129.586311 -379.687614) (xy 129.56888 -379.750696) (xy 129.543131 -379.810863) (xy 129.526792 -379.83922)
			(xy 129.52347 -379.845241) (xy 129.519869 -379.858508) (xy 129.51968 -379.865382) (xy 129.51968 -380.151386)
			(xy 129.519156 -380.161541) (xy 129.511389 -380.180306) (xy 129.497033 -380.194671) (xy 129.478272 -380.202449)
			(xy 129.468118 -380.202948) (xy 128.751838 -380.202948) (xy 128.741667 -380.202505) (xy 128.722871 -380.19473)
			(xy 128.708484 -380.18035) (xy 128.7007 -380.161557) (xy 128.700276 -380.151386) (xy 128.700276 -379.865382)
			(xy 128.700094 -379.858508) (xy 128.696479 -379.845245) (xy 128.693164 -379.83922) (xy 128.676865 -379.810843)
			(xy 128.651116 -379.750681) (xy 128.633684 -379.687605) (xy 128.624886 -379.622759) (xy 128.624881 -379.557319)
			(xy 128.633668 -379.492472) (xy 128.65109 -379.429393) (xy 128.676829 -379.369228) (xy 128.693164 -379.340872)
			(xy 128.696486 -379.334851) (xy 128.700087 -379.321584) (xy 128.700276 -379.31471) (xy 128.700276 -378.56541)
			(xy 128.700083 -378.558537) (xy 128.696476 -378.545274) (xy 128.693164 -378.539248) (xy 128.676804 -378.510904)
			(xy 128.651061 -378.450735) (xy 128.633636 -378.387652) (xy 128.624845 -378.3228) (xy 125.195287 -378.3228)
			(xy 125.186498 -378.387646) (xy 125.169076 -378.450725) (xy 125.143338 -378.510891) (xy 125.127004 -378.539248)
			(xy 125.123672 -378.545264) (xy 125.120077 -378.558535) (xy 125.119892 -378.56541) (xy 125.119892 -379.31471)
			(xy 125.120081 -379.321583) (xy 125.123691 -379.334846) (xy 125.127004 -379.340872) (xy 125.143379 -379.369207)
			(xy 125.169117 -379.429379) (xy 125.186538 -379.492464) (xy 125.195325 -379.557317) (xy 125.19532 -379.622762)
			(xy 125.186522 -379.687614) (xy 125.169091 -379.750695) (xy 125.143343 -379.810863) (xy 125.127004 -379.83922)
			(xy 125.123682 -379.845241) (xy 125.120081 -379.858508) (xy 125.119892 -379.865382) (xy 125.119892 -380.151386)
			(xy 125.119356 -380.161539) (xy 125.111592 -380.180302) (xy 125.097239 -380.194667) (xy 125.078483 -380.202447)
			(xy 125.06833 -380.202948) (xy 124.35205 -380.202948) (xy 124.34188 -380.202495) (xy 124.323084 -380.194724)
			(xy 124.308696 -380.180347) (xy 124.300912 -380.161556) (xy 124.300488 -380.151386) (xy 124.300488 -379.865382)
			(xy 124.300305 -379.858508) (xy 124.296691 -379.845245) (xy 124.293376 -379.83922) (xy 124.277076 -379.810843)
			(xy 124.251327 -379.750681) (xy 124.233895 -379.687606) (xy 124.225096 -379.62276) (xy 124.225091 -379.557319)
			(xy 124.233879 -379.492472) (xy 124.251301 -379.429393) (xy 124.277041 -379.369228) (xy 124.293376 -379.340872)
			(xy 124.296699 -379.334851) (xy 124.3003 -379.321585) (xy 124.300488 -379.31471) (xy 124.300488 -378.56541)
			(xy 124.300294 -378.558537) (xy 124.296687 -378.545274) (xy 124.293376 -378.539248) (xy 124.277015 -378.510904)
			(xy 124.251272 -378.450735) (xy 124.233846 -378.387652) (xy 124.225055 -378.3228) (xy 120.795251 -378.3228)
			(xy 120.786461 -378.387646) (xy 120.769038 -378.450726) (xy 120.743298 -378.510892) (xy 120.726962 -378.539248)
			(xy 120.723582 -378.545255) (xy 120.719856 -378.558522) (xy 120.719596 -378.56541) (xy 120.719596 -379.31471)
			(xy 120.719826 -379.321602) (xy 120.723571 -379.334867) (xy 120.726962 -379.340872) (xy 120.743338 -379.369207)
			(xy 120.769079 -379.429378) (xy 120.786501 -379.492463) (xy 120.795289 -379.557316) (xy 120.795283 -379.622762)
			(xy 120.786485 -379.687614) (xy 120.769052 -379.750696) (xy 120.743302 -379.810864) (xy 120.726962 -379.83922)
			(xy 120.723592 -379.845232) (xy 120.71986 -379.858495) (xy 120.719596 -379.865382) (xy 120.719596 -380.151386)
			(xy 120.719063 -380.161507) (xy 120.711347 -380.180221) (xy 120.697075 -380.194577) (xy 120.678406 -380.202403)
			(xy 120.668288 -380.202948) (xy 119.952008 -380.202948) (xy 119.94186 -380.202473) (xy 119.923117 -380.194689)
			(xy 119.908795 -380.180309) (xy 119.901087 -380.161535) (xy 119.9007 -380.151386) (xy 119.9007 -379.865382)
			(xy 119.900435 -379.858493) (xy 119.896714 -379.845227) (xy 119.893334 -379.83922) (xy 119.877036 -379.810842)
			(xy 119.851289 -379.750681) (xy 119.833858 -379.687605) (xy 119.82506 -379.622759) (xy 119.825055 -379.55732)
			(xy 119.833842 -379.492473) (xy 119.851262 -379.429394) (xy 119.877 -379.369228) (xy 119.893334 -379.340872)
			(xy 119.896707 -379.334861) (xy 119.900437 -379.321598) (xy 119.9007 -379.31471) (xy 119.9007 -378.56541)
			(xy 119.900463 -378.558519) (xy 119.896723 -378.545253) (xy 119.893334 -378.539248) (xy 119.876975 -378.510904)
			(xy 119.851233 -378.450734) (xy 119.833809 -378.387652) (xy 119.825019 -378.3228) (xy 116.395215 -378.3228)
			(xy 116.386424 -378.387647) (xy 116.368999 -378.450726) (xy 116.343257 -378.510892) (xy 116.32692 -378.539248)
			(xy 116.32359 -378.545265) (xy 116.319993 -378.558535) (xy 116.319808 -378.56541) (xy 116.319808 -379.31471)
			(xy 116.319995 -379.321584) (xy 116.323606 -379.334846) (xy 116.32692 -379.340872) (xy 116.343298 -379.369206)
			(xy 116.36904 -379.429378) (xy 116.386464 -379.492462) (xy 116.395253 -379.557316) (xy 116.395247 -379.622763)
			(xy 116.386448 -379.687615) (xy 116.369014 -379.750697) (xy 116.343262 -379.810864) (xy 116.32692 -379.83922)
			(xy 116.3236 -379.845242) (xy 116.319997 -379.858508) (xy 116.319808 -379.865382) (xy 116.319808 -380.151386)
			(xy 116.319256 -380.161537) (xy 116.311495 -380.180297) (xy 116.297148 -380.194661) (xy 116.278397 -380.202445)
			(xy 116.268246 -380.202948) (xy 115.551966 -380.202948) (xy 115.541804 -380.202494) (xy 115.523032 -380.194706)
			(xy 115.508667 -380.180328) (xy 115.500896 -380.161548) (xy 115.500404 -380.151386) (xy 115.500404 -379.865382)
			(xy 115.500219 -379.858508) (xy 115.496606 -379.845245) (xy 115.493292 -379.83922) (xy 115.476992 -379.810843)
			(xy 115.451242 -379.750682) (xy 115.433809 -379.687606) (xy 115.42501 -379.62276) (xy 115.425005 -379.557319)
			(xy 115.433793 -379.492472) (xy 115.451216 -379.429393) (xy 115.476956 -379.369228) (xy 115.493292 -379.340872)
			(xy 115.496616 -379.334852) (xy 115.500216 -379.321585) (xy 115.500404 -379.31471) (xy 115.500404 -378.56541)
			(xy 115.500208 -378.558537) (xy 115.496603 -378.545274) (xy 115.493292 -378.539248) (xy 115.476931 -378.510905)
			(xy 115.451186 -378.450735) (xy 115.43376 -378.387653) (xy 115.424969 -378.3228) (xy 100.583999 -378.3228)
			(xy 100.52685 -380.870714) (xy 100.544884 -380.89713) (xy 100.560124 -380.902972) (xy 100.585247 -380.913069)
			(xy 100.632596 -380.939328) (xy 100.675765 -380.972006) (xy 100.713889 -381.010451) (xy 100.746206 -381.053891)
			(xy 100.759514 -381.07747) (xy 100.766572 -381.08941) (xy 100.785924 -381.109261) (xy 100.809908 -381.123167)
			(xy 100.83675 -381.1301) (xy 100.864468 -381.129549) (xy 100.891014 -381.121554) (xy 100.914425 -381.106705)
			(xy 100.932973 -381.0861) (xy 100.9396 -381.073914) (xy 100.951797 -381.050373) (xy 100.981718 -381.006606)
			(xy 101.017405 -380.967397) (xy 101.058172 -380.933501) (xy 101.103236 -380.905568) (xy 101.151729 -380.884137)
			(xy 101.20272 -380.869618) (xy 101.255229 -380.86229) (xy 101.281738 -380.861824) (xy 101.309007 -380.862313)
			(xy 101.362988 -380.870079) (xy 101.388498 -380.877572) (xy 105.0036 -380.877572) (xy 105.0036 -380.013972)
			(xy 105.00409 -379.983988) (xy 105.011918 -379.924532) (xy 105.027439 -379.866607) (xy 105.050388 -379.811203)
			(xy 105.080372 -379.759269) (xy 105.116878 -379.711693) (xy 105.159283 -379.669288) (xy 105.206859 -379.632782)
			(xy 105.258793 -379.602798) (xy 105.314197 -379.579849) (xy 105.372122 -379.564328) (xy 105.431578 -379.5565)
			(xy 105.491546 -379.5565) (xy 105.551002 -379.564328) (xy 105.608927 -379.579849) (xy 105.664331 -379.602798)
			(xy 105.716265 -379.632782) (xy 105.763841 -379.669288) (xy 105.806246 -379.711693) (xy 105.842752 -379.759269)
			(xy 105.872736 -379.811203) (xy 105.895685 -379.866607) (xy 105.911206 -379.924532) (xy 105.919034 -379.983988)
			(xy 105.919524 -380.013972) (xy 105.919524 -380.657396) (xy 117.624888 -380.657396) (xy 117.633679 -380.592547)
			(xy 117.651105 -380.529468) (xy 117.676849 -380.469302) (xy 117.693186 -380.440946) (xy 117.696564 -380.434938)
			(xy 117.700292 -380.421672) (xy 117.700552 -380.414784) (xy 117.700552 -379.665484) (xy 117.700315 -379.658592)
			(xy 117.696589 -379.645319) (xy 117.693186 -379.639322) (xy 117.676888 -379.610944) (xy 117.651138 -379.550783)
			(xy 117.633705 -379.487707) (xy 117.624906 -379.422861) (xy 117.624901 -379.357421) (xy 117.633688 -379.292574)
			(xy 117.65111 -379.229495) (xy 117.67685 -379.16933) (xy 117.693186 -379.140974) (xy 117.696554 -379.134961)
			(xy 117.700288 -379.121699) (xy 117.700552 -379.114812) (xy 117.700552 -378.828554) (xy 117.700989 -378.818423)
			(xy 117.708734 -378.799698) (xy 117.723036 -378.785343) (xy 117.741731 -378.777528) (xy 117.75186 -378.776992)
			(xy 118.46814 -378.776992) (xy 118.478296 -378.777389) (xy 118.497047 -378.785196) (xy 118.511369 -378.7996)
			(xy 118.519069 -378.818396) (xy 118.519448 -378.828554) (xy 118.519448 -379.114812) (xy 118.519687 -379.121704)
			(xy 118.523411 -379.134976) (xy 118.526814 -379.140974) (xy 118.543194 -379.169307) (xy 118.568936 -379.229479)
			(xy 118.58636 -379.292564) (xy 118.595149 -379.357418) (xy 118.595143 -379.422865) (xy 118.586343 -379.487717)
			(xy 118.568909 -379.550799) (xy 118.543156 -379.610966) (xy 118.526814 -379.639322) (xy 118.523447 -379.645336)
			(xy 118.519712 -379.658597) (xy 118.519448 -379.665484) (xy 118.519448 -380.414784) (xy 118.519659 -380.421679)
			(xy 118.523403 -380.43495) (xy 118.526814 -380.440946) (xy 118.54317 -380.469292) (xy 118.568915 -380.529461)
			(xy 118.586341 -380.592543) (xy 118.595133 -380.657395) (xy 118.595133 -380.657396) (xy 122.024938 -380.657396)
			(xy 122.033728 -380.592548) (xy 122.051152 -380.529469) (xy 122.076892 -380.469302) (xy 122.093228 -380.440946)
			(xy 122.096528 -380.434914) (xy 122.100143 -380.421656) (xy 122.10034 -380.414784) (xy 122.10034 -379.665484)
			(xy 122.100149 -379.658611) (xy 122.09654 -379.645348) (xy 122.093228 -379.639322) (xy 122.076932 -379.610943)
			(xy 122.051185 -379.550782) (xy 122.033754 -379.487706) (xy 122.024956 -379.422861) (xy 122.024951 -379.357421)
			(xy 122.033737 -379.292575) (xy 122.051157 -379.229496) (xy 122.076894 -379.16933) (xy 122.093228 -379.140974)
			(xy 122.096554 -379.134955) (xy 122.100152 -379.121687) (xy 122.10034 -379.114812) (xy 122.10034 -378.828554)
			(xy 122.100796 -378.818393) (xy 122.108586 -378.799623) (xy 122.122963 -378.785259) (xy 122.141741 -378.777486)
			(xy 122.151902 -378.776992) (xy 122.868182 -378.776992) (xy 122.878333 -378.777547) (xy 122.897093 -378.785307)
			(xy 122.911457 -378.799653) (xy 122.919241 -378.818404) (xy 122.919744 -378.828554) (xy 122.919744 -379.114812)
			(xy 122.919926 -379.121686) (xy 122.92354 -379.134949) (xy 122.926856 -379.140974) (xy 122.943234 -379.169308)
			(xy 122.968975 -379.22948) (xy 122.986397 -379.292564) (xy 122.995185 -379.357418) (xy 122.995179 -379.422864)
			(xy 122.98638 -379.487716) (xy 122.968947 -379.550798) (xy 122.943197 -379.610966) (xy 122.926856 -379.639322)
			(xy 122.923538 -379.645345) (xy 122.919934 -379.65861) (xy 122.919744 -379.665484) (xy 122.919744 -380.414784)
			(xy 122.919937 -380.421657) (xy 122.923544 -380.43492) (xy 122.926856 -380.440946) (xy 122.94321 -380.469293)
			(xy 122.968953 -380.529462) (xy 122.986378 -380.592544) (xy 122.995169 -380.657395) (xy 122.995169 -380.657396)
			(xy 126.424974 -380.657396) (xy 126.433765 -380.592547) (xy 126.45119 -380.529468) (xy 126.476933 -380.469302)
			(xy 126.49327 -380.440946) (xy 126.496655 -380.434941) (xy 126.500377 -380.421673) (xy 126.500636 -380.414784)
			(xy 126.500636 -379.665484) (xy 126.500401 -379.658591) (xy 126.496674 -379.645319) (xy 126.49327 -379.639322)
			(xy 126.476972 -379.610944) (xy 126.451223 -379.550783) (xy 126.433791 -379.487707) (xy 126.424992 -379.422861)
			(xy 126.424987 -379.357421) (xy 126.433774 -379.292574) (xy 126.451196 -379.229495) (xy 126.476935 -379.16933)
			(xy 126.49327 -379.140974) (xy 126.496645 -379.134964) (xy 126.500373 -379.1217) (xy 126.500636 -379.114812)
			(xy 126.500636 -378.828554) (xy 126.501089 -378.818425) (xy 126.508831 -378.799703) (xy 126.523127 -378.785349)
			(xy 126.541817 -378.777531) (xy 126.551944 -378.776992) (xy 127.268224 -378.776992) (xy 127.278379 -378.777402)
			(xy 127.29713 -378.785204) (xy 127.311452 -378.799604) (xy 127.319153 -378.818397) (xy 127.319532 -378.828554)
			(xy 127.319532 -379.114812) (xy 127.319773 -379.121704) (xy 127.323496 -379.134976) (xy 127.326898 -379.140974)
			(xy 127.343275 -379.169308) (xy 127.369013 -379.22948) (xy 127.386434 -379.292565) (xy 127.395221 -379.357418)
			(xy 127.395215 -379.422864) (xy 127.386417 -379.487716) (xy 127.368986 -379.550797) (xy 127.343237 -379.610965)
			(xy 127.326898 -379.639322) (xy 127.32353 -379.645335) (xy 127.319796 -379.658597) (xy 127.319532 -379.665484)
			(xy 127.319532 -380.414784) (xy 127.319767 -380.421675) (xy 127.323508 -380.434941) (xy 127.326898 -380.440946)
			(xy 127.343251 -380.469293) (xy 127.368992 -380.529462) (xy 127.386415 -380.592544) (xy 127.395205 -380.657395)
			(xy 127.395205 -380.657397) (xy 130.825024 -380.657397) (xy 130.833814 -380.592548) (xy 130.851237 -380.529469)
			(xy 130.876977 -380.469302) (xy 130.893312 -380.440946) (xy 130.896611 -380.434914) (xy 130.900226 -380.421656)
			(xy 130.900424 -380.414784) (xy 130.900424 -379.665484) (xy 130.900235 -379.658611) (xy 130.896624 -379.645348)
			(xy 130.893312 -379.639322) (xy 130.877016 -379.610943) (xy 130.85127 -379.550781) (xy 130.83384 -379.487706)
			(xy 130.825042 -379.422861) (xy 130.825037 -379.357421) (xy 130.833823 -379.292575) (xy 130.851243 -379.229496)
			(xy 130.876979 -379.16933) (xy 130.893312 -379.140974) (xy 130.896637 -379.134954) (xy 130.900236 -379.121687)
			(xy 130.900424 -379.114812) (xy 130.900424 -378.828554) (xy 130.900895 -378.818395) (xy 130.908682 -378.799628)
			(xy 130.923054 -378.785264) (xy 130.941827 -378.777489) (xy 130.951986 -378.776992) (xy 131.668266 -378.776992)
			(xy 131.678416 -378.77756) (xy 131.697175 -378.785315) (xy 131.71154 -378.799657) (xy 131.719324 -378.818405)
			(xy 131.719828 -378.828554) (xy 131.719828 -379.114812) (xy 131.720012 -379.121686) (xy 131.723625 -379.134949)
			(xy 131.72694 -379.140974) (xy 131.743319 -379.169307) (xy 131.76906 -379.229479) (xy 131.786483 -379.292564)
			(xy 131.795271 -379.357418) (xy 131.795265 -379.422864) (xy 131.786466 -379.487717) (xy 131.769033 -379.550799)
			(xy 131.752235 -379.590046) (xy 133.023872 -379.590046) (xy 133.027863 -379.527879) (xy 133.039772 -379.466732)
			(xy 133.059401 -379.407611) (xy 133.08643 -379.351485) (xy 133.120414 -379.299276) (xy 133.160796 -379.251841)
			(xy 133.206912 -379.20996) (xy 133.258004 -379.17432) (xy 133.313235 -379.145506) (xy 133.371697 -379.123992)
			(xy 133.432431 -379.11013) (xy 133.494438 -379.104148) (xy 133.556701 -379.106144) (xy 133.618198 -379.116087)
			(xy 133.677919 -379.133811) (xy 133.734882 -379.159028) (xy 133.788153 -379.191321) (xy 133.836858 -379.230161)
			(xy 133.880195 -379.274911) (xy 133.917455 -379.324835) (xy 133.948024 -379.379114) (xy 133.952491 -379.390148)
			(xy 135.22402 -379.390148) (xy 135.228011 -379.327981) (xy 135.23992 -379.266834) (xy 135.259549 -379.207713)
			(xy 135.286578 -379.151587) (xy 135.320562 -379.099378) (xy 135.360944 -379.051943) (xy 135.40706 -379.010062)
			(xy 135.458152 -378.974422) (xy 135.513383 -378.945608) (xy 135.571845 -378.924094) (xy 135.632579 -378.910232)
			(xy 135.694586 -378.90425) (xy 135.756849 -378.906246) (xy 135.818346 -378.916189) (xy 135.878067 -378.933913)
			(xy 135.93503 -378.95913) (xy 135.988301 -378.991423) (xy 136.037006 -379.030263) (xy 136.080343 -379.075013)
			(xy 136.117603 -379.124937) (xy 136.148172 -379.179216) (xy 136.17155 -379.236959) (xy 136.187351 -379.297217)
			(xy 136.195317 -379.359) (xy 136.195816 -379.390148) (xy 136.195317 -379.421296) (xy 136.187351 -379.483079)
			(xy 136.17155 -379.543337) (xy 136.148172 -379.60108) (xy 136.117603 -379.655359) (xy 136.080343 -379.705283)
			(xy 136.037006 -379.750033) (xy 135.988301 -379.788873) (xy 135.93503 -379.821166) (xy 135.878067 -379.846383)
			(xy 135.818346 -379.864107) (xy 135.756849 -379.87405) (xy 135.694586 -379.876046) (xy 135.632579 -379.870064)
			(xy 135.571845 -379.856202) (xy 135.513383 -379.834688) (xy 135.458152 -379.805874) (xy 135.40706 -379.770234)
			(xy 135.360944 -379.728353) (xy 135.320562 -379.680918) (xy 135.286578 -379.628709) (xy 135.259549 -379.572583)
			(xy 135.23992 -379.513462) (xy 135.228011 -379.452315) (xy 135.22402 -379.390148) (xy 133.952491 -379.390148)
			(xy 133.971402 -379.436857) (xy 133.987203 -379.497115) (xy 133.995169 -379.558898) (xy 133.995668 -379.590046)
			(xy 133.995169 -379.621194) (xy 133.987203 -379.682977) (xy 133.971402 -379.743235) (xy 133.948024 -379.800978)
			(xy 133.917455 -379.855257) (xy 133.880195 -379.905181) (xy 133.836858 -379.949931) (xy 133.788153 -379.988771)
			(xy 133.734882 -380.021064) (xy 133.677919 -380.046281) (xy 133.618198 -380.064005) (xy 133.556701 -380.073948)
			(xy 133.494438 -380.075944) (xy 133.432431 -380.069962) (xy 133.371697 -380.0561) (xy 133.313235 -380.034586)
			(xy 133.258004 -380.005772) (xy 133.206912 -379.970132) (xy 133.160796 -379.928251) (xy 133.120414 -379.880816)
			(xy 133.08643 -379.828607) (xy 133.059401 -379.772481) (xy 133.039772 -379.71336) (xy 133.027863 -379.652213)
			(xy 133.023872 -379.590046) (xy 131.752235 -379.590046) (xy 131.743281 -379.610966) (xy 131.72694 -379.639322)
			(xy 131.723621 -379.645344) (xy 131.720018 -379.65861) (xy 131.719828 -379.665484) (xy 131.719828 -380.414784)
			(xy 131.720023 -380.421657) (xy 131.723629 -380.43492) (xy 131.72694 -380.440946) (xy 131.743295 -380.469293)
			(xy 131.769038 -380.529461) (xy 131.786464 -380.592543) (xy 131.795255 -380.657395) (xy 131.795254 -380.69012)
			(xy 135.22402 -380.69012) (xy 135.228011 -380.627953) (xy 135.23992 -380.566806) (xy 135.259549 -380.507685)
			(xy 135.286578 -380.451559) (xy 135.320562 -380.39935) (xy 135.360944 -380.351915) (xy 135.40706 -380.310034)
			(xy 135.458152 -380.274394) (xy 135.513383 -380.24558) (xy 135.571845 -380.224066) (xy 135.632579 -380.210204)
			(xy 135.694586 -380.204222) (xy 135.756849 -380.206218) (xy 135.818346 -380.216161) (xy 135.878067 -380.233885)
			(xy 135.93503 -380.259102) (xy 135.988301 -380.291395) (xy 136.037006 -380.330235) (xy 136.080343 -380.374985)
			(xy 136.117603 -380.424909) (xy 136.148172 -380.479188) (xy 136.17155 -380.536931) (xy 136.187351 -380.597189)
			(xy 136.195317 -380.658972) (xy 136.195816 -380.69012) (xy 136.195317 -380.721268) (xy 136.187351 -380.783051)
			(xy 136.17155 -380.843309) (xy 136.148172 -380.901052) (xy 136.117603 -380.955331) (xy 136.080343 -381.005255)
			(xy 136.037006 -381.050005) (xy 135.988301 -381.088845) (xy 135.93503 -381.121138) (xy 135.878067 -381.146355)
			(xy 135.818346 -381.164079) (xy 135.756849 -381.174022) (xy 135.694586 -381.176018) (xy 135.632579 -381.170036)
			(xy 135.571845 -381.156174) (xy 135.513383 -381.13466) (xy 135.458152 -381.105846) (xy 135.40706 -381.070206)
			(xy 135.360944 -381.028325) (xy 135.320562 -380.98089) (xy 135.286578 -380.928681) (xy 135.259549 -380.872555)
			(xy 135.23992 -380.813434) (xy 135.228011 -380.752287) (xy 135.22402 -380.69012) (xy 131.795254 -380.69012)
			(xy 131.795253 -380.722839) (xy 131.786457 -380.78769) (xy 131.769027 -380.850771) (xy 131.743279 -380.910938)
			(xy 131.72694 -380.939294) (xy 131.723631 -380.945321) (xy 131.720021 -380.958583) (xy 131.719828 -380.965456)
			(xy 131.719828 -381.251206) (xy 131.71944 -381.261382) (xy 131.711647 -381.280184) (xy 131.69725 -381.294569)
			(xy 131.678443 -381.302348) (xy 131.668266 -381.302768) (xy 130.951986 -381.302768) (xy 130.941828 -381.302278)
			(xy 130.92306 -381.2945) (xy 130.908695 -381.280133) (xy 130.90092 -381.261364) (xy 130.900424 -381.251206)
			(xy 130.900424 -380.965456) (xy 130.900208 -380.958585) (xy 130.896616 -380.945322) (xy 130.893312 -380.939294)
			(xy 130.876992 -380.910928) (xy 130.851248 -380.850763) (xy 130.833821 -380.787685) (xy 130.825027 -380.722838)
			(xy 130.825024 -380.657397) (xy 127.395205 -380.657397) (xy 127.395203 -380.722839) (xy 127.386408 -380.787689)
			(xy 127.36898 -380.85077) (xy 127.343236 -380.910937) (xy 127.326898 -380.939294) (xy 127.32354 -380.945312)
			(xy 127.3198 -380.95857) (xy 127.319532 -380.965456) (xy 127.319532 -381.251206) (xy 127.319077 -381.261337)
			(xy 127.311342 -381.280063) (xy 127.297046 -381.29442) (xy 127.278352 -381.302234) (xy 127.268224 -381.302768)
			(xy 126.551944 -381.302768) (xy 126.541789 -381.302342) (xy 126.523031 -381.294555) (xy 126.508705 -381.280159)
			(xy 126.50101 -381.261363) (xy 126.500636 -381.251206) (xy 126.500636 -380.965456) (xy 126.500412 -380.958562)
			(xy 126.496678 -380.94529) (xy 126.49327 -380.939294) (xy 126.476949 -380.910929) (xy 126.451202 -380.850765)
			(xy 126.433772 -380.787686) (xy 126.424976 -380.722838) (xy 126.424974 -380.657396) (xy 122.995169 -380.657396)
			(xy 122.995166 -380.722839) (xy 122.986371 -380.78769) (xy 122.968942 -380.850771) (xy 122.943195 -380.910938)
			(xy 122.926856 -380.939294) (xy 122.923548 -380.945322) (xy 122.919937 -380.958583) (xy 122.919744 -380.965456)
			(xy 122.919744 -381.251206) (xy 122.919341 -381.26138) (xy 122.91155 -381.280178) (xy 122.897158 -381.294564)
			(xy 122.878356 -381.302345) (xy 122.868182 -381.302768) (xy 122.151902 -381.302768) (xy 122.141745 -381.302265)
			(xy 122.122977 -381.294492) (xy 122.108612 -381.28013) (xy 122.100836 -381.261363) (xy 122.10034 -381.251206)
			(xy 122.10034 -380.965456) (xy 122.100122 -380.958585) (xy 122.096531 -380.945322) (xy 122.093228 -380.939294)
			(xy 122.076908 -380.910928) (xy 122.051163 -380.850764) (xy 122.033735 -380.787686) (xy 122.02494 -380.722838)
			(xy 122.024938 -380.657396) (xy 118.595133 -380.657396) (xy 118.59513 -380.72284) (xy 118.586334 -380.787691)
			(xy 118.568903 -380.850772) (xy 118.543154 -380.910938) (xy 118.526814 -380.939294) (xy 118.523457 -380.945313)
			(xy 118.519716 -380.95857) (xy 118.519448 -380.965456) (xy 118.519448 -381.251206) (xy 118.518978 -381.261335)
			(xy 118.511246 -381.280058) (xy 118.496954 -381.294415) (xy 118.478266 -381.302231) (xy 118.46814 -381.302768)
			(xy 117.75186 -381.302768) (xy 117.741699 -381.30241) (xy 117.72294 -381.294596) (xy 117.708617 -381.280179)
			(xy 117.700924 -381.261369) (xy 117.700552 -381.251206) (xy 117.700552 -380.965456) (xy 117.700326 -380.958563)
			(xy 117.696593 -380.945291) (xy 117.693186 -380.939294) (xy 117.676864 -380.910929) (xy 117.651116 -380.850765)
			(xy 117.633686 -380.787687) (xy 117.62489 -380.722838) (xy 117.624888 -380.657396) (xy 105.919524 -380.657396)
			(xy 105.919524 -380.877572) (xy 105.919034 -380.907556) (xy 105.911206 -380.967012) (xy 105.895685 -381.024937)
			(xy 105.872736 -381.080341) (xy 105.842752 -381.132275) (xy 105.806246 -381.179851) (xy 105.763841 -381.222256)
			(xy 105.716265 -381.258762) (xy 105.664331 -381.288746) (xy 105.608927 -381.311695) (xy 105.551002 -381.327216)
			(xy 105.491546 -381.335044) (xy 105.431578 -381.335044) (xy 105.372122 -381.327216) (xy 105.314197 -381.311695)
			(xy 105.258793 -381.288746) (xy 105.206859 -381.258762) (xy 105.159283 -381.222256) (xy 105.116878 -381.179851)
			(xy 105.080372 -381.132275) (xy 105.050388 -381.080341) (xy 105.027439 -381.024937) (xy 105.011918 -380.967012)
			(xy 105.00409 -380.907556) (xy 105.0036 -380.877572) (xy 101.388498 -380.877572) (xy 101.415315 -380.885449)
			(xy 101.464922 -380.908108) (xy 101.5108 -380.937596) (xy 101.552015 -380.973312) (xy 101.587727 -381.01453)
			(xy 101.61721 -381.060411) (xy 101.639865 -381.110021) (xy 101.655229 -381.162349) (xy 101.66299 -381.216331)
			(xy 101.66299 -381.270869) (xy 101.655229 -381.324851) (xy 101.639865 -381.377179) (xy 101.61721 -381.426789)
			(xy 101.587727 -381.47267) (xy 101.552015 -381.513888) (xy 101.5108 -381.549604) (xy 101.464922 -381.579092)
			(xy 101.415315 -381.601751) (xy 101.362988 -381.617121) (xy 101.309007 -381.624887) (xy 101.281738 -381.625348)
			(xy 101.252447 -381.624817) (xy 101.194551 -381.615873) (xy 101.138701 -381.598189) (xy 101.086209 -381.572181)
			(xy 101.038306 -381.538458) (xy 100.996117 -381.497814) (xy 100.960632 -381.4512) (xy 100.946204 -381.425704)
			(xy 100.939145 -381.413764) (xy 100.919789 -381.393913) (xy 100.895803 -381.380007) (xy 100.868959 -381.373072)
			(xy 100.841239 -381.373621) (xy 100.81469 -381.381613) (xy 100.791274 -381.396458) (xy 100.772719 -381.41706)
			(xy 100.766118 -381.42926) (xy 100.752886 -381.454784) (xy 100.719919 -381.501882) (xy 100.68026 -381.543502)
			(xy 100.634807 -381.578702) (xy 100.584587 -381.606685) (xy 100.557838 -381.61722) (xy 100.550726 -381.61976)
			(xy 100.539042 -381.62865) (xy 100.518468 -381.656336) (xy 100.514149 -381.662796) (xy 100.509237 -381.677532)
			(xy 100.508816 -381.685292) (xy 100.496745 -382.222714) (xy 115.424978 -382.222714) (xy 115.424979 -382.157269)
			(xy 115.433775 -382.092419) (xy 115.451204 -382.029338) (xy 115.476952 -381.969172) (xy 115.493292 -381.940816)
			(xy 115.4966 -381.934788) (xy 115.50021 -381.921527) (xy 115.500404 -381.914654) (xy 115.500404 -381.628904)
			(xy 115.500825 -381.61875) (xy 115.50862 -381.599997) (xy 115.523017 -381.585673) (xy 115.54181 -381.577974)
			(xy 115.551966 -381.577596) (xy 116.268246 -381.577596) (xy 116.27837 -381.578088) (xy 116.297084 -381.585822)
			(xy 116.311437 -381.600106) (xy 116.319262 -381.618782) (xy 116.319808 -381.628904) (xy 116.319808 -381.914654)
			(xy 116.320017 -381.921526) (xy 116.323613 -381.934789) (xy 116.32692 -381.940816) (xy 116.34325 -381.969176)
			(xy 116.368997 -382.029342) (xy 116.386426 -382.092421) (xy 116.395221 -382.15727) (xy 116.395222 -382.222713)
			(xy 119.825028 -382.222713) (xy 119.82503 -382.15727) (xy 119.833824 -382.09242) (xy 119.851251 -382.029339)
			(xy 119.876996 -381.969172) (xy 119.893334 -381.940816) (xy 119.896691 -381.934797) (xy 119.900431 -381.92154)
			(xy 119.9007 -381.914654) (xy 119.9007 -381.628904) (xy 119.901119 -381.618782) (xy 119.908866 -381.600078)
			(xy 119.923182 -381.585764) (xy 119.941886 -381.578019) (xy 119.952008 -381.577596) (xy 120.668288 -381.577596)
			(xy 120.678409 -381.578026) (xy 120.697112 -381.585769) (xy 120.711426 -381.600081) (xy 120.719173 -381.618783)
			(xy 120.719596 -381.628904) (xy 120.719596 -381.914654) (xy 120.719848 -381.921544) (xy 120.723577 -381.93481)
			(xy 120.726962 -381.940816) (xy 120.743291 -381.969177) (xy 120.769035 -382.029342) (xy 120.786463 -382.092422)
			(xy 120.795257 -382.15727) (xy 120.795258 -382.222713) (xy 124.225064 -382.222713) (xy 124.225066 -382.157269)
			(xy 124.233861 -382.092419) (xy 124.25129 -382.029338) (xy 124.277037 -381.969172) (xy 124.293376 -381.940816)
			(xy 124.296683 -381.934788) (xy 124.300294 -381.921527) (xy 124.300488 -381.914654) (xy 124.300488 -381.628904)
			(xy 124.300925 -381.618752) (xy 124.308717 -381.600002) (xy 124.323109 -381.585679) (xy 124.341896 -381.577977)
			(xy 124.35205 -381.577596) (xy 125.06833 -381.577596) (xy 125.078453 -381.578101) (xy 125.097167 -381.58583)
			(xy 125.11152 -381.60011) (xy 125.119346 -381.618783) (xy 125.119892 -381.628904) (xy 125.119892 -381.914654)
			(xy 125.120103 -381.921526) (xy 125.123698 -381.934789) (xy 125.127004 -381.940816) (xy 125.143332 -381.969177)
			(xy 125.169074 -382.029343) (xy 125.1865 -382.092422) (xy 125.195293 -382.157271) (xy 125.195294 -382.222712)
			(xy 125.195294 -382.222713) (xy 128.624854 -382.222713) (xy 128.624855 -382.157269) (xy 128.63365 -382.092419)
			(xy 128.651079 -382.029339) (xy 128.676825 -381.969172) (xy 128.693164 -381.940816) (xy 128.69647 -381.934787)
			(xy 128.700082 -381.921527) (xy 128.700276 -381.914654) (xy 128.700276 -381.628904) (xy 128.700724 -381.618753)
			(xy 128.708514 -381.600005) (xy 128.722902 -381.585683) (xy 128.741685 -381.577979) (xy 128.751838 -381.577596)
			(xy 129.468118 -381.577596) (xy 129.47824 -381.57811) (xy 129.496954 -381.585836) (xy 129.511308 -381.600113)
			(xy 129.519134 -381.618784) (xy 129.51968 -381.628904) (xy 129.51968 -381.914654) (xy 129.519892 -381.921526)
			(xy 129.523487 -381.934788) (xy 129.526792 -381.940816) (xy 129.54312 -381.969177) (xy 129.568863 -382.029343)
			(xy 129.586289 -382.092422) (xy 129.595083 -382.15727) (xy 129.595083 -382.18999) (xy 133.023872 -382.18999)
			(xy 133.027863 -382.127823) (xy 133.039772 -382.066676) (xy 133.059401 -382.007555) (xy 133.08643 -381.951429)
			(xy 133.120414 -381.89922) (xy 133.160796 -381.851785) (xy 133.206912 -381.809904) (xy 133.258004 -381.774264)
			(xy 133.313235 -381.74545) (xy 133.371697 -381.723936) (xy 133.432431 -381.710074) (xy 133.494438 -381.704092)
			(xy 133.556701 -381.706088) (xy 133.618198 -381.716031) (xy 133.677919 -381.733755) (xy 133.734882 -381.758972)
			(xy 133.788153 -381.791265) (xy 133.836858 -381.830105) (xy 133.880195 -381.874855) (xy 133.917455 -381.924779)
			(xy 133.948024 -381.979058) (xy 133.971402 -382.036801) (xy 133.987203 -382.097059) (xy 133.995169 -382.158842)
			(xy 133.995668 -382.18999) (xy 133.995169 -382.221138) (xy 133.987203 -382.282921) (xy 133.971402 -382.343179)
			(xy 133.948024 -382.400922) (xy 133.917455 -382.455201) (xy 133.880195 -382.505125) (xy 133.836858 -382.549875)
			(xy 133.788153 -382.588715) (xy 133.734882 -382.621008) (xy 133.677919 -382.646225) (xy 133.618198 -382.663949)
			(xy 133.556701 -382.673892) (xy 133.494438 -382.675888) (xy 133.432431 -382.669906) (xy 133.371697 -382.656044)
			(xy 133.313235 -382.63453) (xy 133.258004 -382.605716) (xy 133.206912 -382.570076) (xy 133.160796 -382.528195)
			(xy 133.120414 -382.48076) (xy 133.08643 -382.428551) (xy 133.059401 -382.372425) (xy 133.039772 -382.313304)
			(xy 133.027863 -382.252157) (xy 133.023872 -382.18999) (xy 129.595083 -382.18999) (xy 129.595084 -382.222712)
			(xy 129.586293 -382.287561) (xy 129.568869 -382.350641) (xy 129.543128 -382.410808) (xy 129.526792 -382.439164)
			(xy 129.523489 -382.445195) (xy 129.519876 -382.458454) (xy 129.51968 -382.465326) (xy 129.51968 -383.21488)
			(xy 129.519882 -383.221752) (xy 129.523484 -383.235015) (xy 129.526792 -383.241042) (xy 129.543142 -383.269391)
			(xy 129.565988 -383.322792) (xy 130.824995 -383.322792) (xy 130.824999 -383.257347) (xy 130.833796 -383.192495)
			(xy 130.851226 -383.129414) (xy 130.876973 -383.069247) (xy 130.893312 -383.04089) (xy 130.896631 -383.034868)
			(xy 130.900234 -383.021602) (xy 130.900424 -383.014728) (xy 130.900424 -382.728724) (xy 130.900842 -382.718568)
			(xy 130.908634 -382.699812) (xy 130.923032 -382.685487) (xy 130.941828 -382.67779) (xy 130.951986 -382.677416)
			(xy 131.668266 -382.677416) (xy 131.678388 -382.677954) (xy 131.697103 -382.685666) (xy 131.71146 -382.699937)
			(xy 131.719284 -382.718606) (xy 131.719828 -382.728724) (xy 131.719828 -383.014728) (xy 131.720005 -383.021602)
			(xy 131.723623 -383.034865) (xy 131.72694 -383.04089) (xy 131.743248 -383.069263) (xy 131.768995 -383.129425)
			(xy 131.786426 -383.192502) (xy 131.795223 -383.257349) (xy 131.795227 -383.32279) (xy 131.786438 -383.387637)
			(xy 131.769016 -383.450716) (xy 131.752117 -383.490216) (xy 133.023872 -383.490216) (xy 133.027863 -383.428049)
			(xy 133.039772 -383.366902) (xy 133.059401 -383.307781) (xy 133.08643 -383.251655) (xy 133.120414 -383.199446)
			(xy 133.160796 -383.152011) (xy 133.206912 -383.11013) (xy 133.258004 -383.07449) (xy 133.313235 -383.045676)
			(xy 133.371697 -383.024162) (xy 133.432431 -383.0103) (xy 133.494438 -383.004318) (xy 133.556701 -383.006314)
			(xy 133.618198 -383.016257) (xy 133.677919 -383.033981) (xy 133.734882 -383.059198) (xy 133.788153 -383.091491)
			(xy 133.836858 -383.130331) (xy 133.880195 -383.175081) (xy 133.917455 -383.225005) (xy 133.948024 -383.279284)
			(xy 133.952388 -383.290064) (xy 135.22402 -383.290064) (xy 135.228011 -383.227897) (xy 135.23992 -383.16675)
			(xy 135.259549 -383.107629) (xy 135.286578 -383.051503) (xy 135.320562 -382.999294) (xy 135.360944 -382.951859)
			(xy 135.40706 -382.909978) (xy 135.458152 -382.874338) (xy 135.513383 -382.845524) (xy 135.571845 -382.82401)
			(xy 135.632579 -382.810148) (xy 135.694586 -382.804166) (xy 135.756849 -382.806162) (xy 135.818346 -382.816105)
			(xy 135.878067 -382.833829) (xy 135.93503 -382.859046) (xy 135.988301 -382.891339) (xy 136.037006 -382.930179)
			(xy 136.080343 -382.974929) (xy 136.117603 -383.024853) (xy 136.148172 -383.079132) (xy 136.17155 -383.136875)
			(xy 136.187351 -383.197133) (xy 136.195317 -383.258916) (xy 136.195816 -383.290064) (xy 136.195317 -383.321212)
			(xy 136.187351 -383.382995) (xy 136.17155 -383.443253) (xy 136.148172 -383.500996) (xy 136.117603 -383.555275)
			(xy 136.080343 -383.605199) (xy 136.037006 -383.649949) (xy 135.988301 -383.688789) (xy 135.93503 -383.721082)
			(xy 135.878067 -383.746299) (xy 135.818346 -383.764023) (xy 135.756849 -383.773966) (xy 135.694586 -383.775962)
			(xy 135.632579 -383.76998) (xy 135.571845 -383.756118) (xy 135.513383 -383.734604) (xy 135.458152 -383.70579)
			(xy 135.40706 -383.67015) (xy 135.360944 -383.628269) (xy 135.320562 -383.580834) (xy 135.286578 -383.528625)
			(xy 135.259549 -383.472499) (xy 135.23992 -383.413378) (xy 135.228011 -383.352231) (xy 135.22402 -383.290064)
			(xy 133.952388 -383.290064) (xy 133.971402 -383.337027) (xy 133.987203 -383.397285) (xy 133.995169 -383.459068)
			(xy 133.995668 -383.490216) (xy 133.995169 -383.521364) (xy 133.987203 -383.583147) (xy 133.971402 -383.643405)
			(xy 133.948024 -383.701148) (xy 133.917455 -383.755427) (xy 133.880195 -383.805351) (xy 133.836858 -383.850101)
			(xy 133.788153 -383.888941) (xy 133.734882 -383.921234) (xy 133.677919 -383.946451) (xy 133.618198 -383.964175)
			(xy 133.556701 -383.974118) (xy 133.494438 -383.976114) (xy 133.432431 -383.970132) (xy 133.371697 -383.95627)
			(xy 133.313235 -383.934756) (xy 133.258004 -383.905942) (xy 133.206912 -383.870302) (xy 133.160796 -383.828421)
			(xy 133.120414 -383.780986) (xy 133.08643 -383.728777) (xy 133.059401 -383.672651) (xy 133.039772 -383.61353)
			(xy 133.027863 -383.552383) (xy 133.023872 -383.490216) (xy 131.752117 -383.490216) (xy 131.743276 -383.510882)
			(xy 131.72694 -383.539238) (xy 131.723615 -383.545258) (xy 131.720015 -383.558525) (xy 131.719828 -383.5654)
			(xy 131.719828 -384.3147) (xy 131.720017 -384.321574) (xy 131.723627 -384.334836) (xy 131.72694 -384.340862)
			(xy 131.743309 -384.369201) (xy 131.769051 -384.429372) (xy 131.786475 -384.492455) (xy 131.795264 -384.557308)
			(xy 131.795262 -384.590036) (xy 135.22402 -384.590036) (xy 135.228011 -384.527869) (xy 135.23992 -384.466722)
			(xy 135.259549 -384.407601) (xy 135.286578 -384.351475) (xy 135.320562 -384.299266) (xy 135.360944 -384.251831)
			(xy 135.40706 -384.20995) (xy 135.458152 -384.17431) (xy 135.513383 -384.145496) (xy 135.571845 -384.123982)
			(xy 135.632579 -384.11012) (xy 135.694586 -384.104138) (xy 135.756849 -384.106134) (xy 135.818346 -384.116077)
			(xy 135.878067 -384.133801) (xy 135.93503 -384.159018) (xy 135.988301 -384.191311) (xy 136.037006 -384.230151)
			(xy 136.080343 -384.274901) (xy 136.117603 -384.324825) (xy 136.148172 -384.379104) (xy 136.17155 -384.436847)
			(xy 136.187351 -384.497105) (xy 136.195317 -384.558888) (xy 136.195816 -384.590036) (xy 136.195317 -384.621184)
			(xy 136.187351 -384.682967) (xy 136.17155 -384.743225) (xy 136.148172 -384.800968) (xy 136.117603 -384.855247)
			(xy 136.080343 -384.905171) (xy 136.037006 -384.949921) (xy 135.988301 -384.988761) (xy 135.93503 -385.021054)
			(xy 135.878067 -385.046271) (xy 135.818346 -385.063995) (xy 135.756849 -385.073938) (xy 135.694586 -385.075934)
			(xy 135.632579 -385.069952) (xy 135.571845 -385.05609) (xy 135.513383 -385.034576) (xy 135.458152 -385.005762)
			(xy 135.40706 -384.970122) (xy 135.360944 -384.928241) (xy 135.320562 -384.880806) (xy 135.286578 -384.828597)
			(xy 135.259549 -384.772471) (xy 135.23992 -384.71335) (xy 135.228011 -384.652203) (xy 135.22402 -384.590036)
			(xy 131.795262 -384.590036) (xy 131.79526 -384.622754) (xy 131.786462 -384.687605) (xy 131.76903 -384.750687)
			(xy 131.74328 -384.810854) (xy 131.72694 -384.83921) (xy 131.723625 -384.845235) (xy 131.720019 -384.858498)
			(xy 131.719828 -384.865372) (xy 131.719828 -385.151376) (xy 131.719359 -385.161525) (xy 131.711577 -385.180272)
			(xy 131.697195 -385.194595) (xy 131.678417 -385.202301) (xy 131.668266 -385.202684) (xy 130.951986 -385.202684)
			(xy 130.941861 -385.202185) (xy 130.923145 -385.194457) (xy 130.90879 -385.180175) (xy 130.900967 -385.161498)
			(xy 130.900424 -385.151376) (xy 130.900424 -384.865372) (xy 130.90024 -384.858498) (xy 130.896626 -384.845236)
			(xy 130.893312 -384.83921) (xy 130.877006 -384.810837) (xy 130.851261 -384.750674) (xy 130.833832 -384.687597)
			(xy 130.825036 -384.622751) (xy 130.825031 -384.557311) (xy 130.833819 -384.492463) (xy 130.85124 -384.429385)
			(xy 130.876978 -384.369218) (xy 130.893312 -384.340862) (xy 130.896641 -384.334844) (xy 130.900237 -384.321575)
			(xy 130.900424 -384.3147) (xy 130.900424 -383.5654) (xy 130.900229 -383.558527) (xy 130.896623 -383.545264)
			(xy 130.893312 -383.539238) (xy 130.876945 -383.510898) (xy 130.851205 -383.450728) (xy 130.833783 -383.387644)
			(xy 130.824995 -383.322792) (xy 129.565988 -383.322792) (xy 129.568883 -383.32956) (xy 129.586307 -383.392641)
			(xy 129.595097 -383.457492) (xy 129.595096 -383.522936) (xy 129.586301 -383.587786) (xy 129.568874 -383.650866)
			(xy 129.543129 -383.711033) (xy 129.526792 -383.73939) (xy 129.52348 -383.745416) (xy 129.519873 -383.758679)
			(xy 129.51968 -383.765552) (xy 129.51968 -384.051556) (xy 129.519242 -384.06171) (xy 129.511457 -384.080465)
			(xy 129.497065 -384.094791) (xy 129.478274 -384.102488) (xy 129.468118 -384.102864) (xy 128.751838 -384.102864)
			(xy 128.741714 -384.102342) (xy 128.722995 -384.094628) (xy 128.708637 -384.080352) (xy 128.700816 -384.061677)
			(xy 128.700276 -384.051556) (xy 128.700276 -383.765552) (xy 128.700067 -383.75868) (xy 128.696471 -383.745417)
			(xy 128.693164 -383.73939) (xy 128.676839 -383.711027) (xy 128.651093 -383.650862) (xy 128.633664 -383.587783)
			(xy 128.624869 -383.522935) (xy 128.624867 -383.457493) (xy 128.633659 -383.392644) (xy 128.651084 -383.329564)
			(xy 128.676827 -383.269398) (xy 128.693164 -383.241042) (xy 128.696461 -383.235009) (xy 128.700078 -383.221752)
			(xy 128.700276 -383.21488) (xy 128.700276 -382.465326) (xy 128.700077 -382.458453) (xy 128.696474 -382.44519)
			(xy 128.693164 -382.439164) (xy 128.676817 -382.410813) (xy 128.651073 -382.350645) (xy 128.633647 -382.287564)
			(xy 128.624854 -382.222713) (xy 125.195294 -382.222713) (xy 125.186503 -382.287561) (xy 125.16908 -382.35064)
			(xy 125.143339 -382.410807) (xy 125.127004 -382.439164) (xy 125.123702 -382.445195) (xy 125.120088 -382.458454)
			(xy 125.119892 -382.465326) (xy 125.119892 -383.21488) (xy 125.120092 -383.221753) (xy 125.123695 -383.235015)
			(xy 125.127004 -383.241042) (xy 125.143354 -383.269391) (xy 125.166199 -383.322792) (xy 126.424945 -383.322792)
			(xy 126.424949 -383.257346) (xy 126.433747 -383.192494) (xy 126.451179 -383.129413) (xy 126.476929 -383.069246)
			(xy 126.49327 -383.04089) (xy 126.496639 -383.034878) (xy 126.500371 -383.021615) (xy 126.500636 -383.014728)
			(xy 126.500636 -382.728724) (xy 126.501036 -382.718599) (xy 126.508783 -382.699889) (xy 126.523105 -382.685572)
			(xy 126.541818 -382.677832) (xy 126.551944 -382.677416) (xy 127.268224 -382.677416) (xy 127.278336 -382.677866)
			(xy 127.297018 -382.685614) (xy 127.311313 -382.699922) (xy 127.319044 -382.718611) (xy 127.319532 -382.728724)
			(xy 127.319532 -383.014728) (xy 127.319767 -383.021621) (xy 127.323494 -383.034893) (xy 127.326898 -383.04089)
			(xy 127.343204 -383.069263) (xy 127.368948 -383.129427) (xy 127.386377 -383.192503) (xy 127.395173 -383.257349)
			(xy 127.395177 -383.322789) (xy 127.386389 -383.387636) (xy 127.368969 -383.450715) (xy 127.343232 -383.510881)
			(xy 127.326898 -383.539238) (xy 127.323524 -383.545248) (xy 127.319794 -383.558512) (xy 127.319532 -383.5654)
			(xy 127.319532 -384.3147) (xy 127.319761 -384.321592) (xy 127.323506 -384.334858) (xy 127.326898 -384.340862)
			(xy 127.343265 -384.369202) (xy 127.369004 -384.429373) (xy 127.386426 -384.492456) (xy 127.395214 -384.557308)
			(xy 127.39521 -384.622753) (xy 127.386413 -384.687604) (xy 127.368983 -384.750686) (xy 127.343237 -384.810853)
			(xy 127.326898 -384.83921) (xy 127.323534 -384.845225) (xy 127.319798 -384.858485) (xy 127.319532 -384.865372)
			(xy 127.319532 -385.151376) (xy 127.318996 -385.161479) (xy 127.311272 -385.180151) (xy 127.296991 -385.194445)
			(xy 127.278327 -385.202187) (xy 127.268224 -385.202684) (xy 126.551944 -385.202684) (xy 126.541822 -385.202247)
			(xy 126.523117 -385.194511) (xy 126.5088 -385.1802) (xy 126.501056 -385.161497) (xy 126.500636 -385.151376)
			(xy 126.500636 -384.865372) (xy 126.500405 -384.858479) (xy 126.496675 -384.845207) (xy 126.49327 -384.83921)
			(xy 126.476962 -384.810837) (xy 126.451214 -384.750675) (xy 126.433783 -384.687598) (xy 126.424986 -384.622751)
			(xy 126.424981 -384.55731) (xy 126.43377 -384.492462) (xy 126.451193 -384.429384) (xy 126.476934 -384.369218)
			(xy 126.49327 -384.340862) (xy 126.496649 -384.334854) (xy 126.500375 -384.321588) (xy 126.500636 -384.3147)
			(xy 126.500636 -383.5654) (xy 126.500433 -383.558505) (xy 126.496684 -383.545233) (xy 126.49327 -383.539238)
			(xy 126.476901 -383.510899) (xy 126.451158 -383.450729) (xy 126.433734 -383.387645) (xy 126.424945 -383.322792)
			(xy 125.166199 -383.322792) (xy 125.169094 -383.32956) (xy 125.186517 -383.392642) (xy 125.195308 -383.457492)
			(xy 125.195306 -383.522935) (xy 125.186512 -383.587785) (xy 125.169085 -383.650866) (xy 125.143341 -383.711033)
			(xy 125.127004 -383.73939) (xy 125.123693 -383.745417) (xy 125.120085 -383.758679) (xy 125.119892 -383.765552)
			(xy 125.119892 -384.051556) (xy 125.119442 -384.061708) (xy 125.11166 -384.080461) (xy 125.097271 -384.094786)
			(xy 125.078484 -384.102486) (xy 125.06833 -384.102864) (xy 124.35205 -384.102864) (xy 124.341927 -384.102333)
			(xy 124.323208 -384.094622) (xy 124.30885 -384.080349) (xy 124.301028 -384.061676) (xy 124.300488 -384.051556)
			(xy 124.300488 -383.765552) (xy 124.300278 -383.75868) (xy 124.296682 -383.745417) (xy 124.293376 -383.73939)
			(xy 124.277051 -383.711027) (xy 124.251304 -383.650862) (xy 124.233875 -383.587783) (xy 124.225079 -383.522935)
			(xy 124.225077 -383.457493) (xy 124.233869 -383.392643) (xy 124.251295 -383.329564) (xy 124.277039 -383.269398)
			(xy 124.293376 -383.241042) (xy 124.296674 -383.235009) (xy 124.300291 -383.221752) (xy 124.300488 -383.21488)
			(xy 124.300488 -382.465326) (xy 124.300287 -382.458453) (xy 124.296685 -382.445191) (xy 124.293376 -382.439164)
			(xy 124.277029 -382.410813) (xy 124.251284 -382.350645) (xy 124.233857 -382.287564) (xy 124.225064 -382.222713)
			(xy 120.795258 -382.222713) (xy 120.786466 -382.287562) (xy 120.769041 -382.350641) (xy 120.743299 -382.410808)
			(xy 120.726962 -382.439164) (xy 120.723612 -382.445186) (xy 120.719867 -382.458441) (xy 120.719596 -382.465326)
			(xy 120.719596 -383.21488) (xy 120.719838 -383.221771) (xy 120.723574 -383.235037) (xy 120.726962 -383.241042)
			(xy 120.743313 -383.269391) (xy 120.76616 -383.322792) (xy 122.024908 -383.322792) (xy 122.024913 -383.257346)
			(xy 122.03371 -383.192495) (xy 122.05114 -383.129414) (xy 122.076889 -383.069246) (xy 122.093228 -383.04089)
			(xy 122.096548 -383.034868) (xy 122.10015 -383.021602) (xy 122.10034 -383.014728) (xy 122.10034 -382.728724)
			(xy 122.100742 -382.718566) (xy 122.108537 -382.699807) (xy 122.122941 -382.685481) (xy 122.141742 -382.677788)
			(xy 122.151902 -382.677416) (xy 122.868182 -382.677416) (xy 122.878305 -382.677941) (xy 122.897021 -382.685658)
			(xy 122.911377 -382.699932) (xy 122.919201 -382.718604) (xy 122.919744 -382.728724) (xy 122.919744 -383.014728)
			(xy 122.91992 -383.021603) (xy 122.923539 -383.034865) (xy 122.926856 -383.04089) (xy 122.943163 -383.069263)
			(xy 122.96891 -383.129426) (xy 122.98634 -383.192502) (xy 122.995137 -383.257349) (xy 122.995141 -383.322789)
			(xy 122.986352 -383.387637) (xy 122.96893 -383.450716) (xy 122.943191 -383.510882) (xy 122.926856 -383.539238)
			(xy 122.923532 -383.545258) (xy 122.919932 -383.558525) (xy 122.919744 -383.5654) (xy 122.919744 -384.3147)
			(xy 122.919931 -384.321574) (xy 122.923542 -384.334837) (xy 122.926856 -384.340862) (xy 122.943224 -384.369201)
			(xy 122.968965 -384.429372) (xy 122.986389 -384.492455) (xy 122.995178 -384.557308) (xy 122.995174 -384.622754)
			(xy 122.986376 -384.687605) (xy 122.968945 -384.750687) (xy 122.943196 -384.810854) (xy 122.926856 -384.83921)
			(xy 122.923542 -384.845235) (xy 122.919935 -384.858498) (xy 122.919744 -384.865372) (xy 122.919744 -385.151376)
			(xy 122.91926 -385.161523) (xy 122.91148 -385.180267) (xy 122.897103 -385.194589) (xy 122.878331 -385.202298)
			(xy 122.868182 -385.202684) (xy 122.151902 -385.202684) (xy 122.141778 -385.202172) (xy 122.123062 -385.19445)
			(xy 122.108706 -385.180171) (xy 122.100883 -385.161497) (xy 122.10034 -385.151376) (xy 122.10034 -384.865372)
			(xy 122.100154 -384.858498) (xy 122.096541 -384.845236) (xy 122.093228 -384.83921) (xy 122.076921 -384.810837)
			(xy 122.051175 -384.750674) (xy 122.033746 -384.687597) (xy 122.024949 -384.622751) (xy 122.024945 -384.557311)
			(xy 122.033734 -384.492463) (xy 122.051155 -384.429384) (xy 122.076893 -384.369218) (xy 122.093228 -384.340862)
			(xy 122.096558 -384.334845) (xy 122.100154 -384.321575) (xy 122.10034 -384.3147) (xy 122.10034 -383.5654)
			(xy 122.100143 -383.558527) (xy 122.096538 -383.545265) (xy 122.093228 -383.539238) (xy 122.07686 -383.510899)
			(xy 122.05112 -383.450728) (xy 122.033697 -383.387644) (xy 122.024908 -383.322792) (xy 120.76616 -383.322792)
			(xy 120.769055 -383.329559) (xy 120.78648 -383.392641) (xy 120.795272 -383.457492) (xy 120.79527 -383.522936)
			(xy 120.786475 -383.587786) (xy 120.769046 -383.650867) (xy 120.7433 -383.711034) (xy 120.726962 -383.73939)
			(xy 120.723602 -383.745407) (xy 120.719864 -383.758666) (xy 120.719596 -383.765552) (xy 120.719596 -384.051556)
			(xy 120.719148 -384.061676) (xy 120.711413 -384.080379) (xy 120.697106 -384.094695) (xy 120.678408 -384.102441)
			(xy 120.668288 -384.102864) (xy 119.952008 -384.102864) (xy 119.941882 -384.102477) (xy 119.923171 -384.094724)
			(xy 119.908855 -384.080399) (xy 119.901116 -384.061683) (xy 119.9007 -384.051556) (xy 119.9007 -383.765552)
			(xy 119.900447 -383.758662) (xy 119.896718 -383.745396) (xy 119.893334 -383.73939) (xy 119.87701 -383.711026)
			(xy 119.851265 -383.650861) (xy 119.833838 -383.587783) (xy 119.825043 -383.522935) (xy 119.825041 -383.457493)
			(xy 119.833832 -383.392644) (xy 119.851256 -383.329565) (xy 119.876998 -383.269398) (xy 119.893334 -383.241042)
			(xy 119.896717 -383.235036) (xy 119.900441 -383.221769) (xy 119.9007 -383.21488) (xy 119.9007 -382.465326)
			(xy 119.900457 -382.458435) (xy 119.896721 -382.44517) (xy 119.893334 -382.439164) (xy 119.876988 -382.410812)
			(xy 119.851245 -382.350645) (xy 119.83382 -382.287564) (xy 119.825028 -382.222713) (xy 116.395222 -382.222713)
			(xy 116.386429 -382.287562) (xy 116.369003 -382.350642) (xy 116.343258 -382.410808) (xy 116.32692 -382.439164)
			(xy 116.323619 -382.445196) (xy 116.320004 -382.458454) (xy 116.319808 -382.465326) (xy 116.319808 -383.21488)
			(xy 116.320007 -383.221753) (xy 116.32361 -383.235015) (xy 116.32692 -383.241042) (xy 116.343272 -383.26939)
			(xy 116.366122 -383.322792) (xy 117.624858 -383.322792) (xy 117.624862 -383.257346) (xy 117.633661 -383.192494)
			(xy 117.651094 -383.129413) (xy 117.676845 -383.069246) (xy 117.693186 -383.04089) (xy 117.696549 -383.034874)
			(xy 117.700286 -383.021615) (xy 117.700552 -383.014728) (xy 117.700552 -382.728724) (xy 117.701103 -382.718623)
			(xy 117.708824 -382.699954) (xy 117.7231 -382.68566) (xy 117.741759 -382.677916) (xy 117.75186 -382.677416)
			(xy 118.46814 -382.677416) (xy 118.478253 -382.677853) (xy 118.496935 -382.685607) (xy 118.511229 -382.699918)
			(xy 118.51896 -382.71861) (xy 118.519448 -382.728724) (xy 118.519448 -383.014728) (xy 118.519681 -383.021621)
			(xy 118.523409 -383.034893) (xy 118.526814 -383.04089) (xy 118.543122 -383.069263) (xy 118.568872 -383.129425)
			(xy 118.586303 -383.192502) (xy 118.595101 -383.257349) (xy 118.595105 -383.32279) (xy 118.586315 -383.387638)
			(xy 118.568892 -383.450717) (xy 118.54315 -383.510882) (xy 118.526814 -383.539238) (xy 118.523441 -383.545249)
			(xy 118.51971 -383.558512) (xy 118.519448 -383.5654) (xy 118.519448 -384.3147) (xy 118.519653 -384.321595)
			(xy 118.523401 -384.334867) (xy 118.526814 -384.340862) (xy 118.543183 -384.369201) (xy 118.568927 -384.429371)
			(xy 118.586352 -384.492455) (xy 118.595142 -384.557308) (xy 118.595138 -384.622754) (xy 118.586339 -384.687606)
			(xy 118.568906 -384.750687) (xy 118.543155 -384.810854) (xy 118.526814 -384.83921) (xy 118.523451 -384.845226)
			(xy 118.519714 -384.858485) (xy 118.519448 -384.865372) (xy 118.519448 -385.151376) (xy 118.518897 -385.161477)
			(xy 118.511176 -385.180146) (xy 118.4969 -385.19444) (xy 118.478241 -385.202184) (xy 118.46814 -385.202684)
			(xy 117.75186 -385.202684) (xy 117.741747 -385.202247) (xy 117.723065 -385.194493) (xy 117.708771 -385.180182)
			(xy 117.70104 -385.16149) (xy 117.700552 -385.151376) (xy 117.700552 -384.865372) (xy 117.700319 -384.858479)
			(xy 117.696591 -384.845207) (xy 117.693186 -384.83921) (xy 117.676878 -384.810837) (xy 117.651128 -384.750675)
			(xy 117.633697 -384.687598) (xy 117.624899 -384.622751) (xy 117.624895 -384.55731) (xy 117.633685 -384.492462)
			(xy 117.651108 -384.429383) (xy 117.67685 -384.369218) (xy 117.693186 -384.340862) (xy 117.696559 -384.334851)
			(xy 117.70029 -384.321588) (xy 117.700552 -384.3147) (xy 117.700552 -383.5654) (xy 117.700347 -383.558505)
			(xy 117.696599 -383.545233) (xy 117.693186 -383.539238) (xy 117.676817 -383.510899) (xy 117.651073 -383.450729)
			(xy 117.633648 -383.387645) (xy 117.624858 -383.322792) (xy 116.366122 -383.322792) (xy 116.369017 -383.329558)
			(xy 116.386443 -383.39264) (xy 116.395235 -383.457491) (xy 116.395234 -383.522936) (xy 116.386438 -383.587787)
			(xy 116.369008 -383.650868) (xy 116.34326 -383.711034) (xy 116.32692 -383.73939) (xy 116.32361 -383.745417)
			(xy 116.320001 -383.758679) (xy 116.319808 -383.765552) (xy 116.319808 -384.051556) (xy 116.319342 -384.061706)
			(xy 116.311563 -384.080456) (xy 116.297179 -384.094781) (xy 116.278398 -384.102483) (xy 116.268246 -384.102864)
			(xy 115.551966 -384.102864) (xy 115.541838 -384.102401) (xy 115.523116 -384.094663) (xy 115.508761 -384.08037)
			(xy 115.500943 -384.061682) (xy 115.500404 -384.051556) (xy 115.500404 -383.765552) (xy 115.500191 -383.75868)
			(xy 115.496597 -383.745418) (xy 115.493292 -383.73939) (xy 115.476967 -383.711027) (xy 115.451219 -383.650862)
			(xy 115.433789 -383.587784) (xy 115.424993 -383.522935) (xy 115.424991 -383.457492) (xy 115.433783 -383.392643)
			(xy 115.451209 -383.329564) (xy 115.476954 -383.269398) (xy 115.493292 -383.241042) (xy 115.496591 -383.23501)
			(xy 115.500207 -383.221752) (xy 115.500404 -383.21488) (xy 115.500404 -382.465326) (xy 115.500202 -382.458454)
			(xy 115.496601 -382.445191) (xy 115.493292 -382.439164) (xy 115.476944 -382.410813) (xy 115.451199 -382.350646)
			(xy 115.433771 -382.287565) (xy 115.424978 -382.222714) (xy 100.496745 -382.222714) (xy 100.496116 -382.250696)
			(xy 100.450396 -384.287268) (xy 100.450396 -384.290062) (xy 100.451276 -384.304206) (xy 100.459862 -384.331202)
			(xy 100.475543 -384.354794) (xy 100.49711 -384.373162) (xy 100.522897 -384.384887) (xy 100.550916 -384.389065)
			(xy 100.579002 -384.385373) (xy 100.60499 -384.374097) (xy 100.616258 -384.3655) (xy 100.640878 -384.346069)
			(xy 100.694428 -384.313413) (xy 100.751935 -384.288375) (xy 100.812322 -384.271424) (xy 100.874457 -384.262876)
			(xy 100.905818 -384.262376) (xy 100.935802 -384.262846) (xy 100.995257 -384.270676) (xy 101.053181 -384.2862)
			(xy 101.108583 -384.309151) (xy 101.160515 -384.339138) (xy 101.208089 -384.375647) (xy 101.25049 -384.418054)
			(xy 101.286993 -384.465632) (xy 101.316973 -384.517568) (xy 101.339918 -384.572972) (xy 101.355435 -384.630898)
			(xy 101.363257 -384.690354) (xy 101.36378 -384.720338) (xy 101.36378 -385.319283) (xy 104.635826 -385.319283)
			(xy 104.635826 -385.259317) (xy 104.643653 -385.199864) (xy 104.659172 -385.141942) (xy 104.682119 -385.08654)
			(xy 104.7121 -385.034608) (xy 104.748603 -384.987032) (xy 104.791004 -384.944628) (xy 104.838576 -384.908121)
			(xy 104.890506 -384.878136) (xy 104.945906 -384.855184) (xy 105.003827 -384.83966) (xy 105.063279 -384.831828)
			(xy 105.093262 -384.831336) (xy 105.956862 -384.831336) (xy 105.986849 -384.831807) (xy 106.046311 -384.83963)
			(xy 106.104243 -384.855149) (xy 106.159653 -384.878097) (xy 106.211594 -384.908081) (xy 106.259176 -384.944589)
			(xy 106.301586 -384.986995) (xy 106.338098 -385.034574) (xy 106.368087 -385.086513) (xy 106.391039 -385.141921)
			(xy 106.406562 -385.199852) (xy 106.414391 -385.259313) (xy 106.414391 -385.319287) (xy 106.406562 -385.378748)
			(xy 106.391039 -385.436679) (xy 106.368087 -385.492087) (xy 106.338098 -385.544026) (xy 106.301586 -385.591605)
			(xy 106.259176 -385.634011) (xy 106.211594 -385.670519) (xy 106.159653 -385.700503) (xy 106.104243 -385.723451)
			(xy 106.046311 -385.73897) (xy 105.986849 -385.746793) (xy 105.956862 -385.74726) (xy 105.093262 -385.74726)
			(xy 105.063279 -385.746772) (xy 105.003827 -385.73894) (xy 104.945906 -385.723416) (xy 104.890506 -385.700464)
			(xy 104.838576 -385.670479) (xy 104.791004 -385.633972) (xy 104.748603 -385.591568) (xy 104.7121 -385.543992)
			(xy 104.682119 -385.49206) (xy 104.659172 -385.436658) (xy 104.643653 -385.378736) (xy 104.635826 -385.319283)
			(xy 101.36378 -385.319283) (xy 101.36378 -385.583938) (xy 101.363288 -385.613921) (xy 101.355456 -385.673374)
			(xy 101.339932 -385.731296) (xy 101.316981 -385.786696) (xy 101.286996 -385.838627) (xy 101.250489 -385.886201)
			(xy 101.208085 -385.928602) (xy 101.160511 -385.965107) (xy 101.108578 -385.99509) (xy 101.053177 -386.018038)
			(xy 100.995254 -386.03356) (xy 100.935801 -386.041389) (xy 100.905818 -386.0419) (xy 100.905564 -386.0419)
			(xy 100.876958 -386.041463) (xy 100.82019 -386.034342) (xy 100.764752 -386.020202) (xy 100.711508 -385.999265)
			(xy 100.661287 -385.971857) (xy 100.614874 -385.938405) (xy 100.593652 -385.919218) (xy 100.582853 -385.909863)
			(xy 100.557352 -385.897008) (xy 100.529288 -385.891719) (xy 100.500857 -385.894411) (xy 100.474284 -385.904872)
			(xy 100.451649 -385.922284) (xy 100.434722 -385.945285) (xy 100.424828 -385.972075) (xy 100.423218 -385.986274)
			(xy 100.422964 -385.990084) (xy 100.422964 -386.451348) (xy 145.01622 -386.451348) (xy 145.016665 -386.424798)
			(xy 145.024028 -386.372211) (xy 145.038619 -386.321156) (xy 145.060154 -386.272619) (xy 145.088218 -386.227541)
			(xy 145.122267 -386.186795) (xy 145.161641 -386.151168) (xy 145.183352 -386.13588) (xy 145.192242 -386.129784)
			(xy 145.203418 -386.112004) (xy 145.217642 -386.017008) (xy 145.212308 -385.996688) (xy 145.20545 -385.988306)
			(xy 145.189739 -385.967951) (xy 145.16336 -385.923815) (xy 145.143146 -385.876536) (xy 145.129463 -385.826971)
			(xy 145.122558 -385.776017) (xy 145.122138 -385.750308) (xy 145.122624 -385.723057) (xy 145.13038 -385.669109)
			(xy 145.145735 -385.616814) (xy 145.168377 -385.567237) (xy 145.197843 -385.521387) (xy 145.233534 -385.480196)
			(xy 145.274725 -385.444505) (xy 145.320575 -385.415039) (xy 145.370152 -385.392397) (xy 145.422447 -385.377042)
			(xy 145.476395 -385.369286) (xy 145.530897 -385.369286) (xy 145.584845 -385.377042) (xy 145.63714 -385.392397)
			(xy 145.686717 -385.415039) (xy 145.732567 -385.444505) (xy 145.773758 -385.480196) (xy 145.809449 -385.521387)
			(xy 145.838915 -385.567237) (xy 145.861557 -385.616814) (xy 145.876912 -385.669109) (xy 145.884668 -385.723057)
			(xy 145.885154 -385.750308) (xy 145.884687 -385.776857) (xy 145.877329 -385.829443) (xy 145.862743 -385.880499)
			(xy 145.841212 -385.929036) (xy 145.813151 -385.974114) (xy 145.779105 -386.014861) (xy 145.739732 -386.050488)
			(xy 145.718022 -386.065776) (xy 145.709132 -386.071872) (xy 145.697956 -386.089652) (xy 145.683732 -386.184648)
			(xy 145.689066 -386.204968) (xy 145.695924 -386.21335) (xy 145.711625 -386.233711) (xy 145.738003 -386.277847)
			(xy 145.758218 -386.325125) (xy 145.771904 -386.374688) (xy 145.778813 -386.425639) (xy 145.779236 -386.451348)
			(xy 145.77875 -386.478599) (xy 145.770994 -386.532547) (xy 145.755639 -386.584842) (xy 145.732997 -386.634419)
			(xy 145.703531 -386.680269) (xy 145.66784 -386.72146) (xy 145.626649 -386.757151) (xy 145.580799 -386.786617)
			(xy 145.531222 -386.809259) (xy 145.478927 -386.824614) (xy 145.424979 -386.83237) (xy 145.370477 -386.83237)
			(xy 145.316529 -386.824614) (xy 145.264234 -386.809259) (xy 145.214657 -386.786617) (xy 145.168807 -386.757151)
			(xy 145.127616 -386.72146) (xy 145.091925 -386.680269) (xy 145.062459 -386.634419) (xy 145.039817 -386.584842)
			(xy 145.024462 -386.532547) (xy 145.016706 -386.478599) (xy 145.01622 -386.451348) (xy 100.422964 -386.451348)
			(xy 100.422964 -387.486144) (xy 100.422964 -387.684518) (xy 100.419916 -387.691376) (xy 100.419154 -387.693916)
			(xy 100.350066 -387.860794) (xy 100.347272 -387.867652) (xy 99.914894 -388.911846) (xy 103.494838 -388.911846)
			(xy 103.498909 -388.856224) (xy 103.511035 -388.801787) (xy 103.530958 -388.749696) (xy 103.558254 -388.701061)
			(xy 103.59234 -388.656918) (xy 103.632489 -388.618209) (xy 103.677847 -388.585758) (xy 103.727447 -388.560257)
			(xy 103.780231 -388.54225) (xy 103.835074 -388.53212) (xy 103.890808 -388.530083) (xy 103.946245 -388.536183)
			(xy 104.000202 -388.550289) (xy 104.051531 -388.572101) (xy 104.099137 -388.601155) (xy 104.142005 -388.63683)
			(xy 104.179222 -388.678367) (xy 104.209995 -388.72488) (xy 104.233667 -388.775377) (xy 104.249735 -388.828784)
			(xy 104.257855 -388.88396) (xy 104.258364 -388.911846) (xy 104.257855 -388.939732) (xy 104.249735 -388.994908)
			(xy 104.233667 -389.048315) (xy 104.209995 -389.098812) (xy 104.179222 -389.145325) (xy 104.142005 -389.186862)
			(xy 104.099137 -389.222537) (xy 104.051531 -389.251591) (xy 104.000202 -389.273403) (xy 103.946245 -389.287509)
			(xy 103.890808 -389.293609) (xy 103.835074 -389.291572) (xy 103.780231 -389.281442) (xy 103.727447 -389.263435)
			(xy 103.677847 -389.237934) (xy 103.632489 -389.205483) (xy 103.59234 -389.166774) (xy 103.558254 -389.122631)
			(xy 103.530958 -389.073996) (xy 103.511035 -389.021905) (xy 103.498909 -388.967468) (xy 103.494838 -388.911846)
			(xy 99.914894 -388.911846) (xy 99.355148 -390.263634) (xy 99.353624 -390.279128) (xy 99.355656 -390.287002)
			(xy 99.360191 -390.30811) (xy 99.365023 -390.351013) (xy 99.365308 -390.3726) (xy 99.364786 -390.400997)
			(xy 99.356369 -390.457163) (xy 99.339721 -390.511462) (xy 99.315208 -390.562693) (xy 99.291552 -390.597644)
			(xy 99.793806 -390.597644) (xy 99.794296 -390.570275) (xy 99.802108 -390.516097) (xy 99.817591 -390.463594)
			(xy 99.840428 -390.413846) (xy 99.870147 -390.367878) (xy 99.887786 -390.346946) (xy 99.893882 -390.339834)
			(xy 99.900232 -390.322816) (xy 99.900232 -390.237472) (xy 99.893882 -390.220454) (xy 99.887786 -390.213342)
			(xy 99.870151 -390.192407) (xy 99.840439 -390.146435) (xy 99.817602 -390.096688) (xy 99.80211 -390.044188)
			(xy 99.794281 -389.990013) (xy 99.793806 -389.962644) (xy 99.794292 -389.935393) (xy 99.802048 -389.881445)
			(xy 99.817403 -389.82915) (xy 99.840045 -389.779573) (xy 99.869511 -389.733723) (xy 99.905202 -389.692532)
			(xy 99.946393 -389.656841) (xy 99.992243 -389.627375) (xy 100.04182 -389.604733) (xy 100.094115 -389.589378)
			(xy 100.148063 -389.581622) (xy 100.202565 -389.581622) (xy 100.256513 -389.589378) (xy 100.308808 -389.604733)
			(xy 100.358385 -389.627375) (xy 100.404235 -389.656841) (xy 100.445426 -389.692532) (xy 100.475893 -389.727694)
			(xy 106.942888 -389.727694) (xy 106.946959 -389.672072) (xy 106.959085 -389.617635) (xy 106.979008 -389.565544)
			(xy 107.006304 -389.516909) (xy 107.04039 -389.472766) (xy 107.080539 -389.434057) (xy 107.125897 -389.401606)
			(xy 107.175497 -389.376105) (xy 107.228281 -389.358098) (xy 107.283124 -389.347968) (xy 107.338858 -389.345931)
			(xy 107.394295 -389.352031) (xy 107.448252 -389.366137) (xy 107.499581 -389.387949) (xy 107.547187 -389.417003)
			(xy 107.590055 -389.452678) (xy 107.627272 -389.494215) (xy 107.658045 -389.540728) (xy 107.681717 -389.591225)
			(xy 107.697785 -389.644632) (xy 107.705905 -389.699808) (xy 107.706414 -389.727694) (xy 107.705905 -389.75558)
			(xy 107.697785 -389.810756) (xy 107.681717 -389.864163) (xy 107.658045 -389.91466) (xy 107.627272 -389.961173)
			(xy 107.590055 -390.00271) (xy 107.547187 -390.038385) (xy 107.499581 -390.067439) (xy 107.448252 -390.089251)
			(xy 107.394295 -390.103357) (xy 107.338858 -390.109457) (xy 107.283124 -390.10742) (xy 107.228281 -390.09729)
			(xy 107.175497 -390.079283) (xy 107.125897 -390.053782) (xy 107.080539 -390.021331) (xy 107.04039 -389.982622)
			(xy 107.006304 -389.938479) (xy 106.979008 -389.889844) (xy 106.959085 -389.837753) (xy 106.946959 -389.783316)
			(xy 106.942888 -389.727694) (xy 100.475893 -389.727694) (xy 100.481117 -389.733723) (xy 100.510583 -389.779573)
			(xy 100.533225 -389.82915) (xy 100.54858 -389.881445) (xy 100.556336 -389.935393) (xy 100.556822 -389.962644)
			(xy 100.556342 -389.990014) (xy 100.548531 -390.044193) (xy 100.533046 -390.096697) (xy 100.510207 -390.146444)
			(xy 100.480483 -390.192411) (xy 100.462842 -390.213342) (xy 100.456746 -390.220454) (xy 100.450396 -390.237472)
			(xy 100.450396 -390.322816) (xy 100.456746 -390.339834) (xy 100.462842 -390.346946) (xy 100.480476 -390.367882)
			(xy 100.510187 -390.413854) (xy 100.533024 -390.463601) (xy 100.548516 -390.5161) (xy 100.556347 -390.570275)
			(xy 100.556822 -390.597644) (xy 100.556336 -390.624895) (xy 100.54858 -390.678843) (xy 100.533225 -390.731138)
			(xy 100.510583 -390.780715) (xy 100.481117 -390.826565) (xy 100.445426 -390.867756) (xy 100.404235 -390.903447)
			(xy 100.358385 -390.932913) (xy 100.308808 -390.955555) (xy 100.256513 -390.97091) (xy 100.202565 -390.978666)
			(xy 100.148063 -390.978666) (xy 100.094115 -390.97091) (xy 100.04182 -390.955555) (xy 99.992243 -390.932913)
			(xy 99.946393 -390.903447) (xy 99.905202 -390.867756) (xy 99.869511 -390.826565) (xy 99.840045 -390.780715)
			(xy 99.817403 -390.731138) (xy 99.802048 -390.678843) (xy 99.794292 -390.624895) (xy 99.793806 -390.597644)
			(xy 99.291552 -390.597644) (xy 99.283374 -390.609726) (xy 99.244921 -390.651521) (xy 99.200697 -390.687156)
			(xy 99.151681 -390.715843) (xy 99.098955 -390.736948) (xy 99.07143 -390.743948) (xy 99.064318 -390.745472)
			(xy 99.05238 -390.75233) (xy 98.510344 -391.294366) (xy 99.119942 -391.294366) (xy 99.124013 -391.238744)
			(xy 99.136139 -391.184307) (xy 99.156062 -391.132216) (xy 99.183358 -391.083581) (xy 99.217444 -391.039438)
			(xy 99.257593 -391.000729) (xy 99.302951 -390.968278) (xy 99.352551 -390.942777) (xy 99.405335 -390.92477)
			(xy 99.460178 -390.91464) (xy 99.515912 -390.912603) (xy 99.571349 -390.918703) (xy 99.625306 -390.932809)
			(xy 99.676635 -390.954621) (xy 99.724241 -390.983675) (xy 99.767109 -391.01935) (xy 99.804326 -391.060887)
			(xy 99.835099 -391.1074) (xy 99.857137 -391.154412) (xy 106.201208 -391.154412) (xy 106.205279 -391.09879)
			(xy 106.217405 -391.044353) (xy 106.237328 -390.992262) (xy 106.264624 -390.943627) (xy 106.29871 -390.899484)
			(xy 106.338859 -390.860775) (xy 106.384217 -390.828324) (xy 106.433817 -390.802823) (xy 106.486601 -390.784816)
			(xy 106.541444 -390.774686) (xy 106.597178 -390.772649) (xy 106.652615 -390.778749) (xy 106.706572 -390.792855)
			(xy 106.757901 -390.814667) (xy 106.805507 -390.843721) (xy 106.848375 -390.879396) (xy 106.885592 -390.920933)
			(xy 106.916365 -390.967446) (xy 106.940037 -391.017943) (xy 106.956105 -391.07135) (xy 106.964225 -391.126526)
			(xy 106.964734 -391.154412) (xy 106.964225 -391.182298) (xy 106.956105 -391.237474) (xy 106.940037 -391.290881)
			(xy 106.916365 -391.341378) (xy 106.885592 -391.387891) (xy 106.848375 -391.429428) (xy 106.805507 -391.465103)
			(xy 106.757901 -391.494157) (xy 106.706572 -391.515969) (xy 106.652615 -391.530075) (xy 106.597178 -391.536175)
			(xy 106.541444 -391.534138) (xy 106.486601 -391.524008) (xy 106.433817 -391.506001) (xy 106.384217 -391.4805)
			(xy 106.338859 -391.448049) (xy 106.29871 -391.40934) (xy 106.264624 -391.365197) (xy 106.237328 -391.316562)
			(xy 106.217405 -391.264471) (xy 106.205279 -391.210034) (xy 106.201208 -391.154412) (xy 99.857137 -391.154412)
			(xy 99.858771 -391.157897) (xy 99.874839 -391.211304) (xy 99.882959 -391.26648) (xy 99.883468 -391.294366)
			(xy 99.882959 -391.322252) (xy 99.874839 -391.377428) (xy 99.858771 -391.430835) (xy 99.835099 -391.481332)
			(xy 99.804326 -391.527845) (xy 99.767109 -391.569382) (xy 99.724241 -391.605057) (xy 99.676635 -391.634111)
			(xy 99.628565 -391.654538) (xy 108.000036 -391.654538) (xy 108.004107 -391.598916) (xy 108.016233 -391.544479)
			(xy 108.036156 -391.492388) (xy 108.063452 -391.443753) (xy 108.097538 -391.39961) (xy 108.137687 -391.360901)
			(xy 108.183045 -391.32845) (xy 108.232645 -391.302949) (xy 108.285429 -391.284942) (xy 108.340272 -391.274812)
			(xy 108.396006 -391.272775) (xy 108.451443 -391.278875) (xy 108.5054 -391.292981) (xy 108.556729 -391.314793)
			(xy 108.604335 -391.343847) (xy 108.647203 -391.379522) (xy 108.68442 -391.421059) (xy 108.715193 -391.467572)
			(xy 108.738865 -391.518069) (xy 108.754933 -391.571476) (xy 108.763053 -391.626652) (xy 108.763562 -391.654538)
			(xy 108.763053 -391.682424) (xy 108.754933 -391.7376) (xy 108.738865 -391.791007) (xy 108.715193 -391.841504)
			(xy 108.68442 -391.888017) (xy 108.647203 -391.929554) (xy 108.604335 -391.965229) (xy 108.556729 -391.994283)
			(xy 108.5054 -392.016095) (xy 108.451443 -392.030201) (xy 108.396006 -392.036301) (xy 108.340272 -392.034264)
			(xy 108.285429 -392.024134) (xy 108.232645 -392.006127) (xy 108.183045 -391.980626) (xy 108.137687 -391.948175)
			(xy 108.097538 -391.909466) (xy 108.063452 -391.865323) (xy 108.036156 -391.816688) (xy 108.016233 -391.764597)
			(xy 108.004107 -391.71016) (xy 108.000036 -391.654538) (xy 99.628565 -391.654538) (xy 99.625306 -391.655923)
			(xy 99.571349 -391.670029) (xy 99.515912 -391.676129) (xy 99.460178 -391.674092) (xy 99.405335 -391.663962)
			(xy 99.352551 -391.645955) (xy 99.302951 -391.620454) (xy 99.257593 -391.588003) (xy 99.217444 -391.549294)
			(xy 99.183358 -391.505151) (xy 99.156062 -391.456516) (xy 99.136139 -391.404425) (xy 99.124013 -391.349988)
			(xy 99.119942 -391.294366) (xy 98.510344 -391.294366) (xy 97.387918 -392.416792) (xy 97.380552 -392.431016)
			(xy 97.379282 -392.43889) (xy 97.374655 -392.465122) (xy 97.359078 -392.51606) (xy 97.336565 -392.564335)
			(xy 97.320049 -392.589766) (xy 99.119942 -392.589766) (xy 99.124013 -392.534144) (xy 99.136139 -392.479707)
			(xy 99.156062 -392.427616) (xy 99.183358 -392.378981) (xy 99.217444 -392.334838) (xy 99.257593 -392.296129)
			(xy 99.302951 -392.263678) (xy 99.352551 -392.238177) (xy 99.405335 -392.22017) (xy 99.460178 -392.21004)
			(xy 99.515912 -392.208003) (xy 99.571349 -392.214103) (xy 99.625306 -392.228209) (xy 99.676635 -392.250021)
			(xy 99.724241 -392.279075) (xy 99.767109 -392.31475) (xy 99.785029 -392.33475) (xy 106.667298 -392.33475)
			(xy 106.671369 -392.279128) (xy 106.683495 -392.224691) (xy 106.703418 -392.1726) (xy 106.730714 -392.123965)
			(xy 106.7648 -392.079822) (xy 106.804949 -392.041113) (xy 106.850307 -392.008662) (xy 106.899907 -391.983161)
			(xy 106.952691 -391.965154) (xy 107.007534 -391.955024) (xy 107.063268 -391.952987) (xy 107.118705 -391.959087)
			(xy 107.172662 -391.973193) (xy 107.223991 -391.995005) (xy 107.271597 -392.024059) (xy 107.314465 -392.059734)
			(xy 107.351682 -392.101271) (xy 107.382455 -392.147784) (xy 107.406127 -392.198281) (xy 107.422195 -392.251688)
			(xy 107.430315 -392.306864) (xy 107.430824 -392.33475) (xy 107.430315 -392.362636) (xy 107.422195 -392.417812)
			(xy 107.406127 -392.471219) (xy 107.382455 -392.521716) (xy 107.351682 -392.568229) (xy 107.314465 -392.609766)
			(xy 107.271597 -392.645441) (xy 107.223991 -392.674495) (xy 107.172662 -392.696307) (xy 107.118705 -392.710413)
			(xy 107.063268 -392.716513) (xy 107.007534 -392.714476) (xy 106.952691 -392.704346) (xy 106.899907 -392.686339)
			(xy 106.850307 -392.660838) (xy 106.804949 -392.628387) (xy 106.7648 -392.589678) (xy 106.730714 -392.545535)
			(xy 106.703418 -392.4969) (xy 106.683495 -392.444809) (xy 106.671369 -392.390372) (xy 106.667298 -392.33475)
			(xy 99.785029 -392.33475) (xy 99.804326 -392.356287) (xy 99.835099 -392.4028) (xy 99.858771 -392.453297)
			(xy 99.874839 -392.506704) (xy 99.882959 -392.56188) (xy 99.883468 -392.589766) (xy 99.882959 -392.617652)
			(xy 99.874839 -392.672828) (xy 99.858771 -392.726235) (xy 99.835099 -392.776732) (xy 99.804326 -392.823245)
			(xy 99.767109 -392.864782) (xy 99.724241 -392.900457) (xy 99.676635 -392.929511) (xy 99.625306 -392.951323)
			(xy 99.571349 -392.965429) (xy 99.515912 -392.971529) (xy 99.460178 -392.969492) (xy 99.405335 -392.959362)
			(xy 99.352551 -392.941355) (xy 99.302951 -392.915854) (xy 99.257593 -392.883403) (xy 99.217444 -392.844694)
			(xy 99.183358 -392.800551) (xy 99.156062 -392.751916) (xy 99.136139 -392.699825) (xy 99.124013 -392.645388)
			(xy 99.119942 -392.589766) (xy 97.320049 -392.589766) (xy 97.307553 -392.609007) (xy 97.272607 -392.649207)
			(xy 97.232407 -392.684153) (xy 97.187735 -392.713165) (xy 97.13946 -392.735678) (xy 97.088522 -392.751255)
			(xy 97.06229 -392.755882) (xy 97.054416 -392.757152) (xy 97.040192 -392.764518) (xy 96.435672 -393.368784)
			(xy 96.423226 -393.38123) (xy 96.422972 -393.381484) (xy 96.295464 -393.508992) (xy 96.28886 -393.511786)
			(xy 96.287336 -393.512548) (xy 96.28632 -393.512802) (xy 96.286066 -393.513056) (xy 96.11995 -393.58189)
			(xy 96.119696 -393.58189) (xy 96.11233 -393.585192) (xy 95.387996 -393.885166) (xy 99.119942 -393.885166)
			(xy 99.124013 -393.829544) (xy 99.136139 -393.775107) (xy 99.156062 -393.723016) (xy 99.183358 -393.674381)
			(xy 99.217444 -393.630238) (xy 99.257593 -393.591529) (xy 99.302951 -393.559078) (xy 99.352551 -393.533577)
			(xy 99.405335 -393.51557) (xy 99.460178 -393.50544) (xy 99.515912 -393.503403) (xy 99.571349 -393.509503)
			(xy 99.625306 -393.523609) (xy 99.676635 -393.545421) (xy 99.724241 -393.574475) (xy 99.767109 -393.61015)
			(xy 99.804326 -393.651687) (xy 99.835099 -393.6982) (xy 99.858771 -393.748697) (xy 99.874839 -393.802104)
			(xy 99.882959 -393.85728) (xy 99.883468 -393.885166) (xy 99.882959 -393.913052) (xy 99.874839 -393.968228)
			(xy 99.858771 -394.021635) (xy 99.835099 -394.072132) (xy 99.804326 -394.118645) (xy 99.767109 -394.160182)
			(xy 99.724241 -394.195857) (xy 99.676635 -394.224911) (xy 99.625306 -394.246723) (xy 99.571349 -394.260829)
			(xy 99.515912 -394.266929) (xy 99.460178 -394.264892) (xy 99.405335 -394.254762) (xy 99.352551 -394.236755)
			(xy 99.302951 -394.211254) (xy 99.257593 -394.178803) (xy 99.217444 -394.140094) (xy 99.183358 -394.095951)
			(xy 99.156062 -394.047316) (xy 99.136139 -393.995225) (xy 99.124013 -393.940788) (xy 99.119942 -393.885166)
			(xy 95.387996 -393.885166) (xy 94.320201 -394.32738) (xy 105.828336 -394.32738) (xy 105.832407 -394.271758)
			(xy 105.844533 -394.217321) (xy 105.864456 -394.16523) (xy 105.891752 -394.116595) (xy 105.925838 -394.072452)
			(xy 105.965987 -394.033743) (xy 106.011345 -394.001292) (xy 106.060945 -393.975791) (xy 106.113729 -393.957784)
			(xy 106.168572 -393.947654) (xy 106.224306 -393.945617) (xy 106.279743 -393.951717) (xy 106.3337 -393.965823)
			(xy 106.385029 -393.987635) (xy 106.432635 -394.016689) (xy 106.475503 -394.052364) (xy 106.51272 -394.093901)
			(xy 106.543493 -394.140414) (xy 106.567165 -394.190911) (xy 106.583233 -394.244318) (xy 106.591353 -394.299494)
			(xy 106.591862 -394.32738) (xy 106.591353 -394.355266) (xy 106.583233 -394.410442) (xy 106.567165 -394.463849)
			(xy 106.543493 -394.514346) (xy 106.51272 -394.560859) (xy 106.475503 -394.602396) (xy 106.432635 -394.638071)
			(xy 106.385029 -394.667125) (xy 106.3337 -394.688937) (xy 106.279743 -394.703043) (xy 106.224306 -394.709143)
			(xy 106.168572 -394.707106) (xy 106.113729 -394.696976) (xy 106.060945 -394.678969) (xy 106.011345 -394.653468)
			(xy 105.965987 -394.621017) (xy 105.925838 -394.582308) (xy 105.891752 -394.538165) (xy 105.864456 -394.48953)
			(xy 105.844533 -394.437439) (xy 105.832407 -394.383002) (xy 105.828336 -394.32738) (xy 94.320201 -394.32738)
			(xy 94.078552 -394.427456) (xy 94.069454 -394.431683) (xy 94.055301 -394.445878) (xy 94.047688 -394.464421)
			(xy 94.04731 -394.474446) (xy 94.04731 -395.180566) (xy 99.119942 -395.180566) (xy 99.124013 -395.124944)
			(xy 99.136139 -395.070507) (xy 99.156062 -395.018416) (xy 99.183358 -394.969781) (xy 99.217444 -394.925638)
			(xy 99.257593 -394.886929) (xy 99.302951 -394.854478) (xy 99.352551 -394.828977) (xy 99.405335 -394.81097)
			(xy 99.460178 -394.80084) (xy 99.515912 -394.798803) (xy 99.571349 -394.804903) (xy 99.625306 -394.819009)
			(xy 99.676635 -394.840821) (xy 99.724241 -394.869875) (xy 99.767109 -394.90555) (xy 99.804326 -394.947087)
			(xy 99.835099 -394.9936) (xy 99.858771 -395.044097) (xy 99.874839 -395.097504) (xy 99.882959 -395.15268)
			(xy 99.883468 -395.180566) (xy 99.883347 -395.18717) (xy 101.058724 -395.18717) (xy 101.062795 -395.131548)
			(xy 101.074921 -395.077111) (xy 101.094844 -395.02502) (xy 101.12214 -394.976385) (xy 101.156226 -394.932242)
			(xy 101.196375 -394.893533) (xy 101.241733 -394.861082) (xy 101.291333 -394.835581) (xy 101.344117 -394.817574)
			(xy 101.39896 -394.807444) (xy 101.454694 -394.805407) (xy 101.510131 -394.811507) (xy 101.564088 -394.825613)
			(xy 101.615417 -394.847425) (xy 101.663023 -394.876479) (xy 101.705891 -394.912154) (xy 101.743108 -394.953691)
			(xy 101.773881 -395.000204) (xy 101.797553 -395.050701) (xy 101.813621 -395.104108) (xy 101.821741 -395.159284)
			(xy 101.82225 -395.18717) (xy 101.821741 -395.215056) (xy 101.813621 -395.270232) (xy 101.797553 -395.323639)
			(xy 101.773881 -395.374136) (xy 101.743108 -395.420649) (xy 101.705891 -395.462186) (xy 101.663023 -395.497861)
			(xy 101.615417 -395.526915) (xy 101.564088 -395.548727) (xy 101.510131 -395.562833) (xy 101.454694 -395.568933)
			(xy 101.39896 -395.566896) (xy 101.344117 -395.556766) (xy 101.291333 -395.538759) (xy 101.241733 -395.513258)
			(xy 101.196375 -395.480807) (xy 101.156226 -395.442098) (xy 101.12214 -395.397955) (xy 101.094844 -395.34932)
			(xy 101.074921 -395.297229) (xy 101.062795 -395.242792) (xy 101.058724 -395.18717) (xy 99.883347 -395.18717)
			(xy 99.882959 -395.208452) (xy 99.874839 -395.263628) (xy 99.858771 -395.317035) (xy 99.835099 -395.367532)
			(xy 99.804326 -395.414045) (xy 99.767109 -395.455582) (xy 99.724241 -395.491257) (xy 99.676635 -395.520311)
			(xy 99.625306 -395.542123) (xy 99.571349 -395.556229) (xy 99.515912 -395.562329) (xy 99.460178 -395.560292)
			(xy 99.405335 -395.550162) (xy 99.352551 -395.532155) (xy 99.302951 -395.506654) (xy 99.257593 -395.474203)
			(xy 99.217444 -395.435494) (xy 99.183358 -395.391351) (xy 99.156062 -395.342716) (xy 99.136139 -395.290625)
			(xy 99.124013 -395.236188) (xy 99.119942 -395.180566) (xy 94.04731 -395.180566) (xy 94.04731 -396.1638)
			(xy 96.6503 -396.1638) (xy 96.654371 -396.108178) (xy 96.666497 -396.053741) (xy 96.68642 -396.00165)
			(xy 96.713716 -395.953015) (xy 96.747802 -395.908872) (xy 96.787951 -395.870163) (xy 96.833309 -395.837712)
			(xy 96.882909 -395.812211) (xy 96.935693 -395.794204) (xy 96.990536 -395.784074) (xy 97.04627 -395.782037)
			(xy 97.101707 -395.788137) (xy 97.155664 -395.802243) (xy 97.206993 -395.824055) (xy 97.254599 -395.853109)
			(xy 97.297467 -395.888784) (xy 97.334684 -395.930321) (xy 97.365457 -395.976834) (xy 97.389129 -396.027331)
			(xy 97.405197 -396.080738) (xy 97.413317 -396.135914) (xy 97.413826 -396.1638) (xy 97.413317 -396.191686)
			(xy 97.405197 -396.246862) (xy 97.389129 -396.300269) (xy 97.365457 -396.350766) (xy 97.334684 -396.397279)
			(xy 97.297467 -396.438816) (xy 97.254599 -396.474491) (xy 97.212644 -396.500096) (xy 100.023166 -396.500096)
			(xy 100.027237 -396.444474) (xy 100.039363 -396.390037) (xy 100.059286 -396.337946) (xy 100.086582 -396.289311)
			(xy 100.120668 -396.245168) (xy 100.160817 -396.206459) (xy 100.206175 -396.174008) (xy 100.255775 -396.148507)
			(xy 100.308559 -396.1305) (xy 100.363402 -396.12037) (xy 100.419136 -396.118333) (xy 100.474573 -396.124433)
			(xy 100.52853 -396.138539) (xy 100.579859 -396.160351) (xy 100.627465 -396.189405) (xy 100.670333 -396.22508)
			(xy 100.70755 -396.266617) (xy 100.738323 -396.31313) (xy 100.761995 -396.363627) (xy 100.778063 -396.417034)
			(xy 100.786183 -396.47221) (xy 100.786692 -396.500096) (xy 101.318566 -396.500096) (xy 101.322637 -396.444474)
			(xy 101.334763 -396.390037) (xy 101.354686 -396.337946) (xy 101.381982 -396.289311) (xy 101.416068 -396.245168)
			(xy 101.456217 -396.206459) (xy 101.501575 -396.174008) (xy 101.551175 -396.148507) (xy 101.603959 -396.1305)
			(xy 101.658802 -396.12037) (xy 101.714536 -396.118333) (xy 101.769973 -396.124433) (xy 101.82393 -396.138539)
			(xy 101.875259 -396.160351) (xy 101.922865 -396.189405) (xy 101.965733 -396.22508) (xy 102.00295 -396.266617)
			(xy 102.033723 -396.31313) (xy 102.057395 -396.363627) (xy 102.073463 -396.417034) (xy 102.081583 -396.47221)
			(xy 102.082092 -396.500096) (xy 102.613966 -396.500096) (xy 102.618037 -396.444474) (xy 102.630163 -396.390037)
			(xy 102.650086 -396.337946) (xy 102.677382 -396.289311) (xy 102.711468 -396.245168) (xy 102.751617 -396.206459)
			(xy 102.796975 -396.174008) (xy 102.846575 -396.148507) (xy 102.899359 -396.1305) (xy 102.954202 -396.12037)
			(xy 103.009936 -396.118333) (xy 103.065373 -396.124433) (xy 103.11933 -396.138539) (xy 103.170659 -396.160351)
			(xy 103.218265 -396.189405) (xy 103.261133 -396.22508) (xy 103.29835 -396.266617) (xy 103.329123 -396.31313)
			(xy 103.352795 -396.363627) (xy 103.368863 -396.417034) (xy 103.376983 -396.47221) (xy 103.377492 -396.500096)
			(xy 103.909366 -396.500096) (xy 103.913437 -396.444474) (xy 103.925563 -396.390037) (xy 103.945486 -396.337946)
			(xy 103.972782 -396.289311) (xy 104.006868 -396.245168) (xy 104.047017 -396.206459) (xy 104.092375 -396.174008)
			(xy 104.141975 -396.148507) (xy 104.194759 -396.1305) (xy 104.249602 -396.12037) (xy 104.305336 -396.118333)
			(xy 104.360773 -396.124433) (xy 104.41473 -396.138539) (xy 104.466059 -396.160351) (xy 104.513665 -396.189405)
			(xy 104.556533 -396.22508) (xy 104.59375 -396.266617) (xy 104.624523 -396.31313) (xy 104.648195 -396.363627)
			(xy 104.664263 -396.417034) (xy 104.672383 -396.47221) (xy 104.672892 -396.500096) (xy 104.672383 -396.527982)
			(xy 104.664263 -396.583158) (xy 104.648195 -396.636565) (xy 104.624523 -396.687062) (xy 104.59375 -396.733575)
			(xy 104.556533 -396.775112) (xy 104.513665 -396.810787) (xy 104.466059 -396.839841) (xy 104.41473 -396.861653)
			(xy 104.360773 -396.875759) (xy 104.305336 -396.881859) (xy 104.249602 -396.879822) (xy 104.194759 -396.869692)
			(xy 104.141975 -396.851685) (xy 104.092375 -396.826184) (xy 104.047017 -396.793733) (xy 104.006868 -396.755024)
			(xy 103.972782 -396.710881) (xy 103.945486 -396.662246) (xy 103.925563 -396.610155) (xy 103.913437 -396.555718)
			(xy 103.909366 -396.500096) (xy 103.377492 -396.500096) (xy 103.376983 -396.527982) (xy 103.368863 -396.583158)
			(xy 103.352795 -396.636565) (xy 103.329123 -396.687062) (xy 103.29835 -396.733575) (xy 103.261133 -396.775112)
			(xy 103.218265 -396.810787) (xy 103.170659 -396.839841) (xy 103.11933 -396.861653) (xy 103.065373 -396.875759)
			(xy 103.009936 -396.881859) (xy 102.954202 -396.879822) (xy 102.899359 -396.869692) (xy 102.846575 -396.851685)
			(xy 102.796975 -396.826184) (xy 102.751617 -396.793733) (xy 102.711468 -396.755024) (xy 102.677382 -396.710881)
			(xy 102.650086 -396.662246) (xy 102.630163 -396.610155) (xy 102.618037 -396.555718) (xy 102.613966 -396.500096)
			(xy 102.082092 -396.500096) (xy 102.081583 -396.527982) (xy 102.073463 -396.583158) (xy 102.057395 -396.636565)
			(xy 102.033723 -396.687062) (xy 102.00295 -396.733575) (xy 101.965733 -396.775112) (xy 101.922865 -396.810787)
			(xy 101.875259 -396.839841) (xy 101.82393 -396.861653) (xy 101.769973 -396.875759) (xy 101.714536 -396.881859)
			(xy 101.658802 -396.879822) (xy 101.603959 -396.869692) (xy 101.551175 -396.851685) (xy 101.501575 -396.826184)
			(xy 101.456217 -396.793733) (xy 101.416068 -396.755024) (xy 101.381982 -396.710881) (xy 101.354686 -396.662246)
			(xy 101.334763 -396.610155) (xy 101.322637 -396.555718) (xy 101.318566 -396.500096) (xy 100.786692 -396.500096)
			(xy 100.786183 -396.527982) (xy 100.778063 -396.583158) (xy 100.761995 -396.636565) (xy 100.738323 -396.687062)
			(xy 100.70755 -396.733575) (xy 100.670333 -396.775112) (xy 100.627465 -396.810787) (xy 100.579859 -396.839841)
			(xy 100.52853 -396.861653) (xy 100.474573 -396.875759) (xy 100.419136 -396.881859) (xy 100.363402 -396.879822)
			(xy 100.308559 -396.869692) (xy 100.255775 -396.851685) (xy 100.206175 -396.826184) (xy 100.160817 -396.793733)
			(xy 100.120668 -396.755024) (xy 100.086582 -396.710881) (xy 100.059286 -396.662246) (xy 100.039363 -396.610155)
			(xy 100.027237 -396.555718) (xy 100.023166 -396.500096) (xy 97.212644 -396.500096) (xy 97.206993 -396.503545)
			(xy 97.155664 -396.525357) (xy 97.101707 -396.539463) (xy 97.04627 -396.545563) (xy 96.990536 -396.543526)
			(xy 96.935693 -396.533396) (xy 96.882909 -396.515389) (xy 96.833309 -396.489888) (xy 96.787951 -396.457437)
			(xy 96.747802 -396.418728) (xy 96.713716 -396.374585) (xy 96.68642 -396.32595) (xy 96.666497 -396.273859)
			(xy 96.654371 -396.219422) (xy 96.6503 -396.1638) (xy 94.04731 -396.1638) (xy 94.04731 -397.822891)
			(xy 115.424962 -397.822891) (xy 115.424967 -397.757444) (xy 115.433765 -397.692592) (xy 115.451199 -397.629511)
			(xy 115.47695 -397.569344) (xy 115.493292 -397.540988) (xy 115.49661 -397.534965) (xy 115.500214 -397.5217)
			(xy 115.500404 -397.514826) (xy 115.500404 -396.765526) (xy 115.500202 -396.758654) (xy 115.496601 -396.745391)
			(xy 115.493292 -396.739364) (xy 115.476944 -396.711013) (xy 115.451199 -396.650846) (xy 115.433771 -396.587765)
			(xy 115.424978 -396.522914) (xy 115.424979 -396.457469) (xy 115.433775 -396.392619) (xy 115.451204 -396.329538)
			(xy 115.476952 -396.269372) (xy 115.493292 -396.241016) (xy 115.4966 -396.234988) (xy 115.50021 -396.221727)
			(xy 115.500404 -396.214854) (xy 115.500404 -395.92885) (xy 115.500904 -395.918686) (xy 115.508666 -395.899899)
			(xy 115.523028 -395.885513) (xy 115.541803 -395.87772) (xy 115.551966 -395.877288) (xy 116.268246 -395.877288)
			(xy 116.278427 -395.877627) (xy 116.297232 -395.885437) (xy 116.311617 -395.899849) (xy 116.319392 -395.918668)
			(xy 116.319808 -395.92885) (xy 116.319808 -396.214854) (xy 116.320017 -396.221726) (xy 116.323613 -396.234989)
			(xy 116.32692 -396.241016) (xy 116.34325 -396.269376) (xy 116.368997 -396.329542) (xy 116.386426 -396.392621)
			(xy 116.395221 -396.45747) (xy 116.395222 -396.522913) (xy 116.386429 -396.587762) (xy 116.369003 -396.650842)
			(xy 116.343258 -396.711008) (xy 116.32692 -396.739364) (xy 116.323619 -396.745396) (xy 116.320004 -396.758654)
			(xy 116.319808 -396.765526) (xy 116.319808 -397.514826) (xy 116.319989 -397.5217) (xy 116.323604 -397.534963)
			(xy 116.32692 -397.540988) (xy 116.336287 -397.557287) (xy 117.624883 -397.557287) (xy 117.633676 -397.492438)
			(xy 117.651103 -397.429358) (xy 117.676848 -397.369192) (xy 117.693186 -397.340836) (xy 117.696533 -397.334812)
			(xy 117.70028 -397.321559) (xy 117.700552 -397.314674) (xy 117.700552 -397.028924) (xy 117.701103 -397.018823)
			(xy 117.708824 -397.000154) (xy 117.7231 -396.98586) (xy 117.741759 -396.978116) (xy 117.75186 -396.977616)
			(xy 118.46814 -396.977616) (xy 118.478253 -396.978053) (xy 118.496935 -396.985807) (xy 118.511229 -397.000118)
			(xy 118.51896 -397.01881) (xy 118.519448 -397.028924) (xy 118.519448 -397.314674) (xy 118.519663 -397.321568)
			(xy 118.523404 -397.33484) (xy 118.526814 -397.340836) (xy 118.543161 -397.369187) (xy 118.568907 -397.429354)
			(xy 118.586334 -397.492436) (xy 118.595127 -397.557286) (xy 118.595126 -397.622731) (xy 118.586331 -397.687581)
			(xy 118.568901 -397.750662) (xy 118.543154 -397.810828) (xy 118.536203 -397.82289) (xy 119.825012 -397.82289)
			(xy 119.825017 -397.757445) (xy 119.833814 -397.692593) (xy 119.851246 -397.629512) (xy 119.876994 -397.569344)
			(xy 119.893334 -397.540988) (xy 119.896701 -397.534974) (xy 119.900435 -397.521713) (xy 119.9007 -397.514826)
			(xy 119.9007 -396.765526) (xy 119.900457 -396.758635) (xy 119.896721 -396.74537) (xy 119.893334 -396.739364)
			(xy 119.876988 -396.711012) (xy 119.851245 -396.650845) (xy 119.83382 -396.587764) (xy 119.825028 -396.522913)
			(xy 119.82503 -396.45747) (xy 119.833824 -396.39262) (xy 119.851251 -396.329539) (xy 119.876996 -396.269372)
			(xy 119.893334 -396.241016) (xy 119.896691 -396.234997) (xy 119.900431 -396.22174) (xy 119.9007 -396.214854)
			(xy 119.9007 -395.92885) (xy 119.901266 -395.918731) (xy 119.90897 -395.900019) (xy 119.923232 -395.885662)
			(xy 119.941893 -395.877834) (xy 119.952008 -395.877288) (xy 120.668288 -395.877288) (xy 120.67844 -395.877731)
			(xy 120.69719 -395.885521) (xy 120.711513 -395.899911) (xy 120.719215 -395.918696) (xy 120.719596 -395.92885)
			(xy 120.719596 -396.214854) (xy 120.719848 -396.221744) (xy 120.723577 -396.23501) (xy 120.726962 -396.241016)
			(xy 120.743291 -396.269377) (xy 120.769035 -396.329542) (xy 120.786463 -396.392622) (xy 120.795257 -396.45747)
			(xy 120.795258 -396.522913) (xy 120.786466 -396.587762) (xy 120.769041 -396.650841) (xy 120.743299 -396.711008)
			(xy 120.726962 -396.739364) (xy 120.723612 -396.745386) (xy 120.719867 -396.758641) (xy 120.719596 -396.765526)
			(xy 120.719596 -397.514826) (xy 120.719858 -397.521715) (xy 120.723581 -397.534981) (xy 120.726962 -397.540988)
			(xy 120.736329 -397.557288) (xy 122.024933 -397.557288) (xy 122.033725 -397.492439) (xy 122.05115 -397.429359)
			(xy 122.076892 -397.369192) (xy 122.093228 -397.340836) (xy 122.096532 -397.334806) (xy 122.100144 -397.321546)
			(xy 122.10034 -397.314674) (xy 122.10034 -397.028924) (xy 122.100742 -397.018766) (xy 122.108537 -397.000007)
			(xy 122.122941 -396.985681) (xy 122.141742 -396.977988) (xy 122.151902 -396.977616) (xy 122.868182 -396.977616)
			(xy 122.878305 -396.978141) (xy 122.897021 -396.985858) (xy 122.911377 -397.000132) (xy 122.919201 -397.018804)
			(xy 122.919744 -397.028924) (xy 122.919744 -397.314674) (xy 122.91994 -397.321547) (xy 122.923545 -397.33481)
			(xy 122.926856 -397.340836) (xy 122.943202 -397.369187) (xy 122.968945 -397.429355) (xy 122.986371 -397.492436)
			(xy 122.995163 -397.557287) (xy 122.995162 -397.62273) (xy 122.986368 -397.687581) (xy 122.96894 -397.750661)
			(xy 122.943194 -397.810828) (xy 122.936244 -397.82289) (xy 124.225049 -397.82289) (xy 124.225053 -397.757444)
			(xy 124.233851 -397.692592) (xy 124.251284 -397.629511) (xy 124.277035 -397.569344) (xy 124.293376 -397.540988)
			(xy 124.296693 -397.534965) (xy 124.300298 -397.5217) (xy 124.300488 -397.514826) (xy 124.300488 -396.765526)
			(xy 124.300287 -396.758653) (xy 124.296685 -396.745391) (xy 124.293376 -396.739364) (xy 124.277029 -396.711013)
			(xy 124.251284 -396.650845) (xy 124.233857 -396.587764) (xy 124.225064 -396.522913) (xy 124.225066 -396.457469)
			(xy 124.233861 -396.392619) (xy 124.25129 -396.329538) (xy 124.277037 -396.269372) (xy 124.293376 -396.241016)
			(xy 124.296683 -396.234988) (xy 124.300294 -396.221727) (xy 124.300488 -396.214854) (xy 124.300488 -395.92885)
			(xy 124.300906 -395.918675) (xy 124.308684 -395.899872) (xy 124.323072 -395.885484) (xy 124.341875 -395.877706)
			(xy 124.35205 -395.877288) (xy 125.06833 -395.877288) (xy 125.07851 -395.87764) (xy 125.097315 -395.885445)
			(xy 125.1117 -395.899852) (xy 125.119475 -395.91867) (xy 125.119892 -395.92885) (xy 125.119892 -396.214854)
			(xy 125.120103 -396.221726) (xy 125.123698 -396.234989) (xy 125.127004 -396.241016) (xy 125.143332 -396.269377)
			(xy 125.169074 -396.329543) (xy 125.1865 -396.392622) (xy 125.195293 -396.457471) (xy 125.195294 -396.522912)
			(xy 125.186503 -396.587761) (xy 125.16908 -396.65084) (xy 125.143339 -396.711007) (xy 125.127004 -396.739364)
			(xy 125.123702 -396.745395) (xy 125.120088 -396.758654) (xy 125.119892 -396.765526) (xy 125.119892 -397.514826)
			(xy 125.120075 -397.5217) (xy 125.123689 -397.534963) (xy 125.127004 -397.540988) (xy 125.13637 -397.557287)
			(xy 126.42497 -397.557287) (xy 126.433762 -397.492438) (xy 126.451188 -397.429358) (xy 126.476932 -397.369192)
			(xy 126.49327 -397.340836) (xy 126.496623 -397.334816) (xy 126.500365 -397.321559) (xy 126.500636 -397.314674)
			(xy 126.500636 -397.028924) (xy 126.501036 -397.018799) (xy 126.508783 -397.000089) (xy 126.523105 -396.985772)
			(xy 126.541818 -396.978032) (xy 126.551944 -396.977616) (xy 127.268224 -396.977616) (xy 127.278336 -396.978066)
			(xy 127.297018 -396.985814) (xy 127.311313 -397.000122) (xy 127.319044 -397.018811) (xy 127.319532 -397.028924)
			(xy 127.319532 -397.314674) (xy 127.319771 -397.321565) (xy 127.323509 -397.334831) (xy 127.326898 -397.340836)
			(xy 127.343243 -397.369188) (xy 127.368984 -397.429356) (xy 127.386408 -397.492437) (xy 127.395199 -397.557287)
			(xy 127.395198 -397.62273) (xy 127.386405 -397.68758) (xy 127.368978 -397.75066) (xy 127.343235 -397.810827)
			(xy 127.336285 -397.82289) (xy 128.624838 -397.82289) (xy 128.624843 -397.757444) (xy 128.633641 -397.692593)
			(xy 128.651073 -397.629511) (xy 128.676823 -397.569344) (xy 128.693164 -397.540988) (xy 128.69648 -397.534964)
			(xy 128.700085 -397.5217) (xy 128.700276 -397.514826) (xy 128.700276 -396.765526) (xy 128.700077 -396.758653)
			(xy 128.696474 -396.74539) (xy 128.693164 -396.739364) (xy 128.676817 -396.711013) (xy 128.651073 -396.650845)
			(xy 128.633647 -396.587764) (xy 128.624854 -396.522913) (xy 128.624855 -396.457469) (xy 128.63365 -396.392619)
			(xy 128.651079 -396.329539) (xy 128.676825 -396.269372) (xy 128.693164 -396.241016) (xy 128.69647 -396.234987)
			(xy 128.700082 -396.221727) (xy 128.700276 -396.214854) (xy 128.700276 -395.92885) (xy 128.700706 -395.918677)
			(xy 128.708481 -395.899876) (xy 128.722866 -395.885488) (xy 128.741665 -395.877708) (xy 128.751838 -395.877288)
			(xy 129.468118 -395.877288) (xy 129.478297 -395.87765) (xy 129.497102 -395.885451) (xy 129.511487 -395.899856)
			(xy 129.519263 -395.91867) (xy 129.51968 -395.92885) (xy 129.51968 -396.214854) (xy 129.519892 -396.221726)
			(xy 129.523487 -396.234988) (xy 129.526792 -396.241016) (xy 129.54312 -396.269377) (xy 129.568863 -396.329543)
			(xy 129.586289 -396.392622) (xy 129.595083 -396.45747) (xy 129.595083 -396.49019) (xy 133.023872 -396.49019)
			(xy 133.027863 -396.428023) (xy 133.039772 -396.366876) (xy 133.059401 -396.307755) (xy 133.08643 -396.251629)
			(xy 133.120414 -396.19942) (xy 133.160796 -396.151985) (xy 133.206912 -396.110104) (xy 133.258004 -396.074464)
			(xy 133.313235 -396.04565) (xy 133.371697 -396.024136) (xy 133.432431 -396.010274) (xy 133.494438 -396.004292)
			(xy 133.556701 -396.006288) (xy 133.618198 -396.016231) (xy 133.677919 -396.033955) (xy 133.734882 -396.059172)
			(xy 133.788153 -396.091465) (xy 133.836858 -396.130305) (xy 133.880195 -396.175055) (xy 133.917455 -396.224979)
			(xy 133.948024 -396.279258) (xy 133.971402 -396.337001) (xy 133.987203 -396.397259) (xy 133.995169 -396.459042)
			(xy 133.995668 -396.49019) (xy 133.995169 -396.521338) (xy 133.987203 -396.583121) (xy 133.971402 -396.643379)
			(xy 133.948024 -396.701122) (xy 133.917455 -396.755401) (xy 133.880195 -396.805325) (xy 133.836858 -396.850075)
			(xy 133.788153 -396.888915) (xy 133.734882 -396.921208) (xy 133.677919 -396.946425) (xy 133.618198 -396.964149)
			(xy 133.556701 -396.974092) (xy 133.494438 -396.976088) (xy 133.432431 -396.970106) (xy 133.371697 -396.956244)
			(xy 133.313235 -396.93473) (xy 133.258004 -396.905916) (xy 133.206912 -396.870276) (xy 133.160796 -396.828395)
			(xy 133.120414 -396.78096) (xy 133.08643 -396.728751) (xy 133.059401 -396.672625) (xy 133.039772 -396.613504)
			(xy 133.027863 -396.552357) (xy 133.023872 -396.49019) (xy 129.595083 -396.49019) (xy 129.595084 -396.522912)
			(xy 129.586293 -396.587761) (xy 129.568869 -396.650841) (xy 129.543128 -396.711008) (xy 129.526792 -396.739364)
			(xy 129.523489 -396.745395) (xy 129.519876 -396.758654) (xy 129.51968 -396.765526) (xy 129.51968 -397.514826)
			(xy 129.519865 -397.5217) (xy 129.523478 -397.534962) (xy 129.526792 -397.540988) (xy 129.536158 -397.557288)
			(xy 130.82502 -397.557288) (xy 130.833811 -397.492439) (xy 130.851235 -397.429359) (xy 130.876976 -397.369192)
			(xy 130.893312 -397.340836) (xy 130.896615 -397.334806) (xy 130.900228 -397.321546) (xy 130.900424 -397.314674)
			(xy 130.900424 -397.028924) (xy 130.900842 -397.018768) (xy 130.908634 -397.000012) (xy 130.923032 -396.985687)
			(xy 130.941828 -396.97799) (xy 130.951986 -396.977616) (xy 131.668266 -396.977616) (xy 131.678388 -396.978154)
			(xy 131.697103 -396.985866) (xy 131.71146 -397.000137) (xy 131.719284 -397.018806) (xy 131.719828 -397.028924)
			(xy 131.719828 -397.314674) (xy 131.720026 -397.321547) (xy 131.72363 -397.33481) (xy 131.72694 -397.340836)
			(xy 131.743287 -397.369187) (xy 131.769031 -397.429355) (xy 131.786457 -397.492436) (xy 131.795249 -397.557287)
			(xy 131.795248 -397.622731) (xy 131.786454 -397.687581) (xy 131.769025 -397.750661) (xy 131.752122 -397.790162)
			(xy 133.023872 -397.790162) (xy 133.027863 -397.727995) (xy 133.039772 -397.666848) (xy 133.059401 -397.607727)
			(xy 133.08643 -397.551601) (xy 133.120414 -397.499392) (xy 133.160796 -397.451957) (xy 133.206912 -397.410076)
			(xy 133.258004 -397.374436) (xy 133.313235 -397.345622) (xy 133.371697 -397.324108) (xy 133.432431 -397.310246)
			(xy 133.494438 -397.304264) (xy 133.556701 -397.30626) (xy 133.618198 -397.316203) (xy 133.677919 -397.333927)
			(xy 133.734882 -397.359144) (xy 133.788153 -397.391437) (xy 133.836858 -397.430277) (xy 133.880195 -397.475027)
			(xy 133.917455 -397.524951) (xy 133.948024 -397.57923) (xy 133.971402 -397.636973) (xy 133.987203 -397.697231)
			(xy 133.995169 -397.759014) (xy 133.995668 -397.790162) (xy 133.995169 -397.82131) (xy 133.987203 -397.883093)
			(xy 133.971402 -397.943351) (xy 133.948024 -398.001094) (xy 133.917455 -398.055373) (xy 133.880195 -398.105297)
			(xy 133.836858 -398.150047) (xy 133.788153 -398.188887) (xy 133.734882 -398.22118) (xy 133.677919 -398.246397)
			(xy 133.618198 -398.264121) (xy 133.556701 -398.274064) (xy 133.494438 -398.27606) (xy 133.432431 -398.270078)
			(xy 133.371697 -398.256216) (xy 133.313235 -398.234702) (xy 133.258004 -398.205888) (xy 133.206912 -398.170248)
			(xy 133.160796 -398.128367) (xy 133.120414 -398.080932) (xy 133.08643 -398.028723) (xy 133.059401 -397.972597)
			(xy 133.039772 -397.913476) (xy 133.027863 -397.852329) (xy 133.023872 -397.790162) (xy 131.752122 -397.790162)
			(xy 131.743279 -397.810828) (xy 131.72694 -397.839184) (xy 131.723634 -397.845213) (xy 131.720023 -397.858473)
			(xy 131.719828 -397.865346) (xy 131.719828 -398.6149) (xy 131.720017 -398.621774) (xy 131.723627 -398.635036)
			(xy 131.72694 -398.641062) (xy 131.743309 -398.669401) (xy 131.769051 -398.729572) (xy 131.786475 -398.792655)
			(xy 131.795264 -398.857508) (xy 131.79526 -398.922954) (xy 131.786462 -398.987805) (xy 131.76903 -399.050887)
			(xy 131.74328 -399.111054) (xy 131.72694 -399.13941) (xy 131.723625 -399.145435) (xy 131.720019 -399.158698)
			(xy 131.719828 -399.165572) (xy 131.719828 -399.451576) (xy 131.719359 -399.461725) (xy 131.711577 -399.480472)
			(xy 131.697195 -399.494795) (xy 131.678417 -399.502501) (xy 131.668266 -399.502884) (xy 130.951986 -399.502884)
			(xy 130.941861 -399.502385) (xy 130.923145 -399.494657) (xy 130.90879 -399.480375) (xy 130.900967 -399.461698)
			(xy 130.900424 -399.451576) (xy 130.900424 -399.165572) (xy 130.90024 -399.158698) (xy 130.896626 -399.145436)
			(xy 130.893312 -399.13941) (xy 130.877006 -399.111037) (xy 130.851261 -399.050874) (xy 130.833832 -398.987797)
			(xy 130.825036 -398.922951) (xy 130.825031 -398.857511) (xy 130.833819 -398.792663) (xy 130.85124 -398.729585)
			(xy 130.876978 -398.669418) (xy 130.893312 -398.641062) (xy 130.896641 -398.635044) (xy 130.900237 -398.621775)
			(xy 130.900424 -398.6149) (xy 130.900424 -397.865346) (xy 130.900212 -397.858474) (xy 130.896617 -397.845212)
			(xy 130.893312 -397.839184) (xy 130.876984 -397.810823) (xy 130.851241 -397.750657) (xy 130.833814 -397.687578)
			(xy 130.825021 -397.62273) (xy 130.82502 -397.557288) (xy 129.536158 -397.557288) (xy 129.543096 -397.569362)
			(xy 129.568841 -397.629525) (xy 129.58627 -397.692601) (xy 129.595067 -397.757447) (xy 129.595071 -397.822887)
			(xy 129.586283 -397.887735) (xy 129.568863 -397.950813) (xy 129.543126 -398.01098) (xy 129.526792 -398.039336)
			(xy 129.523464 -398.045354) (xy 129.519867 -398.058623) (xy 129.51968 -398.065498) (xy 129.51968 -398.351502)
			(xy 129.519169 -398.361658) (xy 129.511397 -398.380423) (xy 129.497037 -398.394788) (xy 129.478274 -398.402565)
			(xy 129.468118 -398.403064) (xy 128.751838 -398.403064) (xy 128.741669 -398.402605) (xy 128.722876 -398.394833)
			(xy 128.70849 -398.380458) (xy 128.700703 -398.361671) (xy 128.700276 -398.351502) (xy 128.700276 -398.065498)
			(xy 128.700088 -398.058624) (xy 128.696477 -398.045362) (xy 128.693164 -398.039336) (xy 128.676794 -398.010998)
			(xy 128.651051 -397.950827) (xy 128.633628 -397.887743) (xy 128.624838 -397.82289) (xy 127.336285 -397.82289)
			(xy 127.326898 -397.839184) (xy 127.323543 -397.845204) (xy 127.319801 -397.85846) (xy 127.319532 -397.865346)
			(xy 127.319532 -398.6149) (xy 127.319761 -398.621792) (xy 127.323506 -398.635058) (xy 127.326898 -398.641062)
			(xy 127.343265 -398.669402) (xy 127.369004 -398.729573) (xy 127.386426 -398.792656) (xy 127.395214 -398.857508)
			(xy 127.39521 -398.922953) (xy 127.386413 -398.987804) (xy 127.368983 -399.050886) (xy 127.343237 -399.111053)
			(xy 127.326898 -399.13941) (xy 127.323534 -399.145425) (xy 127.319798 -399.158685) (xy 127.319532 -399.165572)
			(xy 127.319532 -399.451576) (xy 127.318996 -399.461679) (xy 127.311272 -399.480351) (xy 127.296991 -399.494645)
			(xy 127.278327 -399.502387) (xy 127.268224 -399.502884) (xy 126.551944 -399.502884) (xy 126.541822 -399.502447)
			(xy 126.523117 -399.494711) (xy 126.5088 -399.4804) (xy 126.501056 -399.461697) (xy 126.500636 -399.451576)
			(xy 126.500636 -399.165572) (xy 126.500405 -399.158679) (xy 126.496675 -399.145407) (xy 126.49327 -399.13941)
			(xy 126.476962 -399.111037) (xy 126.451214 -399.050875) (xy 126.433783 -398.987798) (xy 126.424986 -398.922951)
			(xy 126.424981 -398.85751) (xy 126.43377 -398.792662) (xy 126.451193 -398.729584) (xy 126.476934 -398.669418)
			(xy 126.49327 -398.641062) (xy 126.496649 -398.635054) (xy 126.500375 -398.621788) (xy 126.500636 -398.6149)
			(xy 126.500636 -397.865346) (xy 126.500416 -397.858452) (xy 126.496679 -397.84518) (xy 126.49327 -397.839184)
			(xy 126.47694 -397.810823) (xy 126.451194 -397.750658) (xy 126.433765 -397.687579) (xy 126.424971 -397.62273)
			(xy 126.42497 -397.557287) (xy 125.13637 -397.557287) (xy 125.143308 -397.569362) (xy 125.169052 -397.629525)
			(xy 125.186481 -397.692602) (xy 125.195277 -397.757448) (xy 125.195281 -397.822887) (xy 125.186494 -397.887734)
			(xy 125.169074 -397.950813) (xy 125.143337 -398.010979) (xy 125.127004 -398.039336) (xy 125.123677 -398.045355)
			(xy 125.120079 -398.058623) (xy 125.119892 -398.065498) (xy 125.119892 -398.351502) (xy 125.119369 -398.361656)
			(xy 125.111599 -398.38042) (xy 125.097243 -398.394784) (xy 125.078484 -398.402563) (xy 125.06833 -398.403064)
			(xy 124.35205 -398.403064) (xy 124.341882 -398.402595) (xy 124.323089 -398.394827) (xy 124.308702 -398.380455)
			(xy 124.300915 -398.36167) (xy 124.300488 -398.351502) (xy 124.300488 -398.065498) (xy 124.300299 -398.058625)
			(xy 124.296689 -398.045362) (xy 124.293376 -398.039336) (xy 124.277005 -398.010998) (xy 124.251262 -397.950827)
			(xy 124.233838 -397.887744) (xy 124.225049 -397.82289) (xy 122.936244 -397.82289) (xy 122.926856 -397.839184)
			(xy 122.923551 -397.845214) (xy 122.919939 -397.858473) (xy 122.919744 -397.865346) (xy 122.919744 -398.6149)
			(xy 122.919931 -398.621774) (xy 122.923542 -398.635037) (xy 122.926856 -398.641062) (xy 122.943224 -398.669401)
			(xy 122.968965 -398.729572) (xy 122.986389 -398.792655) (xy 122.995178 -398.857508) (xy 122.995174 -398.922954)
			(xy 122.986376 -398.987805) (xy 122.968945 -399.050887) (xy 122.943196 -399.111054) (xy 122.926856 -399.13941)
			(xy 122.923542 -399.145435) (xy 122.919935 -399.158698) (xy 122.919744 -399.165572) (xy 122.919744 -399.451576)
			(xy 122.91926 -399.461723) (xy 122.91148 -399.480467) (xy 122.897103 -399.494789) (xy 122.878331 -399.502498)
			(xy 122.868182 -399.502884) (xy 122.151902 -399.502884) (xy 122.141778 -399.502372) (xy 122.123062 -399.49465)
			(xy 122.108706 -399.480371) (xy 122.100883 -399.461697) (xy 122.10034 -399.451576) (xy 122.10034 -399.165572)
			(xy 122.100154 -399.158698) (xy 122.096541 -399.145436) (xy 122.093228 -399.13941) (xy 122.076921 -399.111037)
			(xy 122.051175 -399.050874) (xy 122.033746 -398.987797) (xy 122.024949 -398.922951) (xy 122.024945 -398.857511)
			(xy 122.033734 -398.792663) (xy 122.051155 -398.729584) (xy 122.076893 -398.669418) (xy 122.093228 -398.641062)
			(xy 122.096558 -398.635045) (xy 122.100154 -398.621775) (xy 122.10034 -398.6149) (xy 122.10034 -397.865346)
			(xy 122.100126 -397.858474) (xy 122.096532 -397.845212) (xy 122.093228 -397.839184) (xy 122.076899 -397.810823)
			(xy 122.051155 -397.750657) (xy 122.033728 -397.687578) (xy 122.024935 -397.62273) (xy 122.024933 -397.557288)
			(xy 120.736329 -397.557288) (xy 120.743267 -397.569362) (xy 120.769014 -397.629525) (xy 120.786444 -397.692601)
			(xy 120.795241 -397.757447) (xy 120.795245 -397.822888) (xy 120.786457 -397.887735) (xy 120.769036 -397.950814)
			(xy 120.743297 -398.01098) (xy 120.726962 -398.039336) (xy 120.723586 -398.045345) (xy 120.719858 -398.05861)
			(xy 120.719596 -398.065498) (xy 120.719596 -398.351502) (xy 120.719076 -398.361624) (xy 120.711354 -398.380339)
			(xy 120.697079 -398.394694) (xy 120.678408 -398.402519) (xy 120.668288 -398.403064) (xy 119.952008 -398.403064)
			(xy 119.94185 -398.402671) (xy 119.923091 -398.394871) (xy 119.908766 -398.380465) (xy 119.901072 -398.361662)
			(xy 119.9007 -398.351502) (xy 119.9007 -398.065498) (xy 119.900467 -398.058607) (xy 119.896725 -398.045341)
			(xy 119.893334 -398.039336) (xy 119.876965 -398.010998) (xy 119.851224 -397.950827) (xy 119.833801 -397.887743)
			(xy 119.825012 -397.82289) (xy 118.536203 -397.82289) (xy 118.526814 -397.839184) (xy 118.52346 -397.845204)
			(xy 118.519717 -397.85846) (xy 118.519448 -397.865346) (xy 118.519448 -398.6149) (xy 118.519653 -398.621795)
			(xy 118.523401 -398.635067) (xy 118.526814 -398.641062) (xy 118.543183 -398.669401) (xy 118.568927 -398.729571)
			(xy 118.586352 -398.792655) (xy 118.595142 -398.857508) (xy 118.595138 -398.922954) (xy 118.586339 -398.987806)
			(xy 118.568906 -399.050887) (xy 118.543155 -399.111054) (xy 118.526814 -399.13941) (xy 118.523451 -399.145426)
			(xy 118.519714 -399.158685) (xy 118.519448 -399.165572) (xy 118.519448 -399.451576) (xy 118.518897 -399.461677)
			(xy 118.511176 -399.480346) (xy 118.4969 -399.49464) (xy 118.478241 -399.502384) (xy 118.46814 -399.502884)
			(xy 117.75186 -399.502884) (xy 117.741747 -399.502447) (xy 117.723065 -399.494693) (xy 117.708771 -399.480382)
			(xy 117.70104 -399.46169) (xy 117.700552 -399.451576) (xy 117.700552 -399.165572) (xy 117.700319 -399.158679)
			(xy 117.696591 -399.145407) (xy 117.693186 -399.13941) (xy 117.676878 -399.111037) (xy 117.651128 -399.050875)
			(xy 117.633697 -398.987798) (xy 117.624899 -398.922951) (xy 117.624895 -398.85751) (xy 117.633685 -398.792662)
			(xy 117.651108 -398.729583) (xy 117.67685 -398.669418) (xy 117.693186 -398.641062) (xy 117.696559 -398.635051)
			(xy 117.70029 -398.621788) (xy 117.700552 -398.6149) (xy 117.700552 -397.865346) (xy 117.700329 -397.858452)
			(xy 117.696594 -397.84518) (xy 117.693186 -397.839184) (xy 117.676856 -397.810824) (xy 117.651108 -397.750658)
			(xy 117.633679 -397.687579) (xy 117.624885 -397.62273) (xy 117.624883 -397.557287) (xy 116.336287 -397.557287)
			(xy 116.343226 -397.569362) (xy 116.368975 -397.629524) (xy 116.386407 -397.6926) (xy 116.395205 -397.757447)
			(xy 116.395209 -397.822888) (xy 116.38642 -397.887736) (xy 116.368997 -397.950815) (xy 116.343256 -398.01098)
			(xy 116.32692 -398.039336) (xy 116.323594 -398.045355) (xy 116.319995 -398.058623) (xy 116.319808 -398.065498)
			(xy 116.319808 -398.351502) (xy 116.319269 -398.361654) (xy 116.311503 -398.380415) (xy 116.297152 -398.394778)
			(xy 116.278398 -398.402561) (xy 116.268246 -398.403064) (xy 115.551966 -398.403064) (xy 115.541806 -398.402595)
			(xy 115.523037 -398.394809) (xy 115.508673 -398.380436) (xy 115.500899 -398.361662) (xy 115.500404 -398.351502)
			(xy 115.500404 -398.065498) (xy 115.500212 -398.058625) (xy 115.496604 -398.045362) (xy 115.493292 -398.039336)
			(xy 115.476921 -398.010998) (xy 115.451177 -397.950828) (xy 115.433752 -397.887744) (xy 115.424962 -397.822891)
			(xy 94.04731 -397.822891) (xy 94.04731 -398.66824) (xy 100.573076 -398.66824) (xy 100.577147 -398.612618)
			(xy 100.589273 -398.558181) (xy 100.609196 -398.50609) (xy 100.636492 -398.457455) (xy 100.670578 -398.413312)
			(xy 100.710727 -398.374603) (xy 100.756085 -398.342152) (xy 100.805685 -398.316651) (xy 100.858469 -398.298644)
			(xy 100.913312 -398.288514) (xy 100.969046 -398.286477) (xy 101.024483 -398.292577) (xy 101.07844 -398.306683)
			(xy 101.129769 -398.328495) (xy 101.177375 -398.357549) (xy 101.220243 -398.393224) (xy 101.25746 -398.434761)
			(xy 101.288233 -398.481274) (xy 101.311905 -398.531771) (xy 101.327973 -398.585178) (xy 101.336093 -398.640354)
			(xy 101.336602 -398.66824) (xy 101.589076 -398.66824) (xy 101.593147 -398.612618) (xy 101.605273 -398.558181)
			(xy 101.625196 -398.50609) (xy 101.652492 -398.457455) (xy 101.686578 -398.413312) (xy 101.726727 -398.374603)
			(xy 101.772085 -398.342152) (xy 101.821685 -398.316651) (xy 101.874469 -398.298644) (xy 101.929312 -398.288514)
			(xy 101.985046 -398.286477) (xy 102.040483 -398.292577) (xy 102.09444 -398.306683) (xy 102.145769 -398.328495)
			(xy 102.193375 -398.357549) (xy 102.236243 -398.393224) (xy 102.27346 -398.434761) (xy 102.304233 -398.481274)
			(xy 102.327905 -398.531771) (xy 102.343973 -398.585178) (xy 102.352093 -398.640354) (xy 102.352602 -398.66824)
			(xy 102.352491 -398.674336) (xy 105.653076 -398.674336) (xy 105.657147 -398.618714) (xy 105.669273 -398.564277)
			(xy 105.689196 -398.512186) (xy 105.716492 -398.463551) (xy 105.750578 -398.419408) (xy 105.790727 -398.380699)
			(xy 105.836085 -398.348248) (xy 105.885685 -398.322747) (xy 105.938469 -398.30474) (xy 105.993312 -398.29461)
			(xy 106.049046 -398.292573) (xy 106.104483 -398.298673) (xy 106.15844 -398.312779) (xy 106.209769 -398.334591)
			(xy 106.257375 -398.363645) (xy 106.300243 -398.39932) (xy 106.33746 -398.440857) (xy 106.368233 -398.48737)
			(xy 106.391905 -398.537867) (xy 106.407973 -398.591274) (xy 106.416093 -398.64645) (xy 106.416602 -398.674336)
			(xy 106.416093 -398.702222) (xy 106.407973 -398.757398) (xy 106.391905 -398.810805) (xy 106.368233 -398.861302)
			(xy 106.33746 -398.907815) (xy 106.300243 -398.949352) (xy 106.257375 -398.985027) (xy 106.209769 -399.014081)
			(xy 106.15844 -399.035893) (xy 106.104483 -399.049999) (xy 106.049046 -399.056099) (xy 105.993312 -399.054062)
			(xy 105.938469 -399.043932) (xy 105.885685 -399.025925) (xy 105.836085 -399.000424) (xy 105.790727 -398.967973)
			(xy 105.750578 -398.929264) (xy 105.716492 -398.885121) (xy 105.689196 -398.836486) (xy 105.669273 -398.784395)
			(xy 105.657147 -398.729958) (xy 105.653076 -398.674336) (xy 102.352491 -398.674336) (xy 102.352093 -398.696126)
			(xy 102.343973 -398.751302) (xy 102.327905 -398.804709) (xy 102.304233 -398.855206) (xy 102.27346 -398.901719)
			(xy 102.236243 -398.943256) (xy 102.193375 -398.978931) (xy 102.145769 -399.007985) (xy 102.09444 -399.029797)
			(xy 102.040483 -399.043903) (xy 101.985046 -399.050003) (xy 101.929312 -399.047966) (xy 101.874469 -399.037836)
			(xy 101.821685 -399.019829) (xy 101.772085 -398.994328) (xy 101.726727 -398.961877) (xy 101.686578 -398.923168)
			(xy 101.652492 -398.879025) (xy 101.625196 -398.83039) (xy 101.605273 -398.778299) (xy 101.593147 -398.723862)
			(xy 101.589076 -398.66824) (xy 101.336602 -398.66824) (xy 101.336093 -398.696126) (xy 101.327973 -398.751302)
			(xy 101.311905 -398.804709) (xy 101.288233 -398.855206) (xy 101.25746 -398.901719) (xy 101.220243 -398.943256)
			(xy 101.177375 -398.978931) (xy 101.129769 -399.007985) (xy 101.07844 -399.029797) (xy 101.024483 -399.043903)
			(xy 100.969046 -399.050003) (xy 100.913312 -399.047966) (xy 100.858469 -399.037836) (xy 100.805685 -399.019829)
			(xy 100.756085 -398.994328) (xy 100.710727 -398.961877) (xy 100.670578 -398.923168) (xy 100.636492 -398.879025)
			(xy 100.609196 -398.83039) (xy 100.589273 -398.778299) (xy 100.577147 -398.723862) (xy 100.573076 -398.66824)
			(xy 94.04731 -398.66824) (xy 94.04731 -401.722804) (xy 115.424971 -401.722804) (xy 115.424974 -401.657359)
			(xy 115.433771 -401.592507) (xy 115.451202 -401.529426) (xy 115.476952 -401.46926) (xy 115.493292 -401.440904)
			(xy 115.496605 -401.434878) (xy 115.500212 -401.421615) (xy 115.500404 -401.414742) (xy 115.500404 -400.665442)
			(xy 115.500195 -400.65857) (xy 115.496598 -400.645307) (xy 115.493292 -400.63928) (xy 115.476958 -400.610922)
			(xy 115.451211 -400.550756) (xy 115.433782 -400.487676) (xy 115.424987 -400.422827) (xy 115.424987 -400.357384)
			(xy 115.43378 -400.292534) (xy 115.451207 -400.229454) (xy 115.476953 -400.169288) (xy 115.493292 -400.140932)
			(xy 115.496595 -400.134902) (xy 115.500208 -400.121642) (xy 115.500404 -400.11477) (xy 115.500404 -399.828766)
			(xy 115.500905 -399.81861) (xy 115.508684 -399.799847) (xy 115.523047 -399.785484) (xy 115.54181 -399.777705)
			(xy 115.551966 -399.777204) (xy 116.268246 -399.777204) (xy 116.278403 -399.777695) (xy 116.297166 -399.785478)
			(xy 116.311529 -399.799844) (xy 116.319307 -399.818609) (xy 116.319808 -399.828766) (xy 116.319808 -400.11477)
			(xy 116.320011 -400.121642) (xy 116.323612 -400.134905) (xy 116.32692 -400.140932) (xy 116.343264 -400.169285)
			(xy 116.369009 -400.229452) (xy 116.386437 -400.292533) (xy 116.39523 -400.357383) (xy 116.395229 -400.422827)
			(xy 116.386435 -400.487677) (xy 116.369006 -400.550758) (xy 116.343259 -400.610924) (xy 116.32692 -400.63928)
			(xy 116.323614 -400.645309) (xy 116.320002 -400.658569) (xy 116.319808 -400.665442) (xy 116.319808 -401.414742)
			(xy 116.320021 -401.421614) (xy 116.323615 -401.434876) (xy 116.32692 -401.440904) (xy 116.34324 -401.46927)
			(xy 116.368988 -401.529434) (xy 116.386418 -401.592512) (xy 116.395214 -401.65736) (xy 116.395216 -401.722802)
			(xy 116.386425 -401.787651) (xy 116.369 -401.85073) (xy 116.343257 -401.910896) (xy 116.32692 -401.939252)
			(xy 116.323588 -401.945268) (xy 116.319993 -401.958538) (xy 116.319808 -401.965414) (xy 116.319808 -402.251418)
			(xy 116.319283 -402.261571) (xy 116.311511 -402.280332) (xy 116.297156 -402.294695) (xy 116.278399 -402.302477)
			(xy 116.268246 -402.30298) (xy 115.551966 -402.30298) (xy 115.541808 -402.302495) (xy 115.523042 -402.294713)
			(xy 115.508678 -402.280345) (xy 115.500902 -402.261576) (xy 115.500404 -402.251418) (xy 115.500404 -401.965414)
			(xy 115.500206 -401.958541) (xy 115.496602 -401.945278) (xy 115.493292 -401.939252) (xy 115.476934 -401.910907)
			(xy 115.451189 -401.850738) (xy 115.433763 -401.787656) (xy 115.424971 -401.722804) (xy 94.04731 -401.722804)
			(xy 94.04731 -402.822882) (xy 117.624851 -402.822882) (xy 117.624857 -402.757435) (xy 117.633657 -402.692583)
			(xy 117.651091 -402.629501) (xy 117.676844 -402.569334) (xy 117.693186 -402.540978) (xy 117.696553 -402.534964)
			(xy 117.700288 -402.521703) (xy 117.700552 -402.514816) (xy 117.700552 -401.765516) (xy 117.700341 -401.758621)
			(xy 117.696597 -401.74535) (xy 117.693186 -401.739354) (xy 117.67683 -401.711008) (xy 117.651085 -401.650839)
			(xy 117.633659 -401.587757) (xy 117.624867 -401.522905) (xy 117.62487 -401.45746) (xy 117.633666 -401.392609)
			(xy 117.651097 -401.329528) (xy 117.676846 -401.269362) (xy 117.693186 -401.241006) (xy 117.696543 -401.234987)
			(xy 117.700284 -401.22173) (xy 117.700552 -401.214844) (xy 117.700552 -400.92884) (xy 117.701117 -400.91874)
			(xy 117.708832 -400.900072) (xy 117.723105 -400.885777) (xy 117.741761 -400.878033) (xy 117.75186 -400.877532)
			(xy 118.46814 -400.877532) (xy 118.478255 -400.877953) (xy 118.49694 -400.88571) (xy 118.511235 -400.900027)
			(xy 118.518963 -400.918724) (xy 118.519448 -400.92884) (xy 118.519448 -401.214844) (xy 118.519674 -401.221737)
			(xy 118.523407 -401.235009) (xy 118.526814 -401.241006) (xy 118.543136 -401.269371) (xy 118.568884 -401.329535)
			(xy 118.586314 -401.392613) (xy 118.59511 -401.457462) (xy 118.595112 -401.522904) (xy 118.586321 -401.587753)
			(xy 118.568895 -401.650832) (xy 118.543151 -401.710998) (xy 118.53635 -401.722803) (xy 119.825022 -401.722803)
			(xy 119.825024 -401.657359) (xy 119.83382 -401.592508) (xy 119.851249 -401.529427) (xy 119.876995 -401.46926)
			(xy 119.893334 -401.440904) (xy 119.896695 -401.434888) (xy 119.900433 -401.421628) (xy 119.9007 -401.414742)
			(xy 119.9007 -400.665442) (xy 119.900451 -400.658552) (xy 119.896719 -400.645286) (xy 119.893334 -400.63928)
			(xy 119.877002 -400.610921) (xy 119.851258 -400.550755) (xy 119.833831 -400.487675) (xy 119.825037 -400.422826)
			(xy 119.825037 -400.357384) (xy 119.833829 -400.292535) (xy 119.851254 -400.229455) (xy 119.876997 -400.169288)
			(xy 119.893334 -400.140932) (xy 119.896686 -400.134911) (xy 119.900429 -400.121655) (xy 119.9007 -400.11477)
			(xy 119.9007 -399.828766) (xy 119.901197 -399.818642) (xy 119.908929 -399.799928) (xy 119.923211 -399.785574)
			(xy 119.941887 -399.777749) (xy 119.952008 -399.777204) (xy 120.668288 -399.777204) (xy 120.678442 -399.777631)
			(xy 120.697195 -399.785424) (xy 120.711519 -399.799819) (xy 120.719218 -399.81861) (xy 120.719596 -399.828766)
			(xy 120.719596 -400.11477) (xy 120.719841 -400.12166) (xy 120.723576 -400.134926) (xy 120.726962 -400.140932)
			(xy 120.743304 -400.169285) (xy 120.769048 -400.229453) (xy 120.786474 -400.292533) (xy 120.795266 -400.357383)
			(xy 120.795265 -400.422827) (xy 120.786472 -400.487677) (xy 120.769044 -400.550757) (xy 120.7433 -400.610924)
			(xy 120.726962 -400.63928) (xy 120.723606 -400.645299) (xy 120.719865 -400.658556) (xy 120.719596 -400.665442)
			(xy 120.719596 -401.414742) (xy 120.719852 -401.421632) (xy 120.723579 -401.434898) (xy 120.726962 -401.440904)
			(xy 120.743281 -401.46927) (xy 120.769026 -401.529435) (xy 120.786455 -401.592513) (xy 120.79525 -401.65736)
			(xy 120.795253 -401.722802) (xy 120.786462 -401.78765) (xy 120.769039 -401.85073) (xy 120.743298 -401.910896)
			(xy 120.726962 -401.939252) (xy 120.723581 -401.945259) (xy 120.719856 -401.958525) (xy 120.719596 -401.965414)
			(xy 120.719596 -402.251418) (xy 120.719089 -402.261541) (xy 120.711362 -402.280256) (xy 120.697083 -402.294611)
			(xy 120.678409 -402.302436) (xy 120.668288 -402.30298) (xy 119.952008 -402.30298) (xy 119.941852 -402.302571)
			(xy 119.923096 -402.294775) (xy 119.908771 -402.280374) (xy 119.901075 -402.261576) (xy 119.9007 -402.251418)
			(xy 119.9007 -401.965414) (xy 119.900461 -401.958523) (xy 119.896723 -401.945257) (xy 119.893334 -401.939252)
			(xy 119.876978 -401.910906) (xy 119.851236 -401.850737) (xy 119.833812 -401.787655) (xy 119.825022 -401.722803)
			(xy 118.53635 -401.722803) (xy 118.526814 -401.739354) (xy 118.523436 -401.745362) (xy 118.519708 -401.758628)
			(xy 118.519448 -401.765516) (xy 118.519448 -402.514816) (xy 118.519685 -402.521708) (xy 118.523411 -402.534981)
			(xy 118.526814 -402.540978) (xy 118.543112 -402.569356) (xy 118.568862 -402.629517) (xy 118.586295 -402.692593)
			(xy 118.595094 -402.757439) (xy 118.595099 -402.822879) (xy 118.595099 -402.822882) (xy 122.024902 -402.822882)
			(xy 122.024907 -402.757436) (xy 122.033706 -402.692584) (xy 122.051138 -402.629502) (xy 122.076888 -402.569334)
			(xy 122.093228 -402.540978) (xy 122.096553 -402.534958) (xy 122.100151 -402.521691) (xy 122.10034 -402.514816)
			(xy 122.10034 -401.765516) (xy 122.100137 -401.758644) (xy 122.096536 -401.745381) (xy 122.093228 -401.739354)
			(xy 122.076874 -401.711007) (xy 122.051132 -401.650838) (xy 122.033708 -401.587756) (xy 122.024917 -401.522905)
			(xy 122.02492 -401.457461) (xy 122.033715 -401.39261) (xy 122.051144 -401.329529) (xy 122.07689 -401.269362)
			(xy 122.093228 -401.241006) (xy 122.096543 -401.234981) (xy 122.100148 -401.221718) (xy 122.10034 -401.214844)
			(xy 122.10034 -400.92884) (xy 122.100755 -400.918684) (xy 122.108545 -400.899924) (xy 122.122945 -400.885598)
			(xy 122.141743 -400.877904) (xy 122.151902 -400.877532) (xy 122.868182 -400.877532) (xy 122.878307 -400.878041)
			(xy 122.897026 -400.885761) (xy 122.911383 -400.900041) (xy 122.919204 -400.918718) (xy 122.919744 -400.92884)
			(xy 122.919744 -401.214844) (xy 122.919952 -401.221716) (xy 122.923549 -401.234979) (xy 122.926856 -401.241006)
			(xy 122.943177 -401.269371) (xy 122.968922 -401.329536) (xy 122.986351 -401.392614) (xy 122.995146 -401.457462)
			(xy 122.995148 -401.522904) (xy 122.986358 -401.587752) (xy 122.968934 -401.650832) (xy 122.943192 -401.710998)
			(xy 122.936391 -401.722804) (xy 124.225058 -401.722804) (xy 124.22506 -401.657359) (xy 124.233857 -401.592508)
			(xy 124.251287 -401.529427) (xy 124.277036 -401.46926) (xy 124.293376 -401.440904) (xy 124.296688 -401.434878)
			(xy 124.300296 -401.421615) (xy 124.300488 -401.414742) (xy 124.300488 -400.665442) (xy 124.300281 -400.65857)
			(xy 124.296683 -400.645307) (xy 124.293376 -400.63928) (xy 124.277043 -400.610921) (xy 124.251296 -400.550756)
			(xy 124.233868 -400.487676) (xy 124.225074 -400.422827) (xy 124.225073 -400.357384) (xy 124.233866 -400.292534)
			(xy 124.251293 -400.229454) (xy 124.277038 -400.169288) (xy 124.293376 -400.140932) (xy 124.296678 -400.134901)
			(xy 124.300292 -400.121642) (xy 124.300488 -400.11477) (xy 124.300488 -399.828766) (xy 124.300837 -399.818586)
			(xy 124.308643 -399.799781) (xy 124.323052 -399.785395) (xy 124.341869 -399.777621) (xy 124.35205 -399.777204)
			(xy 125.06833 -399.777204) (xy 125.078486 -399.777708) (xy 125.097249 -399.785486) (xy 125.111612 -399.799848)
			(xy 125.119391 -399.818611) (xy 125.119892 -399.828766) (xy 125.119892 -400.11477) (xy 125.120096 -400.121642)
			(xy 125.123696 -400.134905) (xy 125.127004 -400.140932) (xy 125.143345 -400.169286) (xy 125.169086 -400.229454)
			(xy 125.186511 -400.292534) (xy 125.195302 -400.357384) (xy 125.195301 -400.422827) (xy 125.186508 -400.487676)
			(xy 125.169083 -400.550756) (xy 125.14334 -400.610923) (xy 125.127004 -400.63928) (xy 125.123697 -400.645308)
			(xy 125.120086 -400.658569) (xy 125.119892 -400.665442) (xy 125.119892 -401.414742) (xy 125.120107 -401.421614)
			(xy 125.1237 -401.434876) (xy 125.127004 -401.440904) (xy 125.143321 -401.469271) (xy 125.169065 -401.529436)
			(xy 125.186492 -401.592513) (xy 125.195286 -401.657361) (xy 125.195289 -401.722802) (xy 125.186499 -401.78765)
			(xy 125.169077 -401.850729) (xy 125.143339 -401.910895) (xy 125.127004 -401.939252) (xy 125.123671 -401.945268)
			(xy 125.120077 -401.958538) (xy 125.119892 -401.965414) (xy 125.119892 -402.251418) (xy 125.119382 -402.261573)
			(xy 125.111608 -402.280337) (xy 125.097247 -402.294701) (xy 125.078485 -402.30248) (xy 125.06833 -402.30298)
			(xy 124.35205 -402.30298) (xy 124.341884 -402.302496) (xy 124.323094 -402.29473) (xy 124.308708 -402.280363)
			(xy 124.300918 -402.261584) (xy 124.300488 -402.251418) (xy 124.300488 -401.965414) (xy 124.300292 -401.958541)
			(xy 124.296687 -401.945278) (xy 124.293376 -401.939252) (xy 124.277019 -401.910907) (xy 124.251275 -401.850738)
			(xy 124.233849 -401.787655) (xy 124.225058 -401.722804) (xy 122.936391 -401.722804) (xy 122.926856 -401.739354)
			(xy 122.923562 -401.745389) (xy 122.919943 -401.758645) (xy 122.919744 -401.765516) (xy 122.919744 -402.514816)
			(xy 122.919924 -402.52169) (xy 122.92354 -402.534953) (xy 122.926856 -402.540978) (xy 122.943153 -402.569357)
			(xy 122.968901 -402.629518) (xy 122.986332 -402.692593) (xy 122.99513 -402.757439) (xy 122.995136 -402.822879)
			(xy 122.995136 -402.822882) (xy 126.424938 -402.822882) (xy 126.424943 -402.757436) (xy 126.433743 -402.692583)
			(xy 126.451177 -402.629501) (xy 126.476928 -402.569334) (xy 126.49327 -402.540978) (xy 126.496644 -402.534968)
			(xy 126.500373 -402.521704) (xy 126.500636 -402.514816) (xy 126.500636 -401.765516) (xy 126.500427 -401.758621)
			(xy 126.496682 -401.745349) (xy 126.49327 -401.739354) (xy 126.476915 -401.711008) (xy 126.451171 -401.650839)
			(xy 126.433745 -401.587757) (xy 126.424954 -401.522905) (xy 126.424956 -401.45746) (xy 126.433752 -401.39261)
			(xy 126.451182 -401.329529) (xy 126.47693 -401.269362) (xy 126.49327 -401.241006) (xy 126.496634 -401.234991)
			(xy 126.500369 -401.221731) (xy 126.500636 -401.214844) (xy 126.500636 -400.92884) (xy 126.50105 -400.918716)
			(xy 126.508791 -400.900006) (xy 126.523109 -400.885689) (xy 126.54182 -400.877949) (xy 126.551944 -400.877532)
			(xy 127.268224 -400.877532) (xy 127.278352 -400.877897) (xy 127.297062 -400.885659) (xy 127.311377 -400.899991)
			(xy 127.319116 -400.918711) (xy 127.319532 -400.92884) (xy 127.319532 -401.214844) (xy 127.319761 -401.221737)
			(xy 127.323492 -401.235009) (xy 127.326898 -401.241006) (xy 127.343217 -401.269372) (xy 127.368961 -401.329537)
			(xy 127.386388 -401.392615) (xy 127.395182 -401.457462) (xy 127.395184 -401.522903) (xy 127.386395 -401.587752)
			(xy 127.368972 -401.650831) (xy 127.343233 -401.710997) (xy 127.336432 -401.722804) (xy 128.624847 -401.722804)
			(xy 128.62485 -401.657359) (xy 128.633646 -401.592508) (xy 128.651076 -401.529427) (xy 128.676824 -401.46926)
			(xy 128.693164 -401.440904) (xy 128.696474 -401.434877) (xy 128.700083 -401.421615) (xy 128.700276 -401.414742)
			(xy 128.700276 -400.665442) (xy 128.700071 -400.65857) (xy 128.696472 -400.645307) (xy 128.693164 -400.63928)
			(xy 128.676831 -400.610921) (xy 128.651085 -400.550755) (xy 128.633657 -400.487676) (xy 128.624863 -400.422827)
			(xy 128.624863 -400.357384) (xy 128.633655 -400.292534) (xy 128.651082 -400.229454) (xy 128.676826 -400.169288)
			(xy 128.693164 -400.140932) (xy 128.696464 -400.1349) (xy 128.700079 -400.121642) (xy 128.700276 -400.11477)
			(xy 128.700276 -399.828766) (xy 128.700637 -399.818587) (xy 128.70844 -399.799785) (xy 128.722845 -399.7854)
			(xy 128.741659 -399.777623) (xy 128.751838 -399.777204) (xy 129.468118 -399.777204) (xy 129.478273 -399.777718)
			(xy 129.497036 -399.785492) (xy 129.511399 -399.799851) (xy 129.519179 -399.818611) (xy 129.51968 -399.828766)
			(xy 129.51968 -400.11477) (xy 129.519886 -400.121642) (xy 129.523485 -400.134905) (xy 129.526792 -400.140932)
			(xy 129.543133 -400.169286) (xy 129.568875 -400.229453) (xy 129.5863 -400.292534) (xy 129.595092 -400.357384)
			(xy 129.595091 -400.390106) (xy 133.023872 -400.390106) (xy 133.027863 -400.327939) (xy 133.039772 -400.266792)
			(xy 133.059401 -400.207671) (xy 133.08643 -400.151545) (xy 133.120414 -400.099336) (xy 133.160796 -400.051901)
			(xy 133.206912 -400.01002) (xy 133.258004 -399.97438) (xy 133.313235 -399.945566) (xy 133.371697 -399.924052)
			(xy 133.432431 -399.91019) (xy 133.494438 -399.904208) (xy 133.556701 -399.906204) (xy 133.618198 -399.916147)
			(xy 133.677919 -399.933871) (xy 133.734882 -399.959088) (xy 133.788153 -399.991381) (xy 133.836858 -400.030221)
			(xy 133.880195 -400.074971) (xy 133.917455 -400.124895) (xy 133.948024 -400.179174) (xy 133.971402 -400.236917)
			(xy 133.987203 -400.297175) (xy 133.995169 -400.358958) (xy 133.995668 -400.390106) (xy 133.995169 -400.421254)
			(xy 133.987203 -400.483037) (xy 133.971402 -400.543295) (xy 133.948024 -400.601038) (xy 133.917455 -400.655317)
			(xy 133.880195 -400.705241) (xy 133.836858 -400.749991) (xy 133.788153 -400.788831) (xy 133.734882 -400.821124)
			(xy 133.677919 -400.846341) (xy 133.618198 -400.864065) (xy 133.556701 -400.874008) (xy 133.494438 -400.876004)
			(xy 133.432431 -400.870022) (xy 133.371697 -400.85616) (xy 133.313235 -400.834646) (xy 133.258004 -400.805832)
			(xy 133.206912 -400.770192) (xy 133.160796 -400.728311) (xy 133.120414 -400.680876) (xy 133.08643 -400.628667)
			(xy 133.059401 -400.572541) (xy 133.039772 -400.51342) (xy 133.027863 -400.452273) (xy 133.023872 -400.390106)
			(xy 129.595091 -400.390106) (xy 129.595091 -400.422827) (xy 129.586298 -400.487676) (xy 129.568872 -400.550756)
			(xy 129.543129 -400.610923) (xy 129.526792 -400.63928) (xy 129.523484 -400.645308) (xy 129.519874 -400.658569)
			(xy 129.51968 -400.665442) (xy 129.51968 -401.414742) (xy 129.519897 -401.421613) (xy 129.523489 -401.434876)
			(xy 129.526792 -401.440904) (xy 129.54311 -401.469271) (xy 129.568854 -401.529435) (xy 129.586281 -401.592513)
			(xy 129.595076 -401.657361) (xy 129.595078 -401.722802) (xy 129.586289 -401.78765) (xy 129.568866 -401.850729)
			(xy 129.543127 -401.910896) (xy 129.526792 -401.939252) (xy 129.523458 -401.945267) (xy 129.519865 -401.958538)
			(xy 129.51968 -401.965414) (xy 129.51968 -402.251418) (xy 129.519182 -402.261575) (xy 129.511405 -402.280341)
			(xy 129.497041 -402.294705) (xy 129.478275 -402.302482) (xy 129.468118 -402.30298) (xy 128.751838 -402.30298)
			(xy 128.741671 -402.302505) (xy 128.722881 -402.294736) (xy 128.708495 -402.280366) (xy 128.700706 -402.261584)
			(xy 128.700276 -402.251418) (xy 128.700276 -401.965414) (xy 128.700082 -401.958541) (xy 128.696475 -401.945278)
			(xy 128.693164 -401.939252) (xy 128.676807 -401.910906) (xy 128.651064 -401.850738) (xy 128.633638 -401.787655)
			(xy 128.624847 -401.722804) (xy 127.336432 -401.722804) (xy 127.326898 -401.739354) (xy 127.323519 -401.745362)
			(xy 127.319792 -401.758628) (xy 127.319532 -401.765516) (xy 127.319532 -402.514816) (xy 127.319771 -402.521708)
			(xy 127.323496 -402.53498) (xy 127.326898 -402.540978) (xy 127.343194 -402.569357) (xy 127.368939 -402.629519)
			(xy 127.386369 -402.692594) (xy 127.395166 -402.757439) (xy 127.395172 -402.822878) (xy 127.395171 -402.822882)
			(xy 130.824988 -402.822882) (xy 130.824993 -402.757436) (xy 130.833792 -402.692584) (xy 130.851223 -402.629502)
			(xy 130.876972 -402.569335) (xy 130.893312 -402.540978) (xy 130.896635 -402.534958) (xy 130.900235 -402.521691)
			(xy 130.900424 -402.514816) (xy 130.900424 -401.765516) (xy 130.900223 -401.758643) (xy 130.896621 -401.745381)
			(xy 130.893312 -401.739354) (xy 130.876959 -401.711007) (xy 130.851218 -401.650838) (xy 130.833794 -401.587756)
			(xy 130.825004 -401.522905) (xy 130.825006 -401.457461) (xy 130.833801 -401.392611) (xy 130.851229 -401.32953)
			(xy 130.876974 -401.269362) (xy 130.893312 -401.241006) (xy 130.896625 -401.234981) (xy 130.900232 -401.221717)
			(xy 130.900424 -401.214844) (xy 130.900424 -400.92884) (xy 130.900855 -400.918686) (xy 130.908642 -400.899929)
			(xy 130.923036 -400.885604) (xy 130.94183 -400.877907) (xy 130.951986 -400.877532) (xy 131.668266 -400.877532)
			(xy 131.67839 -400.878054) (xy 131.697108 -400.88577) (xy 131.711465 -400.900045) (xy 131.719287 -400.918719)
			(xy 131.719828 -400.92884) (xy 131.719828 -401.214844) (xy 131.720038 -401.221716) (xy 131.723634 -401.234979)
			(xy 131.72694 -401.241006) (xy 131.743261 -401.269371) (xy 131.769008 -401.329536) (xy 131.786437 -401.392614)
			(xy 131.795232 -401.457462) (xy 131.795234 -401.522904) (xy 131.786444 -401.587752) (xy 131.769019 -401.650832)
			(xy 131.752228 -401.690078) (xy 133.023872 -401.690078) (xy 133.027863 -401.627911) (xy 133.039772 -401.566764)
			(xy 133.059401 -401.507643) (xy 133.08643 -401.451517) (xy 133.120414 -401.399308) (xy 133.160796 -401.351873)
			(xy 133.206912 -401.309992) (xy 133.258004 -401.274352) (xy 133.313235 -401.245538) (xy 133.371697 -401.224024)
			(xy 133.432431 -401.210162) (xy 133.494438 -401.20418) (xy 133.556701 -401.206176) (xy 133.618198 -401.216119)
			(xy 133.677919 -401.233843) (xy 133.734882 -401.25906) (xy 133.788153 -401.291353) (xy 133.836858 -401.330193)
			(xy 133.880195 -401.374943) (xy 133.917455 -401.424867) (xy 133.948024 -401.479146) (xy 133.971402 -401.536889)
			(xy 133.987203 -401.597147) (xy 133.995169 -401.65893) (xy 133.995668 -401.690078) (xy 133.995169 -401.721226)
			(xy 133.987203 -401.783009) (xy 133.971402 -401.843267) (xy 133.948024 -401.90101) (xy 133.917455 -401.955289)
			(xy 133.880195 -402.005213) (xy 133.836858 -402.049963) (xy 133.788153 -402.088803) (xy 133.734882 -402.121096)
			(xy 133.677919 -402.146313) (xy 133.618198 -402.164037) (xy 133.556701 -402.17398) (xy 133.494438 -402.175976)
			(xy 133.432431 -402.169994) (xy 133.371697 -402.156132) (xy 133.313235 -402.134618) (xy 133.258004 -402.105804)
			(xy 133.206912 -402.070164) (xy 133.160796 -402.028283) (xy 133.120414 -401.980848) (xy 133.08643 -401.928639)
			(xy 133.059401 -401.872513) (xy 133.039772 -401.813392) (xy 133.027863 -401.752245) (xy 133.023872 -401.690078)
			(xy 131.752228 -401.690078) (xy 131.743277 -401.710998) (xy 131.72694 -401.739354) (xy 131.723645 -401.745388)
			(xy 131.720026 -401.758645) (xy 131.719828 -401.765516) (xy 131.719828 -402.514816) (xy 131.720011 -402.52169)
			(xy 131.723625 -402.534953) (xy 131.72694 -402.540978) (xy 131.743237 -402.569356) (xy 131.768986 -402.629518)
			(xy 131.786418 -402.692593) (xy 131.795216 -402.757439) (xy 131.795222 -402.822879) (xy 131.786434 -402.887726)
			(xy 131.769013 -402.950804) (xy 131.743275 -403.01097) (xy 131.72694 -403.039326) (xy 131.723619 -403.045348)
			(xy 131.720017 -403.058614) (xy 131.719828 -403.065488) (xy 131.719828 -403.351492) (xy 131.719372 -403.361642)
			(xy 131.711585 -403.380389) (xy 131.697199 -403.394712) (xy 131.678418 -403.402417) (xy 131.668266 -403.4028)
			(xy 130.951986 -403.4028) (xy 130.941863 -403.402286) (xy 130.92315 -403.394561) (xy 130.908795 -403.380284)
			(xy 130.90097 -403.361612) (xy 130.900424 -403.351492) (xy 130.900424 -403.065488) (xy 130.900234 -403.058615)
			(xy 130.896624 -403.045352) (xy 130.893312 -403.039326) (xy 130.876935 -403.010992) (xy 130.851196 -402.95082)
			(xy 130.833775 -402.887735) (xy 130.824988 -402.822882) (xy 127.395171 -402.822882) (xy 127.386385 -402.887725)
			(xy 127.368967 -402.950803) (xy 127.343231 -403.01097) (xy 127.326898 -403.039326) (xy 127.323528 -403.045338)
			(xy 127.319796 -403.058601) (xy 127.319532 -403.065488) (xy 127.319532 -403.351492) (xy 127.319009 -403.361596)
			(xy 127.31128 -403.380268) (xy 127.296995 -403.394562) (xy 127.278328 -403.402303) (xy 127.268224 -403.4028)
			(xy 126.551944 -403.4028) (xy 126.541824 -403.402348) (xy 126.523122 -403.394614) (xy 126.508806 -403.380308)
			(xy 126.501059 -403.361611) (xy 126.500636 -403.351492) (xy 126.500636 -403.065488) (xy 126.500399 -403.058596)
			(xy 126.496673 -403.045323) (xy 126.49327 -403.039326) (xy 126.476891 -403.010993) (xy 126.451149 -402.950821)
			(xy 126.433726 -402.887736) (xy 126.424938 -402.822882) (xy 122.995136 -402.822882) (xy 122.986348 -402.887726)
			(xy 122.968928 -402.950804) (xy 122.94319 -403.01097) (xy 122.926856 -403.039326) (xy 122.923536 -403.045348)
			(xy 122.919933 -403.058614) (xy 122.919744 -403.065488) (xy 122.919744 -403.351492) (xy 122.919273 -403.36164)
			(xy 122.911488 -403.380384) (xy 122.897107 -403.394706) (xy 122.878332 -403.402414) (xy 122.868182 -403.4028)
			(xy 122.151902 -403.4028) (xy 122.14178 -403.402273) (xy 122.123067 -403.394553) (xy 122.108712 -403.38028)
			(xy 122.100886 -403.361611) (xy 122.10034 -403.351492) (xy 122.10034 -403.065488) (xy 122.100148 -403.058615)
			(xy 122.096539 -403.045352) (xy 122.093228 -403.039326) (xy 122.07685 -403.010992) (xy 122.051111 -402.95082)
			(xy 122.033689 -402.887735) (xy 122.024902 -402.822882) (xy 118.595099 -402.822882) (xy 118.586312 -402.887726)
			(xy 118.56889 -402.950805) (xy 118.54315 -403.01097) (xy 118.526814 -403.039326) (xy 118.523446 -403.045339)
			(xy 118.519712 -403.058601) (xy 118.519448 -403.065488) (xy 118.519448 -403.351492) (xy 118.51891 -403.361594)
			(xy 118.511183 -403.380263) (xy 118.496903 -403.394557) (xy 118.478242 -403.4023) (xy 118.46814 -403.4028)
			(xy 117.75186 -403.4028) (xy 117.741749 -403.402348) (xy 117.72307 -403.394597) (xy 117.708776 -403.38029)
			(xy 117.701043 -403.361604) (xy 117.700552 -403.351492) (xy 117.700552 -403.065488) (xy 117.700313 -403.058596)
			(xy 117.696589 -403.045324) (xy 117.693186 -403.039326) (xy 117.676806 -403.010993) (xy 117.651064 -402.950821)
			(xy 117.63364 -402.887736) (xy 117.624851 -402.822882) (xy 94.04731 -402.822882) (xy 94.04731 -405.622717)
			(xy 115.424981 -405.622717) (xy 115.424981 -405.557273) (xy 115.433776 -405.492422) (xy 115.451205 -405.429342)
			(xy 115.476953 -405.369176) (xy 115.493292 -405.34082) (xy 115.496599 -405.334792) (xy 115.50021 -405.321531)
			(xy 115.500404 -405.314658) (xy 115.500404 -404.565358) (xy 115.500189 -404.558486) (xy 115.496596 -404.545224)
			(xy 115.493292 -404.539196) (xy 115.476972 -404.51083) (xy 115.451223 -404.450666) (xy 115.433793 -404.387588)
			(xy 115.424997 -404.32274) (xy 115.424994 -404.257298) (xy 115.433785 -404.192449) (xy 115.451211 -404.129369)
			(xy 115.476954 -404.069204) (xy 115.493292 -404.040848) (xy 115.496625 -404.034832) (xy 115.500219 -404.021562)
			(xy 115.500404 -404.014686) (xy 115.500404 -403.728682) (xy 115.500918 -403.718527) (xy 115.508692 -403.699764)
			(xy 115.523051 -403.685401) (xy 115.541811 -403.677621) (xy 115.551966 -403.67712) (xy 116.268246 -403.67712)
			(xy 116.278404 -403.677595) (xy 116.297171 -403.685382) (xy 116.311534 -403.699752) (xy 116.31931 -403.718523)
			(xy 116.319808 -403.728682) (xy 116.319808 -404.014686) (xy 116.320005 -404.021559) (xy 116.32361 -404.034822)
			(xy 116.32692 -404.040848) (xy 116.343277 -404.069193) (xy 116.369022 -404.129362) (xy 116.386448 -404.192445)
			(xy 116.395239 -404.257296) (xy 116.395236 -404.322741) (xy 116.38644 -404.387592) (xy 116.369009 -404.450673)
			(xy 116.34326 -404.51084) (xy 116.32692 -404.539196) (xy 116.323608 -404.545222) (xy 116.32 -404.558485)
			(xy 116.319808 -404.565358) (xy 116.319808 -405.314658) (xy 116.320015 -405.32153) (xy 116.323613 -405.334793)
			(xy 116.32692 -405.34082) (xy 116.343254 -405.369179) (xy 116.369 -405.429344) (xy 116.386429 -405.492424)
			(xy 116.395223 -405.557273) (xy 116.395224 -405.622716) (xy 116.386431 -405.687566) (xy 116.369004 -405.750646)
			(xy 116.343258 -405.810812) (xy 116.32692 -405.839168) (xy 116.323618 -405.845199) (xy 116.320004 -405.858458)
			(xy 116.319808 -405.86533) (xy 116.319808 -406.151334) (xy 116.319296 -406.161488) (xy 116.311519 -406.180249)
			(xy 116.297159 -406.194612) (xy 116.2784 -406.202393) (xy 116.268246 -406.202896) (xy 115.551966 -406.202896)
			(xy 115.54181 -406.202395) (xy 115.523047 -406.194616) (xy 115.508684 -406.180253) (xy 115.500905 -406.16149)
			(xy 115.500404 -406.151334) (xy 115.500404 -405.86533) (xy 115.5002 -405.858458) (xy 115.4966 -405.845195)
			(xy 115.493292 -405.839168) (xy 115.476948 -405.810815) (xy 115.451202 -405.750648) (xy 115.433774 -405.687567)
			(xy 115.424981 -405.622717) (xy 94.04731 -405.622717) (xy 94.04731 -406.722795) (xy 117.624861 -406.722795)
			(xy 117.624864 -406.65735) (xy 117.633662 -406.592498) (xy 117.651094 -406.529417) (xy 117.676845 -406.46925)
			(xy 117.693186 -406.440894) (xy 117.696547 -406.434877) (xy 117.700286 -406.421618) (xy 117.700552 -406.414732)
			(xy 117.700552 -405.665432) (xy 117.700335 -405.658538) (xy 117.696596 -405.645266) (xy 117.693186 -405.63927)
			(xy 117.676844 -405.610916) (xy 117.651098 -405.550749) (xy 117.63367 -405.487669) (xy 117.624877 -405.422818)
			(xy 117.624877 -405.357375) (xy 117.633671 -405.292524) (xy 117.6511 -405.229444) (xy 117.676847 -405.169278)
			(xy 117.693186 -405.140922) (xy 117.696538 -405.134901) (xy 117.700282 -405.121645) (xy 117.700552 -405.11476)
			(xy 117.700552 -404.828756) (xy 117.701048 -404.81865) (xy 117.708791 -404.79998) (xy 117.723084 -404.785689)
			(xy 117.741754 -404.777947) (xy 117.75186 -404.777448) (xy 118.46814 -404.777448) (xy 118.478245 -404.777951)
			(xy 118.496914 -404.785692) (xy 118.511206 -404.799983) (xy 118.518948 -404.818651) (xy 118.519448 -404.828756)
			(xy 118.519448 -405.11476) (xy 118.519668 -405.121654) (xy 118.523405 -405.134926) (xy 118.526814 -405.140922)
			(xy 118.543149 -405.16928) (xy 118.568896 -405.229445) (xy 118.586325 -405.292525) (xy 118.595119 -405.357375)
			(xy 118.595119 -405.422818) (xy 118.586326 -405.487668) (xy 118.568898 -405.550748) (xy 118.543153 -405.610914)
			(xy 118.536352 -405.622717) (xy 119.825031 -405.622717) (xy 119.825031 -405.557273) (xy 119.833825 -405.492423)
			(xy 119.851252 -405.429343) (xy 119.876996 -405.369176) (xy 119.893334 -405.34082) (xy 119.89669 -405.334801)
			(xy 119.900431 -405.321544) (xy 119.9007 -405.314658) (xy 119.9007 -404.565358) (xy 119.900444 -404.558468)
			(xy 119.896717 -404.545202) (xy 119.893334 -404.539196) (xy 119.877015 -404.510829) (xy 119.85127 -404.450665)
			(xy 119.833842 -404.387587) (xy 119.825047 -404.32274) (xy 119.825044 -404.257298) (xy 119.833834 -404.19245)
			(xy 119.851258 -404.129371) (xy 119.876998 -404.069204) (xy 119.893334 -404.040848) (xy 119.896715 -404.034841)
			(xy 119.90044 -404.021575) (xy 119.9007 -404.014686) (xy 119.9007 -403.728682) (xy 119.90121 -403.718559)
			(xy 119.908937 -403.699845) (xy 119.923215 -403.685491) (xy 119.941888 -403.677665) (xy 119.952008 -403.67712)
			(xy 120.668288 -403.67712) (xy 120.678444 -403.677532) (xy 120.6972 -403.685327) (xy 120.711524 -403.699727)
			(xy 120.719221 -403.718524) (xy 120.719596 -403.728682) (xy 120.719596 -404.014686) (xy 120.719835 -404.021577)
			(xy 120.723574 -404.034843) (xy 120.726962 -404.040848) (xy 120.743318 -404.069194) (xy 120.76906 -404.129363)
			(xy 120.786484 -404.192445) (xy 120.795275 -404.257297) (xy 120.795273 -404.322741) (xy 120.786477 -404.387592)
			(xy 120.769048 -404.450673) (xy 120.743301 -404.51084) (xy 120.726962 -404.539196) (xy 120.7236 -404.545212)
			(xy 120.719863 -404.558472) (xy 120.719596 -404.565358) (xy 120.719596 -405.314658) (xy 120.719846 -405.321548)
			(xy 120.723577 -405.334814) (xy 120.726962 -405.34082) (xy 120.743294 -405.369179) (xy 120.769039 -405.429345)
			(xy 120.786466 -405.492425) (xy 120.795259 -405.557274) (xy 120.79526 -405.622716) (xy 120.786468 -405.687565)
			(xy 120.769042 -405.750645) (xy 120.743299 -405.810812) (xy 120.726962 -405.839168) (xy 120.72361 -405.845189)
			(xy 120.719867 -405.858445) (xy 120.719596 -405.86533) (xy 120.719596 -406.151334) (xy 120.719102 -406.161458)
			(xy 120.71137 -406.180174) (xy 120.697087 -406.194527) (xy 120.67841 -406.202352) (xy 120.668288 -406.202896)
			(xy 119.952008 -406.202896) (xy 119.941854 -406.202472) (xy 119.923101 -406.194678) (xy 119.908777 -406.180282)
			(xy 119.901078 -406.16149) (xy 119.9007 -406.151334) (xy 119.9007 -405.86533) (xy 119.900455 -405.85844)
			(xy 119.896721 -405.845174) (xy 119.893334 -405.839168) (xy 119.876992 -405.810815) (xy 119.851249 -405.750647)
			(xy 119.833823 -405.687567) (xy 119.825031 -405.622717) (xy 118.536352 -405.622717) (xy 118.526814 -405.63927)
			(xy 118.523465 -405.645293) (xy 118.519719 -405.658547) (xy 118.519448 -405.665432) (xy 118.519448 -406.414732)
			(xy 118.519679 -406.421625) (xy 118.523409 -406.434897) (xy 118.526814 -406.440894) (xy 118.543126 -406.469265)
			(xy 118.568875 -406.529427) (xy 118.586306 -406.592505) (xy 118.595103 -406.657352) (xy 118.595107 -406.722793)
			(xy 118.595107 -406.722795) (xy 122.024911 -406.722795) (xy 122.024914 -406.65735) (xy 122.033711 -406.592499)
			(xy 122.051141 -406.529418) (xy 122.076889 -406.46925) (xy 122.093228 -406.440894) (xy 122.096547 -406.434871)
			(xy 122.100149 -406.421606) (xy 122.10034 -406.414732) (xy 122.10034 -405.665432) (xy 122.100131 -405.65856)
			(xy 122.096534 -405.645297) (xy 122.093228 -405.63927) (xy 122.076888 -405.610916) (xy 122.051145 -405.550748)
			(xy 122.033719 -405.487668) (xy 122.024927 -405.422818) (xy 122.024927 -405.357375) (xy 122.03372 -405.292525)
			(xy 122.051147 -405.229445) (xy 122.076891 -405.169278) (xy 122.093228 -405.140922) (xy 122.096537 -405.134895)
			(xy 122.100146 -405.121633) (xy 122.10034 -405.11476) (xy 122.10034 -404.828756) (xy 122.100686 -404.818594)
			(xy 122.108504 -404.799833) (xy 122.122924 -404.78551) (xy 122.141737 -404.777819) (xy 122.151902 -404.777448)
			(xy 122.868182 -404.777448) (xy 122.878309 -404.777941) (xy 122.897031 -404.785665) (xy 122.911388 -404.799949)
			(xy 122.919207 -404.818632) (xy 122.919744 -404.828756) (xy 122.919744 -405.11476) (xy 122.919946 -405.121633)
			(xy 122.923547 -405.134896) (xy 122.926856 -405.140922) (xy 122.94319 -405.16928) (xy 122.968935 -405.229446)
			(xy 122.986362 -405.292526) (xy 122.995155 -405.357375) (xy 122.995156 -405.422818) (xy 122.986363 -405.487667)
			(xy 122.968937 -405.550747) (xy 122.943193 -405.610914) (xy 122.936393 -405.622717) (xy 124.225067 -405.622717)
			(xy 124.225067 -405.557273) (xy 124.233862 -405.492423) (xy 124.25129 -405.429342) (xy 124.277037 -405.369176)
			(xy 124.293376 -405.34082) (xy 124.296682 -405.334791) (xy 124.300294 -405.321531) (xy 124.300488 -405.314658)
			(xy 124.300488 -404.565358) (xy 124.300275 -404.558486) (xy 124.296681 -404.545223) (xy 124.293376 -404.539196)
			(xy 124.277056 -404.51083) (xy 124.251309 -404.450666) (xy 124.233879 -404.387588) (xy 124.225083 -404.32274)
			(xy 124.22508 -404.257298) (xy 124.233871 -404.192449) (xy 124.251296 -404.12937) (xy 124.277039 -404.069204)
			(xy 124.293376 -404.040848) (xy 124.296708 -404.034832) (xy 124.300303 -404.021562) (xy 124.300488 -404.014686)
			(xy 124.300488 -403.728682) (xy 124.30085 -403.718503) (xy 124.308651 -403.699698) (xy 124.323056 -403.685313)
			(xy 124.34187 -403.677537) (xy 124.35205 -403.67712) (xy 125.06833 -403.67712) (xy 125.078487 -403.677608)
			(xy 125.097254 -403.685389) (xy 125.111617 -403.699756) (xy 125.119394 -403.718524) (xy 125.119892 -403.728682)
			(xy 125.119892 -404.014686) (xy 125.12009 -404.021559) (xy 125.123694 -404.034822) (xy 125.127004 -404.040848)
			(xy 125.143359 -404.069194) (xy 125.169099 -404.129364) (xy 125.186521 -404.192446) (xy 125.195311 -404.257297)
			(xy 125.195309 -404.322741) (xy 125.186514 -404.387591) (xy 125.169086 -404.450672) (xy 125.143341 -404.510839)
			(xy 125.127004 -404.539196) (xy 125.123691 -404.545221) (xy 125.120084 -404.558485) (xy 125.119892 -404.565358)
			(xy 125.119892 -405.314658) (xy 125.120101 -405.32153) (xy 125.123698 -405.334793) (xy 125.127004 -405.34082)
			(xy 125.143335 -405.369179) (xy 125.169077 -405.429346) (xy 125.186502 -405.492425) (xy 125.195295 -405.557274)
			(xy 125.195296 -405.622716) (xy 125.186505 -405.687565) (xy 125.16908 -405.750644) (xy 125.14334 -405.810811)
			(xy 125.127004 -405.839168) (xy 125.123701 -405.845198) (xy 125.120088 -405.858458) (xy 125.119892 -405.86533)
			(xy 125.119892 -406.151334) (xy 125.119395 -406.16149) (xy 125.111615 -406.180254) (xy 125.097251 -406.194617)
			(xy 125.078486 -406.202396) (xy 125.06833 -406.202896) (xy 124.35205 -406.202896) (xy 124.341886 -406.202396)
			(xy 124.323099 -406.194634) (xy 124.308713 -406.180272) (xy 124.30092 -406.161497) (xy 124.300488 -406.151334)
			(xy 124.300488 -405.86533) (xy 124.300286 -405.858458) (xy 124.296685 -405.845195) (xy 124.293376 -405.839168)
			(xy 124.277032 -405.810815) (xy 124.251287 -405.750648) (xy 124.23386 -405.687567) (xy 124.225067 -405.622717)
			(xy 122.936393 -405.622717) (xy 122.926856 -405.63927) (xy 122.923556 -405.645302) (xy 122.91994 -405.65856)
			(xy 122.919744 -405.665432) (xy 122.919744 -406.414732) (xy 122.919918 -406.421607) (xy 122.923538 -406.43487)
			(xy 122.926856 -406.440894) (xy 122.943166 -406.469265) (xy 122.968913 -406.529428) (xy 122.986343 -406.592505)
			(xy 122.995139 -406.657352) (xy 122.995143 -406.722793) (xy 122.995143 -406.722795) (xy 126.424947 -406.722795)
			(xy 126.42495 -406.65735) (xy 126.433748 -406.592498) (xy 126.45118 -406.529417) (xy 126.47693 -406.46925)
			(xy 126.49327 -406.440894) (xy 126.496638 -406.434881) (xy 126.500371 -406.421619) (xy 126.500636 -406.414732)
			(xy 126.500636 -405.665432) (xy 126.500421 -405.658538) (xy 126.496681 -405.645266) (xy 126.49327 -405.63927)
			(xy 126.476928 -405.610916) (xy 126.451183 -405.550749) (xy 126.433756 -405.487669) (xy 126.424963 -405.422818)
			(xy 126.424963 -405.357375) (xy 126.433757 -405.292525) (xy 126.451185 -405.229444) (xy 126.476931 -405.169278)
			(xy 126.49327 -405.140922) (xy 126.496628 -405.134904) (xy 126.500367 -405.121646) (xy 126.500636 -405.11476)
			(xy 126.500636 -404.828756) (xy 126.50105 -404.81864) (xy 126.508809 -404.799954) (xy 126.523128 -404.785659)
			(xy 126.541827 -404.777933) (xy 126.551944 -404.777448) (xy 127.268224 -404.777448) (xy 127.278328 -404.777964)
			(xy 127.296997 -404.7857) (xy 127.311289 -404.799986) (xy 127.319032 -404.818652) (xy 127.319532 -404.828756)
			(xy 127.319532 -405.11476) (xy 127.319755 -405.121654) (xy 127.32349 -405.134925) (xy 127.326898 -405.140922)
			(xy 127.343231 -405.16928) (xy 127.368973 -405.229447) (xy 127.386399 -405.292527) (xy 127.395191 -405.357375)
			(xy 127.395192 -405.422818) (xy 127.3864 -405.487667) (xy 127.368975 -405.550746) (xy 127.343234 -405.610913)
			(xy 127.336434 -405.622717) (xy 128.624856 -405.622717) (xy 128.624857 -405.557273) (xy 128.633651 -405.492423)
			(xy 128.651079 -405.429343) (xy 128.676825 -405.369176) (xy 128.693164 -405.34082) (xy 128.696469 -405.33479)
			(xy 128.700081 -405.321531) (xy 128.700276 -405.314658) (xy 128.700276 -404.565358) (xy 128.700065 -404.558486)
			(xy 128.69647 -404.545223) (xy 128.693164 -404.539196) (xy 128.676845 -404.51083) (xy 128.651098 -404.450666)
			(xy 128.633668 -404.387588) (xy 128.624872 -404.32274) (xy 128.62487 -404.257298) (xy 128.633661 -404.192449)
			(xy 128.651085 -404.12937) (xy 128.676827 -404.069204) (xy 128.693164 -404.040848) (xy 128.696494 -404.034831)
			(xy 128.70009 -404.021561) (xy 128.700276 -404.014686) (xy 128.700276 -403.728682) (xy 128.70065 -403.718505)
			(xy 128.708448 -403.699702) (xy 128.722849 -403.685317) (xy 128.74166 -403.677539) (xy 128.751838 -403.67712)
			(xy 129.468118 -403.67712) (xy 129.478275 -403.677618) (xy 129.497041 -403.685395) (xy 129.511405 -403.699759)
			(xy 129.519182 -403.718525) (xy 129.51968 -403.728682) (xy 129.51968 -404.014686) (xy 129.51988 -404.021559)
			(xy 129.523483 -404.034821) (xy 129.526792 -404.040848) (xy 129.543147 -404.069194) (xy 129.568888 -404.129364)
			(xy 129.586311 -404.192446) (xy 129.595101 -404.257297) (xy 129.595098 -404.322741) (xy 129.586303 -404.387591)
			(xy 129.568875 -404.450672) (xy 129.54313 -404.510839) (xy 129.526792 -404.539196) (xy 129.523478 -404.545221)
			(xy 129.519872 -404.558484) (xy 129.51968 -404.565358) (xy 129.51968 -405.314658) (xy 129.51989 -405.32153)
			(xy 129.523486 -405.334793) (xy 129.526792 -405.34082) (xy 129.543123 -405.369179) (xy 129.568866 -405.429346)
			(xy 129.586292 -405.492425) (xy 129.595085 -405.557274) (xy 129.595086 -405.622716) (xy 129.586294 -405.687565)
			(xy 129.568869 -405.750645) (xy 129.543128 -405.810812) (xy 129.526792 -405.839168) (xy 129.523488 -405.845198)
			(xy 129.519876 -405.858458) (xy 129.51968 -405.86533) (xy 129.51968 -406.151334) (xy 129.519195 -406.161492)
			(xy 129.511413 -406.180258) (xy 129.497045 -406.194622) (xy 129.478276 -406.202398) (xy 129.468118 -406.202896)
			(xy 128.751838 -406.202896) (xy 128.741673 -406.202406) (xy 128.722886 -406.19464) (xy 128.708501 -406.180275)
			(xy 128.700708 -406.161498) (xy 128.700276 -406.151334) (xy 128.700276 -405.86533) (xy 128.700075 -405.858457)
			(xy 128.696473 -405.845194) (xy 128.693164 -405.839168) (xy 128.676821 -405.810815) (xy 128.651076 -405.750648)
			(xy 128.633649 -405.687567) (xy 128.624856 -405.622717) (xy 127.336434 -405.622717) (xy 127.326898 -405.63927)
			(xy 127.323548 -405.645292) (xy 127.319803 -405.658547) (xy 127.319532 -405.665432) (xy 127.319532 -406.414732)
			(xy 127.319765 -406.421625) (xy 127.323494 -406.434897) (xy 127.326898 -406.440894) (xy 127.343207 -406.469266)
			(xy 127.368952 -406.529429) (xy 127.38638 -406.592506) (xy 127.395175 -406.657352) (xy 127.395179 -406.722793)
			(xy 127.395179 -406.722795) (xy 130.824997 -406.722795) (xy 130.825001 -406.65735) (xy 130.833797 -406.592499)
			(xy 130.851227 -406.529418) (xy 130.876973 -406.469251) (xy 130.893312 -406.440894) (xy 130.89663 -406.434871)
			(xy 130.900233 -406.421606) (xy 130.900424 -406.414732) (xy 130.900424 -405.665432) (xy 130.900217 -405.65856)
			(xy 130.896619 -405.645297) (xy 130.893312 -405.63927) (xy 130.876972 -405.610915) (xy 130.85123 -405.550748)
			(xy 130.833805 -405.487668) (xy 130.825013 -405.422818) (xy 130.825013 -405.357375) (xy 130.833806 -405.292526)
			(xy 130.851232 -405.229445) (xy 130.876975 -405.169278) (xy 130.893312 -405.140922) (xy 130.89662 -405.134894)
			(xy 130.90023 -405.121633) (xy 130.900424 -405.11476) (xy 130.900424 -404.828756) (xy 130.900786 -404.818596)
			(xy 130.908601 -404.799838) (xy 130.923016 -404.785515) (xy 130.941823 -404.777822) (xy 130.951986 -404.777448)
			(xy 131.668266 -404.777448) (xy 131.678391 -404.777955) (xy 131.697113 -404.785673) (xy 131.711471 -404.799953)
			(xy 131.71929 -404.818633) (xy 131.719828 -404.828756) (xy 131.719828 -405.11476) (xy 131.720032 -405.121632)
			(xy 131.723632 -405.134895) (xy 131.72694 -405.140922) (xy 131.743275 -405.16928) (xy 131.76902 -405.229446)
			(xy 131.786448 -405.292526) (xy 131.795241 -405.357375) (xy 131.795242 -405.422818) (xy 131.786449 -405.487668)
			(xy 131.769022 -405.550748) (xy 131.743278 -405.610914) (xy 131.72694 -405.63927) (xy 131.723639 -405.645302)
			(xy 131.720024 -405.65856) (xy 131.719828 -405.665432) (xy 131.719828 -406.414732) (xy 131.720004 -406.421606)
			(xy 131.723623 -406.434869) (xy 131.72694 -406.440894) (xy 131.743251 -406.469265) (xy 131.768998 -406.529428)
			(xy 131.786429 -406.592505) (xy 131.795225 -406.657352) (xy 131.795229 -406.722793) (xy 131.78644 -406.787641)
			(xy 131.769017 -406.85072) (xy 131.743276 -406.910886) (xy 131.72694 -406.939242) (xy 131.723614 -406.945261)
			(xy 131.720015 -406.958529) (xy 131.719828 -406.965404) (xy 131.719828 -407.251408) (xy 131.719385 -407.261559)
			(xy 131.711592 -407.280306) (xy 131.697203 -407.294628) (xy 131.678419 -407.302333) (xy 131.668266 -407.302716)
			(xy 130.951986 -407.302716) (xy 130.941853 -407.302283) (xy 130.923123 -407.294543) (xy 130.908766 -407.28024)
			(xy 130.900955 -407.261539) (xy 130.900424 -407.251408) (xy 130.900424 -406.965404) (xy 130.900228 -406.958531)
			(xy 130.896622 -406.945268) (xy 130.893312 -406.939242) (xy 130.876948 -406.910901) (xy 130.851208 -406.85073)
			(xy 130.833786 -406.787647) (xy 130.824997 -406.722795) (xy 127.395179 -406.722795) (xy 127.386391 -406.78764)
			(xy 127.36897 -406.850719) (xy 127.343232 -406.910885) (xy 127.326898 -406.939242) (xy 127.323523 -406.945252)
			(xy 127.319794 -406.958516) (xy 127.319532 -406.965404) (xy 127.319532 -407.251408) (xy 127.319022 -407.261513)
			(xy 127.311288 -407.280185) (xy 127.296999 -407.294479) (xy 127.278329 -407.302219) (xy 127.268224 -407.302716)
			(xy 126.551944 -407.302716) (xy 126.541826 -407.302248) (xy 126.523127 -407.294518) (xy 126.508812 -407.280217)
			(xy 126.501062 -407.261525) (xy 126.500636 -407.251408) (xy 126.500636 -406.965404) (xy 126.500432 -406.958509)
			(xy 126.496684 -406.945237) (xy 126.49327 -406.939242) (xy 126.476905 -406.910901) (xy 126.451162 -406.850731)
			(xy 126.433737 -406.787648) (xy 126.424947 -406.722795) (xy 122.995143 -406.722795) (xy 122.986354 -406.787641)
			(xy 122.968931 -406.85072) (xy 122.943191 -406.910886) (xy 122.926856 -406.939242) (xy 122.923531 -406.945262)
			(xy 122.919931 -406.958529) (xy 122.919744 -406.965404) (xy 122.919744 -407.251408) (xy 122.919286 -407.261557)
			(xy 122.911496 -407.280301) (xy 122.897111 -407.294623) (xy 122.878333 -407.30233) (xy 122.868182 -407.302716)
			(xy 122.151902 -407.302716) (xy 122.14177 -407.30227) (xy 122.123041 -407.294535) (xy 122.108683 -407.280236)
			(xy 122.100871 -407.261538) (xy 122.10034 -407.251408) (xy 122.10034 -406.965404) (xy 122.100141 -406.958531)
			(xy 122.096537 -406.945269) (xy 122.093228 -406.939242) (xy 122.076864 -406.910901) (xy 122.051123 -406.85073)
			(xy 122.0337 -406.787647) (xy 122.024911 -406.722795) (xy 118.595107 -406.722795) (xy 118.586317 -406.787642)
			(xy 118.568893 -406.850721) (xy 118.543151 -406.910886) (xy 118.526814 -406.939242) (xy 118.52344 -406.945252)
			(xy 118.51971 -406.958516) (xy 118.519448 -406.965404) (xy 118.519448 -407.251408) (xy 118.518922 -407.261511)
			(xy 118.511191 -407.28018) (xy 118.496907 -407.294473) (xy 118.478243 -407.302216) (xy 118.46814 -407.302716)
			(xy 117.75186 -407.302716) (xy 117.741751 -407.302248) (xy 117.723075 -407.2945) (xy 117.708782 -407.280198)
			(xy 117.701046 -407.261518) (xy 117.700552 -407.251408) (xy 117.700552 -406.965404) (xy 117.700345 -406.958509)
			(xy 117.696599 -406.945237) (xy 117.693186 -406.939242) (xy 117.67682 -406.910901) (xy 117.651076 -406.850732)
			(xy 117.633651 -406.787648) (xy 117.624861 -406.722795) (xy 94.04731 -406.722795) (xy 94.04731 -409.522892)
			(xy 115.424963 -409.522892) (xy 115.424968 -409.457446) (xy 115.433766 -409.392594) (xy 115.451199 -409.329513)
			(xy 115.476951 -409.269346) (xy 115.493292 -409.24099) (xy 115.49661 -409.234967) (xy 115.500214 -409.221702)
			(xy 115.500404 -409.214828) (xy 115.500404 -408.465528) (xy 115.500201 -408.458656) (xy 115.4966 -408.445393)
			(xy 115.493292 -408.439366) (xy 115.476946 -408.411014) (xy 115.4512 -408.350847) (xy 115.433773 -408.287766)
			(xy 115.424979 -408.222915) (xy 115.42498 -408.157471) (xy 115.433775 -408.092621) (xy 115.451205 -408.02954)
			(xy 115.476952 -407.969374) (xy 115.493292 -407.941018) (xy 115.4966 -407.93499) (xy 115.50021 -407.921729)
			(xy 115.500404 -407.914856) (xy 115.500404 -407.628852) (xy 115.500783 -407.618694) (xy 115.508595 -407.59994)
			(xy 115.523004 -407.585618) (xy 115.541806 -407.577921) (xy 115.551966 -407.577544) (xy 116.268246 -407.577544)
			(xy 116.278376 -407.577989) (xy 116.297099 -407.585733) (xy 116.311454 -407.600031) (xy 116.319271 -407.618724)
			(xy 116.319808 -407.628852) (xy 116.319808 -407.914856) (xy 116.320016 -407.921728) (xy 116.323613 -407.934991)
			(xy 116.32692 -407.941018) (xy 116.343252 -407.969377) (xy 116.368999 -408.029543) (xy 116.386427 -408.092622)
			(xy 116.395222 -408.157472) (xy 116.395223 -408.222915) (xy 116.38643 -408.287764) (xy 116.369003 -408.350844)
			(xy 116.343258 -408.41101) (xy 116.32692 -408.439366) (xy 116.323619 -408.445397) (xy 116.320004 -408.458656)
			(xy 116.319808 -408.465528) (xy 116.319808 -409.214828) (xy 116.319988 -409.221702) (xy 116.323604 -409.234965)
			(xy 116.32692 -409.24099) (xy 116.343228 -409.269363) (xy 116.368977 -409.329525) (xy 116.386408 -409.392602)
			(xy 116.395206 -409.457449) (xy 116.39521 -409.52289) (xy 116.386421 -409.587738) (xy 116.368997 -409.650817)
			(xy 116.343256 -409.710982) (xy 116.32692 -409.739338) (xy 116.323593 -409.745357) (xy 116.319995 -409.758625)
			(xy 116.319808 -409.7655) (xy 116.319808 -410.051504) (xy 116.319382 -410.061657) (xy 116.311586 -410.080408)
			(xy 116.297191 -410.094731) (xy 116.278401 -410.102432) (xy 116.268246 -410.102812) (xy 115.551966 -410.102812)
			(xy 115.541844 -410.102303) (xy 115.523131 -410.094574) (xy 115.508778 -410.080295) (xy 115.500951 -410.061624)
			(xy 115.500404 -410.051504) (xy 115.500404 -409.7655) (xy 115.500212 -409.758627) (xy 115.496604 -409.745364)
			(xy 115.493292 -409.739338) (xy 115.476922 -409.710999) (xy 115.451179 -409.650829) (xy 115.433754 -409.587745)
			(xy 115.424963 -409.522892) (xy 94.04731 -409.522892) (xy 94.04731 -410.622709) (xy 117.62487 -410.622709)
			(xy 117.624872 -410.557264) (xy 117.633667 -410.492413) (xy 117.651098 -410.429332) (xy 117.676846 -410.369166)
			(xy 117.693186 -410.34081) (xy 117.696542 -410.334791) (xy 117.700284 -410.321534) (xy 117.700552 -410.314648)
			(xy 117.700552 -409.565348) (xy 117.700329 -409.558454) (xy 117.696594 -409.545182) (xy 117.693186 -409.539186)
			(xy 117.676857 -409.510825) (xy 117.65111 -409.45066) (xy 117.633681 -409.387581) (xy 117.624886 -409.322732)
			(xy 117.624884 -409.257289) (xy 117.633677 -409.19244) (xy 117.651103 -409.12936) (xy 117.676848 -409.069194)
			(xy 117.693186 -409.040838) (xy 117.696567 -409.034831) (xy 117.700293 -409.021565) (xy 117.700552 -409.014676)
			(xy 117.700552 -408.728672) (xy 117.701061 -408.718567) (xy 117.708799 -408.699898) (xy 117.723088 -408.685606)
			(xy 117.741756 -408.677863) (xy 117.75186 -408.677364) (xy 118.46814 -408.677364) (xy 118.478247 -408.677852)
			(xy 118.496919 -408.685596) (xy 118.511211 -408.699891) (xy 118.518951 -408.718565) (xy 118.519448 -408.728672)
			(xy 118.519448 -409.014676) (xy 118.519662 -409.02157) (xy 118.523404 -409.034842) (xy 118.526814 -409.040838)
			(xy 118.543163 -409.069188) (xy 118.568908 -409.129356) (xy 118.586335 -409.192437) (xy 118.595128 -409.257288)
			(xy 118.595127 -409.322732) (xy 118.586331 -409.387583) (xy 118.568902 -409.450664) (xy 118.543154 -409.51083)
			(xy 118.536203 -409.522892) (xy 119.825014 -409.522892) (xy 119.825018 -409.457446) (xy 119.833815 -409.392595)
			(xy 119.851246 -409.329514) (xy 119.876994 -409.269346) (xy 119.893334 -409.24099) (xy 119.8967 -409.234976)
			(xy 119.900435 -409.221715) (xy 119.9007 -409.214828) (xy 119.9007 -408.465528) (xy 119.900456 -408.458638)
			(xy 119.896721 -408.445372) (xy 119.893334 -408.439366) (xy 119.87699 -408.411014) (xy 119.851247 -408.350846)
			(xy 119.833822 -408.287765) (xy 119.825029 -408.222915) (xy 119.82503 -408.157471) (xy 119.833824 -408.092621)
			(xy 119.851252 -408.029541) (xy 119.876996 -407.969374) (xy 119.893334 -407.941018) (xy 119.89669 -407.934999)
			(xy 119.900431 -407.921742) (xy 119.9007 -407.914856) (xy 119.9007 -407.628852) (xy 119.901146 -407.61874)
			(xy 119.908899 -407.600061) (xy 119.923208 -407.585768) (xy 119.941896 -407.578035) (xy 119.952008 -407.577544)
			(xy 120.668288 -407.577544) (xy 120.678389 -407.578094) (xy 120.697056 -407.585817) (xy 120.71135 -407.600093)
			(xy 120.719095 -407.618752) (xy 120.719596 -407.628852) (xy 120.719596 -407.914856) (xy 120.719847 -407.921746)
			(xy 120.723577 -407.935012) (xy 120.726962 -407.941018) (xy 120.743293 -407.969378) (xy 120.769037 -408.029544)
			(xy 120.786464 -408.092623) (xy 120.795258 -408.157472) (xy 120.795259 -408.222914) (xy 120.786467 -408.287763)
			(xy 120.769042 -408.350843) (xy 120.743299 -408.41101) (xy 120.726962 -408.439366) (xy 120.723611 -408.445388)
			(xy 120.719867 -408.458643) (xy 120.719596 -408.465528) (xy 120.719596 -409.214828) (xy 120.719857 -409.221717)
			(xy 120.723581 -409.234983) (xy 120.726962 -409.24099) (xy 120.743269 -409.269363) (xy 120.769016 -409.329526)
			(xy 120.786445 -409.392602) (xy 120.795242 -409.457449) (xy 120.795246 -409.522889) (xy 120.786458 -409.587737)
			(xy 120.769036 -409.650816) (xy 120.743297 -409.710982) (xy 120.726962 -409.739338) (xy 120.723586 -409.745347)
			(xy 120.719858 -409.758612) (xy 120.719596 -409.7655) (xy 120.719596 -410.051504) (xy 120.719187 -410.061627)
			(xy 120.711437 -410.080332) (xy 120.697118 -410.094646) (xy 120.678411 -410.10239) (xy 120.668288 -410.102812)
			(xy 119.952008 -410.102812) (xy 119.941888 -410.102378) (xy 119.923186 -410.094634) (xy 119.908872 -410.080324)
			(xy 119.901125 -410.061624) (xy 119.9007 -410.051504) (xy 119.9007 -409.7655) (xy 119.900467 -409.758609)
			(xy 119.896724 -409.745343) (xy 119.893334 -409.739338) (xy 119.876966 -409.710999) (xy 119.851225 -409.650828)
			(xy 119.833803 -409.587744) (xy 119.825014 -409.522892) (xy 118.536203 -409.522892) (xy 118.526814 -409.539186)
			(xy 118.52346 -409.545206) (xy 118.519717 -409.558462) (xy 118.519448 -409.565348) (xy 118.519448 -410.314648)
			(xy 118.519673 -410.321541) (xy 118.523407 -410.334813) (xy 118.526814 -410.34081) (xy 118.543139 -410.369173)
			(xy 118.568887 -410.429338) (xy 118.586317 -410.492416) (xy 118.595112 -410.557265) (xy 118.595114 -410.622708)
			(xy 122.02492 -410.622708) (xy 122.024922 -410.557264) (xy 122.033716 -410.492414) (xy 122.051144 -410.429333)
			(xy 122.07689 -410.369166) (xy 122.093228 -410.34081) (xy 122.096541 -410.334785) (xy 122.100147 -410.321521)
			(xy 122.10034 -410.314648) (xy 122.10034 -409.565348) (xy 122.100125 -409.558477) (xy 122.096532 -409.545214)
			(xy 122.093228 -409.539186) (xy 122.076901 -409.510824) (xy 122.051157 -409.450659) (xy 122.03373 -409.38758)
			(xy 122.024936 -409.322731) (xy 122.024934 -409.257289) (xy 122.033726 -409.19244) (xy 122.05115 -409.129361)
			(xy 122.076892 -409.069194) (xy 122.093228 -409.040838) (xy 122.096531 -409.034808) (xy 122.100144 -409.021548)
			(xy 122.10034 -409.014676) (xy 122.10034 -408.728672) (xy 122.100699 -408.718511) (xy 122.108512 -408.69975)
			(xy 122.122928 -408.685426) (xy 122.141738 -408.677735) (xy 122.151902 -408.677364) (xy 122.868182 -408.677364)
			(xy 122.878311 -408.677842) (xy 122.897036 -408.685568) (xy 122.911394 -408.699858) (xy 122.919209 -408.718546)
			(xy 122.919744 -408.728672) (xy 122.919744 -409.014676) (xy 122.91994 -409.021549) (xy 122.923545 -409.034812)
			(xy 122.926856 -409.040838) (xy 122.943204 -409.069189) (xy 122.968947 -409.129356) (xy 122.986372 -409.192438)
			(xy 122.995164 -409.257288) (xy 122.995163 -409.322732) (xy 122.986368 -409.387582) (xy 122.96894 -409.450663)
			(xy 122.943194 -409.51083) (xy 122.936244 -409.522892) (xy 124.22505 -409.522892) (xy 124.225054 -409.457446)
			(xy 124.233852 -409.392594) (xy 124.251284 -409.329513) (xy 124.277035 -409.269346) (xy 124.293376 -409.24099)
			(xy 124.296693 -409.234966) (xy 124.300298 -409.221702) (xy 124.300488 -409.214828) (xy 124.300488 -408.465528)
			(xy 124.300287 -408.458655) (xy 124.296685 -408.445393) (xy 124.293376 -408.439366) (xy 124.277031 -408.411014)
			(xy 124.251285 -408.350847) (xy 124.233858 -408.287766) (xy 124.225066 -408.222915) (xy 124.225067 -408.157471)
			(xy 124.233861 -408.092621) (xy 124.25129 -408.02954) (xy 124.277037 -407.969374) (xy 124.293376 -407.941018)
			(xy 124.296683 -407.934989) (xy 124.300294 -407.921729) (xy 124.300488 -407.914856) (xy 124.300488 -407.628852)
			(xy 124.300882 -407.618696) (xy 124.308691 -407.599945) (xy 124.323096 -407.585624) (xy 124.341892 -407.577924)
			(xy 124.35205 -407.577544) (xy 125.06833 -407.577544) (xy 125.078459 -407.578002) (xy 125.097182 -407.58574)
			(xy 125.111537 -407.600035) (xy 125.119355 -407.618725) (xy 125.119892 -407.628852) (xy 125.119892 -407.914856)
			(xy 125.120102 -407.921728) (xy 125.123698 -407.934991) (xy 125.127004 -407.941018) (xy 125.143333 -407.969378)
			(xy 125.169076 -408.029545) (xy 125.186501 -408.092624) (xy 125.195294 -408.157472) (xy 125.195295 -408.222914)
			(xy 125.186504 -408.287763) (xy 125.16908 -408.350842) (xy 125.143339 -408.411009) (xy 125.127004 -408.439366)
			(xy 125.123702 -408.445397) (xy 125.120088 -408.458656) (xy 125.119892 -408.465528) (xy 125.119892 -409.214828)
			(xy 125.120074 -409.221702) (xy 125.123689 -409.234965) (xy 125.127004 -409.24099) (xy 125.14331 -409.269363)
			(xy 125.169054 -409.329527) (xy 125.186482 -409.392603) (xy 125.195278 -409.457449) (xy 125.195282 -409.522889)
			(xy 125.186495 -409.587736) (xy 125.169074 -409.650815) (xy 125.143338 -409.710981) (xy 125.127004 -409.739338)
			(xy 125.123676 -409.745356) (xy 125.120079 -409.758625) (xy 125.119892 -409.7655) (xy 125.119892 -410.051504)
			(xy 125.119481 -410.061659) (xy 125.111683 -410.080413) (xy 125.097283 -410.094737) (xy 125.078487 -410.102435)
			(xy 125.06833 -410.102812) (xy 124.35205 -410.102812) (xy 124.341933 -410.102234) (xy 124.323223 -410.094532)
			(xy 124.308867 -410.080274) (xy 124.301036 -410.061618) (xy 124.300488 -410.051504) (xy 124.300488 -409.7655)
			(xy 124.300297 -409.758627) (xy 124.296688 -409.745364) (xy 124.293376 -409.739338) (xy 124.277007 -409.710999)
			(xy 124.251264 -409.650829) (xy 124.23384 -409.587745) (xy 124.22505 -409.522892) (xy 122.936244 -409.522892)
			(xy 122.926856 -409.539186) (xy 122.923551 -409.545215) (xy 122.919938 -409.558475) (xy 122.919744 -409.565348)
			(xy 122.919744 -410.314648) (xy 122.91995 -410.32152) (xy 122.923548 -410.334783) (xy 122.926856 -410.34081)
			(xy 122.94318 -410.369174) (xy 122.968925 -410.429339) (xy 122.986353 -410.492417) (xy 122.995148 -410.557265)
			(xy 122.99515 -410.622707) (xy 122.99515 -410.622709) (xy 126.424956 -410.622709) (xy 126.424958 -410.557264)
			(xy 126.433753 -410.492413) (xy 126.451183 -410.429333) (xy 126.476931 -410.369166) (xy 126.49327 -410.34081)
			(xy 126.496632 -410.334794) (xy 126.500369 -410.321534) (xy 126.500636 -410.314648) (xy 126.500636 -409.565348)
			(xy 126.500415 -409.558454) (xy 126.496679 -409.545182) (xy 126.49327 -409.539186) (xy 126.476942 -409.510825)
			(xy 126.451195 -409.450659) (xy 126.433767 -409.38758) (xy 126.424972 -409.322732) (xy 126.42497 -409.257289)
			(xy 126.433763 -409.19244) (xy 126.451189 -409.12936) (xy 126.476932 -409.069194) (xy 126.49327 -409.040838)
			(xy 126.496658 -409.034835) (xy 126.500378 -409.021565) (xy 126.500636 -409.014676) (xy 126.500636 -408.728672)
			(xy 126.500994 -408.718543) (xy 126.508758 -408.699832) (xy 126.523093 -408.685517) (xy 126.541815 -408.67778)
			(xy 126.551944 -408.677364) (xy 127.268224 -408.677364) (xy 127.27833 -408.677864) (xy 127.297002 -408.685603)
			(xy 127.311294 -408.699895) (xy 127.319035 -408.718566) (xy 127.319532 -408.728672) (xy 127.319532 -409.014676)
			(xy 127.31977 -409.021567) (xy 127.323509 -409.034833) (xy 127.326898 -409.040838) (xy 127.343244 -409.069189)
			(xy 127.368985 -409.129357) (xy 127.386409 -409.192438) (xy 127.3952 -409.257289) (xy 127.395199 -409.322732)
			(xy 127.386405 -409.387582) (xy 127.368979 -409.450662) (xy 127.343235 -409.510829) (xy 127.336285 -409.522892)
			(xy 128.624839 -409.522892) (xy 128.624844 -409.457446) (xy 128.633641 -409.392595) (xy 128.651073 -409.329513)
			(xy 128.676823 -409.269346) (xy 128.693164 -409.24099) (xy 128.696479 -409.234966) (xy 128.700085 -409.221702)
			(xy 128.700276 -409.214828) (xy 128.700276 -408.465528) (xy 128.700076 -408.458655) (xy 128.696474 -408.445392)
			(xy 128.693164 -408.439366) (xy 128.676819 -408.411014) (xy 128.651074 -408.350846) (xy 128.633648 -408.287766)
			(xy 128.624855 -408.222915) (xy 128.624856 -408.157471) (xy 128.633651 -408.092621) (xy 128.651079 -408.029541)
			(xy 128.676825 -407.969374) (xy 128.693164 -407.941018) (xy 128.696469 -407.934989) (xy 128.700081 -407.921729)
			(xy 128.700276 -407.914856) (xy 128.700276 -407.628852) (xy 128.700682 -407.618698) (xy 128.708489 -407.599949)
			(xy 128.72289 -407.585628) (xy 128.741682 -407.577926) (xy 128.751838 -407.577544) (xy 129.468118 -407.577544)
			(xy 129.478246 -407.578012) (xy 129.496969 -407.585746) (xy 129.511325 -407.600038) (xy 129.519143 -407.618726)
			(xy 129.51968 -407.628852) (xy 129.51968 -407.914856) (xy 129.519891 -407.921728) (xy 129.523486 -407.934991)
			(xy 129.526792 -407.941018) (xy 129.543122 -407.969378) (xy 129.568865 -408.029544) (xy 129.586291 -408.092624)
			(xy 129.595084 -408.157472) (xy 129.595085 -408.222914) (xy 129.586293 -408.287763) (xy 129.568869 -408.350843)
			(xy 129.543128 -408.41101) (xy 129.526792 -408.439366) (xy 129.523489 -408.445396) (xy 129.519876 -408.458656)
			(xy 129.51968 -408.465528) (xy 129.51968 -409.214828) (xy 129.519864 -409.221702) (xy 129.523478 -409.234964)
			(xy 129.526792 -409.24099) (xy 129.543098 -409.269363) (xy 129.568843 -409.329526) (xy 129.586272 -409.392603)
			(xy 129.595068 -409.457449) (xy 129.595072 -409.522889) (xy 129.586284 -409.587737) (xy 129.568863 -409.650815)
			(xy 129.543126 -409.710982) (xy 129.526792 -409.739338) (xy 129.523463 -409.745356) (xy 129.519867 -409.758625)
			(xy 129.51968 -409.7655) (xy 129.51968 -410.051504) (xy 129.519281 -410.061661) (xy 129.511481 -410.080417)
			(xy 129.497077 -410.094741) (xy 129.478277 -410.102437) (xy 129.468118 -410.102812) (xy 128.751838 -410.102812)
			(xy 128.74172 -410.102244) (xy 128.72301 -410.094538) (xy 128.708654 -410.080277) (xy 128.700824 -410.061618)
			(xy 128.700276 -410.051504) (xy 128.700276 -409.7655) (xy 128.700087 -409.758627) (xy 128.696477 -409.745364)
			(xy 128.693164 -409.739338) (xy 128.676795 -409.710999) (xy 128.651053 -409.650829) (xy 128.633629 -409.587745)
			(xy 128.624839 -409.522892) (xy 127.336285 -409.522892) (xy 127.326898 -409.539186) (xy 127.323542 -409.545205)
			(xy 127.319801 -409.558462) (xy 127.319532 -409.565348) (xy 127.319532 -410.314648) (xy 127.319759 -410.321541)
			(xy 127.323492 -410.334813) (xy 127.326898 -410.34081) (xy 127.343221 -410.369174) (xy 127.368964 -410.429339)
			(xy 127.38639 -410.492418) (xy 127.395184 -410.557266) (xy 127.395186 -410.622707) (xy 127.395186 -410.622708)
			(xy 130.825006 -410.622708) (xy 130.825008 -410.557264) (xy 130.833802 -410.492414) (xy 130.85123 -410.429334)
			(xy 130.876974 -410.369166) (xy 130.893312 -410.34081) (xy 130.896624 -410.334784) (xy 130.900231 -410.321521)
			(xy 130.900424 -410.314648) (xy 130.900424 -409.565348) (xy 130.900211 -409.558476) (xy 130.896617 -409.545214)
			(xy 130.893312 -409.539186) (xy 130.876986 -409.510824) (xy 130.851242 -409.450658) (xy 130.833816 -409.387579)
			(xy 130.825022 -409.322731) (xy 130.825021 -409.257289) (xy 130.833812 -409.192441) (xy 130.851235 -409.129361)
			(xy 130.876976 -409.069194) (xy 130.893312 -409.040838) (xy 130.896614 -409.034807) (xy 130.900227 -409.021548)
			(xy 130.900424 -409.014676) (xy 130.900424 -408.728672) (xy 130.900799 -408.718513) (xy 130.908608 -408.699755)
			(xy 130.92302 -408.685432) (xy 130.941825 -408.677738) (xy 130.951986 -408.677364) (xy 131.668266 -408.677364)
			(xy 131.678393 -408.677855) (xy 131.697118 -408.685576) (xy 131.711477 -408.699862) (xy 131.719293 -408.718547)
			(xy 131.719828 -408.728672) (xy 131.719828 -409.014676) (xy 131.720026 -409.021549) (xy 131.72363 -409.034812)
			(xy 131.72694 -409.040838) (xy 131.743288 -409.069188) (xy 131.769032 -409.129356) (xy 131.786458 -409.192437)
			(xy 131.79525 -409.257288) (xy 131.795249 -409.322732) (xy 131.786454 -409.387583) (xy 131.769025 -409.450663)
			(xy 131.743279 -409.51083) (xy 131.72694 -409.539186) (xy 131.723634 -409.545215) (xy 131.720022 -409.558475)
			(xy 131.719828 -409.565348) (xy 131.719828 -410.314648) (xy 131.720036 -410.32152) (xy 131.723633 -410.334783)
			(xy 131.72694 -410.34081) (xy 131.743264 -410.369173) (xy 131.769011 -410.429338) (xy 131.786439 -410.492417)
			(xy 131.795234 -410.557265) (xy 131.795236 -410.622707) (xy 131.786445 -410.687556) (xy 131.76902 -410.750636)
			(xy 131.743277 -410.810802) (xy 131.72694 -410.839158) (xy 131.723643 -410.845192) (xy 131.720026 -410.858448)
			(xy 131.719828 -410.86532) (xy 131.719828 -411.151324) (xy 131.719399 -411.161476) (xy 131.7116 -411.180224)
			(xy 131.697207 -411.194545) (xy 131.67842 -411.202249) (xy 131.668266 -411.202632) (xy 130.951986 -411.202632)
			(xy 130.941855 -411.202184) (xy 130.923128 -411.194446) (xy 130.908772 -411.180148) (xy 130.900958 -411.161453)
			(xy 130.900424 -411.151324) (xy 130.900424 -410.86532) (xy 130.900221 -410.858448) (xy 130.89662 -410.845185)
			(xy 130.893312 -410.839158) (xy 130.876962 -410.810809) (xy 130.851221 -410.75064) (xy 130.833797 -410.687559)
			(xy 130.825006 -410.622708) (xy 127.395186 -410.622708) (xy 127.386396 -410.687555) (xy 127.368973 -410.750635)
			(xy 127.343233 -410.810801) (xy 127.326898 -410.839158) (xy 127.323517 -410.845165) (xy 127.319791 -410.858431)
			(xy 127.319532 -410.86532) (xy 127.319532 -411.151324) (xy 127.319035 -411.16143) (xy 127.311296 -411.180103)
			(xy 127.297003 -411.194396) (xy 127.27833 -411.202135) (xy 127.268224 -411.202632) (xy 126.551944 -411.202632)
			(xy 126.541828 -411.202149) (xy 126.523132 -411.194421) (xy 126.508817 -411.180125) (xy 126.501065 -411.161439)
			(xy 126.500636 -411.151324) (xy 126.500636 -410.86532) (xy 126.500426 -410.858425) (xy 126.496682 -410.845153)
			(xy 126.49327 -410.839158) (xy 126.476918 -410.81081) (xy 126.451174 -410.750641) (xy 126.433748 -410.68756)
			(xy 126.424956 -410.622709) (xy 122.99515 -410.622709) (xy 122.986359 -410.687556) (xy 122.968934 -410.750636)
			(xy 122.943192 -410.810802) (xy 122.926856 -410.839158) (xy 122.923561 -410.845192) (xy 122.919942 -410.858448)
			(xy 122.919744 -410.86532) (xy 122.919744 -411.151324) (xy 122.919299 -411.161474) (xy 122.911504 -411.180219)
			(xy 122.897115 -411.19454) (xy 122.878334 -411.202246) (xy 122.868182 -411.202632) (xy 122.151902 -411.202632)
			(xy 122.141772 -411.202171) (xy 122.123046 -411.194439) (xy 122.108688 -411.180144) (xy 122.100874 -411.161452)
			(xy 122.10034 -411.151324) (xy 122.10034 -410.86532) (xy 122.100135 -410.858448) (xy 122.096535 -410.845185)
			(xy 122.093228 -410.839158) (xy 122.076877 -410.810809) (xy 122.051135 -410.750641) (xy 122.033711 -410.687559)
			(xy 122.02492 -410.622708) (xy 118.595114 -410.622708) (xy 118.586322 -410.687557) (xy 118.568896 -410.750636)
			(xy 118.543152 -410.810802) (xy 118.526814 -410.839158) (xy 118.523434 -410.845165) (xy 118.519708 -410.858432)
			(xy 118.519448 -410.86532) (xy 118.519448 -411.151324) (xy 118.518936 -411.161428) (xy 118.511199 -411.180098)
			(xy 118.496911 -411.19439) (xy 118.478244 -411.202133) (xy 118.46814 -411.202632) (xy 117.75186 -411.202632)
			(xy 117.741753 -411.202148) (xy 117.72308 -411.194404) (xy 117.708787 -411.180107) (xy 117.701048 -411.161431)
			(xy 117.700552 -411.151324) (xy 117.700552 -410.86532) (xy 117.700339 -410.858426) (xy 117.696597 -410.845154)
			(xy 117.693186 -410.839158) (xy 117.676834 -410.81081) (xy 117.651088 -410.750642) (xy 117.633662 -410.68756)
			(xy 117.62487 -410.622709) (xy 94.04731 -410.622709) (xy 94.04731 -414.527746) (xy 94.046879 -414.537813)
			(xy 94.039154 -414.556406) (xy 94.032324 -414.563814) (xy 93.974666 -414.621472) (xy 93.9673 -414.628584)
			(xy 93.95968 -414.64738) (xy 93.95968 -417.782502) (xy 93.960136 -417.792381) (xy 93.967573 -417.810685)
			(xy 93.974158 -417.818062) (xy 93.974412 -417.818316) (xy 94.03461 -417.878514) (xy 94.035118 -417.879022)
			(xy 94.042496 -417.885613) (xy 94.060795 -417.893081) (xy 94.070678 -417.8935) (xy 140.572998 -417.8935)
		)
		(stroke
			(width 0)
			(type solid)
		)
		(fill yes)
		(layer "In9.Cu")
		(net "GND")
	)
	(gr_poly
		(pts
			(xy 211.802726 -223.610932) (xy 211.803234 -223.610932) (xy 211.816442 -223.61144) (xy 212.24494 -223.61144)
			(xy 212.255006 -223.611008) (xy 212.273594 -223.603277) (xy 212.281008 -223.596454) (xy 212.284056 -223.593406)
			(xy 212.3186 -223.549972) (xy 212.325607 -223.54015) (xy 212.330508 -223.516561) (xy 212.327998 -223.50476)
			(xy 212.32622 -223.49841) (xy 212.320374 -223.474646) (xy 212.314132 -223.426106) (xy 212.313774 -223.401636)
			(xy 212.313774 -223.40062) (xy 212.314235 -223.373366) (xy 212.32199 -223.319412) (xy 212.337344 -223.26711)
			(xy 212.359985 -223.217526) (xy 212.389453 -223.171669) (xy 212.425146 -223.130473) (xy 212.466339 -223.094775)
			(xy 212.512193 -223.065304) (xy 212.561775 -223.042657) (xy 212.614074 -223.027298) (xy 212.668028 -223.019538)
			(xy 212.695282 -223.019112) (xy 212.695536 -223.019112) (xy 212.708981 -223.01924) (xy 212.735802 -223.021148)
			(xy 212.74913 -223.022922) (xy 212.75421 -223.023684) (xy 212.75548 -223.023684) (xy 212.780609 -223.026668)
			(xy 212.829828 -223.038434) (xy 212.877053 -223.056618) (xy 212.921453 -223.080898) (xy 212.962245 -223.110847)
			(xy 212.980778 -223.128078) (xy 212.982302 -223.129602) (xy 212.989922 -223.135698) (xy 212.99678 -223.140016)
			(xy 213.003388 -223.14404) (xy 213.018254 -223.148301) (xy 213.02599 -223.148398) (xy 213.097364 -223.146366)
			(xy 213.108032 -223.146112) (xy 213.127082 -223.137222) (xy 213.134194 -223.129348) (xy 213.152365 -223.109552)
			(xy 213.193313 -223.074756) (xy 213.23874 -223.046055) (xy 213.287748 -223.024017) (xy 213.339365 -223.00908)
			(xy 213.392569 -223.001539) (xy 213.419436 -223.001078) (xy 213.446686 -223.001566) (xy 213.500631 -223.009327)
			(xy 213.552922 -223.024685) (xy 213.602495 -223.047328) (xy 213.648342 -223.076795) (xy 213.689529 -223.112486)
			(xy 213.725218 -223.153675) (xy 213.754683 -223.199524) (xy 213.777323 -223.249099) (xy 213.792678 -223.301391)
			(xy 213.800435 -223.355336) (xy 213.800944 -223.382586) (xy 213.800944 -223.38284) (xy 213.800506 -223.408105)
			(xy 213.793757 -223.458185) (xy 213.787482 -223.482662) (xy 213.787482 -223.482916) (xy 213.784434 -223.494346)
			(xy 213.78672 -223.506284) (xy 213.787992 -223.511973) (xy 213.79274 -223.522615) (xy 213.796118 -223.527366)
			(xy 213.844886 -223.591374) (xy 213.846156 -223.592898) (xy 213.846156 -223.593152) (xy 213.85376 -223.601407)
			(xy 213.874062 -223.610911) (xy 213.885272 -223.61144) (xy 214.386668 -223.61144) (xy 214.398421 -223.61084)
			(xy 214.419464 -223.600369) (xy 214.427054 -223.591374) (xy 214.474044 -223.529652) (xy 214.474806 -223.528636)
			(xy 214.479218 -223.522007) (xy 214.484141 -223.506874) (xy 214.484458 -223.498918) (xy 214.484458 -223.48317)
			(xy 214.483696 -223.479614) (xy 214.483442 -223.478852) (xy 214.48268 -223.475804) (xy 214.477247 -223.452947)
			(xy 214.471393 -223.406331) (xy 214.470996 -223.38284) (xy 214.470996 -223.382586) (xy 214.471483 -223.355336)
			(xy 214.479241 -223.30139) (xy 214.494597 -223.249097) (xy 214.517239 -223.199521) (xy 214.546706 -223.153673)
			(xy 214.582398 -223.112485) (xy 214.623588 -223.076795) (xy 214.669437 -223.047331) (xy 214.719014 -223.024691)
			(xy 214.771307 -223.009337) (xy 214.825253 -223.001581) (xy 214.852504 -223.001078) (xy 214.879944 -223.00155)
			(xy 214.934258 -223.009414) (xy 214.98688 -223.024993) (xy 215.036721 -223.047964) (xy 215.082748 -223.077851)
			(xy 215.10371 -223.095566) (xy 215.110822 -223.101916) (xy 215.12784 -223.108266) (xy 215.2142 -223.108266)
			(xy 215.231218 -223.101916) (xy 215.23833 -223.095566) (xy 215.259294 -223.07786) (xy 215.305341 -223.048014)
			(xy 215.355184 -223.025061) (xy 215.407798 -223.009474) (xy 215.4621 -223.001574) (xy 215.489536 -223.001078)
			(xy 215.48979 -223.001078) (xy 215.515136 -223.001512) (xy 215.565378 -223.008264) (xy 215.614283 -223.021609)
			(xy 215.660989 -223.041313) (xy 215.704675 -223.06703) (xy 215.744571 -223.098305) (xy 215.762586 -223.11614)
			(xy 215.76284 -223.116394) (xy 215.76411 -223.117664) (xy 215.767478 -223.120862) (xy 215.775146 -223.126102)
			(xy 215.77935 -223.128078) (xy 215.807544 -223.140778) (xy 215.882728 -223.140778) (xy 215.910922 -223.128078)
			(xy 215.915126 -223.126104) (xy 215.922794 -223.120863) (xy 215.926162 -223.117664) (xy 215.927432 -223.116394)
			(xy 215.927686 -223.11614) (xy 215.945702 -223.098277) (xy 215.985639 -223.066986) (xy 216.029371 -223.041264)
			(xy 216.076126 -223.021567) (xy 216.12508 -223.00824) (xy 216.175368 -223.00152) (xy 216.200736 -223.001078)
			(xy 216.210388 -223.001078) (xy 216.23705 -223.002195) (xy 216.289688 -223.010958) (xy 216.340591 -223.026972)
			(xy 216.388765 -223.049925) (xy 216.433269 -223.079368) (xy 216.473236 -223.114727) (xy 216.507884 -223.155311)
			(xy 216.536538 -223.200328) (xy 216.558638 -223.248899) (xy 216.573752 -223.300076) (xy 216.581586 -223.352861)
			(xy 216.582244 -223.379538) (xy 216.582244 -223.38284) (xy 216.581806 -223.408105) (xy 216.575057 -223.458185)
			(xy 216.568782 -223.482662) (xy 216.568782 -223.482916) (xy 216.565734 -223.494346) (xy 216.56802 -223.506284)
			(xy 216.569292 -223.511973) (xy 216.57404 -223.522615) (xy 216.577418 -223.527366) (xy 216.626186 -223.591374)
			(xy 216.627456 -223.592898) (xy 216.627456 -223.593152) (xy 216.63506 -223.601407) (xy 216.655362 -223.610911)
			(xy 216.666572 -223.61144) (xy 217.77071 -223.61144) (xy 217.780778 -223.611013) (xy 217.799374 -223.60329)
			(xy 217.806778 -223.596454) (xy 217.810334 -223.592898) (xy 217.867484 -223.52381) (xy 217.873072 -223.50222)
			(xy 217.870786 -223.49079) (xy 217.867558 -223.472931) (xy 217.864121 -223.436801) (xy 217.863928 -223.418654)
			(xy 217.863928 -223.4184) (xy 217.864423 -223.390617) (xy 217.872472 -223.335638) (xy 217.888414 -223.282409)
			(xy 217.911912 -223.232057) (xy 217.942469 -223.185648) (xy 217.979436 -223.144164) (xy 218.022033 -223.108485)
			(xy 218.069356 -223.079364) (xy 218.120404 -223.057419) (xy 218.147138 -223.049846) (xy 218.155639 -223.047198)
			(xy 218.170251 -223.037048) (xy 218.180521 -223.02252) (xy 218.183206 -223.014032) (xy 218.206066 -222.929196)
			(xy 218.207712 -222.921885) (xy 218.207185 -222.906916) (xy 218.20505 -222.899732) (xy 218.204796 -222.89897)
			(xy 218.204288 -222.8977) (xy 218.202274 -222.892608) (xy 218.196371 -222.883387) (xy 218.192604 -222.879412)
			(xy 216.716356 -221.403164) (xy 216.690448 -221.396052) (xy 216.67724 -221.399608) (xy 216.604342 -221.418404)
			(xy 216.600278 -221.419674) (xy 216.590226 -221.423764) (xy 216.574568 -221.438762) (xy 216.570052 -221.44863)
			(xy 216.568782 -221.451932) (xy 216.56802 -221.454472) (xy 216.560066 -221.480768) (xy 216.537657 -221.530926)
			(xy 216.508291 -221.577355) (xy 216.472573 -221.619095) (xy 216.431242 -221.655286) (xy 216.385151 -221.685179)
			(xy 216.335251 -221.708157) (xy 216.282573 -221.723747) (xy 216.228204 -221.731626) (xy 216.200736 -221.732094)
			(xy 216.200482 -221.732094) (xy 216.175134 -221.731664) (xy 216.124888 -221.724921) (xy 216.075978 -221.711582)
			(xy 216.029266 -221.691883) (xy 215.985574 -221.66617) (xy 215.945673 -221.634897) (xy 215.927686 -221.617032)
			(xy 215.927432 -221.616778) (xy 215.926162 -221.615508) (xy 215.922792 -221.612313) (xy 215.915121 -221.607079)
			(xy 215.910922 -221.605094) (xy 215.882728 -221.592394) (xy 215.807544 -221.592394) (xy 215.77935 -221.605094)
			(xy 215.775146 -221.607069) (xy 215.76748 -221.612311) (xy 215.76411 -221.615508) (xy 215.76284 -221.616778)
			(xy 215.762586 -221.617032) (xy 215.744571 -221.6349) (xy 215.704637 -221.666201) (xy 215.660907 -221.691932)
			(xy 215.614152 -221.71164) (xy 215.565196 -221.724977) (xy 215.514906 -221.731707) (xy 215.489536 -221.732094)
			(xy 215.479884 -221.732094) (xy 215.453082 -221.730969) (xy 215.400171 -221.722129) (xy 215.349021 -221.705963)
			(xy 215.30064 -221.68279) (xy 215.255984 -221.653065) (xy 215.215933 -221.617377) (xy 215.181279 -221.576429)
			(xy 215.152703 -221.531029) (xy 215.130771 -221.482073) (xy 215.115915 -221.430527) (xy 215.108428 -221.377408)
			(xy 215.108028 -221.350586) (xy 215.108492 -221.323335) (xy 215.116251 -221.269387) (xy 215.131609 -221.217093)
			(xy 215.154253 -221.167517) (xy 215.183721 -221.121668) (xy 215.219416 -221.08048) (xy 215.260608 -221.044791)
			(xy 215.306461 -221.015329) (xy 215.35604 -220.992691) (xy 215.408336 -220.97734) (xy 215.462285 -220.969589)
			(xy 215.489536 -220.969078) (xy 215.48979 -220.969078) (xy 215.515136 -220.969512) (xy 215.565378 -220.976264)
			(xy 215.614283 -220.989609) (xy 215.660989 -221.009313) (xy 215.704675 -221.03503) (xy 215.744571 -221.066305)
			(xy 215.762586 -221.08414) (xy 215.76284 -221.084394) (xy 215.76411 -221.085664) (xy 215.767478 -221.088862)
			(xy 215.775146 -221.094102) (xy 215.77935 -221.096078) (xy 215.807544 -221.108778) (xy 215.867234 -221.108778)
			(xy 215.876886 -221.107762) (xy 215.885268 -221.106238) (xy 215.891618 -221.105222) (xy 215.919558 -221.092522)
			(xy 215.926416 -221.08541) (xy 215.939619 -221.072001) (xy 215.968248 -221.047573) (xy 215.983566 -221.036642)
			(xy 215.994996 -221.028768) (xy 216.006426 -221.00413) (xy 215.99779 -220.91396) (xy 215.996549 -220.904947)
			(xy 215.988622 -220.888585) (xy 215.975509 -220.875991) (xy 215.96731 -220.87205) (xy 215.933837 -220.856858)
			(xy 215.870628 -220.819333) (xy 215.812601 -220.774206) (xy 215.760665 -220.722186) (xy 215.737694 -220.693488)
			(xy 215.737186 -220.69298) (xy 215.731344 -220.685868) (xy 215.724232 -220.681296) (xy 215.720399 -220.678942)
			(xy 215.712096 -220.675487) (xy 215.707722 -220.674438) (xy 215.68664 -220.669866) (xy 215.675464 -220.672406)
			(xy 215.660986 -220.675708) (xy 215.655906 -220.678248) (xy 215.629911 -220.690207) (xy 215.575234 -220.707076)
			(xy 215.518654 -220.715602) (xy 215.490044 -220.716094) (xy 215.484202 -220.716094) (xy 215.455862 -220.715186)
			(xy 215.399908 -220.706017) (xy 215.345932 -220.688656) (xy 215.295125 -220.663486) (xy 215.24861 -220.631063)
			(xy 215.227662 -220.611954) (xy 215.22055 -220.605096) (xy 215.211152 -220.60154) (xy 215.202262 -220.59773)
			(xy 215.13292 -220.596968) (xy 215.128116 -220.597011) (xy 215.118657 -220.59868) (xy 215.114124 -220.60027)
			(xy 215.090502 -220.609414) (xy 215.083898 -220.615002) (xy 215.063172 -220.631778) (xy 215.017951 -220.660031)
			(xy 214.969242 -220.681726) (xy 214.917992 -220.696444) (xy 214.865194 -220.703898) (xy 214.838534 -220.70441)
			(xy 214.83828 -220.70441) (xy 214.81103 -220.703923) (xy 214.757084 -220.696164) (xy 214.704791 -220.680807)
			(xy 214.655216 -220.658165) (xy 214.609368 -220.628698) (xy 214.56818 -220.593006) (xy 214.53249 -220.551816)
			(xy 214.503026 -220.505966) (xy 214.480386 -220.45639) (xy 214.465032 -220.404097) (xy 214.457276 -220.35015)
			(xy 214.457276 -220.29565) (xy 214.465032 -220.241703) (xy 214.480386 -220.18941) (xy 214.503026 -220.139834)
			(xy 214.53249 -220.093984) (xy 214.56818 -220.052794) (xy 214.609368 -220.017102) (xy 214.655216 -219.987635)
			(xy 214.704791 -219.964993) (xy 214.757084 -219.949636) (xy 214.81103 -219.941877) (xy 214.83828 -219.941394)
			(xy 214.868115 -219.94197) (xy 214.927056 -219.951261) (xy 214.98383 -219.969621) (xy 215.037052 -219.996599)
			(xy 215.085422 -220.031539) (xy 215.107012 -220.052138) (xy 215.11641 -220.055948) (xy 215.1253 -220.059504)
			(xy 215.194896 -220.06052) (xy 215.199701 -220.060484) (xy 215.209166 -220.05883) (xy 215.213692 -220.057218)
			(xy 215.237314 -220.048074) (xy 215.243918 -220.042486) (xy 215.264643 -220.025705) (xy 215.309862 -219.997444)
			(xy 215.35857 -219.975739) (xy 215.40982 -219.96101) (xy 215.46262 -219.953544) (xy 215.489282 -219.953078)
			(xy 215.490044 -219.953078) (xy 215.518656 -219.953565) (xy 215.575242 -219.962069) (xy 215.629921 -219.978939)
			(xy 215.655906 -219.990924) (xy 215.660986 -219.993464) (xy 215.675464 -219.996766) (xy 215.68664 -219.999306)
			(xy 215.707468 -219.994734) (xy 215.714534 -219.992975) (xy 215.727315 -219.986011) (xy 215.732614 -219.981018)
			(xy 215.73617 -219.977462) (xy 215.738202 -219.974922) (xy 215.738456 -219.974668) (xy 215.756712 -219.951872)
			(xy 215.797047 -219.909631) (xy 215.818974 -219.89034) (xy 215.827356 -219.883228) (xy 215.8365 -219.863924)
			(xy 215.838024 -219.806774) (xy 215.838018 -219.80164) (xy 215.836219 -219.791534) (xy 215.834468 -219.786708)
			(xy 215.830404 -219.776802) (xy 215.786462 -219.73286) (xy 215.773307 -219.719594) (xy 215.748522 -219.691633)
			(xy 215.736932 -219.67698) (xy 215.733884 -219.672916) (xy 215.729566 -219.66936) (xy 215.72474 -219.66555)
			(xy 215.713692 -219.660162) (xy 215.707722 -219.658692) (xy 215.68664 -219.653866) (xy 215.675464 -219.656406)
			(xy 215.660986 -219.659708) (xy 215.655906 -219.662248) (xy 215.629911 -219.674207) (xy 215.575234 -219.691076)
			(xy 215.518654 -219.699602) (xy 215.490044 -219.700094) (xy 215.484202 -219.700094) (xy 215.455862 -219.699186)
			(xy 215.399908 -219.690017) (xy 215.345932 -219.672656) (xy 215.295125 -219.647486) (xy 215.24861 -219.615063)
			(xy 215.227662 -219.595954) (xy 215.22055 -219.589096) (xy 215.211152 -219.58554) (xy 215.202262 -219.58173)
			(xy 215.13292 -219.580968) (xy 215.128116 -219.581011) (xy 215.118657 -219.58268) (xy 215.114124 -219.58427)
			(xy 215.090502 -219.593414) (xy 215.083898 -219.599002) (xy 215.063172 -219.615778) (xy 215.017951 -219.644031)
			(xy 214.969242 -219.665726) (xy 214.917992 -219.680444) (xy 214.865194 -219.687898) (xy 214.838534 -219.68841)
			(xy 214.83828 -219.68841) (xy 214.81103 -219.687923) (xy 214.757084 -219.680164) (xy 214.704791 -219.664807)
			(xy 214.655216 -219.642165) (xy 214.609368 -219.612698) (xy 214.56818 -219.577006) (xy 214.53249 -219.535816)
			(xy 214.503026 -219.489966) (xy 214.480386 -219.44039) (xy 214.465032 -219.388097) (xy 214.457276 -219.33415)
			(xy 214.457276 -219.27965) (xy 214.465032 -219.225703) (xy 214.480386 -219.17341) (xy 214.503026 -219.123834)
			(xy 214.53249 -219.077984) (xy 214.56818 -219.036794) (xy 214.609368 -219.001102) (xy 214.655216 -218.971635)
			(xy 214.704791 -218.948993) (xy 214.757084 -218.933636) (xy 214.81103 -218.925877) (xy 214.83828 -218.925394)
			(xy 214.868115 -218.92597) (xy 214.927056 -218.935261) (xy 214.98383 -218.953621) (xy 215.037052 -218.980599)
			(xy 215.085422 -219.015539) (xy 215.107012 -219.036138) (xy 215.11641 -219.039948) (xy 215.1253 -219.043504)
			(xy 215.194896 -219.04452) (xy 215.199701 -219.044484) (xy 215.209166 -219.04283) (xy 215.213692 -219.041218)
			(xy 215.237314 -219.032074) (xy 215.243918 -219.026486) (xy 215.264643 -219.009705) (xy 215.309862 -218.981444)
			(xy 215.35857 -218.959739) (xy 215.40982 -218.94501) (xy 215.46262 -218.937544) (xy 215.489282 -218.937078)
			(xy 215.490044 -218.937078) (xy 215.518656 -218.937565) (xy 215.575242 -218.946069) (xy 215.629921 -218.962939)
			(xy 215.655906 -218.974924) (xy 215.660986 -218.977464) (xy 215.675464 -218.980766) (xy 215.68664 -218.983306)
			(xy 215.707722 -218.978734) (xy 215.712091 -218.97767) (xy 215.720395 -218.974221) (xy 215.724232 -218.971876)
			(xy 215.731344 -218.967304) (xy 215.737186 -218.960192) (xy 215.737694 -218.959684) (xy 215.760646 -218.930969)
			(xy 215.812568 -218.878928) (xy 215.870601 -218.833804) (xy 215.933831 -218.796306) (xy 215.96731 -218.781122)
			(xy 215.975525 -218.777194) (xy 215.988678 -218.764623) (xy 215.996586 -218.748237) (xy 215.99779 -218.739212)
			(xy 216.006426 -218.649042) (xy 215.994996 -218.624404) (xy 215.983566 -218.61653) (xy 215.968326 -218.605645)
			(xy 215.939827 -218.581344) (xy 215.92667 -218.568016) (xy 215.919558 -218.56065) (xy 215.89238 -218.548712)
			(xy 215.882474 -218.544394) (xy 215.824308 -218.544394) (xy 215.814402 -218.54541) (xy 215.804242 -218.547442)
			(xy 215.794082 -218.55049) (xy 215.771222 -218.560396) (xy 215.76411 -218.567762) (xy 215.74608 -218.585827)
			(xy 215.706028 -218.617466) (xy 215.662115 -218.64348) (xy 215.615125 -218.663405) (xy 215.565896 -218.676884)
			(xy 215.51531 -218.683677) (xy 215.48979 -218.684094) (xy 215.489282 -218.684094) (xy 215.466165 -218.683752)
			(xy 215.420268 -218.678164) (xy 215.375381 -218.667085) (xy 215.353646 -218.659202) (xy 215.349328 -218.657678)
			(xy 215.340946 -218.6559) (xy 215.336154 -218.655086) (xy 215.326434 -218.655086) (xy 215.321642 -218.6559)
			(xy 215.31326 -218.657678) (xy 215.308942 -218.659202) (xy 215.287254 -218.667092) (xy 215.24245 -218.678168)
			(xy 215.196636 -218.683745) (xy 215.17356 -218.684094) (xy 215.173052 -218.684094) (xy 215.145804 -218.683604)
			(xy 215.091864 -218.675843) (xy 215.039577 -218.660484) (xy 214.990007 -218.637841) (xy 214.944165 -218.608375)
			(xy 214.902982 -218.572684) (xy 214.867297 -218.531497) (xy 214.837836 -218.485651) (xy 214.815199 -218.436078)
			(xy 214.799847 -218.383789) (xy 214.792092 -218.329848) (xy 214.792092 -218.275352) (xy 214.799847 -218.22141)
			(xy 214.815199 -218.169122) (xy 214.837836 -218.119549) (xy 214.867297 -218.073703) (xy 214.902982 -218.032516)
			(xy 214.944165 -217.996825) (xy 214.990007 -217.967359) (xy 215.039577 -217.944716) (xy 215.091864 -217.929357)
			(xy 215.145804 -217.921596) (xy 215.173052 -217.921078) (xy 215.17356 -217.921078) (xy 215.196634 -217.921446)
			(xy 215.242442 -217.927043) (xy 215.287244 -217.938112) (xy 215.308942 -217.94597) (xy 215.31326 -217.947494)
			(xy 215.321642 -217.949272) (xy 215.326434 -217.950086) (xy 215.336154 -217.950086) (xy 215.340946 -217.949272)
			(xy 215.349328 -217.947494) (xy 215.353646 -217.94597) (xy 215.375374 -217.938067) (xy 215.420263 -217.92698)
			(xy 215.466163 -217.921413) (xy 215.489282 -217.921078) (xy 215.48979 -217.921078) (xy 215.515279 -217.921502)
			(xy 215.565804 -217.928287) (xy 215.614975 -217.941739) (xy 215.661918 -217.961618) (xy 215.705796 -217.98757)
			(xy 215.745828 -218.019132) (xy 215.763856 -218.037156) (xy 215.770714 -218.044522) (xy 215.797638 -218.05646)
			(xy 215.802536 -218.05849) (xy 215.812911 -218.060667) (xy 215.818212 -218.060778) (xy 215.867234 -218.060778)
			(xy 215.876886 -218.059762) (xy 215.885268 -218.058238) (xy 215.891618 -218.057222) (xy 215.919558 -218.044522)
			(xy 215.926416 -218.037156) (xy 215.944453 -218.019142) (xy 215.98448 -217.987573) (xy 216.028355 -217.961617)
			(xy 216.075297 -217.941737) (xy 216.124468 -217.928288) (xy 216.174993 -217.921508) (xy 216.200482 -217.921078)
			(xy 216.200736 -217.921078) (xy 216.227986 -217.921566) (xy 216.281931 -217.929327) (xy 216.334222 -217.944685)
			(xy 216.383795 -217.967328) (xy 216.429642 -217.996795) (xy 216.470829 -218.032486) (xy 216.506518 -218.073675)
			(xy 216.535983 -218.119524) (xy 216.558623 -218.169099) (xy 216.573978 -218.221391) (xy 216.581735 -218.275336)
			(xy 216.582244 -218.302586) (xy 216.581804 -218.328903) (xy 216.581672 -218.329852) (xy 217.922064 -218.329852)
			(xy 217.922064 -218.275348) (xy 217.92982 -218.221399) (xy 217.945176 -218.169103) (xy 217.967817 -218.119524)
			(xy 217.997284 -218.073672) (xy 218.032976 -218.032481) (xy 218.074167 -217.996788) (xy 218.120019 -217.96732)
			(xy 218.169597 -217.944678) (xy 218.221893 -217.929322) (xy 218.275842 -217.921564) (xy 218.303094 -217.921078)
			(xy 218.332857 -217.921643) (xy 218.391659 -217.9309) (xy 218.44831 -217.949174) (xy 218.501438 -217.976023)
			(xy 218.549752 -218.010794) (xy 218.571318 -218.031314) (xy 218.57843 -218.038172) (xy 218.596464 -218.045792)
			(xy 218.687396 -218.046554) (xy 218.705684 -218.039188) (xy 218.71305 -218.03233) (xy 218.734501 -218.012565)
			(xy 218.782254 -217.979078) (xy 218.834544 -217.953241) (xy 218.890156 -217.935658) (xy 218.947794 -217.926736)
			(xy 218.976956 -217.926158) (xy 219.004208 -217.926686) (xy 219.02937 -217.930301) (xy 224.337628 -217.930301)
			(xy 224.337628 -217.878327) (xy 224.345758 -217.826992) (xy 224.361819 -217.777562) (xy 224.385415 -217.731252)
			(xy 224.415965 -217.689204) (xy 224.452716 -217.652453) (xy 224.494764 -217.621903) (xy 224.541074 -217.598307)
			(xy 224.590504 -217.582246) (xy 224.641839 -217.574116) (xy 224.693813 -217.574116) (xy 224.745148 -217.582246)
			(xy 224.794578 -217.598307) (xy 224.840888 -217.621903) (xy 224.882936 -217.652453) (xy 224.919687 -217.689204)
			(xy 224.950237 -217.731252) (xy 224.973833 -217.777562) (xy 224.989894 -217.826992) (xy 224.998024 -217.878327)
			(xy 224.998534 -217.904314) (xy 224.998024 -217.930301) (xy 225.137728 -217.930301) (xy 225.137728 -217.878327)
			(xy 225.145858 -217.826992) (xy 225.161919 -217.777562) (xy 225.185515 -217.731252) (xy 225.216065 -217.689204)
			(xy 225.252816 -217.652453) (xy 225.294864 -217.621903) (xy 225.341174 -217.598307) (xy 225.390604 -217.582246)
			(xy 225.441939 -217.574116) (xy 225.493913 -217.574116) (xy 225.545248 -217.582246) (xy 225.594678 -217.598307)
			(xy 225.640988 -217.621903) (xy 225.683036 -217.652453) (xy 225.719787 -217.689204) (xy 225.750337 -217.731252)
			(xy 225.773933 -217.777562) (xy 225.789994 -217.826992) (xy 225.798124 -217.878327) (xy 225.798634 -217.904314)
			(xy 225.798124 -217.930301) (xy 226.737674 -217.930301) (xy 226.737674 -217.878327) (xy 226.745804 -217.826992)
			(xy 226.761865 -217.777562) (xy 226.785461 -217.731252) (xy 226.816011 -217.689204) (xy 226.852762 -217.652453)
			(xy 226.89481 -217.621903) (xy 226.94112 -217.598307) (xy 226.99055 -217.582246) (xy 227.041885 -217.574116)
			(xy 227.093859 -217.574116) (xy 227.145194 -217.582246) (xy 227.194624 -217.598307) (xy 227.240934 -217.621903)
			(xy 227.282982 -217.652453) (xy 227.319733 -217.689204) (xy 227.350283 -217.731252) (xy 227.373879 -217.777562)
			(xy 227.38994 -217.826992) (xy 227.39807 -217.878327) (xy 227.39858 -217.904314) (xy 227.39807 -217.930301)
			(xy 227.537774 -217.930301) (xy 227.537774 -217.878327) (xy 227.545904 -217.826992) (xy 227.561965 -217.777562)
			(xy 227.585561 -217.731252) (xy 227.616111 -217.689204) (xy 227.652862 -217.652453) (xy 227.69491 -217.621903)
			(xy 227.74122 -217.598307) (xy 227.79065 -217.582246) (xy 227.841985 -217.574116) (xy 227.893959 -217.574116)
			(xy 227.945294 -217.582246) (xy 227.994724 -217.598307) (xy 228.041034 -217.621903) (xy 228.083082 -217.652453)
			(xy 228.119833 -217.689204) (xy 228.150383 -217.731252) (xy 228.173979 -217.777562) (xy 228.19004 -217.826992)
			(xy 228.19817 -217.878327) (xy 228.19868 -217.904314) (xy 228.19817 -217.930301) (xy 228.33762 -217.930301)
			(xy 228.33762 -217.878327) (xy 228.34575 -217.826992) (xy 228.361811 -217.777562) (xy 228.385407 -217.731252)
			(xy 228.415957 -217.689204) (xy 228.452708 -217.652453) (xy 228.494756 -217.621903) (xy 228.541066 -217.598307)
			(xy 228.590496 -217.582246) (xy 228.641831 -217.574116) (xy 228.693805 -217.574116) (xy 228.74514 -217.582246)
			(xy 228.79457 -217.598307) (xy 228.84088 -217.621903) (xy 228.882928 -217.652453) (xy 228.919679 -217.689204)
			(xy 228.950229 -217.731252) (xy 228.973825 -217.777562) (xy 228.989886 -217.826992) (xy 228.998016 -217.878327)
			(xy 228.998526 -217.904314) (xy 228.998016 -217.930301) (xy 229.937312 -217.930301) (xy 229.937312 -217.878327)
			(xy 229.945442 -217.826992) (xy 229.961503 -217.777562) (xy 229.985099 -217.731252) (xy 230.015649 -217.689204)
			(xy 230.0524 -217.652453) (xy 230.094448 -217.621903) (xy 230.140758 -217.598307) (xy 230.190188 -217.582246)
			(xy 230.241523 -217.574116) (xy 230.293497 -217.574116) (xy 230.344832 -217.582246) (xy 230.394262 -217.598307)
			(xy 230.440572 -217.621903) (xy 230.48262 -217.652453) (xy 230.519371 -217.689204) (xy 230.549921 -217.731252)
			(xy 230.573517 -217.777562) (xy 230.589578 -217.826992) (xy 230.597708 -217.878327) (xy 230.598218 -217.904314)
			(xy 230.597708 -217.930301) (xy 230.737158 -217.930301) (xy 230.737158 -217.878327) (xy 230.745288 -217.826992)
			(xy 230.761349 -217.777562) (xy 230.784945 -217.731252) (xy 230.815495 -217.689204) (xy 230.852246 -217.652453)
			(xy 230.894294 -217.621903) (xy 230.940604 -217.598307) (xy 230.990034 -217.582246) (xy 231.041369 -217.574116)
			(xy 231.093343 -217.574116) (xy 231.144678 -217.582246) (xy 231.194108 -217.598307) (xy 231.240418 -217.621903)
			(xy 231.282466 -217.652453) (xy 231.319217 -217.689204) (xy 231.349767 -217.731252) (xy 231.373363 -217.777562)
			(xy 231.389424 -217.826992) (xy 231.397554 -217.878327) (xy 231.398064 -217.904314) (xy 231.397554 -217.930301)
			(xy 231.537258 -217.930301) (xy 231.537258 -217.878327) (xy 231.545388 -217.826992) (xy 231.561449 -217.777562)
			(xy 231.585045 -217.731252) (xy 231.615595 -217.689204) (xy 231.652346 -217.652453) (xy 231.694394 -217.621903)
			(xy 231.740704 -217.598307) (xy 231.790134 -217.582246) (xy 231.841469 -217.574116) (xy 231.893443 -217.574116)
			(xy 231.944778 -217.582246) (xy 231.994208 -217.598307) (xy 232.040518 -217.621903) (xy 232.082566 -217.652453)
			(xy 232.119317 -217.689204) (xy 232.149867 -217.731252) (xy 232.173463 -217.777562) (xy 232.189524 -217.826992)
			(xy 232.197654 -217.878327) (xy 232.198164 -217.904314) (xy 232.197654 -217.930301) (xy 233.137204 -217.930301)
			(xy 233.137204 -217.878327) (xy 233.145334 -217.826992) (xy 233.161395 -217.777562) (xy 233.184991 -217.731252)
			(xy 233.215541 -217.689204) (xy 233.252292 -217.652453) (xy 233.29434 -217.621903) (xy 233.34065 -217.598307)
			(xy 233.39008 -217.582246) (xy 233.441415 -217.574116) (xy 233.493389 -217.574116) (xy 233.544724 -217.582246)
			(xy 233.594154 -217.598307) (xy 233.640464 -217.621903) (xy 233.682512 -217.652453) (xy 233.719263 -217.689204)
			(xy 233.749813 -217.731252) (xy 233.773409 -217.777562) (xy 233.78947 -217.826992) (xy 233.7976 -217.878327)
			(xy 233.79811 -217.904314) (xy 233.7976 -217.930301) (xy 233.937304 -217.930301) (xy 233.937304 -217.878327)
			(xy 233.945434 -217.826992) (xy 233.961495 -217.777562) (xy 233.985091 -217.731252) (xy 234.015641 -217.689204)
			(xy 234.052392 -217.652453) (xy 234.09444 -217.621903) (xy 234.14075 -217.598307) (xy 234.19018 -217.582246)
			(xy 234.241515 -217.574116) (xy 234.293489 -217.574116) (xy 234.344824 -217.582246) (xy 234.394254 -217.598307)
			(xy 234.440564 -217.621903) (xy 234.482612 -217.652453) (xy 234.519363 -217.689204) (xy 234.549913 -217.731252)
			(xy 234.573509 -217.777562) (xy 234.58957 -217.826992) (xy 234.5977 -217.878327) (xy 234.59821 -217.904314)
			(xy 234.5977 -217.930301) (xy 234.73715 -217.930301) (xy 234.73715 -217.878327) (xy 234.74528 -217.826992)
			(xy 234.761341 -217.777562) (xy 234.784937 -217.731252) (xy 234.815487 -217.689204) (xy 234.852238 -217.652453)
			(xy 234.894286 -217.621903) (xy 234.940596 -217.598307) (xy 234.990026 -217.582246) (xy 235.041361 -217.574116)
			(xy 235.093335 -217.574116) (xy 235.14467 -217.582246) (xy 235.1941 -217.598307) (xy 235.24041 -217.621903)
			(xy 235.282458 -217.652453) (xy 235.319209 -217.689204) (xy 235.349759 -217.731252) (xy 235.373355 -217.777562)
			(xy 235.389416 -217.826992) (xy 235.397546 -217.878327) (xy 235.398056 -217.904314) (xy 235.397546 -217.930301)
			(xy 235.389416 -217.981636) (xy 235.373355 -218.031066) (xy 235.349759 -218.077376) (xy 235.319209 -218.119424)
			(xy 235.31072 -218.127913) (xy 235.790996 -218.127913) (xy 235.790996 -218.075939) (xy 235.799126 -218.024604)
			(xy 235.815187 -217.975174) (xy 235.838783 -217.928864) (xy 235.869333 -217.886816) (xy 235.906084 -217.850065)
			(xy 235.948132 -217.819515) (xy 235.994442 -217.795919) (xy 236.043872 -217.779858) (xy 236.095207 -217.771728)
			(xy 236.147181 -217.771728) (xy 236.198516 -217.779858) (xy 236.247946 -217.795919) (xy 236.294256 -217.819515)
			(xy 236.336304 -217.850065) (xy 236.373055 -217.886816) (xy 236.403605 -217.928864) (xy 236.427201 -217.975174)
			(xy 236.44016 -218.015058) (xy 237.476792 -218.015058) (xy 237.477278 -217.987807) (xy 237.485034 -217.933859)
			(xy 237.500389 -217.881564) (xy 237.523031 -217.831987) (xy 237.552497 -217.786137) (xy 237.588188 -217.744946)
			(xy 237.629379 -217.709255) (xy 237.675229 -217.679789) (xy 237.724806 -217.657147) (xy 237.777101 -217.641792)
			(xy 237.831049 -217.634036) (xy 237.885551 -217.634036) (xy 237.939499 -217.641792) (xy 237.991794 -217.657147)
			(xy 238.041371 -217.679789) (xy 238.087221 -217.709255) (xy 238.128412 -217.744946) (xy 238.164103 -217.786137)
			(xy 238.166431 -217.78976) (xy 241.703096 -217.78976) (xy 241.707167 -217.734138) (xy 241.719293 -217.679701)
			(xy 241.739216 -217.62761) (xy 241.766512 -217.578975) (xy 241.800598 -217.534832) (xy 241.840747 -217.496123)
			(xy 241.886105 -217.463672) (xy 241.935705 -217.438171) (xy 241.988489 -217.420164) (xy 242.043332 -217.410034)
			(xy 242.099066 -217.407997) (xy 242.154503 -217.414097) (xy 242.20846 -217.428203) (xy 242.259789 -217.450015)
			(xy 242.307395 -217.479069) (xy 242.332787 -217.5002) (xy 242.924582 -217.5002) (xy 242.928653 -217.444578)
			(xy 242.940779 -217.390141) (xy 242.960702 -217.33805) (xy 242.987998 -217.289415) (xy 243.022084 -217.245272)
			(xy 243.062233 -217.206563) (xy 243.107591 -217.174112) (xy 243.157191 -217.148611) (xy 243.209975 -217.130604)
			(xy 243.264818 -217.120474) (xy 243.320552 -217.118437) (xy 243.375989 -217.124537) (xy 243.429946 -217.138643)
			(xy 243.481275 -217.160455) (xy 243.528881 -217.189509) (xy 243.571749 -217.225184) (xy 243.608966 -217.266721)
			(xy 243.639739 -217.313234) (xy 243.663411 -217.363731) (xy 243.679479 -217.417138) (xy 243.687599 -217.472314)
			(xy 243.688108 -217.5002) (xy 248.970292 -217.5002) (xy 248.970814 -217.472815) (xy 248.978659 -217.418609)
			(xy 248.994174 -217.366083) (xy 249.01704 -217.316314) (xy 249.046787 -217.270326) (xy 249.082804 -217.229063)
			(xy 249.12435 -217.193375) (xy 249.170572 -217.163993) (xy 249.220521 -217.141522) (xy 249.273169 -217.126424)
			(xy 249.300238 -217.122248) (xy 249.314655 -217.11981) (xy 249.341335 -217.107883) (xy 249.363537 -217.088879)
			(xy 249.379438 -217.064359) (xy 249.387732 -217.036336) (xy 249.387739 -217.007111) (xy 249.384058 -216.992962)
			(xy 249.376928 -216.966871) (xy 249.369285 -216.913326) (xy 249.368818 -216.886282) (xy 249.369304 -216.859031)
			(xy 249.37706 -216.805083) (xy 249.392415 -216.752788) (xy 249.415057 -216.703211) (xy 249.444523 -216.657361)
			(xy 249.480214 -216.61617) (xy 249.521405 -216.580479) (xy 249.567255 -216.551013) (xy 249.616832 -216.528371)
			(xy 249.669127 -216.513016) (xy 249.723075 -216.50526) (xy 249.777577 -216.50526) (xy 249.831525 -216.513016)
			(xy 249.88382 -216.528371) (xy 249.933397 -216.551013) (xy 249.979247 -216.580479) (xy 250.020438 -216.61617)
			(xy 250.056129 -216.657361) (xy 250.085595 -216.703211) (xy 250.108237 -216.752788) (xy 250.123592 -216.805083)
			(xy 250.131348 -216.859031) (xy 250.131834 -216.886282) (xy 250.131359 -216.913669) (xy 250.123515 -216.96788)
			(xy 250.107998 -217.020412) (xy 250.085129 -217.070184) (xy 250.055377 -217.116175) (xy 250.019355 -217.157439)
			(xy 249.977801 -217.193127) (xy 249.931571 -217.222506) (xy 249.881615 -217.244972) (xy 249.82896 -217.260063)
			(xy 249.801888 -217.264234) (xy 249.787468 -217.266643) (xy 249.760793 -217.278585) (xy 249.738597 -217.297597)
			(xy 249.722699 -217.32212) (xy 249.714404 -217.350144) (xy 249.714391 -217.379369) (xy 249.718068 -217.39352)
			(xy 249.725195 -217.419612) (xy 249.73284 -217.473156) (xy 249.733308 -217.5002) (xy 249.732822 -217.527451)
			(xy 249.725066 -217.581399) (xy 249.709711 -217.633694) (xy 249.687069 -217.683271) (xy 249.657603 -217.729121)
			(xy 249.621912 -217.770312) (xy 249.580721 -217.806003) (xy 249.534871 -217.835469) (xy 249.485294 -217.858111)
			(xy 249.432999 -217.873466) (xy 249.379051 -217.881222) (xy 249.324549 -217.881222) (xy 249.270601 -217.873466)
			(xy 249.218306 -217.858111) (xy 249.168729 -217.835469) (xy 249.122879 -217.806003) (xy 249.081688 -217.770312)
			(xy 249.045997 -217.729121) (xy 249.016531 -217.683271) (xy 248.993889 -217.633694) (xy 248.978534 -217.581399)
			(xy 248.970778 -217.527451) (xy 248.970292 -217.5002) (xy 243.688108 -217.5002) (xy 243.687599 -217.528086)
			(xy 243.679479 -217.583262) (xy 243.663411 -217.636669) (xy 243.639739 -217.687166) (xy 243.608966 -217.733679)
			(xy 243.571749 -217.775216) (xy 243.528881 -217.810891) (xy 243.481275 -217.839945) (xy 243.429946 -217.861757)
			(xy 243.375989 -217.875863) (xy 243.320552 -217.881963) (xy 243.264818 -217.879926) (xy 243.209975 -217.869796)
			(xy 243.157191 -217.851789) (xy 243.107591 -217.826288) (xy 243.062233 -217.793837) (xy 243.022084 -217.755128)
			(xy 242.987998 -217.710985) (xy 242.960702 -217.66235) (xy 242.940779 -217.610259) (xy 242.928653 -217.555822)
			(xy 242.924582 -217.5002) (xy 242.332787 -217.5002) (xy 242.350263 -217.514744) (xy 242.38748 -217.556281)
			(xy 242.418253 -217.602794) (xy 242.441925 -217.653291) (xy 242.457993 -217.706698) (xy 242.466113 -217.761874)
			(xy 242.466622 -217.78976) (xy 242.466113 -217.817646) (xy 242.457993 -217.872822) (xy 242.441925 -217.926229)
			(xy 242.418253 -217.976726) (xy 242.38748 -218.023239) (xy 242.350263 -218.064776) (xy 242.307395 -218.100451)
			(xy 242.259789 -218.129505) (xy 242.20846 -218.151317) (xy 242.154503 -218.165423) (xy 242.099066 -218.171523)
			(xy 242.043332 -218.169486) (xy 241.988489 -218.159356) (xy 241.935705 -218.141349) (xy 241.886105 -218.115848)
			(xy 241.840747 -218.083397) (xy 241.800598 -218.044688) (xy 241.766512 -218.000545) (xy 241.739216 -217.95191)
			(xy 241.719293 -217.899819) (xy 241.707167 -217.845382) (xy 241.703096 -217.78976) (xy 238.166431 -217.78976)
			(xy 238.193569 -217.831987) (xy 238.216211 -217.881564) (xy 238.231566 -217.933859) (xy 238.239322 -217.987807)
			(xy 238.239808 -218.015058) (xy 238.239411 -218.038816) (xy 238.233473 -218.085959) (xy 238.221735 -218.132002)
			(xy 238.213392 -218.15425) (xy 238.209836 -218.163902) (xy 238.21009 -218.183968) (xy 238.247936 -218.269058)
			(xy 238.262668 -218.282774) (xy 238.27232 -218.28633) (xy 238.299168 -218.29701) (xy 238.349552 -218.325293)
			(xy 238.395097 -218.360846) (xy 238.434762 -218.402859) (xy 238.467642 -218.450371) (xy 238.492985 -218.502295)
			(xy 238.510211 -218.557447) (xy 238.518927 -218.614565) (xy 238.519462 -218.643454) (xy 238.518976 -218.670705)
			(xy 238.51122 -218.724653) (xy 238.495865 -218.776948) (xy 238.473223 -218.826525) (xy 238.469025 -218.833057)
			(xy 241.736015 -218.833057) (xy 241.736015 -218.778543) (xy 241.743773 -218.724585) (xy 241.759132 -218.67228)
			(xy 241.781778 -218.622694) (xy 241.811251 -218.576835) (xy 241.84695 -218.535637) (xy 241.888149 -218.49994)
			(xy 241.93401 -218.470469) (xy 241.983597 -218.447826) (xy 242.035903 -218.432469) (xy 242.089861 -218.424714)
			(xy 242.117118 -218.424252) (xy 242.141809 -218.424628) (xy 242.190775 -218.431013) (xy 242.238506 -218.443672)
			(xy 242.2842 -218.462395) (xy 242.30584 -218.47429) (xy 242.316 -218.480132) (xy 242.338606 -218.481656)
			(xy 242.433856 -218.444826) (xy 242.44935 -218.42857) (xy 242.452906 -218.417394) (xy 242.461591 -218.392215)
			(xy 242.484956 -218.344353) (xy 242.514753 -218.300207) (xy 242.550403 -218.260637) (xy 242.591211 -218.226411)
			(xy 242.636385 -218.198196) (xy 242.685045 -218.176541) (xy 242.736244 -218.161867) (xy 242.788988 -218.154459)
			(xy 242.815618 -218.153996) (xy 242.84287 -218.154461) (xy 242.890853 -218.161362) (xy 250.778262 -218.161362)
			(xy 250.782333 -218.10574) (xy 250.794459 -218.051303) (xy 250.814382 -217.999212) (xy 250.841678 -217.950577)
			(xy 250.875764 -217.906434) (xy 250.915913 -217.867725) (xy 250.961271 -217.835274) (xy 251.010871 -217.809773)
			(xy 251.063655 -217.791766) (xy 251.118498 -217.781636) (xy 251.174232 -217.779599) (xy 251.229669 -217.785699)
			(xy 251.283626 -217.799805) (xy 251.334955 -217.821617) (xy 251.382561 -217.850671) (xy 251.425429 -217.886346)
			(xy 251.462646 -217.927883) (xy 251.493419 -217.974396) (xy 251.517091 -218.024893) (xy 251.533159 -218.0783)
			(xy 251.541279 -218.133476) (xy 251.541788 -218.161362) (xy 251.541279 -218.189248) (xy 251.533159 -218.244424)
			(xy 251.517091 -218.297831) (xy 251.493419 -218.348328) (xy 251.462646 -218.394841) (xy 251.425429 -218.436378)
			(xy 251.382561 -218.472053) (xy 251.334955 -218.501107) (xy 251.283626 -218.522919) (xy 251.229669 -218.537025)
			(xy 251.174232 -218.543125) (xy 251.118498 -218.541088) (xy 251.063655 -218.530958) (xy 251.010871 -218.512951)
			(xy 250.961271 -218.48745) (xy 250.915913 -218.454999) (xy 250.875764 -218.41629) (xy 250.841678 -218.372147)
			(xy 250.814382 -218.323512) (xy 250.794459 -218.271421) (xy 250.782333 -218.216984) (xy 250.778262 -218.161362)
			(xy 242.890853 -218.161362) (xy 242.896819 -218.16222) (xy 242.949114 -218.177578) (xy 242.998691 -218.200221)
			(xy 243.044542 -218.22969) (xy 243.085732 -218.265383) (xy 243.121423 -218.306576) (xy 243.150889 -218.352428)
			(xy 243.17353 -218.402007) (xy 243.188885 -218.454303) (xy 243.196641 -218.508252) (xy 243.197126 -218.535504)
			(xy 243.196574 -218.565017) (xy 243.187483 -218.623338) (xy 243.169518 -218.679563) (xy 243.143109 -218.732351)
			(xy 243.108884 -218.780442) (xy 243.088668 -218.80195) (xy 243.082064 -218.808808) (xy 243.074698 -218.825826)
			(xy 243.070634 -218.911932) (xy 243.076476 -218.929712) (xy 243.082318 -218.937078) (xy 243.098304 -218.957553)
			(xy 243.125215 -219.001984) (xy 243.145859 -219.049652) (xy 243.159855 -219.099676) (xy 243.166945 -219.151136)
			(xy 243.167408 -219.177108) (xy 243.16693 -219.204359) (xy 243.159172 -219.258307) (xy 243.143816 -219.310602)
			(xy 243.121174 -219.36018) (xy 243.091707 -219.40603) (xy 243.056014 -219.44722) (xy 243.014824 -219.482912)
			(xy 242.968973 -219.512378) (xy 242.919395 -219.535019) (xy 242.8671 -219.550374) (xy 242.813151 -219.55813)
			(xy 242.7859 -219.558616) (xy 242.758794 -219.55812) (xy 242.705129 -219.550446) (xy 242.65309 -219.535252)
			(xy 242.603727 -219.512844) (xy 242.558032 -219.483674) (xy 242.516927 -219.448328) (xy 242.48124 -219.40752)
			(xy 242.451689 -219.362071) (xy 242.42887 -219.312896) (xy 242.413242 -219.260986) (xy 242.40871 -219.234258)
			(xy 242.406932 -219.22232) (xy 242.393724 -219.20327) (xy 242.302284 -219.15247) (xy 242.27917 -219.151454)
			(xy 242.267994 -219.156026) (xy 242.244071 -219.165876) (xy 242.19424 -219.179785) (xy 242.142985 -219.18682)
			(xy 242.117118 -219.187268) (xy 242.089861 -219.186886) (xy 242.035903 -219.179131) (xy 241.983597 -219.163774)
			(xy 241.93401 -219.141131) (xy 241.888149 -219.11166) (xy 241.84695 -219.075963) (xy 241.811251 -219.034765)
			(xy 241.781778 -218.988906) (xy 241.759132 -218.93932) (xy 241.743773 -218.887015) (xy 241.736015 -218.833057)
			(xy 238.469025 -218.833057) (xy 238.443757 -218.872375) (xy 238.408066 -218.913566) (xy 238.366875 -218.949257)
			(xy 238.321025 -218.978723) (xy 238.271448 -219.001365) (xy 238.219153 -219.01672) (xy 238.165205 -219.024476)
			(xy 238.110703 -219.024476) (xy 238.056755 -219.01672) (xy 238.00446 -219.001365) (xy 237.954883 -218.978723)
			(xy 237.909033 -218.949257) (xy 237.867842 -218.913566) (xy 237.832151 -218.872375) (xy 237.802685 -218.826525)
			(xy 237.780043 -218.776948) (xy 237.764688 -218.724653) (xy 237.756932 -218.670705) (xy 237.756446 -218.643454)
			(xy 237.756843 -218.619696) (xy 237.76278 -218.572553) (xy 237.774519 -218.52651) (xy 237.782862 -218.504262)
			(xy 237.786418 -218.49461) (xy 237.786164 -218.474544) (xy 237.748318 -218.389454) (xy 237.733586 -218.375738)
			(xy 237.723934 -218.372182) (xy 237.69708 -218.361516) (xy 237.646698 -218.333229) (xy 237.601155 -218.297672)
			(xy 237.561491 -218.255657) (xy 237.528613 -218.208144) (xy 237.503271 -218.156218) (xy 237.486045 -218.101066)
			(xy 237.477328 -218.043948) (xy 237.476792 -218.015058) (xy 236.44016 -218.015058) (xy 236.443262 -218.024604)
			(xy 236.451392 -218.075939) (xy 236.451902 -218.101926) (xy 236.451392 -218.127913) (xy 236.443262 -218.179248)
			(xy 236.427201 -218.228678) (xy 236.403605 -218.274988) (xy 236.373055 -218.317036) (xy 236.336304 -218.353787)
			(xy 236.294256 -218.384337) (xy 236.247946 -218.407933) (xy 236.198516 -218.423994) (xy 236.147181 -218.432124)
			(xy 236.095207 -218.432124) (xy 236.043872 -218.423994) (xy 235.994442 -218.407933) (xy 235.948132 -218.384337)
			(xy 235.906084 -218.353787) (xy 235.869333 -218.317036) (xy 235.838783 -218.274988) (xy 235.815187 -218.228678)
			(xy 235.799126 -218.179248) (xy 235.790996 -218.127913) (xy 235.31072 -218.127913) (xy 235.282458 -218.156175)
			(xy 235.24041 -218.186725) (xy 235.1941 -218.210321) (xy 235.14467 -218.226382) (xy 235.093335 -218.234512)
			(xy 235.041361 -218.234512) (xy 234.990026 -218.226382) (xy 234.940596 -218.210321) (xy 234.894286 -218.186725)
			(xy 234.852238 -218.156175) (xy 234.815487 -218.119424) (xy 234.784937 -218.077376) (xy 234.761341 -218.031066)
			(xy 234.74528 -217.981636) (xy 234.73715 -217.930301) (xy 234.5977 -217.930301) (xy 234.58957 -217.981636)
			(xy 234.573509 -218.031066) (xy 234.549913 -218.077376) (xy 234.519363 -218.119424) (xy 234.482612 -218.156175)
			(xy 234.440564 -218.186725) (xy 234.394254 -218.210321) (xy 234.344824 -218.226382) (xy 234.293489 -218.234512)
			(xy 234.241515 -218.234512) (xy 234.19018 -218.226382) (xy 234.14075 -218.210321) (xy 234.09444 -218.186725)
			(xy 234.052392 -218.156175) (xy 234.015641 -218.119424) (xy 233.985091 -218.077376) (xy 233.961495 -218.031066)
			(xy 233.945434 -217.981636) (xy 233.937304 -217.930301) (xy 233.7976 -217.930301) (xy 233.78947 -217.981636)
			(xy 233.773409 -218.031066) (xy 233.749813 -218.077376) (xy 233.719263 -218.119424) (xy 233.682512 -218.156175)
			(xy 233.640464 -218.186725) (xy 233.594154 -218.210321) (xy 233.544724 -218.226382) (xy 233.493389 -218.234512)
			(xy 233.441415 -218.234512) (xy 233.39008 -218.226382) (xy 233.34065 -218.210321) (xy 233.29434 -218.186725)
			(xy 233.252292 -218.156175) (xy 233.215541 -218.119424) (xy 233.184991 -218.077376) (xy 233.161395 -218.031066)
			(xy 233.145334 -217.981636) (xy 233.137204 -217.930301) (xy 232.197654 -217.930301) (xy 232.189524 -217.981636)
			(xy 232.173463 -218.031066) (xy 232.149867 -218.077376) (xy 232.119317 -218.119424) (xy 232.082566 -218.156175)
			(xy 232.040518 -218.186725) (xy 231.994208 -218.210321) (xy 231.944778 -218.226382) (xy 231.893443 -218.234512)
			(xy 231.841469 -218.234512) (xy 231.790134 -218.226382) (xy 231.740704 -218.210321) (xy 231.694394 -218.186725)
			(xy 231.652346 -218.156175) (xy 231.615595 -218.119424) (xy 231.585045 -218.077376) (xy 231.561449 -218.031066)
			(xy 231.545388 -217.981636) (xy 231.537258 -217.930301) (xy 231.397554 -217.930301) (xy 231.389424 -217.981636)
			(xy 231.373363 -218.031066) (xy 231.349767 -218.077376) (xy 231.319217 -218.119424) (xy 231.282466 -218.156175)
			(xy 231.240418 -218.186725) (xy 231.194108 -218.210321) (xy 231.144678 -218.226382) (xy 231.093343 -218.234512)
			(xy 231.041369 -218.234512) (xy 230.990034 -218.226382) (xy 230.940604 -218.210321) (xy 230.894294 -218.186725)
			(xy 230.852246 -218.156175) (xy 230.815495 -218.119424) (xy 230.784945 -218.077376) (xy 230.761349 -218.031066)
			(xy 230.745288 -217.981636) (xy 230.737158 -217.930301) (xy 230.597708 -217.930301) (xy 230.589578 -217.981636)
			(xy 230.573517 -218.031066) (xy 230.549921 -218.077376) (xy 230.519371 -218.119424) (xy 230.48262 -218.156175)
			(xy 230.440572 -218.186725) (xy 230.394262 -218.210321) (xy 230.344832 -218.226382) (xy 230.293497 -218.234512)
			(xy 230.241523 -218.234512) (xy 230.190188 -218.226382) (xy 230.140758 -218.210321) (xy 230.094448 -218.186725)
			(xy 230.0524 -218.156175) (xy 230.015649 -218.119424) (xy 229.985099 -218.077376) (xy 229.961503 -218.031066)
			(xy 229.945442 -217.981636) (xy 229.937312 -217.930301) (xy 228.998016 -217.930301) (xy 228.989886 -217.981636)
			(xy 228.973825 -218.031066) (xy 228.950229 -218.077376) (xy 228.919679 -218.119424) (xy 228.882928 -218.156175)
			(xy 228.84088 -218.186725) (xy 228.79457 -218.210321) (xy 228.74514 -218.226382) (xy 228.693805 -218.234512)
			(xy 228.641831 -218.234512) (xy 228.590496 -218.226382) (xy 228.541066 -218.210321) (xy 228.494756 -218.186725)
			(xy 228.452708 -218.156175) (xy 228.415957 -218.119424) (xy 228.385407 -218.077376) (xy 228.361811 -218.031066)
			(xy 228.34575 -217.981636) (xy 228.33762 -217.930301) (xy 228.19817 -217.930301) (xy 228.19004 -217.981636)
			(xy 228.173979 -218.031066) (xy 228.150383 -218.077376) (xy 228.119833 -218.119424) (xy 228.083082 -218.156175)
			(xy 228.041034 -218.186725) (xy 227.994724 -218.210321) (xy 227.945294 -218.226382) (xy 227.893959 -218.234512)
			(xy 227.841985 -218.234512) (xy 227.79065 -218.226382) (xy 227.74122 -218.210321) (xy 227.69491 -218.186725)
			(xy 227.652862 -218.156175) (xy 227.616111 -218.119424) (xy 227.585561 -218.077376) (xy 227.561965 -218.031066)
			(xy 227.545904 -217.981636) (xy 227.537774 -217.930301) (xy 227.39807 -217.930301) (xy 227.38994 -217.981636)
			(xy 227.373879 -218.031066) (xy 227.350283 -218.077376) (xy 227.319733 -218.119424) (xy 227.282982 -218.156175)
			(xy 227.240934 -218.186725) (xy 227.194624 -218.210321) (xy 227.145194 -218.226382) (xy 227.093859 -218.234512)
			(xy 227.041885 -218.234512) (xy 226.99055 -218.226382) (xy 226.94112 -218.210321) (xy 226.89481 -218.186725)
			(xy 226.852762 -218.156175) (xy 226.816011 -218.119424) (xy 226.785461 -218.077376) (xy 226.761865 -218.031066)
			(xy 226.745804 -217.981636) (xy 226.737674 -217.930301) (xy 225.798124 -217.930301) (xy 225.789994 -217.981636)
			(xy 225.773933 -218.031066) (xy 225.750337 -218.077376) (xy 225.719787 -218.119424) (xy 225.683036 -218.156175)
			(xy 225.640988 -218.186725) (xy 225.594678 -218.210321) (xy 225.545248 -218.226382) (xy 225.493913 -218.234512)
			(xy 225.441939 -218.234512) (xy 225.390604 -218.226382) (xy 225.341174 -218.210321) (xy 225.294864 -218.186725)
			(xy 225.252816 -218.156175) (xy 225.216065 -218.119424) (xy 225.185515 -218.077376) (xy 225.161919 -218.031066)
			(xy 225.145858 -217.981636) (xy 225.137728 -217.930301) (xy 224.998024 -217.930301) (xy 224.989894 -217.981636)
			(xy 224.973833 -218.031066) (xy 224.950237 -218.077376) (xy 224.919687 -218.119424) (xy 224.882936 -218.156175)
			(xy 224.840888 -218.186725) (xy 224.794578 -218.210321) (xy 224.745148 -218.226382) (xy 224.693813 -218.234512)
			(xy 224.641839 -218.234512) (xy 224.590504 -218.226382) (xy 224.541074 -218.210321) (xy 224.494764 -218.186725)
			(xy 224.452716 -218.156175) (xy 224.415965 -218.119424) (xy 224.385415 -218.077376) (xy 224.361819 -218.031066)
			(xy 224.345758 -217.981636) (xy 224.337628 -217.930301) (xy 219.02937 -217.930301) (xy 219.058159 -217.934437)
			(xy 219.110458 -217.949788) (xy 219.160039 -217.972426) (xy 219.205894 -218.00189) (xy 219.247088 -218.037581)
			(xy 219.282783 -218.078771) (xy 219.312253 -218.124622) (xy 219.334896 -218.174201) (xy 219.350253 -218.226498)
			(xy 219.358011 -218.280448) (xy 219.358011 -218.334952) (xy 219.350253 -218.388902) (xy 219.334896 -218.441199)
			(xy 219.312253 -218.490778) (xy 219.282783 -218.536629) (xy 219.247088 -218.577819) (xy 219.205894 -218.61351)
			(xy 219.160039 -218.642974) (xy 219.110458 -218.665612) (xy 219.058159 -218.680963) (xy 219.004208 -218.688714)
			(xy 218.976956 -218.689174) (xy 218.947195 -218.688563) (xy 218.888396 -218.679315) (xy 218.831746 -218.661051)
			(xy 218.778618 -218.634213) (xy 218.7303 -218.599453) (xy 218.708732 -218.578938) (xy 218.70162 -218.57208)
			(xy 218.683586 -218.56446) (xy 218.592654 -218.563698) (xy 218.574366 -218.571064) (xy 218.567 -218.577922)
			(xy 218.545578 -218.597719) (xy 218.497816 -218.631201) (xy 218.445518 -218.65703) (xy 218.389901 -218.674606)
			(xy 218.332258 -218.68352) (xy 218.303094 -218.684094) (xy 218.275842 -218.683636) (xy 218.221893 -218.675878)
			(xy 218.169597 -218.660522) (xy 218.120019 -218.63788) (xy 218.074167 -218.608412) (xy 218.032976 -218.572719)
			(xy 217.997284 -218.531528) (xy 217.967817 -218.485676) (xy 217.945176 -218.436097) (xy 217.92982 -218.383801)
			(xy 217.922064 -218.329852) (xy 216.581672 -218.329852) (xy 216.574573 -218.381037) (xy 216.560246 -218.431683)
			(xy 216.539096 -218.47988) (xy 216.511524 -218.524714) (xy 216.478052 -218.565333) (xy 216.439315 -218.600967)
			(xy 216.417906 -218.616276) (xy 216.406476 -218.62415) (xy 216.395046 -218.648788) (xy 216.403682 -218.739466)
			(xy 216.405227 -218.749973) (xy 216.415589 -218.768483) (xy 216.423748 -218.77528) (xy 216.428574 -218.778836)
			(xy 216.463082 -218.794036) (xy 216.528217 -218.832028) (xy 216.58794 -218.878062) (xy 216.61501 -218.904312)
			(xy 217.749374 -220.038676) (xy 217.752856 -220.041961) (xy 217.760783 -220.047323) (xy 217.765122 -220.049344)
			(xy 217.774349 -220.052874) (xy 217.794081 -220.053411) (xy 217.803476 -220.05036) (xy 217.904314 -220.01226)
			(xy 217.92184 -219.98813) (xy 217.922856 -219.973144) (xy 217.925013 -219.945226) (xy 217.936472 -219.890417)
			(xy 217.955809 -219.837868) (xy 217.982609 -219.788705) (xy 218.016299 -219.74398) (xy 218.035886 -219.72397)
			(xy 218.03614 -219.723716) (xy 218.042383 -219.716854) (xy 218.049938 -219.699926) (xy 218.050872 -219.690696)
			(xy 218.05519 -219.612972) (xy 218.049348 -219.594938) (xy 218.043252 -219.587572) (xy 218.027129 -219.567082)
			(xy 218.000039 -219.522533) (xy 217.979268 -219.47471) (xy 217.965202 -219.424503) (xy 217.958105 -219.37285)
			(xy 217.957654 -219.34678) (xy 217.95814 -219.319529) (xy 217.965896 -219.265581) (xy 217.981251 -219.213286)
			(xy 218.003893 -219.163709) (xy 218.033359 -219.117859) (xy 218.06905 -219.076668) (xy 218.110241 -219.040977)
			(xy 218.156091 -219.011511) (xy 218.205668 -218.988869) (xy 218.257963 -218.973514) (xy 218.311911 -218.965758)
			(xy 218.366413 -218.965758) (xy 218.420361 -218.973514) (xy 218.472656 -218.988869) (xy 218.522233 -219.011511)
			(xy 218.568083 -219.040977) (xy 218.609274 -219.076668) (xy 218.644965 -219.117859) (xy 218.674431 -219.163709)
			(xy 218.697073 -219.213286) (xy 218.712428 -219.265581) (xy 218.720184 -219.319529) (xy 218.72067 -219.34678)
			(xy 218.720091 -219.377048) (xy 218.710531 -219.436824) (xy 218.691648 -219.494339) (xy 218.673273 -219.529993)
			(xy 225.137728 -219.529993) (xy 225.137728 -219.478019) (xy 225.145858 -219.426684) (xy 225.161919 -219.377254)
			(xy 225.185515 -219.330944) (xy 225.216065 -219.288896) (xy 225.252816 -219.252145) (xy 225.294864 -219.221595)
			(xy 225.341174 -219.197999) (xy 225.390604 -219.181938) (xy 225.441939 -219.173808) (xy 225.493913 -219.173808)
			(xy 225.545248 -219.181938) (xy 225.594678 -219.197999) (xy 225.640988 -219.221595) (xy 225.683036 -219.252145)
			(xy 225.719787 -219.288896) (xy 225.750337 -219.330944) (xy 225.773933 -219.377254) (xy 225.789994 -219.426684)
			(xy 225.798124 -219.478019) (xy 225.798634 -219.504006) (xy 225.798124 -219.529993) (xy 226.737674 -219.529993)
			(xy 226.737674 -219.478019) (xy 226.745804 -219.426684) (xy 226.761865 -219.377254) (xy 226.785461 -219.330944)
			(xy 226.816011 -219.288896) (xy 226.852762 -219.252145) (xy 226.89481 -219.221595) (xy 226.94112 -219.197999)
			(xy 226.99055 -219.181938) (xy 227.041885 -219.173808) (xy 227.093859 -219.173808) (xy 227.145194 -219.181938)
			(xy 227.194624 -219.197999) (xy 227.240934 -219.221595) (xy 227.282982 -219.252145) (xy 227.319733 -219.288896)
			(xy 227.350283 -219.330944) (xy 227.373879 -219.377254) (xy 227.38994 -219.426684) (xy 227.39807 -219.478019)
			(xy 227.39858 -219.504006) (xy 227.39807 -219.529993) (xy 227.537774 -219.529993) (xy 227.537774 -219.478019)
			(xy 227.545904 -219.426684) (xy 227.561965 -219.377254) (xy 227.585561 -219.330944) (xy 227.616111 -219.288896)
			(xy 227.652862 -219.252145) (xy 227.69491 -219.221595) (xy 227.74122 -219.197999) (xy 227.79065 -219.181938)
			(xy 227.841985 -219.173808) (xy 227.893959 -219.173808) (xy 227.945294 -219.181938) (xy 227.994724 -219.197999)
			(xy 228.041034 -219.221595) (xy 228.083082 -219.252145) (xy 228.119833 -219.288896) (xy 228.150383 -219.330944)
			(xy 228.173979 -219.377254) (xy 228.19004 -219.426684) (xy 228.19817 -219.478019) (xy 228.19868 -219.504006)
			(xy 228.19817 -219.529993) (xy 228.33762 -219.529993) (xy 228.33762 -219.478019) (xy 228.34575 -219.426684)
			(xy 228.361811 -219.377254) (xy 228.385407 -219.330944) (xy 228.415957 -219.288896) (xy 228.452708 -219.252145)
			(xy 228.494756 -219.221595) (xy 228.541066 -219.197999) (xy 228.590496 -219.181938) (xy 228.641831 -219.173808)
			(xy 228.693805 -219.173808) (xy 228.74514 -219.181938) (xy 228.79457 -219.197999) (xy 228.84088 -219.221595)
			(xy 228.882928 -219.252145) (xy 228.919679 -219.288896) (xy 228.950229 -219.330944) (xy 228.973825 -219.377254)
			(xy 228.989886 -219.426684) (xy 228.998016 -219.478019) (xy 228.998526 -219.504006) (xy 228.998016 -219.529993)
			(xy 229.937312 -219.529993) (xy 229.937312 -219.478019) (xy 229.945442 -219.426684) (xy 229.961503 -219.377254)
			(xy 229.985099 -219.330944) (xy 230.015649 -219.288896) (xy 230.0524 -219.252145) (xy 230.094448 -219.221595)
			(xy 230.140758 -219.197999) (xy 230.190188 -219.181938) (xy 230.241523 -219.173808) (xy 230.293497 -219.173808)
			(xy 230.344832 -219.181938) (xy 230.394262 -219.197999) (xy 230.440572 -219.221595) (xy 230.48262 -219.252145)
			(xy 230.519371 -219.288896) (xy 230.549921 -219.330944) (xy 230.573517 -219.377254) (xy 230.589578 -219.426684)
			(xy 230.597708 -219.478019) (xy 230.598218 -219.504006) (xy 230.597708 -219.529993) (xy 230.737158 -219.529993)
			(xy 230.737158 -219.478019) (xy 230.745288 -219.426684) (xy 230.761349 -219.377254) (xy 230.784945 -219.330944)
			(xy 230.815495 -219.288896) (xy 230.852246 -219.252145) (xy 230.894294 -219.221595) (xy 230.940604 -219.197999)
			(xy 230.990034 -219.181938) (xy 231.041369 -219.173808) (xy 231.093343 -219.173808) (xy 231.144678 -219.181938)
			(xy 231.194108 -219.197999) (xy 231.240418 -219.221595) (xy 231.282466 -219.252145) (xy 231.319217 -219.288896)
			(xy 231.349767 -219.330944) (xy 231.373363 -219.377254) (xy 231.389424 -219.426684) (xy 231.397554 -219.478019)
			(xy 231.398064 -219.504006) (xy 231.397554 -219.529993) (xy 231.537258 -219.529993) (xy 231.537258 -219.478019)
			(xy 231.545388 -219.426684) (xy 231.561449 -219.377254) (xy 231.585045 -219.330944) (xy 231.615595 -219.288896)
			(xy 231.652346 -219.252145) (xy 231.694394 -219.221595) (xy 231.740704 -219.197999) (xy 231.790134 -219.181938)
			(xy 231.841469 -219.173808) (xy 231.893443 -219.173808) (xy 231.944778 -219.181938) (xy 231.994208 -219.197999)
			(xy 232.040518 -219.221595) (xy 232.082566 -219.252145) (xy 232.119317 -219.288896) (xy 232.149867 -219.330944)
			(xy 232.173463 -219.377254) (xy 232.189524 -219.426684) (xy 232.197654 -219.478019) (xy 232.198164 -219.504006)
			(xy 232.197654 -219.529993) (xy 232.337358 -219.529993) (xy 232.337358 -219.478019) (xy 232.345488 -219.426684)
			(xy 232.361549 -219.377254) (xy 232.385145 -219.330944) (xy 232.415695 -219.288896) (xy 232.452446 -219.252145)
			(xy 232.494494 -219.221595) (xy 232.540804 -219.197999) (xy 232.590234 -219.181938) (xy 232.641569 -219.173808)
			(xy 232.693543 -219.173808) (xy 232.744878 -219.181938) (xy 232.794308 -219.197999) (xy 232.840618 -219.221595)
			(xy 232.882666 -219.252145) (xy 232.919417 -219.288896) (xy 232.949967 -219.330944) (xy 232.973563 -219.377254)
			(xy 232.989624 -219.426684) (xy 232.997754 -219.478019) (xy 232.998264 -219.504006) (xy 232.997754 -219.529993)
			(xy 233.137204 -219.529993) (xy 233.137204 -219.478019) (xy 233.145334 -219.426684) (xy 233.161395 -219.377254)
			(xy 233.184991 -219.330944) (xy 233.215541 -219.288896) (xy 233.252292 -219.252145) (xy 233.29434 -219.221595)
			(xy 233.34065 -219.197999) (xy 233.39008 -219.181938) (xy 233.441415 -219.173808) (xy 233.493389 -219.173808)
			(xy 233.544724 -219.181938) (xy 233.594154 -219.197999) (xy 233.640464 -219.221595) (xy 233.682512 -219.252145)
			(xy 233.719263 -219.288896) (xy 233.749813 -219.330944) (xy 233.773409 -219.377254) (xy 233.78947 -219.426684)
			(xy 233.7976 -219.478019) (xy 233.79811 -219.504006) (xy 233.7976 -219.529993) (xy 233.937304 -219.529993)
			(xy 233.937304 -219.478019) (xy 233.945434 -219.426684) (xy 233.961495 -219.377254) (xy 233.985091 -219.330944)
			(xy 234.015641 -219.288896) (xy 234.052392 -219.252145) (xy 234.09444 -219.221595) (xy 234.14075 -219.197999)
			(xy 234.19018 -219.181938) (xy 234.241515 -219.173808) (xy 234.293489 -219.173808) (xy 234.344824 -219.181938)
			(xy 234.394254 -219.197999) (xy 234.440564 -219.221595) (xy 234.482612 -219.252145) (xy 234.519363 -219.288896)
			(xy 234.549913 -219.330944) (xy 234.573509 -219.377254) (xy 234.58957 -219.426684) (xy 234.5977 -219.478019)
			(xy 234.59821 -219.504006) (xy 234.5977 -219.529993) (xy 234.73715 -219.529993) (xy 234.73715 -219.478019)
			(xy 234.74528 -219.426684) (xy 234.761341 -219.377254) (xy 234.784937 -219.330944) (xy 234.815487 -219.288896)
			(xy 234.852238 -219.252145) (xy 234.894286 -219.221595) (xy 234.940596 -219.197999) (xy 234.990026 -219.181938)
			(xy 235.041361 -219.173808) (xy 235.093335 -219.173808) (xy 235.14467 -219.181938) (xy 235.1941 -219.197999)
			(xy 235.24041 -219.221595) (xy 235.282458 -219.252145) (xy 235.319209 -219.288896) (xy 235.349759 -219.330944)
			(xy 235.373355 -219.377254) (xy 235.389416 -219.426684) (xy 235.397546 -219.478019) (xy 235.398056 -219.504006)
			(xy 235.397546 -219.529993) (xy 235.53725 -219.529993) (xy 235.53725 -219.478019) (xy 235.54538 -219.426684)
			(xy 235.561441 -219.377254) (xy 235.585037 -219.330944) (xy 235.615587 -219.288896) (xy 235.652338 -219.252145)
			(xy 235.694386 -219.221595) (xy 235.740696 -219.197999) (xy 235.790126 -219.181938) (xy 235.841461 -219.173808)
			(xy 235.893435 -219.173808) (xy 235.94477 -219.181938) (xy 235.9942 -219.197999) (xy 236.04051 -219.221595)
			(xy 236.082558 -219.252145) (xy 236.119309 -219.288896) (xy 236.149859 -219.330944) (xy 236.173455 -219.377254)
			(xy 236.189516 -219.426684) (xy 236.197646 -219.478019) (xy 236.198156 -219.504006) (xy 236.197646 -219.529993)
			(xy 236.189516 -219.581328) (xy 236.173455 -219.630758) (xy 236.149859 -219.677068) (xy 236.119309 -219.719116)
			(xy 236.082558 -219.755867) (xy 236.04051 -219.786417) (xy 235.9942 -219.810013) (xy 235.94477 -219.826074)
			(xy 235.893435 -219.834204) (xy 235.841461 -219.834204) (xy 235.790126 -219.826074) (xy 235.740696 -219.810013)
			(xy 235.694386 -219.786417) (xy 235.652338 -219.755867) (xy 235.615587 -219.719116) (xy 235.585037 -219.677068)
			(xy 235.561441 -219.630758) (xy 235.54538 -219.581328) (xy 235.53725 -219.529993) (xy 235.397546 -219.529993)
			(xy 235.389416 -219.581328) (xy 235.373355 -219.630758) (xy 235.349759 -219.677068) (xy 235.319209 -219.719116)
			(xy 235.282458 -219.755867) (xy 235.24041 -219.786417) (xy 235.1941 -219.810013) (xy 235.14467 -219.826074)
			(xy 235.093335 -219.834204) (xy 235.041361 -219.834204) (xy 234.990026 -219.826074) (xy 234.940596 -219.810013)
			(xy 234.894286 -219.786417) (xy 234.852238 -219.755867) (xy 234.815487 -219.719116) (xy 234.784937 -219.677068)
			(xy 234.761341 -219.630758) (xy 234.74528 -219.581328) (xy 234.73715 -219.529993) (xy 234.5977 -219.529993)
			(xy 234.58957 -219.581328) (xy 234.573509 -219.630758) (xy 234.549913 -219.677068) (xy 234.519363 -219.719116)
			(xy 234.482612 -219.755867) (xy 234.440564 -219.786417) (xy 234.394254 -219.810013) (xy 234.344824 -219.826074)
			(xy 234.293489 -219.834204) (xy 234.241515 -219.834204) (xy 234.19018 -219.826074) (xy 234.14075 -219.810013)
			(xy 234.09444 -219.786417) (xy 234.052392 -219.755867) (xy 234.015641 -219.719116) (xy 233.985091 -219.677068)
			(xy 233.961495 -219.630758) (xy 233.945434 -219.581328) (xy 233.937304 -219.529993) (xy 233.7976 -219.529993)
			(xy 233.78947 -219.581328) (xy 233.773409 -219.630758) (xy 233.749813 -219.677068) (xy 233.719263 -219.719116)
			(xy 233.682512 -219.755867) (xy 233.640464 -219.786417) (xy 233.594154 -219.810013) (xy 233.544724 -219.826074)
			(xy 233.493389 -219.834204) (xy 233.441415 -219.834204) (xy 233.39008 -219.826074) (xy 233.34065 -219.810013)
			(xy 233.29434 -219.786417) (xy 233.252292 -219.755867) (xy 233.215541 -219.719116) (xy 233.184991 -219.677068)
			(xy 233.161395 -219.630758) (xy 233.145334 -219.581328) (xy 233.137204 -219.529993) (xy 232.997754 -219.529993)
			(xy 232.989624 -219.581328) (xy 232.973563 -219.630758) (xy 232.949967 -219.677068) (xy 232.919417 -219.719116)
			(xy 232.882666 -219.755867) (xy 232.840618 -219.786417) (xy 232.794308 -219.810013) (xy 232.744878 -219.826074)
			(xy 232.693543 -219.834204) (xy 232.641569 -219.834204) (xy 232.590234 -219.826074) (xy 232.540804 -219.810013)
			(xy 232.494494 -219.786417) (xy 232.452446 -219.755867) (xy 232.415695 -219.719116) (xy 232.385145 -219.677068)
			(xy 232.361549 -219.630758) (xy 232.345488 -219.581328) (xy 232.337358 -219.529993) (xy 232.197654 -219.529993)
			(xy 232.189524 -219.581328) (xy 232.173463 -219.630758) (xy 232.149867 -219.677068) (xy 232.119317 -219.719116)
			(xy 232.082566 -219.755867) (xy 232.040518 -219.786417) (xy 231.994208 -219.810013) (xy 231.944778 -219.826074)
			(xy 231.893443 -219.834204) (xy 231.841469 -219.834204) (xy 231.790134 -219.826074) (xy 231.740704 -219.810013)
			(xy 231.694394 -219.786417) (xy 231.652346 -219.755867) (xy 231.615595 -219.719116) (xy 231.585045 -219.677068)
			(xy 231.561449 -219.630758) (xy 231.545388 -219.581328) (xy 231.537258 -219.529993) (xy 231.397554 -219.529993)
			(xy 231.389424 -219.581328) (xy 231.373363 -219.630758) (xy 231.349767 -219.677068) (xy 231.319217 -219.719116)
			(xy 231.282466 -219.755867) (xy 231.240418 -219.786417) (xy 231.194108 -219.810013) (xy 231.144678 -219.826074)
			(xy 231.093343 -219.834204) (xy 231.041369 -219.834204) (xy 230.990034 -219.826074) (xy 230.940604 -219.810013)
			(xy 230.894294 -219.786417) (xy 230.852246 -219.755867) (xy 230.815495 -219.719116) (xy 230.784945 -219.677068)
			(xy 230.761349 -219.630758) (xy 230.745288 -219.581328) (xy 230.737158 -219.529993) (xy 230.597708 -219.529993)
			(xy 230.589578 -219.581328) (xy 230.573517 -219.630758) (xy 230.549921 -219.677068) (xy 230.519371 -219.719116)
			(xy 230.48262 -219.755867) (xy 230.440572 -219.786417) (xy 230.394262 -219.810013) (xy 230.344832 -219.826074)
			(xy 230.293497 -219.834204) (xy 230.241523 -219.834204) (xy 230.190188 -219.826074) (xy 230.140758 -219.810013)
			(xy 230.094448 -219.786417) (xy 230.0524 -219.755867) (xy 230.015649 -219.719116) (xy 229.985099 -219.677068)
			(xy 229.961503 -219.630758) (xy 229.945442 -219.581328) (xy 229.937312 -219.529993) (xy 228.998016 -219.529993)
			(xy 228.989886 -219.581328) (xy 228.973825 -219.630758) (xy 228.950229 -219.677068) (xy 228.919679 -219.719116)
			(xy 228.882928 -219.755867) (xy 228.84088 -219.786417) (xy 228.79457 -219.810013) (xy 228.74514 -219.826074)
			(xy 228.693805 -219.834204) (xy 228.641831 -219.834204) (xy 228.590496 -219.826074) (xy 228.541066 -219.810013)
			(xy 228.494756 -219.786417) (xy 228.452708 -219.755867) (xy 228.415957 -219.719116) (xy 228.385407 -219.677068)
			(xy 228.361811 -219.630758) (xy 228.34575 -219.581328) (xy 228.33762 -219.529993) (xy 228.19817 -219.529993)
			(xy 228.19004 -219.581328) (xy 228.173979 -219.630758) (xy 228.150383 -219.677068) (xy 228.119833 -219.719116)
			(xy 228.083082 -219.755867) (xy 228.041034 -219.786417) (xy 227.994724 -219.810013) (xy 227.945294 -219.826074)
			(xy 227.893959 -219.834204) (xy 227.841985 -219.834204) (xy 227.79065 -219.826074) (xy 227.74122 -219.810013)
			(xy 227.69491 -219.786417) (xy 227.652862 -219.755867) (xy 227.616111 -219.719116) (xy 227.585561 -219.677068)
			(xy 227.561965 -219.630758) (xy 227.545904 -219.581328) (xy 227.537774 -219.529993) (xy 227.39807 -219.529993)
			(xy 227.38994 -219.581328) (xy 227.373879 -219.630758) (xy 227.350283 -219.677068) (xy 227.319733 -219.719116)
			(xy 227.282982 -219.755867) (xy 227.240934 -219.786417) (xy 227.194624 -219.810013) (xy 227.145194 -219.826074)
			(xy 227.093859 -219.834204) (xy 227.041885 -219.834204) (xy 226.99055 -219.826074) (xy 226.94112 -219.810013)
			(xy 226.89481 -219.786417) (xy 226.852762 -219.755867) (xy 226.816011 -219.719116) (xy 226.785461 -219.677068)
			(xy 226.761865 -219.630758) (xy 226.745804 -219.581328) (xy 226.737674 -219.529993) (xy 225.798124 -219.529993)
			(xy 225.789994 -219.581328) (xy 225.773933 -219.630758) (xy 225.750337 -219.677068) (xy 225.719787 -219.719116)
			(xy 225.683036 -219.755867) (xy 225.640988 -219.786417) (xy 225.594678 -219.810013) (xy 225.545248 -219.826074)
			(xy 225.493913 -219.834204) (xy 225.441939 -219.834204) (xy 225.390604 -219.826074) (xy 225.341174 -219.810013)
			(xy 225.294864 -219.786417) (xy 225.252816 -219.755867) (xy 225.216065 -219.719116) (xy 225.185515 -219.677068)
			(xy 225.161919 -219.630758) (xy 225.145858 -219.581328) (xy 225.137728 -219.529993) (xy 218.673273 -219.529993)
			(xy 218.663916 -219.548149) (xy 218.628031 -219.596902) (xy 218.606878 -219.61856) (xy 218.606624 -219.618814)
			(xy 218.600389 -219.625679) (xy 218.592849 -219.642608) (xy 218.591892 -219.651834) (xy 218.587574 -219.729558)
			(xy 218.593416 -219.747592) (xy 218.599512 -219.754958) (xy 218.61562 -219.77546) (xy 218.642712 -219.820006)
			(xy 218.663488 -219.867826) (xy 218.677559 -219.918029) (xy 218.684664 -219.969681) (xy 218.68511 -219.99575)
			(xy 218.684584 -220.024595) (xy 218.675901 -220.081626) (xy 218.658726 -220.1367) (xy 218.633452 -220.188557)
			(xy 218.600653 -220.236016) (xy 218.56108 -220.277992) (xy 218.515636 -220.313528) (xy 218.486642 -220.329839)
			(xy 223.537782 -220.329839) (xy 223.537782 -220.277865) (xy 223.545912 -220.22653) (xy 223.561973 -220.1771)
			(xy 223.585569 -220.13079) (xy 223.616119 -220.088742) (xy 223.65287 -220.051991) (xy 223.694918 -220.021441)
			(xy 223.741228 -219.997845) (xy 223.790658 -219.981784) (xy 223.841993 -219.973654) (xy 223.893967 -219.973654)
			(xy 223.945302 -219.981784) (xy 223.994732 -219.997845) (xy 224.041042 -220.021441) (xy 224.08309 -220.051991)
			(xy 224.119841 -220.088742) (xy 224.150391 -220.13079) (xy 224.173987 -220.1771) (xy 224.190048 -220.22653)
			(xy 224.198178 -220.277865) (xy 224.198688 -220.303852) (xy 224.198178 -220.329839) (xy 224.337628 -220.329839)
			(xy 224.337628 -220.277865) (xy 224.345758 -220.22653) (xy 224.361819 -220.1771) (xy 224.385415 -220.13079)
			(xy 224.415965 -220.088742) (xy 224.452716 -220.051991) (xy 224.494764 -220.021441) (xy 224.541074 -219.997845)
			(xy 224.590504 -219.981784) (xy 224.641839 -219.973654) (xy 224.693813 -219.973654) (xy 224.745148 -219.981784)
			(xy 224.794578 -219.997845) (xy 224.840888 -220.021441) (xy 224.882936 -220.051991) (xy 224.919687 -220.088742)
			(xy 224.950237 -220.13079) (xy 224.973833 -220.1771) (xy 224.989894 -220.22653) (xy 224.998024 -220.277865)
			(xy 224.998534 -220.303852) (xy 224.998024 -220.329839) (xy 225.137728 -220.329839) (xy 225.137728 -220.277865)
			(xy 225.145858 -220.22653) (xy 225.161919 -220.1771) (xy 225.185515 -220.13079) (xy 225.216065 -220.088742)
			(xy 225.252816 -220.051991) (xy 225.294864 -220.021441) (xy 225.341174 -219.997845) (xy 225.390604 -219.981784)
			(xy 225.441939 -219.973654) (xy 225.493913 -219.973654) (xy 225.545248 -219.981784) (xy 225.594678 -219.997845)
			(xy 225.640988 -220.021441) (xy 225.683036 -220.051991) (xy 225.719787 -220.088742) (xy 225.750337 -220.13079)
			(xy 225.773933 -220.1771) (xy 225.789994 -220.22653) (xy 225.798124 -220.277865) (xy 225.798634 -220.303852)
			(xy 225.798124 -220.329839) (xy 226.737674 -220.329839) (xy 226.737674 -220.277865) (xy 226.745804 -220.22653)
			(xy 226.761865 -220.1771) (xy 226.785461 -220.13079) (xy 226.816011 -220.088742) (xy 226.852762 -220.051991)
			(xy 226.89481 -220.021441) (xy 226.94112 -219.997845) (xy 226.99055 -219.981784) (xy 227.041885 -219.973654)
			(xy 227.093859 -219.973654) (xy 227.145194 -219.981784) (xy 227.194624 -219.997845) (xy 227.240934 -220.021441)
			(xy 227.282982 -220.051991) (xy 227.319733 -220.088742) (xy 227.350283 -220.13079) (xy 227.373879 -220.1771)
			(xy 227.38994 -220.22653) (xy 227.39807 -220.277865) (xy 227.39858 -220.303852) (xy 227.39807 -220.329839)
			(xy 227.537774 -220.329839) (xy 227.537774 -220.277865) (xy 227.545904 -220.22653) (xy 227.561965 -220.1771)
			(xy 227.585561 -220.13079) (xy 227.616111 -220.088742) (xy 227.652862 -220.051991) (xy 227.69491 -220.021441)
			(xy 227.74122 -219.997845) (xy 227.79065 -219.981784) (xy 227.841985 -219.973654) (xy 227.893959 -219.973654)
			(xy 227.945294 -219.981784) (xy 227.994724 -219.997845) (xy 228.041034 -220.021441) (xy 228.083082 -220.051991)
			(xy 228.119833 -220.088742) (xy 228.150383 -220.13079) (xy 228.173979 -220.1771) (xy 228.19004 -220.22653)
			(xy 228.19817 -220.277865) (xy 228.19868 -220.303852) (xy 228.19817 -220.329839) (xy 228.33762 -220.329839)
			(xy 228.33762 -220.277865) (xy 228.34575 -220.22653) (xy 228.361811 -220.1771) (xy 228.385407 -220.13079)
			(xy 228.415957 -220.088742) (xy 228.452708 -220.051991) (xy 228.494756 -220.021441) (xy 228.541066 -219.997845)
			(xy 228.590496 -219.981784) (xy 228.641831 -219.973654) (xy 228.693805 -219.973654) (xy 228.74514 -219.981784)
			(xy 228.79457 -219.997845) (xy 228.84088 -220.021441) (xy 228.882928 -220.051991) (xy 228.919679 -220.088742)
			(xy 228.950229 -220.13079) (xy 228.973825 -220.1771) (xy 228.989886 -220.22653) (xy 228.998016 -220.277865)
			(xy 228.998526 -220.303852) (xy 228.998016 -220.329839) (xy 229.937312 -220.329839) (xy 229.937312 -220.277865)
			(xy 229.945442 -220.22653) (xy 229.961503 -220.1771) (xy 229.985099 -220.13079) (xy 230.015649 -220.088742)
			(xy 230.0524 -220.051991) (xy 230.094448 -220.021441) (xy 230.140758 -219.997845) (xy 230.190188 -219.981784)
			(xy 230.241523 -219.973654) (xy 230.293497 -219.973654) (xy 230.344832 -219.981784) (xy 230.394262 -219.997845)
			(xy 230.440572 -220.021441) (xy 230.48262 -220.051991) (xy 230.519371 -220.088742) (xy 230.549921 -220.13079)
			(xy 230.573517 -220.1771) (xy 230.589578 -220.22653) (xy 230.597708 -220.277865) (xy 230.598218 -220.303852)
			(xy 230.597708 -220.329839) (xy 230.737158 -220.329839) (xy 230.737158 -220.277865) (xy 230.745288 -220.22653)
			(xy 230.761349 -220.1771) (xy 230.784945 -220.13079) (xy 230.815495 -220.088742) (xy 230.852246 -220.051991)
			(xy 230.894294 -220.021441) (xy 230.940604 -219.997845) (xy 230.990034 -219.981784) (xy 231.041369 -219.973654)
			(xy 231.093343 -219.973654) (xy 231.144678 -219.981784) (xy 231.194108 -219.997845) (xy 231.240418 -220.021441)
			(xy 231.282466 -220.051991) (xy 231.319217 -220.088742) (xy 231.349767 -220.13079) (xy 231.373363 -220.1771)
			(xy 231.389424 -220.22653) (xy 231.397554 -220.277865) (xy 231.398064 -220.303852) (xy 231.397554 -220.329839)
			(xy 231.537258 -220.329839) (xy 231.537258 -220.277865) (xy 231.545388 -220.22653) (xy 231.561449 -220.1771)
			(xy 231.585045 -220.13079) (xy 231.615595 -220.088742) (xy 231.652346 -220.051991) (xy 231.694394 -220.021441)
			(xy 231.740704 -219.997845) (xy 231.790134 -219.981784) (xy 231.841469 -219.973654) (xy 231.893443 -219.973654)
			(xy 231.944778 -219.981784) (xy 231.994208 -219.997845) (xy 232.040518 -220.021441) (xy 232.082566 -220.051991)
			(xy 232.119317 -220.088742) (xy 232.149867 -220.13079) (xy 232.173463 -220.1771) (xy 232.189524 -220.22653)
			(xy 232.197654 -220.277865) (xy 232.198164 -220.303852) (xy 232.197654 -220.329839) (xy 232.337358 -220.329839)
			(xy 232.337358 -220.277865) (xy 232.345488 -220.22653) (xy 232.361549 -220.1771) (xy 232.385145 -220.13079)
			(xy 232.415695 -220.088742) (xy 232.452446 -220.051991) (xy 232.494494 -220.021441) (xy 232.540804 -219.997845)
			(xy 232.590234 -219.981784) (xy 232.641569 -219.973654) (xy 232.693543 -219.973654) (xy 232.744878 -219.981784)
			(xy 232.794308 -219.997845) (xy 232.840618 -220.021441) (xy 232.882666 -220.051991) (xy 232.919417 -220.088742)
			(xy 232.949967 -220.13079) (xy 232.973563 -220.1771) (xy 232.989624 -220.22653) (xy 232.997754 -220.277865)
			(xy 232.998264 -220.303852) (xy 232.997754 -220.329839) (xy 233.137204 -220.329839) (xy 233.137204 -220.277865)
			(xy 233.145334 -220.22653) (xy 233.161395 -220.1771) (xy 233.184991 -220.13079) (xy 233.215541 -220.088742)
			(xy 233.252292 -220.051991) (xy 233.29434 -220.021441) (xy 233.34065 -219.997845) (xy 233.39008 -219.981784)
			(xy 233.441415 -219.973654) (xy 233.493389 -219.973654) (xy 233.544724 -219.981784) (xy 233.594154 -219.997845)
			(xy 233.640464 -220.021441) (xy 233.682512 -220.051991) (xy 233.719263 -220.088742) (xy 233.749813 -220.13079)
			(xy 233.773409 -220.1771) (xy 233.78947 -220.22653) (xy 233.7976 -220.277865) (xy 233.79811 -220.303852)
			(xy 233.7976 -220.329839) (xy 233.937304 -220.329839) (xy 233.937304 -220.277865) (xy 233.945434 -220.22653)
			(xy 233.961495 -220.1771) (xy 233.985091 -220.13079) (xy 234.015641 -220.088742) (xy 234.052392 -220.051991)
			(xy 234.09444 -220.021441) (xy 234.14075 -219.997845) (xy 234.19018 -219.981784) (xy 234.241515 -219.973654)
			(xy 234.293489 -219.973654) (xy 234.344824 -219.981784) (xy 234.394254 -219.997845) (xy 234.440564 -220.021441)
			(xy 234.482612 -220.051991) (xy 234.519363 -220.088742) (xy 234.549913 -220.13079) (xy 234.573509 -220.1771)
			(xy 234.58957 -220.22653) (xy 234.5977 -220.277865) (xy 234.59821 -220.303852) (xy 234.5977 -220.329839)
			(xy 234.73715 -220.329839) (xy 234.73715 -220.277865) (xy 234.74528 -220.22653) (xy 234.761341 -220.1771)
			(xy 234.784937 -220.13079) (xy 234.815487 -220.088742) (xy 234.852238 -220.051991) (xy 234.894286 -220.021441)
			(xy 234.940596 -219.997845) (xy 234.990026 -219.981784) (xy 235.041361 -219.973654) (xy 235.093335 -219.973654)
			(xy 235.14467 -219.981784) (xy 235.1941 -219.997845) (xy 235.24041 -220.021441) (xy 235.245253 -220.02496)
			(xy 240.991896 -220.02496) (xy 240.995967 -219.969338) (xy 241.008093 -219.914901) (xy 241.028016 -219.86281)
			(xy 241.055312 -219.814175) (xy 241.089398 -219.770032) (xy 241.129547 -219.731323) (xy 241.174905 -219.698872)
			(xy 241.224505 -219.673371) (xy 241.277289 -219.655364) (xy 241.332132 -219.645234) (xy 241.387866 -219.643197)
			(xy 241.443303 -219.649297) (xy 241.482155 -219.659454) (xy 245.44985 -219.659454) (xy 245.453921 -219.603832)
			(xy 245.466047 -219.549395) (xy 245.48597 -219.497304) (xy 245.513266 -219.448669) (xy 245.547352 -219.404526)
			(xy 245.587501 -219.365817) (xy 245.632859 -219.333366) (xy 245.682459 -219.307865) (xy 245.735243 -219.289858)
			(xy 245.790086 -219.279728) (xy 245.84582 -219.277691) (xy 245.901257 -219.283791) (xy 245.955214 -219.297897)
			(xy 246.006543 -219.319709) (xy 246.054149 -219.348763) (xy 246.097017 -219.384438) (xy 246.134234 -219.425975)
			(xy 246.165007 -219.472488) (xy 246.188679 -219.522985) (xy 246.204747 -219.576392) (xy 246.212867 -219.631568)
			(xy 246.213376 -219.659454) (xy 246.212867 -219.68734) (xy 246.204747 -219.742516) (xy 246.188679 -219.795923)
			(xy 246.165007 -219.84642) (xy 246.134234 -219.892933) (xy 246.097017 -219.93447) (xy 246.054149 -219.970145)
			(xy 246.006543 -219.999199) (xy 245.955214 -220.021011) (xy 245.901257 -220.035117) (xy 245.84582 -220.041217)
			(xy 245.790086 -220.03918) (xy 245.735243 -220.02905) (xy 245.682459 -220.011043) (xy 245.632859 -219.985542)
			(xy 245.587501 -219.953091) (xy 245.547352 -219.914382) (xy 245.513266 -219.870239) (xy 245.48597 -219.821604)
			(xy 245.466047 -219.769513) (xy 245.453921 -219.715076) (xy 245.44985 -219.659454) (xy 241.482155 -219.659454)
			(xy 241.49726 -219.663403) (xy 241.548589 -219.685215) (xy 241.596195 -219.714269) (xy 241.639063 -219.749944)
			(xy 241.67628 -219.791481) (xy 241.707053 -219.837994) (xy 241.730725 -219.888491) (xy 241.746793 -219.941898)
			(xy 241.754913 -219.997074) (xy 241.755422 -220.02496) (xy 241.754913 -220.052846) (xy 241.746793 -220.108022)
			(xy 241.730725 -220.161429) (xy 241.722066 -220.1799) (xy 242.275104 -220.1799) (xy 242.279175 -220.124278)
			(xy 242.291301 -220.069841) (xy 242.311224 -220.01775) (xy 242.33852 -219.969115) (xy 242.372606 -219.924972)
			(xy 242.412755 -219.886263) (xy 242.458113 -219.853812) (xy 242.507713 -219.828311) (xy 242.560497 -219.810304)
			(xy 242.61534 -219.800174) (xy 242.671074 -219.798137) (xy 242.726511 -219.804237) (xy 242.780468 -219.818343)
			(xy 242.831797 -219.840155) (xy 242.879403 -219.869209) (xy 242.922271 -219.904884) (xy 242.959488 -219.946421)
			(xy 242.990261 -219.992934) (xy 243.013933 -220.043431) (xy 243.030001 -220.096838) (xy 243.038121 -220.152014)
			(xy 243.03863 -220.1799) (xy 243.038121 -220.207786) (xy 243.030001 -220.262962) (xy 243.013933 -220.316369)
			(xy 242.990261 -220.366866) (xy 242.959488 -220.413379) (xy 242.922271 -220.454916) (xy 242.879403 -220.490591)
			(xy 242.831797 -220.519645) (xy 242.780468 -220.541457) (xy 242.726511 -220.555563) (xy 242.671074 -220.561663)
			(xy 242.61534 -220.559626) (xy 242.560497 -220.549496) (xy 242.507713 -220.531489) (xy 242.458113 -220.505988)
			(xy 242.412755 -220.473537) (xy 242.372606 -220.434828) (xy 242.33852 -220.390685) (xy 242.311224 -220.34205)
			(xy 242.291301 -220.289959) (xy 242.279175 -220.235522) (xy 242.275104 -220.1799) (xy 241.722066 -220.1799)
			(xy 241.707053 -220.211926) (xy 241.67628 -220.258439) (xy 241.639063 -220.299976) (xy 241.596195 -220.335651)
			(xy 241.548589 -220.364705) (xy 241.49726 -220.386517) (xy 241.443303 -220.400623) (xy 241.387866 -220.406723)
			(xy 241.332132 -220.404686) (xy 241.277289 -220.394556) (xy 241.224505 -220.376549) (xy 241.174905 -220.351048)
			(xy 241.129547 -220.318597) (xy 241.089398 -220.279888) (xy 241.055312 -220.235745) (xy 241.028016 -220.18711)
			(xy 241.008093 -220.135019) (xy 240.995967 -220.080582) (xy 240.991896 -220.02496) (xy 235.245253 -220.02496)
			(xy 235.282458 -220.051991) (xy 235.319209 -220.088742) (xy 235.349759 -220.13079) (xy 235.373355 -220.1771)
			(xy 235.389416 -220.22653) (xy 235.397546 -220.277865) (xy 235.398056 -220.303852) (xy 235.397546 -220.329839)
			(xy 235.389416 -220.381174) (xy 235.373355 -220.430604) (xy 235.349759 -220.476914) (xy 235.319209 -220.518962)
			(xy 235.282458 -220.555713) (xy 235.24041 -220.586263) (xy 235.1941 -220.609859) (xy 235.14467 -220.62592)
			(xy 235.093335 -220.63405) (xy 235.041361 -220.63405) (xy 234.990026 -220.62592) (xy 234.940596 -220.609859)
			(xy 234.894286 -220.586263) (xy 234.852238 -220.555713) (xy 234.815487 -220.518962) (xy 234.784937 -220.476914)
			(xy 234.761341 -220.430604) (xy 234.74528 -220.381174) (xy 234.73715 -220.329839) (xy 234.5977 -220.329839)
			(xy 234.58957 -220.381174) (xy 234.573509 -220.430604) (xy 234.549913 -220.476914) (xy 234.519363 -220.518962)
			(xy 234.482612 -220.555713) (xy 234.440564 -220.586263) (xy 234.394254 -220.609859) (xy 234.344824 -220.62592)
			(xy 234.293489 -220.63405) (xy 234.241515 -220.63405) (xy 234.19018 -220.62592) (xy 234.14075 -220.609859)
			(xy 234.09444 -220.586263) (xy 234.052392 -220.555713) (xy 234.015641 -220.518962) (xy 233.985091 -220.476914)
			(xy 233.961495 -220.430604) (xy 233.945434 -220.381174) (xy 233.937304 -220.329839) (xy 233.7976 -220.329839)
			(xy 233.78947 -220.381174) (xy 233.773409 -220.430604) (xy 233.749813 -220.476914) (xy 233.719263 -220.518962)
			(xy 233.682512 -220.555713) (xy 233.640464 -220.586263) (xy 233.594154 -220.609859) (xy 233.544724 -220.62592)
			(xy 233.493389 -220.63405) (xy 233.441415 -220.63405) (xy 233.39008 -220.62592) (xy 233.34065 -220.609859)
			(xy 233.29434 -220.586263) (xy 233.252292 -220.555713) (xy 233.215541 -220.518962) (xy 233.184991 -220.476914)
			(xy 233.161395 -220.430604) (xy 233.145334 -220.381174) (xy 233.137204 -220.329839) (xy 232.997754 -220.329839)
			(xy 232.989624 -220.381174) (xy 232.973563 -220.430604) (xy 232.949967 -220.476914) (xy 232.919417 -220.518962)
			(xy 232.882666 -220.555713) (xy 232.840618 -220.586263) (xy 232.794308 -220.609859) (xy 232.744878 -220.62592)
			(xy 232.693543 -220.63405) (xy 232.641569 -220.63405) (xy 232.590234 -220.62592) (xy 232.540804 -220.609859)
			(xy 232.494494 -220.586263) (xy 232.452446 -220.555713) (xy 232.415695 -220.518962) (xy 232.385145 -220.476914)
			(xy 232.361549 -220.430604) (xy 232.345488 -220.381174) (xy 232.337358 -220.329839) (xy 232.197654 -220.329839)
			(xy 232.189524 -220.381174) (xy 232.173463 -220.430604) (xy 232.149867 -220.476914) (xy 232.119317 -220.518962)
			(xy 232.082566 -220.555713) (xy 232.040518 -220.586263) (xy 231.994208 -220.609859) (xy 231.944778 -220.62592)
			(xy 231.893443 -220.63405) (xy 231.841469 -220.63405) (xy 231.790134 -220.62592) (xy 231.740704 -220.609859)
			(xy 231.694394 -220.586263) (xy 231.652346 -220.555713) (xy 231.615595 -220.518962) (xy 231.585045 -220.476914)
			(xy 231.561449 -220.430604) (xy 231.545388 -220.381174) (xy 231.537258 -220.329839) (xy 231.397554 -220.329839)
			(xy 231.389424 -220.381174) (xy 231.373363 -220.430604) (xy 231.349767 -220.476914) (xy 231.319217 -220.518962)
			(xy 231.282466 -220.555713) (xy 231.240418 -220.586263) (xy 231.194108 -220.609859) (xy 231.144678 -220.62592)
			(xy 231.093343 -220.63405) (xy 231.041369 -220.63405) (xy 230.990034 -220.62592) (xy 230.940604 -220.609859)
			(xy 230.894294 -220.586263) (xy 230.852246 -220.555713) (xy 230.815495 -220.518962) (xy 230.784945 -220.476914)
			(xy 230.761349 -220.430604) (xy 230.745288 -220.381174) (xy 230.737158 -220.329839) (xy 230.597708 -220.329839)
			(xy 230.589578 -220.381174) (xy 230.573517 -220.430604) (xy 230.549921 -220.476914) (xy 230.519371 -220.518962)
			(xy 230.48262 -220.555713) (xy 230.440572 -220.586263) (xy 230.394262 -220.609859) (xy 230.344832 -220.62592)
			(xy 230.293497 -220.63405) (xy 230.241523 -220.63405) (xy 230.190188 -220.62592) (xy 230.140758 -220.609859)
			(xy 230.094448 -220.586263) (xy 230.0524 -220.555713) (xy 230.015649 -220.518962) (xy 229.985099 -220.476914)
			(xy 229.961503 -220.430604) (xy 229.945442 -220.381174) (xy 229.937312 -220.329839) (xy 228.998016 -220.329839)
			(xy 228.989886 -220.381174) (xy 228.973825 -220.430604) (xy 228.950229 -220.476914) (xy 228.919679 -220.518962)
			(xy 228.882928 -220.555713) (xy 228.84088 -220.586263) (xy 228.79457 -220.609859) (xy 228.74514 -220.62592)
			(xy 228.693805 -220.63405) (xy 228.641831 -220.63405) (xy 228.590496 -220.62592) (xy 228.541066 -220.609859)
			(xy 228.494756 -220.586263) (xy 228.452708 -220.555713) (xy 228.415957 -220.518962) (xy 228.385407 -220.476914)
			(xy 228.361811 -220.430604) (xy 228.34575 -220.381174) (xy 228.33762 -220.329839) (xy 228.19817 -220.329839)
			(xy 228.19004 -220.381174) (xy 228.173979 -220.430604) (xy 228.150383 -220.476914) (xy 228.119833 -220.518962)
			(xy 228.083082 -220.555713) (xy 228.041034 -220.586263) (xy 227.994724 -220.609859) (xy 227.945294 -220.62592)
			(xy 227.893959 -220.63405) (xy 227.841985 -220.63405) (xy 227.79065 -220.62592) (xy 227.74122 -220.609859)
			(xy 227.69491 -220.586263) (xy 227.652862 -220.555713) (xy 227.616111 -220.518962) (xy 227.585561 -220.476914)
			(xy 227.561965 -220.430604) (xy 227.545904 -220.381174) (xy 227.537774 -220.329839) (xy 227.39807 -220.329839)
			(xy 227.38994 -220.381174) (xy 227.373879 -220.430604) (xy 227.350283 -220.476914) (xy 227.319733 -220.518962)
			(xy 227.282982 -220.555713) (xy 227.240934 -220.586263) (xy 227.194624 -220.609859) (xy 227.145194 -220.62592)
			(xy 227.093859 -220.63405) (xy 227.041885 -220.63405) (xy 226.99055 -220.62592) (xy 226.94112 -220.609859)
			(xy 226.89481 -220.586263) (xy 226.852762 -220.555713) (xy 226.816011 -220.518962) (xy 226.785461 -220.476914)
			(xy 226.761865 -220.430604) (xy 226.745804 -220.381174) (xy 226.737674 -220.329839) (xy 225.798124 -220.329839)
			(xy 225.789994 -220.381174) (xy 225.773933 -220.430604) (xy 225.750337 -220.476914) (xy 225.719787 -220.518962)
			(xy 225.683036 -220.555713) (xy 225.640988 -220.586263) (xy 225.594678 -220.609859) (xy 225.545248 -220.62592)
			(xy 225.493913 -220.63405) (xy 225.441939 -220.63405) (xy 225.390604 -220.62592) (xy 225.341174 -220.609859)
			(xy 225.294864 -220.586263) (xy 225.252816 -220.555713) (xy 225.216065 -220.518962) (xy 225.185515 -220.476914)
			(xy 225.161919 -220.430604) (xy 225.145858 -220.381174) (xy 225.137728 -220.329839) (xy 224.998024 -220.329839)
			(xy 224.989894 -220.381174) (xy 224.973833 -220.430604) (xy 224.950237 -220.476914) (xy 224.919687 -220.518962)
			(xy 224.882936 -220.555713) (xy 224.840888 -220.586263) (xy 224.794578 -220.609859) (xy 224.745148 -220.62592)
			(xy 224.693813 -220.63405) (xy 224.641839 -220.63405) (xy 224.590504 -220.62592) (xy 224.541074 -220.609859)
			(xy 224.494764 -220.586263) (xy 224.452716 -220.555713) (xy 224.415965 -220.518962) (xy 224.385415 -220.476914)
			(xy 224.361819 -220.430604) (xy 224.345758 -220.381174) (xy 224.337628 -220.329839) (xy 224.198178 -220.329839)
			(xy 224.190048 -220.381174) (xy 224.173987 -220.430604) (xy 224.150391 -220.476914) (xy 224.119841 -220.518962)
			(xy 224.08309 -220.555713) (xy 224.041042 -220.586263) (xy 223.994732 -220.609859) (xy 223.945302 -220.62592)
			(xy 223.893967 -220.63405) (xy 223.841993 -220.63405) (xy 223.790658 -220.62592) (xy 223.741228 -220.609859)
			(xy 223.694918 -220.586263) (xy 223.65287 -220.555713) (xy 223.616119 -220.518962) (xy 223.585569 -220.476914)
			(xy 223.561973 -220.430604) (xy 223.545912 -220.381174) (xy 223.537782 -220.329839) (xy 218.486642 -220.329839)
			(xy 218.465357 -220.341813) (xy 218.41139 -220.362201) (xy 218.354969 -220.374227) (xy 218.326208 -220.376496)
			(xy 218.311222 -220.377512) (xy 218.287092 -220.395038) (xy 218.248992 -220.495876) (xy 218.245932 -220.505195)
			(xy 218.246315 -220.52479) (xy 218.249754 -220.533976) (xy 218.253818 -220.54312) (xy 218.840637 -221.129939)
			(xy 223.537782 -221.129939) (xy 223.537782 -221.077965) (xy 223.545912 -221.02663) (xy 223.561973 -220.9772)
			(xy 223.585569 -220.93089) (xy 223.616119 -220.888842) (xy 223.65287 -220.852091) (xy 223.694918 -220.821541)
			(xy 223.741228 -220.797945) (xy 223.790658 -220.781884) (xy 223.841993 -220.773754) (xy 223.893967 -220.773754)
			(xy 223.945302 -220.781884) (xy 223.994732 -220.797945) (xy 224.041042 -220.821541) (xy 224.08309 -220.852091)
			(xy 224.119841 -220.888842) (xy 224.150391 -220.93089) (xy 224.173987 -220.9772) (xy 224.190048 -221.02663)
			(xy 224.198178 -221.077965) (xy 224.198688 -221.103952) (xy 224.198178 -221.129939) (xy 224.337628 -221.129939)
			(xy 224.337628 -221.077965) (xy 224.345758 -221.02663) (xy 224.361819 -220.9772) (xy 224.385415 -220.93089)
			(xy 224.415965 -220.888842) (xy 224.452716 -220.852091) (xy 224.494764 -220.821541) (xy 224.541074 -220.797945)
			(xy 224.590504 -220.781884) (xy 224.641839 -220.773754) (xy 224.693813 -220.773754) (xy 224.745148 -220.781884)
			(xy 224.794578 -220.797945) (xy 224.840888 -220.821541) (xy 224.882936 -220.852091) (xy 224.919687 -220.888842)
			(xy 224.950237 -220.93089) (xy 224.973833 -220.9772) (xy 224.989894 -221.02663) (xy 224.998024 -221.077965)
			(xy 224.998534 -221.103952) (xy 224.998024 -221.129939) (xy 225.137728 -221.129939) (xy 225.137728 -221.077965)
			(xy 225.145858 -221.02663) (xy 225.161919 -220.9772) (xy 225.185515 -220.93089) (xy 225.216065 -220.888842)
			(xy 225.252816 -220.852091) (xy 225.294864 -220.821541) (xy 225.341174 -220.797945) (xy 225.390604 -220.781884)
			(xy 225.441939 -220.773754) (xy 225.493913 -220.773754) (xy 225.545248 -220.781884) (xy 225.594678 -220.797945)
			(xy 225.640988 -220.821541) (xy 225.683036 -220.852091) (xy 225.719787 -220.888842) (xy 225.750337 -220.93089)
			(xy 225.773933 -220.9772) (xy 225.789994 -221.02663) (xy 225.798124 -221.077965) (xy 225.798634 -221.103952)
			(xy 225.798124 -221.129939) (xy 225.937574 -221.129939) (xy 225.937574 -221.077965) (xy 225.945704 -221.02663)
			(xy 225.961765 -220.9772) (xy 225.985361 -220.93089) (xy 226.015911 -220.888842) (xy 226.052662 -220.852091)
			(xy 226.09471 -220.821541) (xy 226.14102 -220.797945) (xy 226.19045 -220.781884) (xy 226.241785 -220.773754)
			(xy 226.293759 -220.773754) (xy 226.345094 -220.781884) (xy 226.394524 -220.797945) (xy 226.440834 -220.821541)
			(xy 226.482882 -220.852091) (xy 226.519633 -220.888842) (xy 226.550183 -220.93089) (xy 226.573779 -220.9772)
			(xy 226.58984 -221.02663) (xy 226.59797 -221.077965) (xy 226.59848 -221.103952) (xy 226.59797 -221.129939)
			(xy 226.737674 -221.129939) (xy 226.737674 -221.077965) (xy 226.745804 -221.02663) (xy 226.761865 -220.9772)
			(xy 226.785461 -220.93089) (xy 226.816011 -220.888842) (xy 226.852762 -220.852091) (xy 226.89481 -220.821541)
			(xy 226.94112 -220.797945) (xy 226.99055 -220.781884) (xy 227.041885 -220.773754) (xy 227.093859 -220.773754)
			(xy 227.145194 -220.781884) (xy 227.194624 -220.797945) (xy 227.240934 -220.821541) (xy 227.282982 -220.852091)
			(xy 227.319733 -220.888842) (xy 227.350283 -220.93089) (xy 227.373879 -220.9772) (xy 227.38994 -221.02663)
			(xy 227.39807 -221.077965) (xy 227.39858 -221.103952) (xy 227.39807 -221.129939) (xy 227.537774 -221.129939)
			(xy 227.537774 -221.077965) (xy 227.545904 -221.02663) (xy 227.561965 -220.9772) (xy 227.585561 -220.93089)
			(xy 227.616111 -220.888842) (xy 227.652862 -220.852091) (xy 227.69491 -220.821541) (xy 227.74122 -220.797945)
			(xy 227.79065 -220.781884) (xy 227.841985 -220.773754) (xy 227.893959 -220.773754) (xy 227.945294 -220.781884)
			(xy 227.994724 -220.797945) (xy 228.041034 -220.821541) (xy 228.083082 -220.852091) (xy 228.119833 -220.888842)
			(xy 228.150383 -220.93089) (xy 228.173979 -220.9772) (xy 228.19004 -221.02663) (xy 228.19817 -221.077965)
			(xy 228.19868 -221.103952) (xy 228.19817 -221.129939) (xy 228.33762 -221.129939) (xy 228.33762 -221.077965)
			(xy 228.34575 -221.02663) (xy 228.361811 -220.9772) (xy 228.385407 -220.93089) (xy 228.415957 -220.888842)
			(xy 228.452708 -220.852091) (xy 228.494756 -220.821541) (xy 228.541066 -220.797945) (xy 228.590496 -220.781884)
			(xy 228.641831 -220.773754) (xy 228.693805 -220.773754) (xy 228.74514 -220.781884) (xy 228.79457 -220.797945)
			(xy 228.84088 -220.821541) (xy 228.882928 -220.852091) (xy 228.919679 -220.888842) (xy 228.950229 -220.93089)
			(xy 228.973825 -220.9772) (xy 228.989886 -221.02663) (xy 228.998016 -221.077965) (xy 228.998526 -221.103952)
			(xy 228.998016 -221.129939) (xy 229.937312 -221.129939) (xy 229.937312 -221.077965) (xy 229.945442 -221.02663)
			(xy 229.961503 -220.9772) (xy 229.985099 -220.93089) (xy 230.015649 -220.888842) (xy 230.0524 -220.852091)
			(xy 230.094448 -220.821541) (xy 230.140758 -220.797945) (xy 230.190188 -220.781884) (xy 230.241523 -220.773754)
			(xy 230.293497 -220.773754) (xy 230.344832 -220.781884) (xy 230.394262 -220.797945) (xy 230.440572 -220.821541)
			(xy 230.48262 -220.852091) (xy 230.519371 -220.888842) (xy 230.549921 -220.93089) (xy 230.573517 -220.9772)
			(xy 230.589578 -221.02663) (xy 230.597708 -221.077965) (xy 230.598218 -221.103952) (xy 230.597708 -221.129939)
			(xy 230.737158 -221.129939) (xy 230.737158 -221.077965) (xy 230.745288 -221.02663) (xy 230.761349 -220.9772)
			(xy 230.784945 -220.93089) (xy 230.815495 -220.888842) (xy 230.852246 -220.852091) (xy 230.894294 -220.821541)
			(xy 230.940604 -220.797945) (xy 230.990034 -220.781884) (xy 231.041369 -220.773754) (xy 231.093343 -220.773754)
			(xy 231.144678 -220.781884) (xy 231.194108 -220.797945) (xy 231.240418 -220.821541) (xy 231.282466 -220.852091)
			(xy 231.319217 -220.888842) (xy 231.349767 -220.93089) (xy 231.373363 -220.9772) (xy 231.389424 -221.02663)
			(xy 231.397554 -221.077965) (xy 231.398064 -221.103952) (xy 231.397554 -221.129939) (xy 231.537258 -221.129939)
			(xy 231.537258 -221.077965) (xy 231.545388 -221.02663) (xy 231.561449 -220.9772) (xy 231.585045 -220.93089)
			(xy 231.615595 -220.888842) (xy 231.652346 -220.852091) (xy 231.694394 -220.821541) (xy 231.740704 -220.797945)
			(xy 231.790134 -220.781884) (xy 231.841469 -220.773754) (xy 231.893443 -220.773754) (xy 231.944778 -220.781884)
			(xy 231.994208 -220.797945) (xy 232.040518 -220.821541) (xy 232.082566 -220.852091) (xy 232.119317 -220.888842)
			(xy 232.149867 -220.93089) (xy 232.173463 -220.9772) (xy 232.189524 -221.02663) (xy 232.197654 -221.077965)
			(xy 232.198164 -221.103952) (xy 232.197654 -221.129939) (xy 232.337358 -221.129939) (xy 232.337358 -221.077965)
			(xy 232.345488 -221.02663) (xy 232.361549 -220.9772) (xy 232.385145 -220.93089) (xy 232.415695 -220.888842)
			(xy 232.452446 -220.852091) (xy 232.494494 -220.821541) (xy 232.540804 -220.797945) (xy 232.590234 -220.781884)
			(xy 232.641569 -220.773754) (xy 232.693543 -220.773754) (xy 232.744878 -220.781884) (xy 232.794308 -220.797945)
			(xy 232.840618 -220.821541) (xy 232.882666 -220.852091) (xy 232.919417 -220.888842) (xy 232.949967 -220.93089)
			(xy 232.973563 -220.9772) (xy 232.989624 -221.02663) (xy 232.997754 -221.077965) (xy 232.998264 -221.103952)
			(xy 232.997754 -221.129939) (xy 233.137204 -221.129939) (xy 233.137204 -221.077965) (xy 233.145334 -221.02663)
			(xy 233.161395 -220.9772) (xy 233.184991 -220.93089) (xy 233.215541 -220.888842) (xy 233.252292 -220.852091)
			(xy 233.29434 -220.821541) (xy 233.34065 -220.797945) (xy 233.39008 -220.781884) (xy 233.441415 -220.773754)
			(xy 233.493389 -220.773754) (xy 233.544724 -220.781884) (xy 233.594154 -220.797945) (xy 233.640464 -220.821541)
			(xy 233.682512 -220.852091) (xy 233.719263 -220.888842) (xy 233.749813 -220.93089) (xy 233.773409 -220.9772)
			(xy 233.78947 -221.02663) (xy 233.7976 -221.077965) (xy 233.79811 -221.103952) (xy 233.7976 -221.129939)
			(xy 233.937304 -221.129939) (xy 233.937304 -221.077965) (xy 233.945434 -221.02663) (xy 233.961495 -220.9772)
			(xy 233.985091 -220.93089) (xy 234.015641 -220.888842) (xy 234.052392 -220.852091) (xy 234.09444 -220.821541)
			(xy 234.14075 -220.797945) (xy 234.19018 -220.781884) (xy 234.241515 -220.773754) (xy 234.293489 -220.773754)
			(xy 234.344824 -220.781884) (xy 234.394254 -220.797945) (xy 234.440564 -220.821541) (xy 234.482612 -220.852091)
			(xy 234.519363 -220.888842) (xy 234.549913 -220.93089) (xy 234.573509 -220.9772) (xy 234.58957 -221.02663)
			(xy 234.5977 -221.077965) (xy 234.59821 -221.103952) (xy 234.5977 -221.129939) (xy 234.73715 -221.129939)
			(xy 234.73715 -221.077965) (xy 234.74528 -221.02663) (xy 234.761341 -220.9772) (xy 234.784937 -220.93089)
			(xy 234.815487 -220.888842) (xy 234.852238 -220.852091) (xy 234.894286 -220.821541) (xy 234.940596 -220.797945)
			(xy 234.990026 -220.781884) (xy 235.041361 -220.773754) (xy 235.093335 -220.773754) (xy 235.14467 -220.781884)
			(xy 235.1941 -220.797945) (xy 235.24041 -220.821541) (xy 235.282458 -220.852091) (xy 235.319209 -220.888842)
			(xy 235.349759 -220.93089) (xy 235.373355 -220.9772) (xy 235.389416 -221.02663) (xy 235.397546 -221.077965)
			(xy 235.398056 -221.103952) (xy 235.397546 -221.129939) (xy 235.53725 -221.129939) (xy 235.53725 -221.077965)
			(xy 235.54538 -221.02663) (xy 235.561441 -220.9772) (xy 235.585037 -220.93089) (xy 235.615587 -220.888842)
			(xy 235.652338 -220.852091) (xy 235.694386 -220.821541) (xy 235.740696 -220.797945) (xy 235.790126 -220.781884)
			(xy 235.841461 -220.773754) (xy 235.893435 -220.773754) (xy 235.94477 -220.781884) (xy 235.9942 -220.797945)
			(xy 236.04051 -220.821541) (xy 236.082558 -220.852091) (xy 236.119309 -220.888842) (xy 236.149859 -220.93089)
			(xy 236.173455 -220.9772) (xy 236.189516 -221.02663) (xy 236.197646 -221.077965) (xy 236.198156 -221.103952)
			(xy 236.197646 -221.129939) (xy 236.189516 -221.181274) (xy 236.173455 -221.230704) (xy 236.149859 -221.277014)
			(xy 236.119309 -221.319062) (xy 236.082558 -221.355813) (xy 236.04051 -221.386363) (xy 235.9942 -221.409959)
			(xy 235.962516 -221.420254) (xy 236.427959 -221.420254) (xy 236.427959 -221.365746) (xy 236.435717 -221.311794)
			(xy 236.451074 -221.259494) (xy 236.473718 -221.209913) (xy 236.503188 -221.164059) (xy 236.538885 -221.122866)
			(xy 236.58008 -221.087173) (xy 236.625936 -221.057706) (xy 236.675519 -221.035065) (xy 236.727819 -221.019711)
			(xy 236.781772 -221.011958) (xy 236.809026 -221.011496) (xy 236.839365 -221.012104) (xy 236.899276 -221.02171)
			(xy 236.956913 -221.040677) (xy 237.010822 -221.068526) (xy 237.059644 -221.104555) (xy 237.081314 -221.125796)
			(xy 237.088172 -221.132908) (xy 237.105952 -221.140782) (xy 237.195106 -221.144084) (xy 237.213394 -221.137734)
			(xy 237.22076 -221.131384) (xy 237.241702 -221.113701) (xy 237.287705 -221.083906) (xy 237.337501 -221.061005)
			(xy 237.390063 -221.045471) (xy 237.444307 -221.037624) (xy 237.471712 -221.03715) (xy 237.49896 -221.037721)
			(xy 237.521483 -221.04096) (xy 240.991896 -221.04096) (xy 240.995967 -220.985338) (xy 241.008093 -220.930901)
			(xy 241.028016 -220.87881) (xy 241.055312 -220.830175) (xy 241.089398 -220.786032) (xy 241.129547 -220.747323)
			(xy 241.174905 -220.714872) (xy 241.224505 -220.689371) (xy 241.277289 -220.671364) (xy 241.332132 -220.661234)
			(xy 241.387866 -220.659197) (xy 241.443303 -220.665297) (xy 241.49726 -220.679403) (xy 241.548589 -220.701215)
			(xy 241.577131 -220.718634) (xy 245.365522 -220.718634) (xy 245.369593 -220.663012) (xy 245.381719 -220.608575)
			(xy 245.401642 -220.556484) (xy 245.428938 -220.507849) (xy 245.463024 -220.463706) (xy 245.503173 -220.424997)
			(xy 245.548531 -220.392546) (xy 245.598131 -220.367045) (xy 245.650915 -220.349038) (xy 245.705758 -220.338908)
			(xy 245.761492 -220.336871) (xy 245.816929 -220.342971) (xy 245.870886 -220.357077) (xy 245.922215 -220.378889)
			(xy 245.969821 -220.407943) (xy 246.012689 -220.443618) (xy 246.049906 -220.485155) (xy 246.080679 -220.531668)
			(xy 246.104351 -220.582165) (xy 246.120419 -220.635572) (xy 246.128539 -220.690748) (xy 246.129048 -220.718634)
			(xy 246.128539 -220.74652) (xy 246.120419 -220.801696) (xy 246.104351 -220.855103) (xy 246.099145 -220.866208)
			(xy 248.253502 -220.866208) (xy 248.257573 -220.810586) (xy 248.269699 -220.756149) (xy 248.289622 -220.704058)
			(xy 248.316918 -220.655423) (xy 248.351004 -220.61128) (xy 248.391153 -220.572571) (xy 248.436511 -220.54012)
			(xy 248.486111 -220.514619) (xy 248.538895 -220.496612) (xy 248.593738 -220.486482) (xy 248.649472 -220.484445)
			(xy 248.704909 -220.490545) (xy 248.758866 -220.504651) (xy 248.810195 -220.526463) (xy 248.857801 -220.555517)
			(xy 248.900669 -220.591192) (xy 248.937886 -220.632729) (xy 248.968659 -220.679242) (xy 248.992331 -220.729739)
			(xy 249.008399 -220.783146) (xy 249.016519 -220.838322) (xy 249.017028 -220.866208) (xy 249.016519 -220.894094)
			(xy 249.008399 -220.94927) (xy 248.992331 -221.002677) (xy 248.968659 -221.053174) (xy 248.937886 -221.099687)
			(xy 248.900669 -221.141224) (xy 248.857801 -221.176899) (xy 248.810195 -221.205953) (xy 248.758866 -221.227765)
			(xy 248.704909 -221.241871) (xy 248.649472 -221.247971) (xy 248.593738 -221.245934) (xy 248.538895 -221.235804)
			(xy 248.486111 -221.217797) (xy 248.436511 -221.192296) (xy 248.391153 -221.159845) (xy 248.351004 -221.121136)
			(xy 248.316918 -221.076993) (xy 248.289622 -221.028358) (xy 248.269699 -220.976267) (xy 248.257573 -220.92183)
			(xy 248.253502 -220.866208) (xy 246.099145 -220.866208) (xy 246.080679 -220.9056) (xy 246.049906 -220.952113)
			(xy 246.012689 -220.99365) (xy 245.969821 -221.029325) (xy 245.922215 -221.058379) (xy 245.870886 -221.080191)
			(xy 245.816929 -221.094297) (xy 245.761492 -221.100397) (xy 245.705758 -221.09836) (xy 245.650915 -221.08823)
			(xy 245.598131 -221.070223) (xy 245.548531 -221.044722) (xy 245.503173 -221.012271) (xy 245.463024 -220.973562)
			(xy 245.428938 -220.929419) (xy 245.401642 -220.880784) (xy 245.381719 -220.828693) (xy 245.369593 -220.774256)
			(xy 245.365522 -220.718634) (xy 241.577131 -220.718634) (xy 241.596195 -220.730269) (xy 241.639063 -220.765944)
			(xy 241.67628 -220.807481) (xy 241.707053 -220.853994) (xy 241.730725 -220.904491) (xy 241.746793 -220.957898)
			(xy 241.754913 -221.013074) (xy 241.755422 -221.04096) (xy 241.754913 -221.068846) (xy 241.746793 -221.124022)
			(xy 241.730725 -221.177429) (xy 241.707053 -221.227926) (xy 241.67628 -221.274439) (xy 241.639063 -221.315976)
			(xy 241.596195 -221.351651) (xy 241.548589 -221.380705) (xy 241.49726 -221.402517) (xy 241.443303 -221.416623)
			(xy 241.387866 -221.422723) (xy 241.332132 -221.420686) (xy 241.277289 -221.410556) (xy 241.224505 -221.392549)
			(xy 241.174905 -221.367048) (xy 241.129547 -221.334597) (xy 241.089398 -221.295888) (xy 241.055312 -221.251745)
			(xy 241.028016 -221.20311) (xy 241.008093 -221.151019) (xy 240.995967 -221.096582) (xy 240.991896 -221.04096)
			(xy 237.521483 -221.04096) (xy 237.5529 -221.045478) (xy 237.605188 -221.060832) (xy 237.654758 -221.083472)
			(xy 237.700602 -221.112935) (xy 237.741786 -221.148623) (xy 237.777472 -221.189808) (xy 237.806934 -221.235653)
			(xy 237.829572 -221.285224) (xy 237.844925 -221.337512) (xy 237.85268 -221.391452) (xy 237.85268 -221.445948)
			(xy 237.844925 -221.499888) (xy 237.829572 -221.552176) (xy 237.806934 -221.601747) (xy 237.777472 -221.647592)
			(xy 237.741786 -221.688777) (xy 237.700602 -221.724465) (xy 237.654758 -221.753928) (xy 237.605188 -221.776568)
			(xy 237.5529 -221.791922) (xy 237.49896 -221.799679) (xy 237.471712 -221.800166) (xy 237.441374 -221.799546)
			(xy 237.381462 -221.789944) (xy 237.323825 -221.770981) (xy 237.269916 -221.743134) (xy 237.221094 -221.707106)
			(xy 237.199424 -221.685866) (xy 237.192566 -221.678754) (xy 237.174786 -221.67088) (xy 237.085632 -221.667578)
			(xy 237.067344 -221.673928) (xy 237.059978 -221.680278) (xy 237.03903 -221.697953) (xy 236.993028 -221.727747)
			(xy 236.943233 -221.750649) (xy 236.890673 -221.766185) (xy 236.83643 -221.774035) (xy 236.809026 -221.774512)
			(xy 236.781772 -221.774042) (xy 236.727819 -221.766289) (xy 236.675519 -221.750935) (xy 236.625936 -221.728294)
			(xy 236.58008 -221.698827) (xy 236.538885 -221.663134) (xy 236.503188 -221.621941) (xy 236.473718 -221.576087)
			(xy 236.451074 -221.526506) (xy 236.435717 -221.474206) (xy 236.427959 -221.420254) (xy 235.962516 -221.420254)
			(xy 235.94477 -221.42602) (xy 235.893435 -221.43415) (xy 235.841461 -221.43415) (xy 235.790126 -221.42602)
			(xy 235.740696 -221.409959) (xy 235.694386 -221.386363) (xy 235.652338 -221.355813) (xy 235.615587 -221.319062)
			(xy 235.585037 -221.277014) (xy 235.561441 -221.230704) (xy 235.54538 -221.181274) (xy 235.53725 -221.129939)
			(xy 235.397546 -221.129939) (xy 235.389416 -221.181274) (xy 235.373355 -221.230704) (xy 235.349759 -221.277014)
			(xy 235.319209 -221.319062) (xy 235.282458 -221.355813) (xy 235.24041 -221.386363) (xy 235.1941 -221.409959)
			(xy 235.14467 -221.42602) (xy 235.093335 -221.43415) (xy 235.041361 -221.43415) (xy 234.990026 -221.42602)
			(xy 234.940596 -221.409959) (xy 234.894286 -221.386363) (xy 234.852238 -221.355813) (xy 234.815487 -221.319062)
			(xy 234.784937 -221.277014) (xy 234.761341 -221.230704) (xy 234.74528 -221.181274) (xy 234.73715 -221.129939)
			(xy 234.5977 -221.129939) (xy 234.58957 -221.181274) (xy 234.573509 -221.230704) (xy 234.549913 -221.277014)
			(xy 234.519363 -221.319062) (xy 234.482612 -221.355813) (xy 234.440564 -221.386363) (xy 234.394254 -221.409959)
			(xy 234.344824 -221.42602) (xy 234.293489 -221.43415) (xy 234.241515 -221.43415) (xy 234.19018 -221.42602)
			(xy 234.14075 -221.409959) (xy 234.09444 -221.386363) (xy 234.052392 -221.355813) (xy 234.015641 -221.319062)
			(xy 233.985091 -221.277014) (xy 233.961495 -221.230704) (xy 233.945434 -221.181274) (xy 233.937304 -221.129939)
			(xy 233.7976 -221.129939) (xy 233.78947 -221.181274) (xy 233.773409 -221.230704) (xy 233.749813 -221.277014)
			(xy 233.719263 -221.319062) (xy 233.682512 -221.355813) (xy 233.640464 -221.386363) (xy 233.594154 -221.409959)
			(xy 233.544724 -221.42602) (xy 233.493389 -221.43415) (xy 233.441415 -221.43415) (xy 233.39008 -221.42602)
			(xy 233.34065 -221.409959) (xy 233.29434 -221.386363) (xy 233.252292 -221.355813) (xy 233.215541 -221.319062)
			(xy 233.184991 -221.277014) (xy 233.161395 -221.230704) (xy 233.145334 -221.181274) (xy 233.137204 -221.129939)
			(xy 232.997754 -221.129939) (xy 232.989624 -221.181274) (xy 232.973563 -221.230704) (xy 232.949967 -221.277014)
			(xy 232.919417 -221.319062) (xy 232.882666 -221.355813) (xy 232.840618 -221.386363) (xy 232.794308 -221.409959)
			(xy 232.744878 -221.42602) (xy 232.693543 -221.43415) (xy 232.641569 -221.43415) (xy 232.590234 -221.42602)
			(xy 232.540804 -221.409959) (xy 232.494494 -221.386363) (xy 232.452446 -221.355813) (xy 232.415695 -221.319062)
			(xy 232.385145 -221.277014) (xy 232.361549 -221.230704) (xy 232.345488 -221.181274) (xy 232.337358 -221.129939)
			(xy 232.197654 -221.129939) (xy 232.189524 -221.181274) (xy 232.173463 -221.230704) (xy 232.149867 -221.277014)
			(xy 232.119317 -221.319062) (xy 232.082566 -221.355813) (xy 232.040518 -221.386363) (xy 231.994208 -221.409959)
			(xy 231.944778 -221.42602) (xy 231.893443 -221.43415) (xy 231.841469 -221.43415) (xy 231.790134 -221.42602)
			(xy 231.740704 -221.409959) (xy 231.694394 -221.386363) (xy 231.652346 -221.355813) (xy 231.615595 -221.319062)
			(xy 231.585045 -221.277014) (xy 231.561449 -221.230704) (xy 231.545388 -221.181274) (xy 231.537258 -221.129939)
			(xy 231.397554 -221.129939) (xy 231.389424 -221.181274) (xy 231.373363 -221.230704) (xy 231.349767 -221.277014)
			(xy 231.319217 -221.319062) (xy 231.282466 -221.355813) (xy 231.240418 -221.386363) (xy 231.194108 -221.409959)
			(xy 231.144678 -221.42602) (xy 231.093343 -221.43415) (xy 231.041369 -221.43415) (xy 230.990034 -221.42602)
			(xy 230.940604 -221.409959) (xy 230.894294 -221.386363) (xy 230.852246 -221.355813) (xy 230.815495 -221.319062)
			(xy 230.784945 -221.277014) (xy 230.761349 -221.230704) (xy 230.745288 -221.181274) (xy 230.737158 -221.129939)
			(xy 230.597708 -221.129939) (xy 230.589578 -221.181274) (xy 230.573517 -221.230704) (xy 230.549921 -221.277014)
			(xy 230.519371 -221.319062) (xy 230.48262 -221.355813) (xy 230.440572 -221.386363) (xy 230.394262 -221.409959)
			(xy 230.344832 -221.42602) (xy 230.293497 -221.43415) (xy 230.241523 -221.43415) (xy 230.190188 -221.42602)
			(xy 230.140758 -221.409959) (xy 230.094448 -221.386363) (xy 230.0524 -221.355813) (xy 230.015649 -221.319062)
			(xy 229.985099 -221.277014) (xy 229.961503 -221.230704) (xy 229.945442 -221.181274) (xy 229.937312 -221.129939)
			(xy 228.998016 -221.129939) (xy 228.989886 -221.181274) (xy 228.973825 -221.230704) (xy 228.950229 -221.277014)
			(xy 228.919679 -221.319062) (xy 228.882928 -221.355813) (xy 228.84088 -221.386363) (xy 228.79457 -221.409959)
			(xy 228.74514 -221.42602) (xy 228.693805 -221.43415) (xy 228.641831 -221.43415) (xy 228.590496 -221.42602)
			(xy 228.541066 -221.409959) (xy 228.494756 -221.386363) (xy 228.452708 -221.355813) (xy 228.415957 -221.319062)
			(xy 228.385407 -221.277014) (xy 228.361811 -221.230704) (xy 228.34575 -221.181274) (xy 228.33762 -221.129939)
			(xy 228.19817 -221.129939) (xy 228.19004 -221.181274) (xy 228.173979 -221.230704) (xy 228.150383 -221.277014)
			(xy 228.119833 -221.319062) (xy 228.083082 -221.355813) (xy 228.041034 -221.386363) (xy 227.994724 -221.409959)
			(xy 227.945294 -221.42602) (xy 227.893959 -221.43415) (xy 227.841985 -221.43415) (xy 227.79065 -221.42602)
			(xy 227.74122 -221.409959) (xy 227.69491 -221.386363) (xy 227.652862 -221.355813) (xy 227.616111 -221.319062)
			(xy 227.585561 -221.277014) (xy 227.561965 -221.230704) (xy 227.545904 -221.181274) (xy 227.537774 -221.129939)
			(xy 227.39807 -221.129939) (xy 227.38994 -221.181274) (xy 227.373879 -221.230704) (xy 227.350283 -221.277014)
			(xy 227.319733 -221.319062) (xy 227.282982 -221.355813) (xy 227.240934 -221.386363) (xy 227.194624 -221.409959)
			(xy 227.145194 -221.42602) (xy 227.093859 -221.43415) (xy 227.041885 -221.43415) (xy 226.99055 -221.42602)
			(xy 226.94112 -221.409959) (xy 226.89481 -221.386363) (xy 226.852762 -221.355813) (xy 226.816011 -221.319062)
			(xy 226.785461 -221.277014) (xy 226.761865 -221.230704) (xy 226.745804 -221.181274) (xy 226.737674 -221.129939)
			(xy 226.59797 -221.129939) (xy 226.58984 -221.181274) (xy 226.573779 -221.230704) (xy 226.550183 -221.277014)
			(xy 226.519633 -221.319062) (xy 226.482882 -221.355813) (xy 226.440834 -221.386363) (xy 226.394524 -221.409959)
			(xy 226.345094 -221.42602) (xy 226.293759 -221.43415) (xy 226.241785 -221.43415) (xy 226.19045 -221.42602)
			(xy 226.14102 -221.409959) (xy 226.09471 -221.386363) (xy 226.052662 -221.355813) (xy 226.015911 -221.319062)
			(xy 225.985361 -221.277014) (xy 225.961765 -221.230704) (xy 225.945704 -221.181274) (xy 225.937574 -221.129939)
			(xy 225.798124 -221.129939) (xy 225.789994 -221.181274) (xy 225.773933 -221.230704) (xy 225.750337 -221.277014)
			(xy 225.719787 -221.319062) (xy 225.683036 -221.355813) (xy 225.640988 -221.386363) (xy 225.594678 -221.409959)
			(xy 225.545248 -221.42602) (xy 225.493913 -221.43415) (xy 225.441939 -221.43415) (xy 225.390604 -221.42602)
			(xy 225.341174 -221.409959) (xy 225.294864 -221.386363) (xy 225.252816 -221.355813) (xy 225.216065 -221.319062)
			(xy 225.185515 -221.277014) (xy 225.161919 -221.230704) (xy 225.145858 -221.181274) (xy 225.137728 -221.129939)
			(xy 224.998024 -221.129939) (xy 224.989894 -221.181274) (xy 224.973833 -221.230704) (xy 224.950237 -221.277014)
			(xy 224.919687 -221.319062) (xy 224.882936 -221.355813) (xy 224.840888 -221.386363) (xy 224.794578 -221.409959)
			(xy 224.745148 -221.42602) (xy 224.693813 -221.43415) (xy 224.641839 -221.43415) (xy 224.590504 -221.42602)
			(xy 224.541074 -221.409959) (xy 224.494764 -221.386363) (xy 224.452716 -221.355813) (xy 224.415965 -221.319062)
			(xy 224.385415 -221.277014) (xy 224.361819 -221.230704) (xy 224.345758 -221.181274) (xy 224.337628 -221.129939)
			(xy 224.198178 -221.129939) (xy 224.190048 -221.181274) (xy 224.173987 -221.230704) (xy 224.150391 -221.277014)
			(xy 224.119841 -221.319062) (xy 224.08309 -221.355813) (xy 224.041042 -221.386363) (xy 223.994732 -221.409959)
			(xy 223.945302 -221.42602) (xy 223.893967 -221.43415) (xy 223.841993 -221.43415) (xy 223.790658 -221.42602)
			(xy 223.741228 -221.409959) (xy 223.694918 -221.386363) (xy 223.65287 -221.355813) (xy 223.616119 -221.319062)
			(xy 223.585569 -221.277014) (xy 223.561973 -221.230704) (xy 223.545912 -221.181274) (xy 223.537782 -221.129939)
			(xy 218.840637 -221.129939) (xy 219.640737 -221.930039) (xy 224.337628 -221.930039) (xy 224.337628 -221.878065)
			(xy 224.345758 -221.82673) (xy 224.361819 -221.7773) (xy 224.385415 -221.73099) (xy 224.415965 -221.688942)
			(xy 224.452716 -221.652191) (xy 224.494764 -221.621641) (xy 224.541074 -221.598045) (xy 224.590504 -221.581984)
			(xy 224.641839 -221.573854) (xy 224.693813 -221.573854) (xy 224.745148 -221.581984) (xy 224.794578 -221.598045)
			(xy 224.840888 -221.621641) (xy 224.882936 -221.652191) (xy 224.919687 -221.688942) (xy 224.950237 -221.73099)
			(xy 224.973833 -221.7773) (xy 224.989894 -221.82673) (xy 224.998024 -221.878065) (xy 224.998534 -221.904052)
			(xy 224.998024 -221.930039) (xy 225.137728 -221.930039) (xy 225.137728 -221.878065) (xy 225.145858 -221.82673)
			(xy 225.161919 -221.7773) (xy 225.185515 -221.73099) (xy 225.216065 -221.688942) (xy 225.252816 -221.652191)
			(xy 225.294864 -221.621641) (xy 225.341174 -221.598045) (xy 225.390604 -221.581984) (xy 225.441939 -221.573854)
			(xy 225.493913 -221.573854) (xy 225.545248 -221.581984) (xy 225.594678 -221.598045) (xy 225.640988 -221.621641)
			(xy 225.683036 -221.652191) (xy 225.719787 -221.688942) (xy 225.750337 -221.73099) (xy 225.773933 -221.7773)
			(xy 225.789994 -221.82673) (xy 225.798124 -221.878065) (xy 225.798634 -221.904052) (xy 225.798124 -221.930039)
			(xy 225.937574 -221.930039) (xy 225.937574 -221.878065) (xy 225.945704 -221.82673) (xy 225.961765 -221.7773)
			(xy 225.985361 -221.73099) (xy 226.015911 -221.688942) (xy 226.052662 -221.652191) (xy 226.09471 -221.621641)
			(xy 226.14102 -221.598045) (xy 226.19045 -221.581984) (xy 226.241785 -221.573854) (xy 226.293759 -221.573854)
			(xy 226.345094 -221.581984) (xy 226.394524 -221.598045) (xy 226.440834 -221.621641) (xy 226.482882 -221.652191)
			(xy 226.519633 -221.688942) (xy 226.550183 -221.73099) (xy 226.573779 -221.7773) (xy 226.58984 -221.82673)
			(xy 226.59797 -221.878065) (xy 226.59848 -221.904052) (xy 226.59797 -221.930039) (xy 226.737674 -221.930039)
			(xy 226.737674 -221.878065) (xy 226.745804 -221.82673) (xy 226.761865 -221.7773) (xy 226.785461 -221.73099)
			(xy 226.816011 -221.688942) (xy 226.852762 -221.652191) (xy 226.89481 -221.621641) (xy 226.94112 -221.598045)
			(xy 226.99055 -221.581984) (xy 227.041885 -221.573854) (xy 227.093859 -221.573854) (xy 227.145194 -221.581984)
			(xy 227.194624 -221.598045) (xy 227.240934 -221.621641) (xy 227.282982 -221.652191) (xy 227.319733 -221.688942)
			(xy 227.350283 -221.73099) (xy 227.373879 -221.7773) (xy 227.38994 -221.82673) (xy 227.39807 -221.878065)
			(xy 227.39858 -221.904052) (xy 227.39807 -221.930039) (xy 227.537774 -221.930039) (xy 227.537774 -221.878065)
			(xy 227.545904 -221.82673) (xy 227.561965 -221.7773) (xy 227.585561 -221.73099) (xy 227.616111 -221.688942)
			(xy 227.652862 -221.652191) (xy 227.69491 -221.621641) (xy 227.74122 -221.598045) (xy 227.79065 -221.581984)
			(xy 227.841985 -221.573854) (xy 227.893959 -221.573854) (xy 227.945294 -221.581984) (xy 227.994724 -221.598045)
			(xy 228.041034 -221.621641) (xy 228.083082 -221.652191) (xy 228.119833 -221.688942) (xy 228.150383 -221.73099)
			(xy 228.173979 -221.7773) (xy 228.19004 -221.82673) (xy 228.19817 -221.878065) (xy 228.19868 -221.904052)
			(xy 228.19817 -221.930039) (xy 228.33762 -221.930039) (xy 228.33762 -221.878065) (xy 228.34575 -221.82673)
			(xy 228.361811 -221.7773) (xy 228.385407 -221.73099) (xy 228.415957 -221.688942) (xy 228.452708 -221.652191)
			(xy 228.494756 -221.621641) (xy 228.541066 -221.598045) (xy 228.590496 -221.581984) (xy 228.641831 -221.573854)
			(xy 228.693805 -221.573854) (xy 228.74514 -221.581984) (xy 228.79457 -221.598045) (xy 228.84088 -221.621641)
			(xy 228.882928 -221.652191) (xy 228.919679 -221.688942) (xy 228.950229 -221.73099) (xy 228.973825 -221.7773)
			(xy 228.989886 -221.82673) (xy 228.998016 -221.878065) (xy 228.998526 -221.904052) (xy 228.998016 -221.930039)
			(xy 229.937312 -221.930039) (xy 229.937312 -221.878065) (xy 229.945442 -221.82673) (xy 229.961503 -221.7773)
			(xy 229.985099 -221.73099) (xy 230.015649 -221.688942) (xy 230.0524 -221.652191) (xy 230.094448 -221.621641)
			(xy 230.140758 -221.598045) (xy 230.190188 -221.581984) (xy 230.241523 -221.573854) (xy 230.293497 -221.573854)
			(xy 230.344832 -221.581984) (xy 230.394262 -221.598045) (xy 230.440572 -221.621641) (xy 230.48262 -221.652191)
			(xy 230.519371 -221.688942) (xy 230.549921 -221.73099) (xy 230.573517 -221.7773) (xy 230.589578 -221.82673)
			(xy 230.597708 -221.878065) (xy 230.598218 -221.904052) (xy 230.597708 -221.930039) (xy 230.737158 -221.930039)
			(xy 230.737158 -221.878065) (xy 230.745288 -221.82673) (xy 230.761349 -221.7773) (xy 230.784945 -221.73099)
			(xy 230.815495 -221.688942) (xy 230.852246 -221.652191) (xy 230.894294 -221.621641) (xy 230.940604 -221.598045)
			(xy 230.990034 -221.581984) (xy 231.041369 -221.573854) (xy 231.093343 -221.573854) (xy 231.144678 -221.581984)
			(xy 231.194108 -221.598045) (xy 231.240418 -221.621641) (xy 231.282466 -221.652191) (xy 231.319217 -221.688942)
			(xy 231.349767 -221.73099) (xy 231.373363 -221.7773) (xy 231.389424 -221.82673) (xy 231.397554 -221.878065)
			(xy 231.398064 -221.904052) (xy 231.397554 -221.930039) (xy 232.337358 -221.930039) (xy 232.337358 -221.878065)
			(xy 232.345488 -221.82673) (xy 232.361549 -221.7773) (xy 232.385145 -221.73099) (xy 232.415695 -221.688942)
			(xy 232.452446 -221.652191) (xy 232.494494 -221.621641) (xy 232.540804 -221.598045) (xy 232.590234 -221.581984)
			(xy 232.641569 -221.573854) (xy 232.693543 -221.573854) (xy 232.744878 -221.581984) (xy 232.794308 -221.598045)
			(xy 232.840618 -221.621641) (xy 232.882666 -221.652191) (xy 232.919417 -221.688942) (xy 232.949967 -221.73099)
			(xy 232.973563 -221.7773) (xy 232.989624 -221.82673) (xy 232.997754 -221.878065) (xy 232.998264 -221.904052)
			(xy 232.997754 -221.930039) (xy 233.137204 -221.930039) (xy 233.137204 -221.878065) (xy 233.145334 -221.82673)
			(xy 233.161395 -221.7773) (xy 233.184991 -221.73099) (xy 233.215541 -221.688942) (xy 233.252292 -221.652191)
			(xy 233.29434 -221.621641) (xy 233.34065 -221.598045) (xy 233.39008 -221.581984) (xy 233.441415 -221.573854)
			(xy 233.493389 -221.573854) (xy 233.544724 -221.581984) (xy 233.594154 -221.598045) (xy 233.640464 -221.621641)
			(xy 233.682512 -221.652191) (xy 233.719263 -221.688942) (xy 233.749813 -221.73099) (xy 233.773409 -221.7773)
			(xy 233.78947 -221.82673) (xy 233.7976 -221.878065) (xy 233.79811 -221.904052) (xy 233.7976 -221.930039)
			(xy 233.937304 -221.930039) (xy 233.937304 -221.878065) (xy 233.945434 -221.82673) (xy 233.961495 -221.7773)
			(xy 233.985091 -221.73099) (xy 234.015641 -221.688942) (xy 234.052392 -221.652191) (xy 234.09444 -221.621641)
			(xy 234.14075 -221.598045) (xy 234.19018 -221.581984) (xy 234.241515 -221.573854) (xy 234.293489 -221.573854)
			(xy 234.344824 -221.581984) (xy 234.394254 -221.598045) (xy 234.440564 -221.621641) (xy 234.482612 -221.652191)
			(xy 234.519363 -221.688942) (xy 234.549913 -221.73099) (xy 234.573509 -221.7773) (xy 234.58957 -221.82673)
			(xy 234.5977 -221.878065) (xy 234.59821 -221.904052) (xy 234.5977 -221.930039) (xy 234.73715 -221.930039)
			(xy 234.73715 -221.878065) (xy 234.74528 -221.82673) (xy 234.761341 -221.7773) (xy 234.784937 -221.73099)
			(xy 234.815487 -221.688942) (xy 234.852238 -221.652191) (xy 234.894286 -221.621641) (xy 234.940596 -221.598045)
			(xy 234.990026 -221.581984) (xy 235.041361 -221.573854) (xy 235.093335 -221.573854) (xy 235.14467 -221.581984)
			(xy 235.1941 -221.598045) (xy 235.24041 -221.621641) (xy 235.282458 -221.652191) (xy 235.319209 -221.688942)
			(xy 235.349759 -221.73099) (xy 235.373355 -221.7773) (xy 235.389416 -221.82673) (xy 235.397546 -221.878065)
			(xy 235.398056 -221.904052) (xy 235.397546 -221.930039) (xy 235.53725 -221.930039) (xy 235.53725 -221.878065)
			(xy 235.54538 -221.82673) (xy 235.561441 -221.7773) (xy 235.585037 -221.73099) (xy 235.615587 -221.688942)
			(xy 235.652338 -221.652191) (xy 235.694386 -221.621641) (xy 235.740696 -221.598045) (xy 235.790126 -221.581984)
			(xy 235.841461 -221.573854) (xy 235.893435 -221.573854) (xy 235.94477 -221.581984) (xy 235.9942 -221.598045)
			(xy 236.04051 -221.621641) (xy 236.082558 -221.652191) (xy 236.119309 -221.688942) (xy 236.149859 -221.73099)
			(xy 236.173455 -221.7773) (xy 236.189516 -221.82673) (xy 236.197646 -221.878065) (xy 236.198156 -221.904052)
			(xy 236.197646 -221.930039) (xy 236.189516 -221.981374) (xy 236.173455 -222.030804) (xy 236.149859 -222.077114)
			(xy 236.135713 -222.096584) (xy 238.055148 -222.096584) (xy 238.059219 -222.040962) (xy 238.071345 -221.986525)
			(xy 238.091268 -221.934434) (xy 238.118564 -221.885799) (xy 238.15265 -221.841656) (xy 238.192799 -221.802947)
			(xy 238.238157 -221.770496) (xy 238.287757 -221.744995) (xy 238.340541 -221.726988) (xy 238.395384 -221.716858)
			(xy 238.451118 -221.714821) (xy 238.506555 -221.720921) (xy 238.560512 -221.735027) (xy 238.611841 -221.756839)
			(xy 238.659447 -221.785893) (xy 238.702315 -221.821568) (xy 238.739532 -221.863105) (xy 238.770305 -221.909618)
			(xy 238.793977 -221.960115) (xy 238.810045 -222.013522) (xy 238.818165 -222.068698) (xy 238.818578 -222.091351)
			(xy 240.98275 -222.091351) (xy 240.98275 -222.036849) (xy 240.990506 -221.982901) (xy 241.00586 -221.930606)
			(xy 241.028499 -221.881028) (xy 241.057963 -221.835177) (xy 241.093652 -221.793985) (xy 241.13484 -221.758291)
			(xy 241.180688 -221.728821) (xy 241.230263 -221.706176) (xy 241.282556 -221.690815) (xy 241.336503 -221.683053)
			(xy 241.363754 -221.682564) (xy 241.390937 -221.683028) (xy 241.444753 -221.690752) (xy 241.496927 -221.706038)
			(xy 241.546403 -221.728574) (xy 241.592179 -221.757905) (xy 241.633329 -221.793437) (xy 241.651536 -221.813628)
			(xy 241.658902 -221.822264) (xy 241.679222 -221.831154) (xy 241.779044 -221.830392) (xy 241.798856 -221.82074)
			(xy 241.806222 -221.812104) (xy 241.824479 -221.791134) (xy 241.865974 -221.754131) (xy 241.912398 -221.72354)
			(xy 241.962771 -221.700009) (xy 242.016024 -221.684036) (xy 242.071031 -221.675959) (xy 242.09883 -221.675452)
			(xy 242.12608 -221.67595) (xy 242.180025 -221.683709) (xy 242.232317 -221.699066) (xy 242.281892 -221.721708)
			(xy 242.32774 -221.751174) (xy 242.368929 -221.786864) (xy 242.40462 -221.828052) (xy 242.434087 -221.873899)
			(xy 242.45673 -221.923473) (xy 242.472089 -221.975765) (xy 242.47985 -222.02971) (xy 242.480338 -222.05696)
			(xy 242.479823 -222.08422) (xy 242.472061 -222.138186) (xy 242.456704 -222.190499) (xy 242.434062 -222.240097)
			(xy 242.404598 -222.28597) (xy 242.38712 -222.306896) (xy 242.380516 -222.314262) (xy 242.37442 -222.332296)
			(xy 242.377468 -222.421196) (xy 242.385088 -222.438468) (xy 242.3922 -222.44558) (xy 242.413105 -222.467179)
			(xy 242.448514 -222.515748) (xy 242.475866 -222.56927) (xy 242.494484 -222.62642) (xy 242.503907 -222.685783)
			(xy 242.504468 -222.715836) (xy 242.503982 -222.743087) (xy 242.496226 -222.797035) (xy 242.480871 -222.84933)
			(xy 242.458229 -222.898907) (xy 242.428763 -222.944757) (xy 242.393072 -222.985948) (xy 242.351881 -223.021639)
			(xy 242.306031 -223.051105) (xy 242.256454 -223.073747) (xy 242.204159 -223.089102) (xy 242.150211 -223.096858)
			(xy 242.095709 -223.096858) (xy 242.041761 -223.089102) (xy 241.989466 -223.073747) (xy 241.939889 -223.051105)
			(xy 241.894039 -223.021639) (xy 241.852848 -222.985948) (xy 241.817157 -222.944757) (xy 241.787691 -222.898907)
			(xy 241.765049 -222.84933) (xy 241.749694 -222.797035) (xy 241.741938 -222.743087) (xy 241.741452 -222.715836)
			(xy 241.741967 -222.688576) (xy 241.749729 -222.63461) (xy 241.765087 -222.582297) (xy 241.787728 -222.5327)
			(xy 241.817192 -222.486826) (xy 241.83467 -222.4659) (xy 241.841274 -222.458534) (xy 241.84737 -222.4405)
			(xy 241.844322 -222.3516) (xy 241.836702 -222.334328) (xy 241.82959 -222.327216) (xy 241.811048 -222.307404)
			(xy 241.803682 -222.298768) (xy 241.783362 -222.289878) (xy 241.68354 -222.29064) (xy 241.663728 -222.300292)
			(xy 241.656362 -222.308928) (xy 241.638121 -222.329912) (xy 241.596622 -222.366913) (xy 241.550194 -222.397501)
			(xy 241.499818 -222.421029) (xy 241.446563 -222.437) (xy 241.391553 -222.445074) (xy 241.363754 -222.44558)
			(xy 241.336503 -222.445147) (xy 241.282556 -222.437385) (xy 241.230263 -222.422024) (xy 241.180688 -222.399379)
			(xy 241.13484 -222.369909) (xy 241.093652 -222.334215) (xy 241.057963 -222.293023) (xy 241.028499 -222.247172)
			(xy 241.00586 -222.197594) (xy 240.990506 -222.145299) (xy 240.98275 -222.091351) (xy 238.818578 -222.091351)
			(xy 238.818674 -222.096584) (xy 238.818165 -222.12447) (xy 238.810045 -222.179646) (xy 238.793977 -222.233053)
			(xy 238.770305 -222.28355) (xy 238.739532 -222.330063) (xy 238.702315 -222.3716) (xy 238.659447 -222.407275)
			(xy 238.611841 -222.436329) (xy 238.560512 -222.458141) (xy 238.506555 -222.472247) (xy 238.451118 -222.478347)
			(xy 238.395384 -222.47631) (xy 238.340541 -222.46618) (xy 238.287757 -222.448173) (xy 238.238157 -222.422672)
			(xy 238.192799 -222.390221) (xy 238.15265 -222.351512) (xy 238.118564 -222.307369) (xy 238.091268 -222.258734)
			(xy 238.071345 -222.206643) (xy 238.059219 -222.152206) (xy 238.055148 -222.096584) (xy 236.135713 -222.096584)
			(xy 236.119309 -222.119162) (xy 236.082558 -222.155913) (xy 236.04051 -222.186463) (xy 235.9942 -222.210059)
			(xy 235.94477 -222.22612) (xy 235.893435 -222.23425) (xy 235.841461 -222.23425) (xy 235.790126 -222.22612)
			(xy 235.740696 -222.210059) (xy 235.694386 -222.186463) (xy 235.652338 -222.155913) (xy 235.615587 -222.119162)
			(xy 235.585037 -222.077114) (xy 235.561441 -222.030804) (xy 235.54538 -221.981374) (xy 235.53725 -221.930039)
			(xy 235.397546 -221.930039) (xy 235.389416 -221.981374) (xy 235.373355 -222.030804) (xy 235.349759 -222.077114)
			(xy 235.319209 -222.119162) (xy 235.282458 -222.155913) (xy 235.24041 -222.186463) (xy 235.1941 -222.210059)
			(xy 235.14467 -222.22612) (xy 235.093335 -222.23425) (xy 235.041361 -222.23425) (xy 234.990026 -222.22612)
			(xy 234.940596 -222.210059) (xy 234.894286 -222.186463) (xy 234.852238 -222.155913) (xy 234.815487 -222.119162)
			(xy 234.784937 -222.077114) (xy 234.761341 -222.030804) (xy 234.74528 -221.981374) (xy 234.73715 -221.930039)
			(xy 234.5977 -221.930039) (xy 234.58957 -221.981374) (xy 234.573509 -222.030804) (xy 234.549913 -222.077114)
			(xy 234.519363 -222.119162) (xy 234.482612 -222.155913) (xy 234.440564 -222.186463) (xy 234.394254 -222.210059)
			(xy 234.344824 -222.22612) (xy 234.293489 -222.23425) (xy 234.241515 -222.23425) (xy 234.19018 -222.22612)
			(xy 234.14075 -222.210059) (xy 234.09444 -222.186463) (xy 234.052392 -222.155913) (xy 234.015641 -222.119162)
			(xy 233.985091 -222.077114) (xy 233.961495 -222.030804) (xy 233.945434 -221.981374) (xy 233.937304 -221.930039)
			(xy 233.7976 -221.930039) (xy 233.78947 -221.981374) (xy 233.773409 -222.030804) (xy 233.749813 -222.077114)
			(xy 233.719263 -222.119162) (xy 233.682512 -222.155913) (xy 233.640464 -222.186463) (xy 233.594154 -222.210059)
			(xy 233.544724 -222.22612) (xy 233.493389 -222.23425) (xy 233.441415 -222.23425) (xy 233.39008 -222.22612)
			(xy 233.34065 -222.210059) (xy 233.29434 -222.186463) (xy 233.252292 -222.155913) (xy 233.215541 -222.119162)
			(xy 233.184991 -222.077114) (xy 233.161395 -222.030804) (xy 233.145334 -221.981374) (xy 233.137204 -221.930039)
			(xy 232.997754 -221.930039) (xy 232.989624 -221.981374) (xy 232.973563 -222.030804) (xy 232.949967 -222.077114)
			(xy 232.919417 -222.119162) (xy 232.882666 -222.155913) (xy 232.840618 -222.186463) (xy 232.794308 -222.210059)
			(xy 232.744878 -222.22612) (xy 232.693543 -222.23425) (xy 232.641569 -222.23425) (xy 232.590234 -222.22612)
			(xy 232.540804 -222.210059) (xy 232.494494 -222.186463) (xy 232.452446 -222.155913) (xy 232.415695 -222.119162)
			(xy 232.385145 -222.077114) (xy 232.361549 -222.030804) (xy 232.345488 -221.981374) (xy 232.337358 -221.930039)
			(xy 231.397554 -221.930039) (xy 231.389424 -221.981374) (xy 231.373363 -222.030804) (xy 231.349767 -222.077114)
			(xy 231.319217 -222.119162) (xy 231.282466 -222.155913) (xy 231.240418 -222.186463) (xy 231.194108 -222.210059)
			(xy 231.144678 -222.22612) (xy 231.093343 -222.23425) (xy 231.041369 -222.23425) (xy 230.990034 -222.22612)
			(xy 230.940604 -222.210059) (xy 230.894294 -222.186463) (xy 230.852246 -222.155913) (xy 230.815495 -222.119162)
			(xy 230.784945 -222.077114) (xy 230.761349 -222.030804) (xy 230.745288 -221.981374) (xy 230.737158 -221.930039)
			(xy 230.597708 -221.930039) (xy 230.589578 -221.981374) (xy 230.573517 -222.030804) (xy 230.549921 -222.077114)
			(xy 230.519371 -222.119162) (xy 230.48262 -222.155913) (xy 230.440572 -222.186463) (xy 230.394262 -222.210059)
			(xy 230.344832 -222.22612) (xy 230.293497 -222.23425) (xy 230.241523 -222.23425) (xy 230.190188 -222.22612)
			(xy 230.140758 -222.210059) (xy 230.094448 -222.186463) (xy 230.0524 -222.155913) (xy 230.015649 -222.119162)
			(xy 229.985099 -222.077114) (xy 229.961503 -222.030804) (xy 229.945442 -221.981374) (xy 229.937312 -221.930039)
			(xy 228.998016 -221.930039) (xy 228.989886 -221.981374) (xy 228.973825 -222.030804) (xy 228.950229 -222.077114)
			(xy 228.919679 -222.119162) (xy 228.882928 -222.155913) (xy 228.84088 -222.186463) (xy 228.79457 -222.210059)
			(xy 228.74514 -222.22612) (xy 228.693805 -222.23425) (xy 228.641831 -222.23425) (xy 228.590496 -222.22612)
			(xy 228.541066 -222.210059) (xy 228.494756 -222.186463) (xy 228.452708 -222.155913) (xy 228.415957 -222.119162)
			(xy 228.385407 -222.077114) (xy 228.361811 -222.030804) (xy 228.34575 -221.981374) (xy 228.33762 -221.930039)
			(xy 228.19817 -221.930039) (xy 228.19004 -221.981374) (xy 228.173979 -222.030804) (xy 228.150383 -222.077114)
			(xy 228.119833 -222.119162) (xy 228.083082 -222.155913) (xy 228.041034 -222.186463) (xy 227.994724 -222.210059)
			(xy 227.945294 -222.22612) (xy 227.893959 -222.23425) (xy 227.841985 -222.23425) (xy 227.79065 -222.22612)
			(xy 227.74122 -222.210059) (xy 227.69491 -222.186463) (xy 227.652862 -222.155913) (xy 227.616111 -222.119162)
			(xy 227.585561 -222.077114) (xy 227.561965 -222.030804) (xy 227.545904 -221.981374) (xy 227.537774 -221.930039)
			(xy 227.39807 -221.930039) (xy 227.38994 -221.981374) (xy 227.373879 -222.030804) (xy 227.350283 -222.077114)
			(xy 227.319733 -222.119162) (xy 227.282982 -222.155913) (xy 227.240934 -222.186463) (xy 227.194624 -222.210059)
			(xy 227.145194 -222.22612) (xy 227.093859 -222.23425) (xy 227.041885 -222.23425) (xy 226.99055 -222.22612)
			(xy 226.94112 -222.210059) (xy 226.89481 -222.186463) (xy 226.852762 -222.155913) (xy 226.816011 -222.119162)
			(xy 226.785461 -222.077114) (xy 226.761865 -222.030804) (xy 226.745804 -221.981374) (xy 226.737674 -221.930039)
			(xy 226.59797 -221.930039) (xy 226.58984 -221.981374) (xy 226.573779 -222.030804) (xy 226.550183 -222.077114)
			(xy 226.519633 -222.119162) (xy 226.482882 -222.155913) (xy 226.440834 -222.186463) (xy 226.394524 -222.210059)
			(xy 226.345094 -222.22612) (xy 226.293759 -222.23425) (xy 226.241785 -222.23425) (xy 226.19045 -222.22612)
			(xy 226.14102 -222.210059) (xy 226.09471 -222.186463) (xy 226.052662 -222.155913) (xy 226.015911 -222.119162)
			(xy 225.985361 -222.077114) (xy 225.961765 -222.030804) (xy 225.945704 -221.981374) (xy 225.937574 -221.930039)
			(xy 225.798124 -221.930039) (xy 225.789994 -221.981374) (xy 225.773933 -222.030804) (xy 225.750337 -222.077114)
			(xy 225.719787 -222.119162) (xy 225.683036 -222.155913) (xy 225.640988 -222.186463) (xy 225.594678 -222.210059)
			(xy 225.545248 -222.22612) (xy 225.493913 -222.23425) (xy 225.441939 -222.23425) (xy 225.390604 -222.22612)
			(xy 225.341174 -222.210059) (xy 225.294864 -222.186463) (xy 225.252816 -222.155913) (xy 225.216065 -222.119162)
			(xy 225.185515 -222.077114) (xy 225.161919 -222.030804) (xy 225.145858 -221.981374) (xy 225.137728 -221.930039)
			(xy 224.998024 -221.930039) (xy 224.989894 -221.981374) (xy 224.973833 -222.030804) (xy 224.950237 -222.077114)
			(xy 224.919687 -222.119162) (xy 224.882936 -222.155913) (xy 224.840888 -222.186463) (xy 224.794578 -222.210059)
			(xy 224.745148 -222.22612) (xy 224.693813 -222.23425) (xy 224.641839 -222.23425) (xy 224.590504 -222.22612)
			(xy 224.541074 -222.210059) (xy 224.494764 -222.186463) (xy 224.452716 -222.155913) (xy 224.415965 -222.119162)
			(xy 224.385415 -222.077114) (xy 224.361819 -222.030804) (xy 224.345758 -221.981374) (xy 224.337628 -221.930039)
			(xy 219.640737 -221.930039) (xy 220.367685 -222.656987) (xy 222.631002 -222.656987) (xy 222.631002 -222.605013)
			(xy 222.639132 -222.553678) (xy 222.655193 -222.504248) (xy 222.678789 -222.457938) (xy 222.709339 -222.41589)
			(xy 222.74609 -222.379139) (xy 222.788138 -222.348589) (xy 222.834448 -222.324993) (xy 222.883878 -222.308932)
			(xy 222.935213 -222.300802) (xy 222.987187 -222.300802) (xy 223.038522 -222.308932) (xy 223.087952 -222.324993)
			(xy 223.134262 -222.348589) (xy 223.17631 -222.379139) (xy 223.213061 -222.41589) (xy 223.243611 -222.457938)
			(xy 223.267207 -222.504248) (xy 223.283268 -222.553678) (xy 223.291398 -222.605013) (xy 223.291908 -222.631)
			(xy 223.291398 -222.656987) (xy 223.283268 -222.708322) (xy 223.276262 -222.729885) (xy 223.537782 -222.729885)
			(xy 223.537782 -222.677911) (xy 223.545912 -222.626576) (xy 223.561973 -222.577146) (xy 223.585569 -222.530836)
			(xy 223.616119 -222.488788) (xy 223.65287 -222.452037) (xy 223.694918 -222.421487) (xy 223.741228 -222.397891)
			(xy 223.790658 -222.38183) (xy 223.841993 -222.3737) (xy 223.893967 -222.3737) (xy 223.945302 -222.38183)
			(xy 223.994732 -222.397891) (xy 224.041042 -222.421487) (xy 224.08309 -222.452037) (xy 224.119841 -222.488788)
			(xy 224.150391 -222.530836) (xy 224.173987 -222.577146) (xy 224.190048 -222.626576) (xy 224.198178 -222.677911)
			(xy 224.198688 -222.703898) (xy 224.198178 -222.729885) (xy 224.337628 -222.729885) (xy 224.337628 -222.677911)
			(xy 224.345758 -222.626576) (xy 224.361819 -222.577146) (xy 224.385415 -222.530836) (xy 224.415965 -222.488788)
			(xy 224.452716 -222.452037) (xy 224.494764 -222.421487) (xy 224.541074 -222.397891) (xy 224.590504 -222.38183)
			(xy 224.641839 -222.3737) (xy 224.693813 -222.3737) (xy 224.745148 -222.38183) (xy 224.794578 -222.397891)
			(xy 224.840888 -222.421487) (xy 224.882936 -222.452037) (xy 224.919687 -222.488788) (xy 224.950237 -222.530836)
			(xy 224.973833 -222.577146) (xy 224.989894 -222.626576) (xy 224.998024 -222.677911) (xy 224.998534 -222.703898)
			(xy 224.998024 -222.729885) (xy 225.137728 -222.729885) (xy 225.137728 -222.677911) (xy 225.145858 -222.626576)
			(xy 225.161919 -222.577146) (xy 225.185515 -222.530836) (xy 225.216065 -222.488788) (xy 225.252816 -222.452037)
			(xy 225.294864 -222.421487) (xy 225.341174 -222.397891) (xy 225.390604 -222.38183) (xy 225.441939 -222.3737)
			(xy 225.493913 -222.3737) (xy 225.545248 -222.38183) (xy 225.594678 -222.397891) (xy 225.640988 -222.421487)
			(xy 225.683036 -222.452037) (xy 225.719787 -222.488788) (xy 225.750337 -222.530836) (xy 225.773933 -222.577146)
			(xy 225.789994 -222.626576) (xy 225.798124 -222.677911) (xy 225.798634 -222.703898) (xy 225.798124 -222.729885)
			(xy 225.937574 -222.729885) (xy 225.937574 -222.677911) (xy 225.945704 -222.626576) (xy 225.961765 -222.577146)
			(xy 225.985361 -222.530836) (xy 226.015911 -222.488788) (xy 226.052662 -222.452037) (xy 226.09471 -222.421487)
			(xy 226.14102 -222.397891) (xy 226.19045 -222.38183) (xy 226.241785 -222.3737) (xy 226.293759 -222.3737)
			(xy 226.345094 -222.38183) (xy 226.394524 -222.397891) (xy 226.440834 -222.421487) (xy 226.482882 -222.452037)
			(xy 226.519633 -222.488788) (xy 226.550183 -222.530836) (xy 226.573779 -222.577146) (xy 226.58984 -222.626576)
			(xy 226.59797 -222.677911) (xy 226.59848 -222.703898) (xy 226.59797 -222.729885) (xy 226.737674 -222.729885)
			(xy 226.737674 -222.677911) (xy 226.745804 -222.626576) (xy 226.761865 -222.577146) (xy 226.785461 -222.530836)
			(xy 226.816011 -222.488788) (xy 226.852762 -222.452037) (xy 226.89481 -222.421487) (xy 226.94112 -222.397891)
			(xy 226.99055 -222.38183) (xy 227.041885 -222.3737) (xy 227.093859 -222.3737) (xy 227.145194 -222.38183)
			(xy 227.194624 -222.397891) (xy 227.240934 -222.421487) (xy 227.282982 -222.452037) (xy 227.319733 -222.488788)
			(xy 227.350283 -222.530836) (xy 227.373879 -222.577146) (xy 227.38994 -222.626576) (xy 227.39807 -222.677911)
			(xy 227.39858 -222.703898) (xy 227.39807 -222.729885) (xy 227.537774 -222.729885) (xy 227.537774 -222.677911)
			(xy 227.545904 -222.626576) (xy 227.561965 -222.577146) (xy 227.585561 -222.530836) (xy 227.616111 -222.488788)
			(xy 227.652862 -222.452037) (xy 227.69491 -222.421487) (xy 227.74122 -222.397891) (xy 227.79065 -222.38183)
			(xy 227.841985 -222.3737) (xy 227.893959 -222.3737) (xy 227.945294 -222.38183) (xy 227.994724 -222.397891)
			(xy 228.041034 -222.421487) (xy 228.083082 -222.452037) (xy 228.119833 -222.488788) (xy 228.150383 -222.530836)
			(xy 228.173979 -222.577146) (xy 228.19004 -222.626576) (xy 228.19817 -222.677911) (xy 228.19868 -222.703898)
			(xy 228.19817 -222.729885) (xy 230.737158 -222.729885) (xy 230.737158 -222.677911) (xy 230.745288 -222.626576)
			(xy 230.761349 -222.577146) (xy 230.784945 -222.530836) (xy 230.815495 -222.488788) (xy 230.852246 -222.452037)
			(xy 230.894294 -222.421487) (xy 230.940604 -222.397891) (xy 230.990034 -222.38183) (xy 231.041369 -222.3737)
			(xy 231.093343 -222.3737) (xy 231.144678 -222.38183) (xy 231.194108 -222.397891) (xy 231.240418 -222.421487)
			(xy 231.282466 -222.452037) (xy 231.319217 -222.488788) (xy 231.349767 -222.530836) (xy 231.373363 -222.577146)
			(xy 231.389424 -222.626576) (xy 231.397554 -222.677911) (xy 231.398064 -222.703898) (xy 231.397554 -222.729885)
			(xy 231.537258 -222.729885) (xy 231.537258 -222.677911) (xy 231.545388 -222.626576) (xy 231.561449 -222.577146)
			(xy 231.585045 -222.530836) (xy 231.615595 -222.488788) (xy 231.652346 -222.452037) (xy 231.694394 -222.421487)
			(xy 231.740704 -222.397891) (xy 231.790134 -222.38183) (xy 231.841469 -222.3737) (xy 231.893443 -222.3737)
			(xy 231.944778 -222.38183) (xy 231.994208 -222.397891) (xy 232.040518 -222.421487) (xy 232.082566 -222.452037)
			(xy 232.119317 -222.488788) (xy 232.149867 -222.530836) (xy 232.173463 -222.577146) (xy 232.189524 -222.626576)
			(xy 232.197654 -222.677911) (xy 232.198164 -222.703898) (xy 232.197654 -222.729885) (xy 232.337358 -222.729885)
			(xy 232.337358 -222.677911) (xy 232.345488 -222.626576) (xy 232.361549 -222.577146) (xy 232.385145 -222.530836)
			(xy 232.415695 -222.488788) (xy 232.452446 -222.452037) (xy 232.494494 -222.421487) (xy 232.540804 -222.397891)
			(xy 232.590234 -222.38183) (xy 232.641569 -222.3737) (xy 232.693543 -222.3737) (xy 232.744878 -222.38183)
			(xy 232.794308 -222.397891) (xy 232.840618 -222.421487) (xy 232.882666 -222.452037) (xy 232.919417 -222.488788)
			(xy 232.949967 -222.530836) (xy 232.973563 -222.577146) (xy 232.989624 -222.626576) (xy 232.997754 -222.677911)
			(xy 232.998264 -222.703898) (xy 232.997754 -222.729885) (xy 233.137204 -222.729885) (xy 233.137204 -222.677911)
			(xy 233.145334 -222.626576) (xy 233.161395 -222.577146) (xy 233.184991 -222.530836) (xy 233.215541 -222.488788)
			(xy 233.252292 -222.452037) (xy 233.29434 -222.421487) (xy 233.34065 -222.397891) (xy 233.39008 -222.38183)
			(xy 233.441415 -222.3737) (xy 233.493389 -222.3737) (xy 233.544724 -222.38183) (xy 233.594154 -222.397891)
			(xy 233.640464 -222.421487) (xy 233.682512 -222.452037) (xy 233.719263 -222.488788) (xy 233.749813 -222.530836)
			(xy 233.773409 -222.577146) (xy 233.78947 -222.626576) (xy 233.7976 -222.677911) (xy 233.79811 -222.703898)
			(xy 233.7976 -222.729885) (xy 233.937304 -222.729885) (xy 233.937304 -222.677911) (xy 233.945434 -222.626576)
			(xy 233.961495 -222.577146) (xy 233.985091 -222.530836) (xy 234.015641 -222.488788) (xy 234.052392 -222.452037)
			(xy 234.09444 -222.421487) (xy 234.14075 -222.397891) (xy 234.19018 -222.38183) (xy 234.241515 -222.3737)
			(xy 234.293489 -222.3737) (xy 234.344824 -222.38183) (xy 234.394254 -222.397891) (xy 234.440564 -222.421487)
			(xy 234.482612 -222.452037) (xy 234.519363 -222.488788) (xy 234.549913 -222.530836) (xy 234.573509 -222.577146)
			(xy 234.58957 -222.626576) (xy 234.5977 -222.677911) (xy 234.59821 -222.703898) (xy 234.5977 -222.729885)
			(xy 234.73715 -222.729885) (xy 234.73715 -222.677911) (xy 234.74528 -222.626576) (xy 234.761341 -222.577146)
			(xy 234.784937 -222.530836) (xy 234.815487 -222.488788) (xy 234.852238 -222.452037) (xy 234.894286 -222.421487)
			(xy 234.940596 -222.397891) (xy 234.990026 -222.38183) (xy 235.041361 -222.3737) (xy 235.093335 -222.3737)
			(xy 235.14467 -222.38183) (xy 235.1941 -222.397891) (xy 235.24041 -222.421487) (xy 235.282458 -222.452037)
			(xy 235.319209 -222.488788) (xy 235.349759 -222.530836) (xy 235.373355 -222.577146) (xy 235.389416 -222.626576)
			(xy 235.397546 -222.677911) (xy 235.398056 -222.703898) (xy 235.397546 -222.729885) (xy 235.53725 -222.729885)
			(xy 235.53725 -222.677911) (xy 235.54538 -222.626576) (xy 235.561441 -222.577146) (xy 235.585037 -222.530836)
			(xy 235.615587 -222.488788) (xy 235.652338 -222.452037) (xy 235.694386 -222.421487) (xy 235.740696 -222.397891)
			(xy 235.790126 -222.38183) (xy 235.841461 -222.3737) (xy 235.893435 -222.3737) (xy 235.94477 -222.38183)
			(xy 235.9942 -222.397891) (xy 236.04051 -222.421487) (xy 236.082558 -222.452037) (xy 236.119309 -222.488788)
			(xy 236.149859 -222.530836) (xy 236.173455 -222.577146) (xy 236.189516 -222.626576) (xy 236.197646 -222.677911)
			(xy 236.198156 -222.703898) (xy 236.197646 -222.729885) (xy 236.189516 -222.78122) (xy 236.173455 -222.83065)
			(xy 236.149859 -222.87696) (xy 236.119309 -222.919008) (xy 236.082558 -222.955759) (xy 236.04051 -222.986309)
			(xy 235.9942 -223.009905) (xy 235.94477 -223.025966) (xy 235.893435 -223.034096) (xy 235.841461 -223.034096)
			(xy 235.790126 -223.025966) (xy 235.740696 -223.009905) (xy 235.694386 -222.986309) (xy 235.652338 -222.955759)
			(xy 235.615587 -222.919008) (xy 235.585037 -222.87696) (xy 235.561441 -222.83065) (xy 235.54538 -222.78122)
			(xy 235.53725 -222.729885) (xy 235.397546 -222.729885) (xy 235.389416 -222.78122) (xy 235.373355 -222.83065)
			(xy 235.349759 -222.87696) (xy 235.319209 -222.919008) (xy 235.282458 -222.955759) (xy 235.24041 -222.986309)
			(xy 235.1941 -223.009905) (xy 235.14467 -223.025966) (xy 235.093335 -223.034096) (xy 235.041361 -223.034096)
			(xy 234.990026 -223.025966) (xy 234.940596 -223.009905) (xy 234.894286 -222.986309) (xy 234.852238 -222.955759)
			(xy 234.815487 -222.919008) (xy 234.784937 -222.87696) (xy 234.761341 -222.83065) (xy 234.74528 -222.78122)
			(xy 234.73715 -222.729885) (xy 234.5977 -222.729885) (xy 234.58957 -222.78122) (xy 234.573509 -222.83065)
			(xy 234.549913 -222.87696) (xy 234.519363 -222.919008) (xy 234.482612 -222.955759) (xy 234.440564 -222.986309)
			(xy 234.394254 -223.009905) (xy 234.344824 -223.025966) (xy 234.293489 -223.034096) (xy 234.241515 -223.034096)
			(xy 234.19018 -223.025966) (xy 234.14075 -223.009905) (xy 234.09444 -222.986309) (xy 234.052392 -222.955759)
			(xy 234.015641 -222.919008) (xy 233.985091 -222.87696) (xy 233.961495 -222.83065) (xy 233.945434 -222.78122)
			(xy 233.937304 -222.729885) (xy 233.7976 -222.729885) (xy 233.78947 -222.78122) (xy 233.773409 -222.83065)
			(xy 233.749813 -222.87696) (xy 233.719263 -222.919008) (xy 233.682512 -222.955759) (xy 233.640464 -222.986309)
			(xy 233.594154 -223.009905) (xy 233.544724 -223.025966) (xy 233.493389 -223.034096) (xy 233.441415 -223.034096)
			(xy 233.39008 -223.025966) (xy 233.34065 -223.009905) (xy 233.29434 -222.986309) (xy 233.252292 -222.955759)
			(xy 233.215541 -222.919008) (xy 233.184991 -222.87696) (xy 233.161395 -222.83065) (xy 233.145334 -222.78122)
			(xy 233.137204 -222.729885) (xy 232.997754 -222.729885) (xy 232.989624 -222.78122) (xy 232.973563 -222.83065)
			(xy 232.949967 -222.87696) (xy 232.919417 -222.919008) (xy 232.882666 -222.955759) (xy 232.840618 -222.986309)
			(xy 232.794308 -223.009905) (xy 232.744878 -223.025966) (xy 232.693543 -223.034096) (xy 232.641569 -223.034096)
			(xy 232.590234 -223.025966) (xy 232.540804 -223.009905) (xy 232.494494 -222.986309) (xy 232.452446 -222.955759)
			(xy 232.415695 -222.919008) (xy 232.385145 -222.87696) (xy 232.361549 -222.83065) (xy 232.345488 -222.78122)
			(xy 232.337358 -222.729885) (xy 232.197654 -222.729885) (xy 232.189524 -222.78122) (xy 232.173463 -222.83065)
			(xy 232.149867 -222.87696) (xy 232.119317 -222.919008) (xy 232.082566 -222.955759) (xy 232.040518 -222.986309)
			(xy 231.994208 -223.009905) (xy 231.944778 -223.025966) (xy 231.893443 -223.034096) (xy 231.841469 -223.034096)
			(xy 231.790134 -223.025966) (xy 231.740704 -223.009905) (xy 231.694394 -222.986309) (xy 231.652346 -222.955759)
			(xy 231.615595 -222.919008) (xy 231.585045 -222.87696) (xy 231.561449 -222.83065) (xy 231.545388 -222.78122)
			(xy 231.537258 -222.729885) (xy 231.397554 -222.729885) (xy 231.389424 -222.78122) (xy 231.373363 -222.83065)
			(xy 231.349767 -222.87696) (xy 231.319217 -222.919008) (xy 231.282466 -222.955759) (xy 231.240418 -222.986309)
			(xy 231.194108 -223.009905) (xy 231.144678 -223.025966) (xy 231.093343 -223.034096) (xy 231.041369 -223.034096)
			(xy 230.990034 -223.025966) (xy 230.940604 -223.009905) (xy 230.894294 -222.986309) (xy 230.852246 -222.955759)
			(xy 230.815495 -222.919008) (xy 230.784945 -222.87696) (xy 230.761349 -222.83065) (xy 230.745288 -222.78122)
			(xy 230.737158 -222.729885) (xy 228.19817 -222.729885) (xy 228.19004 -222.78122) (xy 228.173979 -222.83065)
			(xy 228.150383 -222.87696) (xy 228.119833 -222.919008) (xy 228.083082 -222.955759) (xy 228.041034 -222.986309)
			(xy 227.994724 -223.009905) (xy 227.945294 -223.025966) (xy 227.893959 -223.034096) (xy 227.841985 -223.034096)
			(xy 227.79065 -223.025966) (xy 227.74122 -223.009905) (xy 227.69491 -222.986309) (xy 227.652862 -222.955759)
			(xy 227.616111 -222.919008) (xy 227.585561 -222.87696) (xy 227.561965 -222.83065) (xy 227.545904 -222.78122)
			(xy 227.537774 -222.729885) (xy 227.39807 -222.729885) (xy 227.38994 -222.78122) (xy 227.373879 -222.83065)
			(xy 227.350283 -222.87696) (xy 227.319733 -222.919008) (xy 227.282982 -222.955759) (xy 227.240934 -222.986309)
			(xy 227.194624 -223.009905) (xy 227.145194 -223.025966) (xy 227.093859 -223.034096) (xy 227.041885 -223.034096)
			(xy 226.99055 -223.025966) (xy 226.94112 -223.009905) (xy 226.89481 -222.986309) (xy 226.852762 -222.955759)
			(xy 226.816011 -222.919008) (xy 226.785461 -222.87696) (xy 226.761865 -222.83065) (xy 226.745804 -222.78122)
			(xy 226.737674 -222.729885) (xy 226.59797 -222.729885) (xy 226.58984 -222.78122) (xy 226.573779 -222.83065)
			(xy 226.550183 -222.87696) (xy 226.519633 -222.919008) (xy 226.482882 -222.955759) (xy 226.440834 -222.986309)
			(xy 226.394524 -223.009905) (xy 226.345094 -223.025966) (xy 226.293759 -223.034096) (xy 226.241785 -223.034096)
			(xy 226.19045 -223.025966) (xy 226.14102 -223.009905) (xy 226.09471 -222.986309) (xy 226.052662 -222.955759)
			(xy 226.015911 -222.919008) (xy 225.985361 -222.87696) (xy 225.961765 -222.83065) (xy 225.945704 -222.78122)
			(xy 225.937574 -222.729885) (xy 225.798124 -222.729885) (xy 225.789994 -222.78122) (xy 225.773933 -222.83065)
			(xy 225.750337 -222.87696) (xy 225.719787 -222.919008) (xy 225.683036 -222.955759) (xy 225.640988 -222.986309)
			(xy 225.594678 -223.009905) (xy 225.545248 -223.025966) (xy 225.493913 -223.034096) (xy 225.441939 -223.034096)
			(xy 225.390604 -223.025966) (xy 225.341174 -223.009905) (xy 225.294864 -222.986309) (xy 225.252816 -222.955759)
			(xy 225.216065 -222.919008) (xy 225.185515 -222.87696) (xy 225.161919 -222.83065) (xy 225.145858 -222.78122)
			(xy 225.137728 -222.729885) (xy 224.998024 -222.729885) (xy 224.989894 -222.78122) (xy 224.973833 -222.83065)
			(xy 224.950237 -222.87696) (xy 224.919687 -222.919008) (xy 224.882936 -222.955759) (xy 224.840888 -222.986309)
			(xy 224.794578 -223.009905) (xy 224.745148 -223.025966) (xy 224.693813 -223.034096) (xy 224.641839 -223.034096)
			(xy 224.590504 -223.025966) (xy 224.541074 -223.009905) (xy 224.494764 -222.986309) (xy 224.452716 -222.955759)
			(xy 224.415965 -222.919008) (xy 224.385415 -222.87696) (xy 224.361819 -222.83065) (xy 224.345758 -222.78122)
			(xy 224.337628 -222.729885) (xy 224.198178 -222.729885) (xy 224.190048 -222.78122) (xy 224.173987 -222.83065)
			(xy 224.150391 -222.87696) (xy 224.119841 -222.919008) (xy 224.08309 -222.955759) (xy 224.041042 -222.986309)
			(xy 223.994732 -223.009905) (xy 223.945302 -223.025966) (xy 223.893967 -223.034096) (xy 223.841993 -223.034096)
			(xy 223.790658 -223.025966) (xy 223.741228 -223.009905) (xy 223.694918 -222.986309) (xy 223.65287 -222.955759)
			(xy 223.616119 -222.919008) (xy 223.585569 -222.87696) (xy 223.561973 -222.83065) (xy 223.545912 -222.78122)
			(xy 223.537782 -222.729885) (xy 223.276262 -222.729885) (xy 223.267207 -222.757752) (xy 223.243611 -222.804062)
			(xy 223.213061 -222.84611) (xy 223.17631 -222.882861) (xy 223.134262 -222.913411) (xy 223.087952 -222.937007)
			(xy 223.038522 -222.953068) (xy 222.987187 -222.961198) (xy 222.935213 -222.961198) (xy 222.883878 -222.953068)
			(xy 222.834448 -222.937007) (xy 222.788138 -222.913411) (xy 222.74609 -222.882861) (xy 222.709339 -222.84611)
			(xy 222.678789 -222.804062) (xy 222.655193 -222.757752) (xy 222.639132 -222.708322) (xy 222.631002 -222.656987)
			(xy 220.367685 -222.656987) (xy 220.80915 -223.098452) (xy 236.54256 -223.098452) (xy 236.54256 -223.043948)
			(xy 236.550316 -222.99) (xy 236.565671 -222.937704) (xy 236.588312 -222.888126) (xy 236.617778 -222.842274)
			(xy 236.653469 -222.801083) (xy 236.694658 -222.76539) (xy 236.740508 -222.735921) (xy 236.790085 -222.713278)
			(xy 236.84238 -222.69792) (xy 236.896328 -222.690161) (xy 236.92358 -222.689674) (xy 236.95333 -222.690233)
			(xy 237.01211 -222.699462) (xy 237.068747 -222.717699) (xy 237.121868 -222.744502) (xy 237.170187 -222.779224)
			(xy 237.212534 -222.821021) (xy 237.230666 -222.844614) (xy 237.237524 -222.854266) (xy 237.258098 -222.864934)
			(xy 237.36173 -222.867728) (xy 237.383066 -222.85833) (xy 237.390432 -222.849186) (xy 237.408678 -222.827986)
			(xy 237.450261 -222.790582) (xy 237.496858 -222.759647) (xy 237.547471 -222.735844) (xy 237.601015 -222.719681)
			(xy 237.656345 -222.711506) (xy 237.68431 -222.71101) (xy 237.711562 -222.711461) (xy 237.765511 -222.719219)
			(xy 237.817807 -222.734575) (xy 237.867386 -222.757218) (xy 237.913237 -222.786686) (xy 237.954428 -222.822379)
			(xy 237.99012 -222.863571) (xy 238.019587 -222.909423) (xy 238.042228 -222.959002) (xy 238.057584 -223.011299)
			(xy 238.06534 -223.065248) (xy 238.06534 -223.119752) (xy 238.057584 -223.173701) (xy 238.042228 -223.225998)
			(xy 238.019587 -223.275577) (xy 237.99012 -223.321429) (xy 237.954428 -223.362621) (xy 237.913237 -223.398314)
			(xy 237.867386 -223.427782) (xy 237.817807 -223.450425) (xy 237.765511 -223.465781) (xy 237.711562 -223.473539)
			(xy 237.68431 -223.474026) (xy 237.65456 -223.473474) (xy 237.595779 -223.464244) (xy 237.539142 -223.446006)
			(xy 237.486021 -223.4192) (xy 237.437702 -223.384478) (xy 237.395356 -223.342679) (xy 237.377224 -223.319086)
			(xy 237.370366 -223.309434) (xy 237.349792 -223.298766) (xy 237.24616 -223.295972) (xy 237.224824 -223.30537)
			(xy 237.217458 -223.314514) (xy 237.199217 -223.335718) (xy 237.157633 -223.373122) (xy 237.111035 -223.404056)
			(xy 237.060422 -223.427859) (xy 237.006876 -223.444021) (xy 236.951545 -223.452195) (xy 236.92358 -223.45269)
			(xy 236.896328 -223.452239) (xy 236.84238 -223.44448) (xy 236.790085 -223.429122) (xy 236.740508 -223.406479)
			(xy 236.694658 -223.37701) (xy 236.653469 -223.341317) (xy 236.617778 -223.300126) (xy 236.588312 -223.254274)
			(xy 236.565671 -223.204696) (xy 236.550316 -223.1524) (xy 236.54256 -223.098452) (xy 220.80915 -223.098452)
			(xy 221.291658 -223.58096) (xy 221.2975 -223.586802) (xy 221.2975 -223.587056) (xy 221.298516 -223.588072)
			(xy 221.30201 -223.59153) (xy 221.310068 -223.59716) (xy 221.314518 -223.599248) (xy 221.332298 -223.607122)
			(xy 221.337195 -223.609158) (xy 221.34757 -223.611344) (xy 221.352872 -223.61144) (xy 224.235518 -223.61144)
			(xy 224.245307 -223.610998) (xy 224.26347 -223.60369) (xy 224.270824 -223.597216) (xy 224.271332 -223.596708)
			(xy 224.322386 -223.544892) (xy 224.322894 -223.544384) (xy 224.329375 -223.537032) (xy 224.336694 -223.51887)
			(xy 224.337118 -223.509078) (xy 224.337118 -223.503998) (xy 224.337628 -223.478011) (xy 224.345758 -223.426676)
			(xy 224.361819 -223.377246) (xy 224.385415 -223.330936) (xy 224.415965 -223.288888) (xy 224.452716 -223.252137)
			(xy 224.494764 -223.221587) (xy 224.541074 -223.197991) (xy 224.590504 -223.18193) (xy 224.641839 -223.1738)
			(xy 224.693813 -223.1738) (xy 224.745148 -223.18193) (xy 224.794578 -223.197991) (xy 224.840888 -223.221587)
			(xy 224.882936 -223.252137) (xy 224.919687 -223.288888) (xy 224.950237 -223.330936) (xy 224.973833 -223.377246)
			(xy 224.989894 -223.426676) (xy 224.998024 -223.478011) (xy 224.998534 -223.503998) (xy 224.998534 -223.50476)
			(xy 224.998475 -223.515201) (xy 224.997202 -223.536045) (xy 224.995994 -223.546416) (xy 224.995486 -223.549464)
			(xy 224.995486 -223.549718) (xy 224.99447 -223.55683) (xy 224.99447 -223.56064) (xy 224.994964 -223.570645)
			(xy 225.00263 -223.589128) (xy 225.016781 -223.603276) (xy 225.035265 -223.610938) (xy 225.04527 -223.61144)
			(xy 225.090482 -223.61144) (xy 225.100495 -223.610956) (xy 225.119 -223.603301) (xy 225.133168 -223.589149)
			(xy 225.140844 -223.570652) (xy 225.141282 -223.56064) (xy 225.141282 -223.55683) (xy 225.140266 -223.549718)
			(xy 225.140266 -223.549464) (xy 225.139758 -223.546416) (xy 225.138547 -223.536045) (xy 225.137273 -223.515201)
			(xy 225.137218 -223.50476) (xy 225.137218 -223.503998) (xy 225.137728 -223.478011) (xy 225.145858 -223.426676)
			(xy 225.161919 -223.377246) (xy 225.185515 -223.330936) (xy 225.216065 -223.288888) (xy 225.252816 -223.252137)
			(xy 225.294864 -223.221587) (xy 225.341174 -223.197991) (xy 225.390604 -223.18193) (xy 225.441939 -223.1738)
			(xy 225.493913 -223.1738) (xy 225.545248 -223.18193) (xy 225.594678 -223.197991) (xy 225.640988 -223.221587)
			(xy 225.683036 -223.252137) (xy 225.719787 -223.288888) (xy 225.750337 -223.330936) (xy 225.773933 -223.377246)
			(xy 225.789994 -223.426676) (xy 225.798124 -223.478011) (xy 225.798634 -223.503998) (xy 225.798634 -223.50476)
			(xy 225.798575 -223.515201) (xy 225.797302 -223.536045) (xy 225.796094 -223.546416) (xy 225.795586 -223.549464)
			(xy 225.795586 -223.549718) (xy 225.79457 -223.55683) (xy 225.79457 -223.56064) (xy 225.795064 -223.570645)
			(xy 225.80273 -223.589128) (xy 225.816881 -223.603276) (xy 225.835365 -223.610938) (xy 225.84537 -223.61144)
			(xy 225.890328 -223.61144) (xy 225.900335 -223.610948) (xy 225.918824 -223.603285) (xy 225.932978 -223.589134)
			(xy 225.940645 -223.570647) (xy 225.941128 -223.56064) (xy 225.941128 -223.55683) (xy 225.940112 -223.549718)
			(xy 225.940112 -223.549464) (xy 225.939604 -223.546416) (xy 225.938393 -223.536045) (xy 225.937119 -223.515201)
			(xy 225.937064 -223.50476) (xy 225.937064 -223.503998) (xy 225.937574 -223.478011) (xy 225.945704 -223.426676)
			(xy 225.961765 -223.377246) (xy 225.985361 -223.330936) (xy 226.015911 -223.288888) (xy 226.052662 -223.252137)
			(xy 226.09471 -223.221587) (xy 226.14102 -223.197991) (xy 226.19045 -223.18193) (xy 226.241785 -223.1738)
			(xy 226.293759 -223.1738) (xy 226.345094 -223.18193) (xy 226.394524 -223.197991) (xy 226.440834 -223.221587)
			(xy 226.482882 -223.252137) (xy 226.519633 -223.288888) (xy 226.550183 -223.330936) (xy 226.573779 -223.377246)
			(xy 226.58984 -223.426676) (xy 226.59797 -223.478011) (xy 226.59848 -223.503998) (xy 226.59848 -223.50476)
			(xy 226.598421 -223.515201) (xy 226.597148 -223.536045) (xy 226.59594 -223.546416) (xy 226.595432 -223.549464)
			(xy 226.595432 -223.549718) (xy 226.594416 -223.55683) (xy 226.594416 -223.56064) (xy 226.594911 -223.570641)
			(xy 226.602578 -223.589117) (xy 226.616731 -223.603253) (xy 226.635214 -223.6109) (xy 226.645216 -223.61144)
			(xy 226.690428 -223.61144) (xy 226.700435 -223.610948) (xy 226.718924 -223.603285) (xy 226.733078 -223.589134)
			(xy 226.740745 -223.570647) (xy 226.741228 -223.56064) (xy 226.741228 -223.55683) (xy 226.740212 -223.549718)
			(xy 226.740212 -223.549464) (xy 226.739704 -223.546416) (xy 226.738493 -223.536045) (xy 226.737219 -223.515201)
			(xy 226.737164 -223.50476) (xy 226.737164 -223.503998) (xy 226.737674 -223.478011) (xy 226.745804 -223.426676)
			(xy 226.761865 -223.377246) (xy 226.785461 -223.330936) (xy 226.816011 -223.288888) (xy 226.852762 -223.252137)
			(xy 226.89481 -223.221587) (xy 226.94112 -223.197991) (xy 226.99055 -223.18193) (xy 227.041885 -223.1738)
			(xy 227.093859 -223.1738) (xy 227.145194 -223.18193) (xy 227.194624 -223.197991) (xy 227.240934 -223.221587)
			(xy 227.282982 -223.252137) (xy 227.319733 -223.288888) (xy 227.350283 -223.330936) (xy 227.373879 -223.377246)
			(xy 227.38994 -223.426676) (xy 227.39807 -223.478011) (xy 227.39858 -223.503998) (xy 227.39858 -223.50476)
			(xy 227.398521 -223.515201) (xy 227.397248 -223.536045) (xy 227.39604 -223.546416) (xy 227.395532 -223.549464)
			(xy 227.395532 -223.549718) (xy 227.394516 -223.55683) (xy 227.394516 -223.56064) (xy 227.395011 -223.570641)
			(xy 227.402678 -223.589117) (xy 227.416831 -223.603253) (xy 227.435314 -223.6109) (xy 227.445316 -223.61144)
			(xy 227.490528 -223.61144) (xy 227.500535 -223.610948) (xy 227.519024 -223.603285) (xy 227.533178 -223.589134)
			(xy 227.540845 -223.570647) (xy 227.541328 -223.56064) (xy 227.541328 -223.55683) (xy 227.540312 -223.549718)
			(xy 227.540312 -223.549464) (xy 227.539804 -223.546416) (xy 227.538593 -223.536045) (xy 227.537319 -223.515201)
			(xy 227.537264 -223.50476) (xy 227.537264 -223.503998) (xy 227.537774 -223.478011) (xy 227.545904 -223.426676)
			(xy 227.561965 -223.377246) (xy 227.585561 -223.330936) (xy 227.616111 -223.288888) (xy 227.652862 -223.252137)
			(xy 227.69491 -223.221587) (xy 227.74122 -223.197991) (xy 227.79065 -223.18193) (xy 227.841985 -223.1738)
			(xy 227.893959 -223.1738) (xy 227.945294 -223.18193) (xy 227.994724 -223.197991) (xy 228.041034 -223.221587)
			(xy 228.083082 -223.252137) (xy 228.119833 -223.288888) (xy 228.150383 -223.330936) (xy 228.173979 -223.377246)
			(xy 228.19004 -223.426676) (xy 228.19817 -223.478011) (xy 228.19868 -223.503998) (xy 228.19868 -223.50476)
			(xy 228.198621 -223.515201) (xy 228.197348 -223.536045) (xy 228.19614 -223.546416) (xy 228.195632 -223.549464)
			(xy 228.195632 -223.549718) (xy 228.194616 -223.55683) (xy 228.194616 -223.56064) (xy 228.195111 -223.570641)
			(xy 228.202778 -223.589117) (xy 228.216931 -223.603253) (xy 228.235414 -223.6109) (xy 228.245416 -223.61144)
			(xy 228.290374 -223.61144) (xy 228.300388 -223.610957) (xy 228.318896 -223.603304) (xy 228.333066 -223.589151)
			(xy 228.340744 -223.570653) (xy 228.341174 -223.56064) (xy 228.341174 -223.55683) (xy 228.340158 -223.549718)
			(xy 228.340158 -223.549464) (xy 228.33965 -223.546416) (xy 228.338439 -223.536045) (xy 228.337165 -223.515201)
			(xy 228.33711 -223.50476) (xy 228.33711 -223.503998) (xy 228.33762 -223.478011) (xy 228.34575 -223.426676)
			(xy 228.361811 -223.377246) (xy 228.385407 -223.330936) (xy 228.415957 -223.288888) (xy 228.452708 -223.252137)
			(xy 228.494756 -223.221587) (xy 228.541066 -223.197991) (xy 228.590496 -223.18193) (xy 228.641831 -223.1738)
			(xy 228.693805 -223.1738) (xy 228.74514 -223.18193) (xy 228.79457 -223.197991) (xy 228.84088 -223.221587)
			(xy 228.882928 -223.252137) (xy 228.919679 -223.288888) (xy 228.950229 -223.330936) (xy 228.973825 -223.377246)
			(xy 228.989886 -223.426676) (xy 228.998016 -223.478011) (xy 228.998526 -223.503998) (xy 228.998526 -223.509078)
			(xy 228.998997 -223.51895) (xy 229.006459 -223.537231) (xy 229.013004 -223.544638) (xy 229.063804 -223.5962)
			(xy 229.07123 -223.603146) (xy 229.089967 -223.611002) (xy 229.100126 -223.61144) (xy 229.835202 -223.61144)
			(xy 229.844992 -223.611001) (xy 229.863159 -223.603697) (xy 229.870508 -223.597216) (xy 229.871016 -223.596708)
			(xy 229.92207 -223.544892) (xy 229.922578 -223.544384) (xy 229.929061 -223.537032) (xy 229.936381 -223.51887)
			(xy 229.936802 -223.509078) (xy 229.936802 -223.503998) (xy 229.937312 -223.478011) (xy 229.945442 -223.426676)
			(xy 229.961503 -223.377246) (xy 229.985099 -223.330936) (xy 230.015649 -223.288888) (xy 230.0524 -223.252137)
			(xy 230.094448 -223.221587) (xy 230.140758 -223.197991) (xy 230.190188 -223.18193) (xy 230.241523 -223.1738)
			(xy 230.293497 -223.1738) (xy 230.344832 -223.18193) (xy 230.394262 -223.197991) (xy 230.440572 -223.221587)
			(xy 230.48262 -223.252137) (xy 230.519371 -223.288888) (xy 230.549921 -223.330936) (xy 230.573517 -223.377246)
			(xy 230.589578 -223.426676) (xy 230.597708 -223.478011) (xy 230.598218 -223.503998) (xy 230.598218 -223.50476)
			(xy 230.598159 -223.515201) (xy 230.596886 -223.536045) (xy 230.595678 -223.546416) (xy 230.59517 -223.549464)
			(xy 230.59517 -223.549718) (xy 230.594154 -223.55683) (xy 230.594154 -223.56064) (xy 230.594648 -223.570646)
			(xy 230.602313 -223.589132) (xy 230.616463 -223.603283) (xy 230.634948 -223.61095) (xy 230.644954 -223.61144)
			(xy 230.689912 -223.61144) (xy 230.699921 -223.61095) (xy 230.718416 -223.60329) (xy 230.732574 -223.589139)
			(xy 230.740245 -223.570649) (xy 230.740712 -223.56064) (xy 230.740712 -223.55683) (xy 230.739696 -223.549718)
			(xy 230.739696 -223.549464) (xy 230.739188 -223.546416) (xy 230.737977 -223.536045) (xy 230.736703 -223.515201)
			(xy 230.736648 -223.50476) (xy 230.736648 -223.503998) (xy 230.737158 -223.478011) (xy 230.745288 -223.426676)
			(xy 230.761349 -223.377246) (xy 230.784945 -223.330936) (xy 230.815495 -223.288888) (xy 230.852246 -223.252137)
			(xy 230.894294 -223.221587) (xy 230.940604 -223.197991) (xy 230.990034 -223.18193) (xy 231.041369 -223.1738)
			(xy 231.093343 -223.1738) (xy 231.144678 -223.18193) (xy 231.194108 -223.197991) (xy 231.240418 -223.221587)
			(xy 231.282466 -223.252137) (xy 231.319217 -223.288888) (xy 231.349767 -223.330936) (xy 231.373363 -223.377246)
			(xy 231.389424 -223.426676) (xy 231.397554 -223.478011) (xy 231.398064 -223.503998) (xy 231.398064 -223.50476)
			(xy 231.398005 -223.515201) (xy 231.396732 -223.536045) (xy 231.395524 -223.546416) (xy 231.395016 -223.549464)
			(xy 231.395016 -223.549718) (xy 231.394 -223.55683) (xy 231.394 -223.56064) (xy 231.394495 -223.570642)
			(xy 231.402162 -223.58912) (xy 231.416313 -223.603261) (xy 231.434797 -223.610913) (xy 231.4448 -223.61144)
			(xy 231.490012 -223.61144) (xy 231.500021 -223.61095) (xy 231.518516 -223.60329) (xy 231.532674 -223.589139)
			(xy 231.540345 -223.570649) (xy 231.540812 -223.56064) (xy 231.540812 -223.55683) (xy 231.539796 -223.549718)
			(xy 231.539796 -223.549464) (xy 231.539288 -223.546416) (xy 231.538077 -223.536045) (xy 231.536803 -223.515201)
			(xy 231.536748 -223.50476) (xy 231.536748 -223.503998) (xy 231.537258 -223.478011) (xy 231.545388 -223.426676)
			(xy 231.561449 -223.377246) (xy 231.585045 -223.330936) (xy 231.615595 -223.288888) (xy 231.652346 -223.252137)
			(xy 231.694394 -223.221587) (xy 231.740704 -223.197991) (xy 231.790134 -223.18193) (xy 231.841469 -223.1738)
			(xy 231.893443 -223.1738) (xy 231.944778 -223.18193) (xy 231.994208 -223.197991) (xy 232.040518 -223.221587)
			(xy 232.082566 -223.252137) (xy 232.119317 -223.288888) (xy 232.149867 -223.330936) (xy 232.173463 -223.377246)
			(xy 232.189524 -223.426676) (xy 232.197654 -223.478011) (xy 232.198164 -223.503998) (xy 232.198164 -223.50476)
			(xy 232.198105 -223.515201) (xy 232.196832 -223.536045) (xy 232.195624 -223.546416) (xy 232.195116 -223.549464)
			(xy 232.195116 -223.549718) (xy 232.1941 -223.55683) (xy 232.1941 -223.56064) (xy 232.194595 -223.570642)
			(xy 232.202262 -223.58912) (xy 232.216413 -223.603261) (xy 232.234897 -223.610913) (xy 232.2449 -223.61144)
			(xy 232.290112 -223.61144) (xy 232.300121 -223.61095) (xy 232.318616 -223.60329) (xy 232.332774 -223.589139)
			(xy 232.340445 -223.570649) (xy 232.340912 -223.56064) (xy 232.340912 -223.55683) (xy 232.339896 -223.549718)
			(xy 232.339896 -223.549464) (xy 232.339388 -223.546416) (xy 232.338177 -223.536045) (xy 232.336903 -223.515201)
			(xy 232.336848 -223.50476) (xy 232.336848 -223.503998) (xy 232.337358 -223.478011) (xy 232.345488 -223.426676)
			(xy 232.361549 -223.377246) (xy 232.385145 -223.330936) (xy 232.415695 -223.288888) (xy 232.452446 -223.252137)
			(xy 232.494494 -223.221587) (xy 232.540804 -223.197991) (xy 232.590234 -223.18193) (xy 232.641569 -223.1738)
			(xy 232.693543 -223.1738) (xy 232.744878 -223.18193) (xy 232.794308 -223.197991) (xy 232.840618 -223.221587)
			(xy 232.882666 -223.252137) (xy 232.919417 -223.288888) (xy 232.949967 -223.330936) (xy 232.973563 -223.377246)
			(xy 232.989624 -223.426676) (xy 232.997754 -223.478011) (xy 232.998264 -223.503998) (xy 232.998264 -223.50476)
			(xy 232.998205 -223.515201) (xy 232.996932 -223.536045) (xy 232.995724 -223.546416) (xy 232.995216 -223.549464)
			(xy 232.995216 -223.549718) (xy 232.9942 -223.55683) (xy 232.9942 -223.56064) (xy 232.994695 -223.570642)
			(xy 233.002362 -223.58912) (xy 233.016513 -223.603261) (xy 233.034997 -223.610913) (xy 233.045 -223.61144)
			(xy 233.089958 -223.61144) (xy 233.099988 -223.611028) (xy 233.118526 -223.603367) (xy 233.132721 -223.589195)
			(xy 233.140412 -223.570669) (xy 233.140758 -223.56064) (xy 233.140758 -223.55683) (xy 233.139742 -223.549718)
			(xy 233.139742 -223.549464) (xy 233.139234 -223.546416) (xy 233.138023 -223.536045) (xy 233.136749 -223.515201)
			(xy 233.136694 -223.50476) (xy 233.136694 -223.503998) (xy 233.137204 -223.478011) (xy 233.145334 -223.426676)
			(xy 233.161395 -223.377246) (xy 233.184991 -223.330936) (xy 233.215541 -223.288888) (xy 233.252292 -223.252137)
			(xy 233.29434 -223.221587) (xy 233.34065 -223.197991) (xy 233.39008 -223.18193) (xy 233.441415 -223.1738)
			(xy 233.493389 -223.1738) (xy 233.544724 -223.18193) (xy 233.594154 -223.197991) (xy 233.640464 -223.221587)
			(xy 233.682512 -223.252137) (xy 233.719263 -223.288888) (xy 233.749813 -223.330936) (xy 233.773409 -223.377246)
			(xy 233.78947 -223.426676) (xy 233.7976 -223.478011) (xy 233.79811 -223.503998) (xy 233.79811 -223.50476)
			(xy 233.798051 -223.515201) (xy 233.796778 -223.536045) (xy 233.79557 -223.546416) (xy 233.795062 -223.549464)
			(xy 233.795062 -223.549718) (xy 233.794046 -223.55683) (xy 233.794046 -223.56064) (xy 233.794473 -223.570653)
			(xy 233.802152 -223.589148) (xy 233.816324 -223.603296) (xy 233.834833 -223.610944) (xy 233.844846 -223.61144)
			(xy 233.890058 -223.61144) (xy 233.900088 -223.611028) (xy 233.918626 -223.603367) (xy 233.932821 -223.589195)
			(xy 233.940512 -223.570669) (xy 233.940858 -223.56064) (xy 233.940858 -223.55683) (xy 233.939842 -223.549718)
			(xy 233.939842 -223.549464) (xy 233.939334 -223.546416) (xy 233.938123 -223.536045) (xy 233.936849 -223.515201)
			(xy 233.936794 -223.50476) (xy 233.936794 -223.503998) (xy 233.937304 -223.478011) (xy 233.945434 -223.426676)
			(xy 233.961495 -223.377246) (xy 233.985091 -223.330936) (xy 234.015641 -223.288888) (xy 234.052392 -223.252137)
			(xy 234.09444 -223.221587) (xy 234.14075 -223.197991) (xy 234.19018 -223.18193) (xy 234.241515 -223.1738)
			(xy 234.293489 -223.1738) (xy 234.344824 -223.18193) (xy 234.394254 -223.197991) (xy 234.440564 -223.221587)
			(xy 234.482612 -223.252137) (xy 234.519363 -223.288888) (xy 234.549913 -223.330936) (xy 234.573509 -223.377246)
			(xy 234.58957 -223.426676) (xy 234.5977 -223.478011) (xy 234.59821 -223.503998) (xy 234.59821 -223.50476)
			(xy 234.598151 -223.515201) (xy 234.596878 -223.536045) (xy 234.59567 -223.546416) (xy 234.595162 -223.549464)
			(xy 234.595162 -223.549718) (xy 234.594146 -223.55683) (xy 234.594146 -223.56064) (xy 234.594573 -223.570653)
			(xy 234.602252 -223.589148) (xy 234.616424 -223.603296) (xy 234.634933 -223.610944) (xy 234.644946 -223.61144)
			(xy 234.689904 -223.61144) (xy 234.699914 -223.610952) (xy 234.718411 -223.603293) (xy 234.732573 -223.589142)
			(xy 234.740245 -223.57065) (xy 234.740704 -223.56064) (xy 234.740704 -223.55683) (xy 234.739688 -223.549718)
			(xy 234.739688 -223.549464) (xy 234.73918 -223.546416) (xy 234.737969 -223.536045) (xy 234.736695 -223.515201)
			(xy 234.73664 -223.50476) (xy 234.73664 -223.503998) (xy 234.73715 -223.478011) (xy 234.74528 -223.426676)
			(xy 234.761341 -223.377246) (xy 234.784937 -223.330936) (xy 234.815487 -223.288888) (xy 234.852238 -223.252137)
			(xy 234.894286 -223.221587) (xy 234.940596 -223.197991) (xy 234.990026 -223.18193) (xy 235.041361 -223.1738)
			(xy 235.093335 -223.1738) (xy 235.14467 -223.18193) (xy 235.1941 -223.197991) (xy 235.24041 -223.221587)
			(xy 235.282458 -223.252137) (xy 235.319209 -223.288888) (xy 235.349759 -223.330936) (xy 235.373355 -223.377246)
			(xy 235.389416 -223.426676) (xy 235.397546 -223.478011) (xy 235.398056 -223.503998) (xy 235.398056 -223.50476)
			(xy 235.397997 -223.515201) (xy 235.396724 -223.536045) (xy 235.395516 -223.546416) (xy 235.395008 -223.549464)
			(xy 235.395008 -223.549718) (xy 235.393992 -223.55683) (xy 235.393992 -223.56064) (xy 235.394487 -223.570643)
			(xy 235.402153 -223.589122) (xy 235.416305 -223.603265) (xy 235.434789 -223.610919) (xy 235.444792 -223.61144)
			(xy 235.490004 -223.61144) (xy 235.500014 -223.610952) (xy 235.518511 -223.603293) (xy 235.532673 -223.589142)
			(xy 235.540345 -223.57065) (xy 235.540804 -223.56064) (xy 235.540804 -223.55683) (xy 235.539788 -223.549718)
			(xy 235.539788 -223.549464) (xy 235.53928 -223.546416) (xy 235.538069 -223.536045) (xy 235.536795 -223.515201)
			(xy 235.53674 -223.50476) (xy 235.53674 -223.503998) (xy 235.53725 -223.478011) (xy 235.54538 -223.426676)
			(xy 235.561441 -223.377246) (xy 235.585037 -223.330936) (xy 235.615587 -223.288888) (xy 235.652338 -223.252137)
			(xy 235.694386 -223.221587) (xy 235.740696 -223.197991) (xy 235.790126 -223.18193) (xy 235.841461 -223.1738)
			(xy 235.893435 -223.1738) (xy 235.94477 -223.18193) (xy 235.9942 -223.197991) (xy 236.04051 -223.221587)
			(xy 236.082558 -223.252137) (xy 236.119309 -223.288888) (xy 236.149859 -223.330936) (xy 236.173455 -223.377246)
			(xy 236.189516 -223.426676) (xy 236.197646 -223.478011) (xy 236.198156 -223.503998) (xy 236.198156 -223.509078)
			(xy 236.198626 -223.518951) (xy 236.206079 -223.537238) (xy 236.212634 -223.544638) (xy 236.263434 -223.5962)
			(xy 236.270862 -223.603142) (xy 236.289598 -223.610986) (xy 236.299756 -223.61144) (xy 239.960404 -223.61144)
			(xy 239.987836 -223.590358) (xy 239.992154 -223.573594) (xy 239.999715 -223.546762) (xy 240.02155 -223.495472)
			(xy 240.050617 -223.447905) (xy 240.086296 -223.405074) (xy 240.127828 -223.367892) (xy 240.174329 -223.337149)
			(xy 240.224809 -223.3135) (xy 240.278192 -223.297449) (xy 240.333344 -223.289337) (xy 240.389088 -223.289337)
			(xy 240.44424 -223.297449) (xy 240.497623 -223.3135) (xy 240.548103 -223.337149) (xy 240.594604 -223.367892)
			(xy 240.636136 -223.405074) (xy 240.671815 -223.447905) (xy 240.700882 -223.495472) (xy 240.722717 -223.546762)
			(xy 240.730278 -223.573594) (xy 240.734596 -223.590358) (xy 240.762028 -223.61144) (xy 246.97436 -223.61144)
			(xy 246.982742 -223.610678) (xy 246.99035 -223.60917) (xy 247.004193 -223.602193) (xy 247.00992 -223.596962)
			(xy 249.7836 -220.823282) (xy 249.790443 -220.815882) (xy 249.798171 -220.797284) (xy 249.798586 -220.787214)
			(xy 249.798586 -220.769688) (xy 249.7963 -220.76156) (xy 249.789306 -220.735895) (xy 249.781656 -220.683253)
			(xy 249.78106 -220.656658) (xy 249.78106 -220.651324) (xy 249.781775 -220.6244) (xy 249.789848 -220.57115)
			(xy 249.80533 -220.519564) (xy 249.827912 -220.470667) (xy 249.857145 -220.425433) (xy 249.89245 -220.384758)
			(xy 249.933123 -220.349453) (xy 249.978357 -220.320218) (xy 250.027252 -220.297634) (xy 250.078838 -220.282151)
			(xy 250.132088 -220.274076) (xy 250.159012 -220.273372) (xy 250.16333 -220.273372) (xy 250.192302 -220.273929)
			(xy 250.249574 -220.282728) (xy 250.277376 -220.290898) (xy 250.291092 -220.295216) (xy 250.318524 -220.288358)
			(xy 252.350778 -218.256104) (xy 252.351286 -218.255596) (xy 252.357857 -218.248211) (xy 252.365284 -218.229912)
			(xy 252.365764 -218.220036) (xy 252.365764 -212.09889) (xy 252.365287 -212.088552) (xy 252.357171 -212.069535)
			(xy 252.350016 -212.06206) (xy 252.296422 -212.01126) (xy 252.292607 -212.007851) (xy 252.283907 -212.002472)
			(xy 252.27915 -212.000592) (xy 252.270514 -211.99729) (xy 252.25502 -211.99729) (xy 252.238002 -211.997798)
			(xy 252.237494 -211.997798) (xy 252.210244 -211.997311) (xy 252.156298 -211.989554) (xy 252.104006 -211.974199)
			(xy 252.05443 -211.951558) (xy 252.008582 -211.922093) (xy 251.967394 -211.886402) (xy 251.931704 -211.845213)
			(xy 251.902239 -211.799364) (xy 251.879599 -211.749789) (xy 251.864244 -211.697496) (xy 251.856488 -211.64355)
			(xy 251.856488 -211.58905) (xy 251.864244 -211.535104) (xy 251.879599 -211.482811) (xy 251.902239 -211.433236)
			(xy 251.931704 -211.387387) (xy 251.967394 -211.346198) (xy 252.008582 -211.310507) (xy 252.05443 -211.281042)
			(xy 252.104006 -211.258401) (xy 252.156298 -211.243046) (xy 252.210244 -211.235289) (xy 252.237494 -211.234782)
			(xy 252.258576 -211.23529) (xy 252.25883 -211.23529) (xy 252.269104 -211.235341) (xy 252.288371 -211.228264)
			(xy 252.296168 -211.221574) (xy 252.349762 -211.170774) (xy 252.356984 -211.163323) (xy 252.365233 -211.144308)
			(xy 252.365764 -211.133944) (xy 252.365764 -210.94192) (xy 252.35027 -210.917282) (xy 252.336808 -210.910932)
			(xy 252.312653 -210.898998) (xy 252.267671 -210.869347) (xy 252.227308 -210.833662) (xy 252.192366 -210.792654)
			(xy 252.16354 -210.747139) (xy 252.141403 -210.698021) (xy 252.126397 -210.646278) (xy 252.118818 -210.592938)
			(xy 252.118818 -210.539062) (xy 252.126397 -210.485722) (xy 252.141403 -210.433979) (xy 252.16354 -210.384861)
			(xy 252.192366 -210.339346) (xy 252.227308 -210.298338) (xy 252.267671 -210.262653) (xy 252.312653 -210.233002)
			(xy 252.336808 -210.221068) (xy 252.35027 -210.214718) (xy 252.365764 -210.19008) (xy 252.365764 -206.362046)
			(xy 252.36533 -206.351981) (xy 252.357598 -206.333394) (xy 252.350778 -206.325978) (xy 252.335538 -206.310738)
			(xy 252.32741 -206.306928) (xy 252.303105 -206.295048) (xy 252.257823 -206.265451) (xy 252.217174 -206.229755)
			(xy 252.181973 -206.188677) (xy 252.152926 -206.143039) (xy 252.130615 -206.093757) (xy 252.115487 -206.041818)
			(xy 252.107845 -205.988263) (xy 252.107843 -205.934166) (xy 252.115481 -205.88061) (xy 252.130605 -205.82867)
			(xy 252.152912 -205.779386) (xy 252.181956 -205.733746) (xy 252.217153 -205.692665) (xy 252.2578 -205.656967)
			(xy 252.30308 -205.627366) (xy 252.32741 -205.61554) (xy 252.335538 -205.61173) (xy 252.350778 -205.59649)
			(xy 252.351286 -205.595982) (xy 252.35787 -205.588601) (xy 252.365328 -205.570303) (xy 252.365764 -205.560422)
			(xy 252.365764 -205.105508) (xy 252.358144 -205.086712) (xy 252.350778 -205.0796) (xy 250.814332 -203.543154)
			(xy 250.80722 -203.535788) (xy 250.788424 -203.528168) (xy 248.680224 -203.528168) (xy 248.668557 -203.528736)
			(xy 248.647633 -203.539059) (xy 248.640092 -203.54798) (xy 248.583704 -203.621386) (xy 248.579132 -203.644246)
			(xy 248.58218 -203.655676) (xy 248.588112 -203.679623) (xy 248.594488 -203.728545) (xy 248.59488 -203.753212)
			(xy 248.594394 -203.780463) (xy 248.586638 -203.834411) (xy 248.571283 -203.886706) (xy 248.548641 -203.936283)
			(xy 248.519175 -203.982133) (xy 248.483484 -204.023324) (xy 248.442293 -204.059015) (xy 248.396443 -204.088481)
			(xy 248.346866 -204.111123) (xy 248.294571 -204.126478) (xy 248.240623 -204.134234) (xy 248.186121 -204.134234)
			(xy 248.132173 -204.126478) (xy 248.079878 -204.111123) (xy 248.030301 -204.088481) (xy 247.984451 -204.059015)
			(xy 247.94326 -204.023324) (xy 247.907569 -203.982133) (xy 247.878103 -203.936283) (xy 247.855461 -203.886706)
			(xy 247.840106 -203.834411) (xy 247.83235 -203.780463) (xy 247.831864 -203.753212) (xy 247.832249 -203.728544)
			(xy 247.838616 -203.67962) (xy 247.844564 -203.655676) (xy 247.847612 -203.644246) (xy 247.84304 -203.621386)
			(xy 247.786652 -203.54798) (xy 247.779073 -203.539106) (xy 247.758173 -203.528774) (xy 247.74652 -203.528168)
			(xy 246.100346 -203.528168) (xy 246.0752 -203.544678) (xy 246.069104 -203.558648) (xy 246.035068 -203.635864)
			(xy 246.031136 -203.644383) (xy 246.029038 -203.663013) (xy 246.031004 -203.672186) (xy 246.033036 -203.67879)
			(xy 246.041164 -203.698348) (xy 246.047006 -203.704952) (xy 246.064869 -203.725957) (xy 246.094989 -203.772143)
			(xy 246.118143 -203.822184) (xy 246.133848 -203.875039) (xy 246.141779 -203.929605) (xy 246.142256 -203.957174)
			(xy 246.142256 -203.966064) (xy 246.141116 -203.994192) (xy 246.131588 -204.049673) (xy 246.114013 -204.103153)
			(xy 246.088771 -204.15347) (xy 246.056411 -204.199533) (xy 246.017636 -204.240342) (xy 245.973285 -204.275012)
			(xy 245.924323 -204.30279) (xy 245.871811 -204.323073) (xy 245.816888 -204.335422) (xy 245.760748 -204.339569)
			(xy 245.704608 -204.335422) (xy 245.649685 -204.323073) (xy 245.597173 -204.30279) (xy 245.548211 -204.275012)
			(xy 245.50386 -204.240342) (xy 245.465085 -204.199533) (xy 245.432725 -204.15347) (xy 245.407483 -204.103153)
			(xy 245.389908 -204.049673) (xy 245.38038 -203.994192) (xy 245.37924 -203.966064) (xy 245.37924 -203.957174)
			(xy 245.379727 -203.929606) (xy 245.387665 -203.875043) (xy 245.403371 -203.82219) (xy 245.42652 -203.772148)
			(xy 245.456629 -203.725957) (xy 245.47449 -203.704952) (xy 245.480332 -203.698348) (xy 245.48846 -203.67879)
			(xy 245.491254 -203.669138) (xy 245.492016 -203.663296) (xy 245.492289 -203.657115) (xy 245.490235 -203.644917)
			(xy 245.487952 -203.639166) (xy 245.453916 -203.562204) (xy 245.449319 -203.551053) (xy 245.431967 -203.534346)
			(xy 245.420642 -203.5302) (xy 245.41704 -203.529219) (xy 245.409643 -203.5282) (xy 245.40591 -203.528168)
			(xy 242.810538 -203.528168) (xy 242.791742 -203.535788) (xy 242.78463 -203.543154) (xy 241.823494 -204.50429)
			(xy 250.041916 -204.50429) (xy 250.045987 -204.448668) (xy 250.058113 -204.394231) (xy 250.078036 -204.34214)
			(xy 250.105332 -204.293505) (xy 250.139418 -204.249362) (xy 250.179567 -204.210653) (xy 250.224925 -204.178202)
			(xy 250.274525 -204.152701) (xy 250.327309 -204.134694) (xy 250.382152 -204.124564) (xy 250.437886 -204.122527)
			(xy 250.493323 -204.128627) (xy 250.54728 -204.142733) (xy 250.598609 -204.164545) (xy 250.646215 -204.193599)
			(xy 250.689083 -204.229274) (xy 250.7263 -204.270811) (xy 250.757073 -204.317324) (xy 250.780745 -204.367821)
			(xy 250.796813 -204.421228) (xy 250.804933 -204.476404) (xy 250.805442 -204.50429) (xy 250.804933 -204.532176)
			(xy 250.796813 -204.587352) (xy 250.780745 -204.640759) (xy 250.757073 -204.691256) (xy 250.7263 -204.737769)
			(xy 250.689083 -204.779306) (xy 250.646215 -204.814981) (xy 250.598609 -204.844035) (xy 250.54728 -204.865847)
			(xy 250.493323 -204.879953) (xy 250.437886 -204.886053) (xy 250.382152 -204.884016) (xy 250.327309 -204.873886)
			(xy 250.274525 -204.855879) (xy 250.224925 -204.830378) (xy 250.179567 -204.797927) (xy 250.139418 -204.759218)
			(xy 250.105332 -204.715075) (xy 250.078036 -204.66644) (xy 250.058113 -204.614349) (xy 250.045987 -204.559912)
			(xy 250.041916 -204.50429) (xy 241.823494 -204.50429) (xy 241.262408 -205.065376) (xy 241.255042 -205.072488)
			(xy 241.247422 -205.091284) (xy 241.247422 -205.152244) (xy 244.491762 -205.152244) (xy 244.495833 -205.096622)
			(xy 244.507959 -205.042185) (xy 244.527882 -204.990094) (xy 244.555178 -204.941459) (xy 244.589264 -204.897316)
			(xy 244.629413 -204.858607) (xy 244.674771 -204.826156) (xy 244.724371 -204.800655) (xy 244.777155 -204.782648)
			(xy 244.831998 -204.772518) (xy 244.887732 -204.770481) (xy 244.943169 -204.776581) (xy 244.997126 -204.790687)
			(xy 245.048455 -204.812499) (xy 245.096061 -204.841553) (xy 245.138929 -204.877228) (xy 245.176146 -204.918765)
			(xy 245.206919 -204.965278) (xy 245.230591 -205.015775) (xy 245.246659 -205.069182) (xy 245.254779 -205.124358)
			(xy 245.255288 -205.152244) (xy 245.254779 -205.18013) (xy 245.246659 -205.235306) (xy 245.230591 -205.288713)
			(xy 245.206919 -205.33921) (xy 245.176146 -205.385723) (xy 245.138929 -205.42726) (xy 245.096061 -205.462935)
			(xy 245.048455 -205.491989) (xy 244.997126 -205.513801) (xy 244.943169 -205.527907) (xy 244.887732 -205.534007)
			(xy 244.831998 -205.53197) (xy 244.777155 -205.52184) (xy 244.724371 -205.503833) (xy 244.674771 -205.478332)
			(xy 244.629413 -205.445881) (xy 244.589264 -205.407172) (xy 244.555178 -205.363029) (xy 244.527882 -205.314394)
			(xy 244.507959 -205.262303) (xy 244.495833 -205.207866) (xy 244.491762 -205.152244) (xy 241.247422 -205.152244)
			(xy 241.247422 -205.646782) (xy 241.246916 -205.656832) (xy 241.239194 -205.675392) (xy 241.232436 -205.68285)
			(xy 240.81486 -206.100426) (xy 240.807463 -206.107274) (xy 240.788864 -206.115006) (xy 240.778792 -206.115412)
			(xy 234.527344 -206.115412) (xy 234.522668 -206.115495) (xy 234.513465 -206.117155) (xy 234.509056 -206.118714)
			(xy 234.499658 -206.122524) (xy 234.48518 -206.135986) (xy 234.481116 -206.144876) (xy 234.469305 -206.169343)
			(xy 234.439786 -206.214952) (xy 234.404095 -206.255913) (xy 234.362954 -206.291396) (xy 234.317196 -206.320684)
			(xy 234.267746 -206.343185) (xy 234.215604 -206.358443) (xy 234.161824 -206.36615) (xy 234.107496 -206.36615)
			(xy 234.053716 -206.358443) (xy 234.001574 -206.343185) (xy 233.952124 -206.320684) (xy 233.906366 -206.291396)
			(xy 233.865225 -206.255913) (xy 233.829534 -206.214952) (xy 233.800015 -206.169343) (xy 233.788204 -206.144876)
			(xy 233.781854 -206.131414) (xy 233.756962 -206.115412) (xy 233.528362 -206.115412) (xy 233.500422 -206.138526)
			(xy 233.496866 -206.156814) (xy 233.491268 -206.184094) (xy 233.473215 -206.236773) (xy 233.447692 -206.286266)
			(xy 233.415243 -206.331521) (xy 233.376556 -206.371575) (xy 233.332455 -206.405577) (xy 233.283878 -206.432804)
			(xy 233.231858 -206.452675) (xy 233.1775 -206.46477) (xy 233.121962 -206.46883) (xy 233.066424 -206.46477)
			(xy 233.012066 -206.452675) (xy 232.960046 -206.432804) (xy 232.911469 -206.405577) (xy 232.867368 -206.371575)
			(xy 232.828681 -206.331521) (xy 232.796232 -206.286266) (xy 232.770709 -206.236773) (xy 232.752656 -206.184094)
			(xy 232.747058 -206.156814) (xy 232.743502 -206.138526) (xy 232.715562 -206.115412) (xy 232.55605 -206.115412)
			(xy 232.537 -206.12354) (xy 232.529888 -206.130906) (xy 232.529634 -206.13116) (xy 232.479342 -206.183738)
			(xy 232.475931 -206.187479) (xy 232.470554 -206.196055) (xy 232.468674 -206.200756) (xy 232.464864 -206.210408)
			(xy 232.465118 -206.222346) (xy 232.465118 -206.2226) (xy 232.465372 -206.236316) (xy 232.464886 -206.263567)
			(xy 232.45713 -206.317515) (xy 232.441775 -206.36981) (xy 232.419133 -206.419387) (xy 232.389667 -206.465237)
			(xy 232.356492 -206.503524) (xy 244.491762 -206.503524) (xy 244.495833 -206.447902) (xy 244.507959 -206.393465)
			(xy 244.527882 -206.341374) (xy 244.555178 -206.292739) (xy 244.589264 -206.248596) (xy 244.629413 -206.209887)
			(xy 244.674771 -206.177436) (xy 244.724371 -206.151935) (xy 244.777155 -206.133928) (xy 244.831998 -206.123798)
			(xy 244.887732 -206.121761) (xy 244.943169 -206.127861) (xy 244.997126 -206.141967) (xy 245.048455 -206.163779)
			(xy 245.096061 -206.192833) (xy 245.138929 -206.228508) (xy 245.176146 -206.270045) (xy 245.206919 -206.316558)
			(xy 245.230591 -206.367055) (xy 245.23856 -206.393542) (xy 250.443236 -206.393542) (xy 250.447307 -206.33792)
			(xy 250.459433 -206.283483) (xy 250.479356 -206.231392) (xy 250.506652 -206.182757) (xy 250.540738 -206.138614)
			(xy 250.580887 -206.099905) (xy 250.626245 -206.067454) (xy 250.675845 -206.041953) (xy 250.728629 -206.023946)
			(xy 250.783472 -206.013816) (xy 250.839206 -206.011779) (xy 250.894643 -206.017879) (xy 250.9486 -206.031985)
			(xy 250.999929 -206.053797) (xy 251.047535 -206.082851) (xy 251.090403 -206.118526) (xy 251.12762 -206.160063)
			(xy 251.158393 -206.206576) (xy 251.182065 -206.257073) (xy 251.198133 -206.31048) (xy 251.206253 -206.365656)
			(xy 251.206762 -206.393542) (xy 251.206253 -206.421428) (xy 251.198133 -206.476604) (xy 251.182065 -206.530011)
			(xy 251.158393 -206.580508) (xy 251.12762 -206.627021) (xy 251.090403 -206.668558) (xy 251.047535 -206.704233)
			(xy 250.999929 -206.733287) (xy 250.9486 -206.755099) (xy 250.894643 -206.769205) (xy 250.839206 -206.775305)
			(xy 250.783472 -206.773268) (xy 250.728629 -206.763138) (xy 250.675845 -206.745131) (xy 250.626245 -206.71963)
			(xy 250.580887 -206.687179) (xy 250.540738 -206.64847) (xy 250.506652 -206.604327) (xy 250.479356 -206.555692)
			(xy 250.459433 -206.503601) (xy 250.447307 -206.449164) (xy 250.443236 -206.393542) (xy 245.23856 -206.393542)
			(xy 245.246659 -206.420462) (xy 245.254779 -206.475638) (xy 245.255288 -206.503524) (xy 245.254779 -206.53141)
			(xy 245.246659 -206.586586) (xy 245.230591 -206.639993) (xy 245.206919 -206.69049) (xy 245.176146 -206.737003)
			(xy 245.138929 -206.77854) (xy 245.096061 -206.814215) (xy 245.048455 -206.843269) (xy 244.997126 -206.865081)
			(xy 244.943169 -206.879187) (xy 244.887732 -206.885287) (xy 244.831998 -206.88325) (xy 244.777155 -206.87312)
			(xy 244.724371 -206.855113) (xy 244.674771 -206.829612) (xy 244.629413 -206.797161) (xy 244.589264 -206.758452)
			(xy 244.555178 -206.714309) (xy 244.527882 -206.665674) (xy 244.507959 -206.613583) (xy 244.495833 -206.559146)
			(xy 244.491762 -206.503524) (xy 232.356492 -206.503524) (xy 232.353976 -206.506428) (xy 232.312785 -206.542119)
			(xy 232.266935 -206.571585) (xy 232.217358 -206.594227) (xy 232.165063 -206.609582) (xy 232.111115 -206.617338)
			(xy 232.056613 -206.617338) (xy 232.002665 -206.609582) (xy 231.95037 -206.594227) (xy 231.900793 -206.571585)
			(xy 231.854943 -206.542119) (xy 231.813752 -206.506428) (xy 231.778061 -206.465237) (xy 231.748595 -206.419387)
			(xy 231.725953 -206.36981) (xy 231.710598 -206.317515) (xy 231.702842 -206.263567) (xy 231.702356 -206.236316)
			(xy 231.70261 -206.2226) (xy 231.70261 -206.222346) (xy 231.702864 -206.210408) (xy 231.699054 -206.200756)
			(xy 231.697137 -206.196074) (xy 231.691767 -206.187502) (xy 231.688386 -206.183738) (xy 231.638094 -206.13116)
			(xy 231.63784 -206.130906) (xy 231.630728 -206.12354) (xy 231.611678 -206.115412) (xy 231.464866 -206.115412)
			(xy 231.451658 -206.115666) (xy 231.421432 -206.132176) (xy 231.416149 -206.135299) (xy 231.407164 -206.143653)
			(xy 231.403652 -206.148686) (xy 231.403398 -206.14894) (xy 231.38815 -206.171016) (xy 231.352452 -206.211069)
			(xy 231.311499 -206.24573) (xy 231.266097 -206.274317) (xy 231.21714 -206.296266) (xy 231.165593 -206.311146)
			(xy 231.11247 -206.318663) (xy 231.085644 -206.31912) (xy 231.08539 -206.31912) (xy 231.059879 -206.318695)
			(xy 231.00931 -206.3119) (xy 230.960097 -206.298432) (xy 230.913115 -206.278532) (xy 230.869202 -206.252554)
			(xy 230.848916 -206.237078) (xy 230.837486 -206.227934) (xy 230.808784 -206.224886) (xy 230.713026 -206.271114)
			(xy 230.704628 -206.275616) (xy 230.69169 -206.289589) (xy 230.684731 -206.307313) (xy 230.684324 -206.316834)
			(xy 230.684324 -206.454502) (xy 230.683793 -206.480524) (xy 230.675618 -206.531923) (xy 230.659517 -206.581414)
			(xy 230.635885 -206.627784) (xy 230.605301 -206.669894) (xy 230.587296 -206.68869) (xy 230.147622 -207.128364)
			(xy 230.140783 -207.135765) (xy 230.133069 -207.154363) (xy 230.132636 -207.164432) (xy 230.132636 -207.528451)
			(xy 234.626891 -207.528451) (xy 234.626891 -207.473949) (xy 234.634648 -207.420002) (xy 234.650003 -207.367708)
			(xy 234.672644 -207.318132) (xy 234.702111 -207.272283) (xy 234.737802 -207.231094) (xy 234.778992 -207.195403)
			(xy 234.824843 -207.165938) (xy 234.87442 -207.143299) (xy 234.926714 -207.127945) (xy 234.980661 -207.12019)
			(xy 235.007912 -207.119728) (xy 235.033833 -207.120178) (xy 235.085195 -207.127211) (xy 235.135133 -207.141131)
			(xy 235.182727 -207.161682) (xy 235.227101 -207.188487) (xy 235.267439 -207.221051) (xy 235.285534 -207.239616)
			(xy 235.292646 -207.246982) (xy 235.310934 -207.255364) (xy 235.402882 -207.258158) (xy 235.421932 -207.250792)
			(xy 235.429298 -207.243934) (xy 235.450631 -207.224563) (xy 235.498058 -207.191837) (xy 235.549869 -207.166619)
			(xy 235.604885 -207.149485) (xy 235.661853 -207.140825) (xy 235.690664 -207.140302) (xy 235.717919 -207.140742)
			(xy 235.771876 -207.148495) (xy 235.824179 -207.163849) (xy 235.873765 -207.18649) (xy 235.919624 -207.215958)
			(xy 235.960822 -207.251652) (xy 235.996521 -207.292847) (xy 236.025993 -207.338703) (xy 236.048639 -207.388287)
			(xy 236.063997 -207.440589) (xy 236.071755 -207.494545) (xy 236.071755 -207.52181) (xy 236.324646 -207.52181)
			(xy 236.328717 -207.466188) (xy 236.340843 -207.411751) (xy 236.360766 -207.35966) (xy 236.388062 -207.311025)
			(xy 236.422148 -207.266882) (xy 236.462297 -207.228173) (xy 236.507655 -207.195722) (xy 236.557255 -207.170221)
			(xy 236.610039 -207.152214) (xy 236.664882 -207.142084) (xy 236.720616 -207.140047) (xy 236.776053 -207.146147)
			(xy 236.83001 -207.160253) (xy 236.881339 -207.182065) (xy 236.928945 -207.211119) (xy 236.971813 -207.246794)
			(xy 237.00903 -207.288331) (xy 237.039803 -207.334844) (xy 237.063475 -207.385341) (xy 237.079543 -207.438748)
			(xy 237.087663 -207.493924) (xy 237.088172 -207.52181) (xy 237.087663 -207.549696) (xy 237.079543 -207.604872)
			(xy 237.063475 -207.658279) (xy 237.039803 -207.708776) (xy 237.00903 -207.755289) (xy 236.971813 -207.796826)
			(xy 236.928945 -207.832501) (xy 236.881339 -207.861555) (xy 236.83001 -207.883367) (xy 236.776053 -207.897473)
			(xy 236.720616 -207.903573) (xy 236.664882 -207.901536) (xy 236.610039 -207.891406) (xy 236.557255 -207.873399)
			(xy 236.507655 -207.847898) (xy 236.462297 -207.815447) (xy 236.422148 -207.776738) (xy 236.388062 -207.732595)
			(xy 236.360766 -207.68396) (xy 236.340843 -207.631869) (xy 236.328717 -207.577432) (xy 236.324646 -207.52181)
			(xy 236.071755 -207.52181) (xy 236.071755 -207.549055) (xy 236.063997 -207.603011) (xy 236.048639 -207.655313)
			(xy 236.025993 -207.704897) (xy 235.996521 -207.750753) (xy 235.960822 -207.791948) (xy 235.919624 -207.827642)
			(xy 235.873765 -207.85711) (xy 235.824179 -207.879751) (xy 235.771876 -207.895105) (xy 235.717919 -207.902858)
			(xy 235.690664 -207.903318) (xy 235.664743 -207.902869) (xy 235.613381 -207.895835) (xy 235.563444 -207.881913)
			(xy 235.51585 -207.861361) (xy 235.471476 -207.834557) (xy 235.431138 -207.801994) (xy 235.413042 -207.78343)
			(xy 235.40593 -207.776064) (xy 235.387642 -207.767682) (xy 235.295694 -207.764888) (xy 235.276644 -207.772254)
			(xy 235.269278 -207.779112) (xy 235.247921 -207.798455) (xy 235.200499 -207.831183) (xy 235.148694 -207.856405)
			(xy 235.093684 -207.873546) (xy 235.036721 -207.882216) (xy 235.007912 -207.882744) (xy 234.980661 -207.88221)
			(xy 234.926714 -207.874455) (xy 234.87442 -207.859101) (xy 234.824843 -207.836462) (xy 234.778992 -207.806997)
			(xy 234.737802 -207.771306) (xy 234.702111 -207.730117) (xy 234.672644 -207.684268) (xy 234.650003 -207.634692)
			(xy 234.634648 -207.582398) (xy 234.626891 -207.528451) (xy 230.132636 -207.528451) (xy 230.132636 -208.162453)
			(xy 239.104875 -208.162453) (xy 239.104875 -208.107947) (xy 239.112633 -208.053996) (xy 239.12799 -208.001699)
			(xy 239.150633 -207.952119) (xy 239.180103 -207.906267) (xy 239.215798 -207.865075) (xy 239.256992 -207.829383)
			(xy 239.302847 -207.799918) (xy 239.352429 -207.777278) (xy 239.404728 -207.761926) (xy 239.458679 -207.754173)
			(xy 239.485932 -207.753712) (xy 239.512859 -207.754175) (xy 239.566176 -207.761764) (xy 239.617897 -207.776771)
			(xy 239.666995 -207.798899) (xy 239.712495 -207.827709) (xy 239.753494 -207.862628) (xy 239.771682 -207.88249)
			(xy 239.779302 -207.890872) (xy 239.799114 -207.899762) (xy 239.898428 -207.898492) (xy 239.91824 -207.889348)
			(xy 239.925352 -207.880712) (xy 239.943568 -207.859883) (xy 239.985006 -207.823212) (xy 240.031305 -207.79291)
			(xy 240.081494 -207.769611) (xy 240.134522 -207.753803) (xy 240.189277 -207.745819) (xy 240.216944 -207.74533)
			(xy 240.244196 -207.745743) (xy 240.298144 -207.753505) (xy 240.350439 -207.768866) (xy 240.400016 -207.791512)
			(xy 240.445865 -207.820982) (xy 240.487054 -207.856677) (xy 240.522744 -207.89787) (xy 240.552209 -207.943723)
			(xy 240.57485 -207.993302) (xy 240.581542 -208.016094) (xy 244.483126 -208.016094) (xy 244.487197 -207.960472)
			(xy 244.499323 -207.906035) (xy 244.519246 -207.853944) (xy 244.546542 -207.805309) (xy 244.580628 -207.761166)
			(xy 244.620777 -207.722457) (xy 244.666135 -207.690006) (xy 244.715735 -207.664505) (xy 244.768519 -207.646498)
			(xy 244.823362 -207.636368) (xy 244.879096 -207.634331) (xy 244.934533 -207.640431) (xy 244.98849 -207.654537)
			(xy 245.036579 -207.674972) (xy 248.278904 -207.674972) (xy 248.279353 -207.647263) (xy 248.287362 -207.592428)
			(xy 248.303221 -207.539329) (xy 248.326598 -207.489084) (xy 248.357 -207.442751) (xy 248.393786 -207.401304)
			(xy 248.436183 -207.365617) (xy 248.483297 -207.336441) (xy 248.50852 -207.32496) (xy 248.520748 -207.319268)
			(xy 248.541812 -207.302432) (xy 248.557734 -207.280668) (xy 248.567402 -207.255495) (xy 248.570142 -207.228669)
			(xy 248.565763 -207.202061) (xy 248.554569 -207.177528) (xy 248.537343 -207.156781) (xy 248.526554 -207.148684)
			(xy 248.50536 -207.133344) (xy 248.467021 -207.097742) (xy 248.433906 -207.057234) (xy 248.406638 -207.012582)
			(xy 248.385728 -206.964622) (xy 248.371567 -206.914254) (xy 248.364422 -206.862424) (xy 248.363994 -206.836264)
			(xy 248.36448 -206.809013) (xy 248.372236 -206.755065) (xy 248.387591 -206.70277) (xy 248.410233 -206.653193)
			(xy 248.439699 -206.607343) (xy 248.47539 -206.566152) (xy 248.516581 -206.530461) (xy 248.562431 -206.500995)
			(xy 248.612008 -206.478353) (xy 248.664303 -206.462998) (xy 248.718251 -206.455242) (xy 248.772753 -206.455242)
			(xy 248.826701 -206.462998) (xy 248.878996 -206.478353) (xy 248.928573 -206.500995) (xy 248.974423 -206.530461)
			(xy 249.015614 -206.566152) (xy 249.051305 -206.607343) (xy 249.080771 -206.653193) (xy 249.103413 -206.70277)
			(xy 249.118768 -206.755065) (xy 249.126524 -206.809013) (xy 249.12701 -206.836264) (xy 249.126499 -206.86397)
			(xy 249.118499 -206.918802) (xy 249.102649 -206.9719) (xy 249.079281 -207.022144) (xy 249.048888 -207.068478)
			(xy 249.01211 -207.109925) (xy 248.969721 -207.145614) (xy 248.922614 -207.174793) (xy 248.897394 -207.186276)
			(xy 248.885216 -207.192064) (xy 248.864156 -207.208884) (xy 248.848235 -207.23063) (xy 248.838564 -207.255787)
			(xy 248.835817 -207.282598) (xy 248.840187 -207.309193) (xy 248.851367 -207.333717) (xy 248.868579 -207.354457)
			(xy 248.87936 -207.362552) (xy 248.900527 -207.377927) (xy 248.938867 -207.413524) (xy 248.971982 -207.454026)
			(xy 248.999254 -207.498672) (xy 249.020169 -207.546626) (xy 249.034335 -207.596988) (xy 249.041487 -207.648814)
			(xy 249.04192 -207.674972) (xy 249.041434 -207.702223) (xy 249.033678 -207.756171) (xy 249.018323 -207.808466)
			(xy 248.995681 -207.858043) (xy 248.966215 -207.903893) (xy 248.938542 -207.93583) (xy 250.545344 -207.93583)
			(xy 250.549415 -207.880208) (xy 250.561541 -207.825771) (xy 250.581464 -207.77368) (xy 250.60876 -207.725045)
			(xy 250.642846 -207.680902) (xy 250.682995 -207.642193) (xy 250.728353 -207.609742) (xy 250.777953 -207.584241)
			(xy 250.830737 -207.566234) (xy 250.88558 -207.556104) (xy 250.941314 -207.554067) (xy 250.996751 -207.560167)
			(xy 251.050708 -207.574273) (xy 251.102037 -207.596085) (xy 251.149643 -207.625139) (xy 251.192511 -207.660814)
			(xy 251.229728 -207.702351) (xy 251.260501 -207.748864) (xy 251.284173 -207.799361) (xy 251.300241 -207.852768)
			(xy 251.308361 -207.907944) (xy 251.30887 -207.93583) (xy 251.308361 -207.963716) (xy 251.300241 -208.018892)
			(xy 251.284173 -208.072299) (xy 251.260501 -208.122796) (xy 251.229728 -208.169309) (xy 251.192511 -208.210846)
			(xy 251.149643 -208.246521) (xy 251.102037 -208.275575) (xy 251.050708 -208.297387) (xy 250.996751 -208.311493)
			(xy 250.941314 -208.317593) (xy 250.88558 -208.315556) (xy 250.830737 -208.305426) (xy 250.777953 -208.287419)
			(xy 250.728353 -208.261918) (xy 250.682995 -208.229467) (xy 250.642846 -208.190758) (xy 250.60876 -208.146615)
			(xy 250.581464 -208.09798) (xy 250.561541 -208.045889) (xy 250.549415 -207.991452) (xy 250.545344 -207.93583)
			(xy 248.938542 -207.93583) (xy 248.930524 -207.945084) (xy 248.889333 -207.980775) (xy 248.843483 -208.010241)
			(xy 248.793906 -208.032883) (xy 248.741611 -208.048238) (xy 248.687663 -208.055994) (xy 248.633161 -208.055994)
			(xy 248.579213 -208.048238) (xy 248.526918 -208.032883) (xy 248.477341 -208.010241) (xy 248.431491 -207.980775)
			(xy 248.3903 -207.945084) (xy 248.354609 -207.903893) (xy 248.325143 -207.858043) (xy 248.302501 -207.808466)
			(xy 248.287146 -207.756171) (xy 248.27939 -207.702223) (xy 248.278904 -207.674972) (xy 245.036579 -207.674972)
			(xy 245.039819 -207.676349) (xy 245.087425 -207.705403) (xy 245.130293 -207.741078) (xy 245.16751 -207.782615)
			(xy 245.198283 -207.829128) (xy 245.221955 -207.879625) (xy 245.238023 -207.933032) (xy 245.246143 -207.988208)
			(xy 245.246652 -208.016094) (xy 245.246143 -208.04398) (xy 245.238023 -208.099156) (xy 245.221955 -208.152563)
			(xy 245.198283 -208.20306) (xy 245.16751 -208.249573) (xy 245.130293 -208.29111) (xy 245.087425 -208.326785)
			(xy 245.039819 -208.355839) (xy 244.98849 -208.377651) (xy 244.934533 -208.391757) (xy 244.879096 -208.397857)
			(xy 244.823362 -208.39582) (xy 244.768519 -208.38569) (xy 244.715735 -208.367683) (xy 244.666135 -208.342182)
			(xy 244.620777 -208.309731) (xy 244.580628 -208.271022) (xy 244.546542 -208.226879) (xy 244.519246 -208.178244)
			(xy 244.499323 -208.126153) (xy 244.487197 -208.071716) (xy 244.483126 -208.016094) (xy 240.581542 -208.016094)
			(xy 240.590204 -208.045599) (xy 240.59796 -208.099548) (xy 240.59796 -208.154052) (xy 240.590204 -208.208001)
			(xy 240.57485 -208.260298) (xy 240.552209 -208.309877) (xy 240.522744 -208.35573) (xy 240.487054 -208.396923)
			(xy 240.445865 -208.432618) (xy 240.400016 -208.462088) (xy 240.350439 -208.484734) (xy 240.298144 -208.500095)
			(xy 240.244196 -208.507857) (xy 240.216944 -208.508346) (xy 240.190018 -208.507845) (xy 240.136702 -208.500266)
			(xy 240.084981 -208.485268) (xy 240.035883 -208.463146) (xy 239.990382 -208.434342) (xy 239.949382 -208.399428)
			(xy 239.931194 -208.379568) (xy 239.923574 -208.371186) (xy 239.903762 -208.362296) (xy 239.804448 -208.363566)
			(xy 239.784636 -208.37271) (xy 239.777524 -208.381346) (xy 239.759311 -208.402178) (xy 239.717874 -208.438851)
			(xy 239.671574 -208.469154) (xy 239.621384 -208.492453) (xy 239.568355 -208.508259) (xy 239.513599 -208.516241)
			(xy 239.485932 -208.516728) (xy 239.458679 -208.516227) (xy 239.404728 -208.508474) (xy 239.352429 -208.493122)
			(xy 239.302847 -208.470482) (xy 239.256992 -208.441016) (xy 239.215798 -208.405325) (xy 239.180103 -208.364133)
			(xy 239.150633 -208.318281) (xy 239.12799 -208.268701) (xy 239.112633 -208.216404) (xy 239.104875 -208.162453)
			(xy 230.132636 -208.162453) (xy 230.132636 -208.590896) (xy 248.084338 -208.590896) (xy 248.088409 -208.535274)
			(xy 248.100535 -208.480837) (xy 248.120458 -208.428746) (xy 248.147754 -208.380111) (xy 248.18184 -208.335968)
			(xy 248.221989 -208.297259) (xy 248.267347 -208.264808) (xy 248.316947 -208.239307) (xy 248.369731 -208.2213)
			(xy 248.424574 -208.21117) (xy 248.480308 -208.209133) (xy 248.535745 -208.215233) (xy 248.589702 -208.229339)
			(xy 248.641031 -208.251151) (xy 248.688637 -208.280205) (xy 248.731505 -208.31588) (xy 248.768722 -208.357417)
			(xy 248.799495 -208.40393) (xy 248.823167 -208.454427) (xy 248.839235 -208.507834) (xy 248.847355 -208.56301)
			(xy 248.847753 -208.5848) (xy 249.122182 -208.5848) (xy 249.126253 -208.529178) (xy 249.138379 -208.474741)
			(xy 249.158302 -208.42265) (xy 249.185598 -208.374015) (xy 249.219684 -208.329872) (xy 249.259833 -208.291163)
			(xy 249.305191 -208.258712) (xy 249.354791 -208.233211) (xy 249.407575 -208.215204) (xy 249.462418 -208.205074)
			(xy 249.518152 -208.203037) (xy 249.573589 -208.209137) (xy 249.627546 -208.223243) (xy 249.678875 -208.245055)
			(xy 249.726481 -208.274109) (xy 249.769349 -208.309784) (xy 249.806566 -208.351321) (xy 249.837339 -208.397834)
			(xy 249.861011 -208.448331) (xy 249.877079 -208.501738) (xy 249.885199 -208.556914) (xy 249.885708 -208.5848)
			(xy 249.885199 -208.612686) (xy 249.877079 -208.667862) (xy 249.861011 -208.721269) (xy 249.837339 -208.771766)
			(xy 249.806566 -208.818279) (xy 249.769349 -208.859816) (xy 249.726481 -208.895491) (xy 249.678875 -208.924545)
			(xy 249.627546 -208.946357) (xy 249.573589 -208.960463) (xy 249.518152 -208.966563) (xy 249.462418 -208.964526)
			(xy 249.407575 -208.954396) (xy 249.354791 -208.936389) (xy 249.305191 -208.910888) (xy 249.259833 -208.878437)
			(xy 249.219684 -208.839728) (xy 249.185598 -208.795585) (xy 249.158302 -208.74695) (xy 249.138379 -208.694859)
			(xy 249.126253 -208.640422) (xy 249.122182 -208.5848) (xy 248.847753 -208.5848) (xy 248.847864 -208.590896)
			(xy 248.847355 -208.618782) (xy 248.839235 -208.673958) (xy 248.823167 -208.727365) (xy 248.799495 -208.777862)
			(xy 248.768722 -208.824375) (xy 248.731505 -208.865912) (xy 248.688637 -208.901587) (xy 248.641031 -208.930641)
			(xy 248.589702 -208.952453) (xy 248.535745 -208.966559) (xy 248.480308 -208.972659) (xy 248.424574 -208.970622)
			(xy 248.369731 -208.960492) (xy 248.316947 -208.942485) (xy 248.267347 -208.916984) (xy 248.221989 -208.884533)
			(xy 248.18184 -208.845824) (xy 248.147754 -208.801681) (xy 248.120458 -208.753046) (xy 248.100535 -208.700955)
			(xy 248.088409 -208.646518) (xy 248.084338 -208.590896) (xy 230.132636 -208.590896) (xy 230.132636 -209.611551)
			(xy 236.453168 -209.611551) (xy 236.453168 -209.557049) (xy 236.460924 -209.503103) (xy 236.476278 -209.450809)
			(xy 236.498918 -209.401232) (xy 236.528382 -209.355382) (xy 236.564071 -209.314191) (xy 236.605259 -209.278499)
			(xy 236.651107 -209.249031) (xy 236.700682 -209.226388) (xy 236.752975 -209.21103) (xy 236.806921 -209.20327)
			(xy 236.834172 -209.202782) (xy 236.86104 -209.203236) (xy 236.914243 -209.210778) (xy 236.96586 -209.225717)
			(xy 237.014868 -209.247756) (xy 237.060296 -209.276458) (xy 237.101243 -209.311256) (xy 237.119414 -209.331052)
			(xy 237.12692 -209.33876) (xy 237.146514 -209.347586) (xy 237.15726 -209.34807) (xy 237.23346 -209.34807)
			(xy 237.24418 -209.347464) (xy 237.263739 -209.338669) (xy 237.271306 -209.331052) (xy 237.289499 -209.311277)
			(xy 237.330444 -209.276483) (xy 237.375868 -209.24778) (xy 237.424871 -209.225739) (xy 237.476483 -209.210795)
			(xy 237.529682 -209.203245) (xy 237.556548 -209.202782) (xy 237.583796 -209.203292) (xy 237.637737 -209.211053)
			(xy 237.690025 -209.226412) (xy 237.739595 -209.249055) (xy 237.785438 -209.278522) (xy 237.826621 -209.314213)
			(xy 237.862307 -209.355401) (xy 237.891768 -209.401247) (xy 237.914405 -209.45082) (xy 237.929757 -209.50311)
			(xy 237.933613 -209.529934) (xy 240.342672 -209.529934) (xy 240.346743 -209.474312) (xy 240.358869 -209.419875)
			(xy 240.378792 -209.367784) (xy 240.406088 -209.319149) (xy 240.440174 -209.275006) (xy 240.480323 -209.236297)
			(xy 240.525681 -209.203846) (xy 240.575281 -209.178345) (xy 240.628065 -209.160338) (xy 240.682908 -209.150208)
			(xy 240.738642 -209.148171) (xy 240.794079 -209.154271) (xy 240.848036 -209.168377) (xy 240.899365 -209.190189)
			(xy 240.946971 -209.219243) (xy 240.989839 -209.254918) (xy 241.027056 -209.296455) (xy 241.057829 -209.342968)
			(xy 241.081501 -209.393465) (xy 241.097569 -209.446872) (xy 241.105689 -209.502048) (xy 241.106198 -209.529934)
			(xy 241.105689 -209.55782) (xy 241.097569 -209.612996) (xy 241.081501 -209.666403) (xy 241.057829 -209.7169)
			(xy 241.027056 -209.763413) (xy 240.989839 -209.80495) (xy 240.946971 -209.840625) (xy 240.899365 -209.869679)
			(xy 240.848036 -209.891491) (xy 240.794079 -209.905597) (xy 240.738642 -209.911697) (xy 240.682908 -209.90966)
			(xy 240.628065 -209.89953) (xy 240.575281 -209.881523) (xy 240.525681 -209.856022) (xy 240.480323 -209.823571)
			(xy 240.440174 -209.784862) (xy 240.406088 -209.740719) (xy 240.378792 -209.692084) (xy 240.358869 -209.639993)
			(xy 240.346743 -209.585556) (xy 240.342672 -209.529934) (xy 237.933613 -209.529934) (xy 237.937512 -209.557052)
			(xy 237.937512 -209.611548) (xy 237.929757 -209.66549) (xy 237.914405 -209.71778) (xy 237.891768 -209.767353)
			(xy 237.862307 -209.813199) (xy 237.826621 -209.854387) (xy 237.785438 -209.890078) (xy 237.739595 -209.919545)
			(xy 237.690025 -209.942188) (xy 237.637737 -209.957547) (xy 237.583796 -209.965308) (xy 237.556548 -209.965798)
			(xy 237.52968 -209.965337) (xy 237.476477 -209.957797) (xy 237.42486 -209.94286) (xy 237.375851 -209.920823)
			(xy 237.330424 -209.892121) (xy 237.289477 -209.857324) (xy 237.271306 -209.837528) (xy 237.263796 -209.829826)
			(xy 237.244205 -209.820997) (xy 237.23346 -209.82051) (xy 237.15726 -209.82051) (xy 237.146538 -209.821103)
			(xy 237.126978 -209.829905) (xy 237.119414 -209.837528) (xy 237.101257 -209.857337) (xy 237.060305 -209.89213)
			(xy 237.014874 -209.920828) (xy 236.965863 -209.942864) (xy 236.914245 -209.9578) (xy 236.86104 -209.96534)
			(xy 236.834172 -209.965798) (xy 236.806921 -209.96533) (xy 236.752975 -209.95757) (xy 236.700682 -209.942212)
			(xy 236.651107 -209.919569) (xy 236.605259 -209.890101) (xy 236.564071 -209.854409) (xy 236.528382 -209.813218)
			(xy 236.498918 -209.767368) (xy 236.476278 -209.717791) (xy 236.460924 -209.665497) (xy 236.453168 -209.611551)
			(xy 230.132636 -209.611551) (xy 230.132636 -209.825082) (xy 230.132943 -209.833276) (xy 230.138124 -209.848824)
			(xy 230.142796 -209.855562) (xy 230.146606 -209.860642) (xy 230.2764 -209.990436) (xy 242.127532 -209.990436)
			(xy 242.127989 -209.963182) (xy 242.135742 -209.909229) (xy 242.151096 -209.856929) (xy 242.173737 -209.807346)
			(xy 242.203205 -209.761491) (xy 242.238899 -209.720297) (xy 242.280094 -209.684602) (xy 242.325949 -209.655135)
			(xy 242.375532 -209.632494) (xy 242.427833 -209.617141) (xy 242.481786 -209.609389) (xy 242.50904 -209.608928)
			(xy 242.53594 -209.60939) (xy 242.589206 -209.616947) (xy 242.640881 -209.631918) (xy 242.689937 -209.654007)
			(xy 242.7354 -209.682775) (xy 242.756182 -209.69986) (xy 242.763548 -209.70621) (xy 242.78209 -209.712306)
			(xy 242.871752 -209.707226) (xy 242.889278 -209.699098) (xy 242.896136 -209.691732) (xy 242.914224 -209.673073)
			(xy 242.954603 -209.640361) (xy 242.99905 -209.613434) (xy 243.046742 -209.592793) (xy 243.096795 -209.578819)
			(xy 243.148282 -209.571771) (xy 243.174266 -209.571336) (xy 243.20152 -209.571787) (xy 243.255474 -209.579541)
			(xy 243.307774 -209.594894) (xy 243.357357 -209.617536) (xy 243.403213 -209.647005) (xy 243.444407 -209.6827)
			(xy 243.480101 -209.723895) (xy 243.509569 -209.769751) (xy 243.532209 -209.819335) (xy 243.547562 -209.871636)
			(xy 243.555314 -209.92559) (xy 243.555774 -209.952844) (xy 243.555206 -209.981771) (xy 243.546465 -210.038962)
			(xy 243.529189 -210.094177) (xy 243.503775 -210.146152) (xy 243.470806 -210.193693) (xy 243.431037 -210.235712)
			(xy 243.38538 -210.271246) (xy 243.334882 -210.299479) (xy 243.2807 -210.319764) (xy 243.252498 -210.326224)
			(xy 243.239798 -210.329018) (xy 243.22024 -210.345782) (xy 243.180362 -210.449922) (xy 243.183918 -210.475576)
			(xy 243.191538 -210.48599) (xy 243.209093 -210.510747) (xy 243.224656 -210.540854) (xy 245.32209 -210.540854)
			(xy 245.322568 -210.512047) (xy 245.331225 -210.455086) (xy 245.348349 -210.400076) (xy 245.373551 -210.348266)
			(xy 245.406258 -210.300835) (xy 245.445727 -210.258863) (xy 245.491058 -210.223303) (xy 245.541222 -210.194966)
			(xy 245.567962 -210.184238) (xy 245.578376 -210.180428) (xy 245.59387 -210.164426) (xy 245.627652 -210.071208)
			(xy 245.625874 -210.04911) (xy 245.62054 -210.039458) (xy 245.608887 -210.017981) (xy 245.590578 -209.972676)
			(xy 245.57819 -209.925407) (xy 245.571925 -209.876946) (xy 245.571518 -209.852514) (xy 245.572004 -209.825263)
			(xy 245.57976 -209.771315) (xy 245.595115 -209.71902) (xy 245.617757 -209.669443) (xy 245.647223 -209.623593)
			(xy 245.682914 -209.582402) (xy 245.724105 -209.546711) (xy 245.769955 -209.517245) (xy 245.819532 -209.494603)
			(xy 245.871827 -209.479248) (xy 245.925775 -209.471492) (xy 245.980277 -209.471492) (xy 246.034225 -209.479248)
			(xy 246.08652 -209.494603) (xy 246.136097 -209.517245) (xy 246.181947 -209.546711) (xy 246.223138 -209.582402)
			(xy 246.258829 -209.623593) (xy 246.288295 -209.669443) (xy 246.310937 -209.71902) (xy 246.326292 -209.771315)
			(xy 246.334048 -209.825263) (xy 246.334534 -209.852514) (xy 246.334012 -209.88132) (xy 246.325361 -209.938277)
			(xy 246.308243 -209.993286) (xy 246.283047 -210.045095) (xy 246.250345 -210.092525) (xy 246.210883 -210.134499)
			(xy 246.165558 -210.17006) (xy 246.1154 -210.1984) (xy 246.088662 -210.20913) (xy 246.078248 -210.21294)
			(xy 246.062754 -210.228942) (xy 246.028972 -210.32216) (xy 246.03075 -210.344258) (xy 246.036084 -210.35391)
			(xy 246.047718 -210.375397) (xy 246.066033 -210.420698) (xy 246.078427 -210.467963) (xy 246.084697 -210.516423)
			(xy 246.085106 -210.540854) (xy 246.08462 -210.568105) (xy 246.079116 -210.606386) (xy 248.335544 -210.606386)
			(xy 248.339615 -210.550764) (xy 248.351741 -210.496327) (xy 248.371664 -210.444236) (xy 248.39896 -210.395601)
			(xy 248.433046 -210.351458) (xy 248.473195 -210.312749) (xy 248.518553 -210.280298) (xy 248.568153 -210.254797)
			(xy 248.620937 -210.23679) (xy 248.67578 -210.22666) (xy 248.731514 -210.224623) (xy 248.786951 -210.230723)
			(xy 248.840908 -210.244829) (xy 248.892237 -210.266641) (xy 248.939843 -210.295695) (xy 248.982711 -210.33137)
			(xy 249.019928 -210.372907) (xy 249.050701 -210.41942) (xy 249.074373 -210.469917) (xy 249.090441 -210.523324)
			(xy 249.098561 -210.5785) (xy 249.09907 -210.606386) (xy 250.49429 -210.606386) (xy 250.498361 -210.550764)
			(xy 250.510487 -210.496327) (xy 250.53041 -210.444236) (xy 250.557706 -210.395601) (xy 250.591792 -210.351458)
			(xy 250.631941 -210.312749) (xy 250.677299 -210.280298) (xy 250.726899 -210.254797) (xy 250.779683 -210.23679)
			(xy 250.834526 -210.22666) (xy 250.89026 -210.224623) (xy 250.945697 -210.230723) (xy 250.999654 -210.244829)
			(xy 251.050983 -210.266641) (xy 251.098589 -210.295695) (xy 251.141457 -210.33137) (xy 251.178674 -210.372907)
			(xy 251.209447 -210.41942) (xy 251.233119 -210.469917) (xy 251.249187 -210.523324) (xy 251.257307 -210.5785)
			(xy 251.257816 -210.606386) (xy 251.257307 -210.634272) (xy 251.249187 -210.689448) (xy 251.233119 -210.742855)
			(xy 251.209447 -210.793352) (xy 251.178674 -210.839865) (xy 251.141457 -210.881402) (xy 251.098589 -210.917077)
			(xy 251.050983 -210.946131) (xy 250.999654 -210.967943) (xy 250.945697 -210.982049) (xy 250.89026 -210.988149)
			(xy 250.834526 -210.986112) (xy 250.779683 -210.975982) (xy 250.726899 -210.957975) (xy 250.677299 -210.932474)
			(xy 250.631941 -210.900023) (xy 250.591792 -210.861314) (xy 250.557706 -210.817171) (xy 250.53041 -210.768536)
			(xy 250.510487 -210.716445) (xy 250.498361 -210.662008) (xy 250.49429 -210.606386) (xy 249.09907 -210.606386)
			(xy 249.098561 -210.634272) (xy 249.090441 -210.689448) (xy 249.074373 -210.742855) (xy 249.050701 -210.793352)
			(xy 249.019928 -210.839865) (xy 248.982711 -210.881402) (xy 248.939843 -210.917077) (xy 248.892237 -210.946131)
			(xy 248.840908 -210.967943) (xy 248.786951 -210.982049) (xy 248.731514 -210.988149) (xy 248.67578 -210.986112)
			(xy 248.620937 -210.975982) (xy 248.568153 -210.957975) (xy 248.518553 -210.932474) (xy 248.473195 -210.900023)
			(xy 248.433046 -210.861314) (xy 248.39896 -210.817171) (xy 248.371664 -210.768536) (xy 248.351741 -210.716445)
			(xy 248.339615 -210.662008) (xy 248.335544 -210.606386) (xy 246.079116 -210.606386) (xy 246.076864 -210.622053)
			(xy 246.061509 -210.674348) (xy 246.038867 -210.723925) (xy 246.009401 -210.769775) (xy 245.97371 -210.810966)
			(xy 245.932519 -210.846657) (xy 245.886669 -210.876123) (xy 245.837092 -210.898765) (xy 245.784797 -210.91412)
			(xy 245.730849 -210.921876) (xy 245.676347 -210.921876) (xy 245.622399 -210.91412) (xy 245.570104 -210.898765)
			(xy 245.520527 -210.876123) (xy 245.474677 -210.846657) (xy 245.433486 -210.810966) (xy 245.397795 -210.769775)
			(xy 245.368329 -210.723925) (xy 245.345687 -210.674348) (xy 245.330332 -210.622053) (xy 245.322576 -210.568105)
			(xy 245.32209 -210.540854) (xy 243.224656 -210.540854) (xy 243.236961 -210.564659) (xy 243.255957 -210.622297)
			(xy 243.265604 -210.682214) (xy 243.266214 -210.712558) (xy 243.265728 -210.739809) (xy 243.257972 -210.793757)
			(xy 243.242617 -210.846052) (xy 243.219975 -210.895629) (xy 243.190509 -210.941479) (xy 243.154818 -210.98267)
			(xy 243.113627 -211.018361) (xy 243.067777 -211.047827) (xy 243.0182 -211.070469) (xy 242.965905 -211.085824)
			(xy 242.911957 -211.09358) (xy 242.857455 -211.09358) (xy 242.803507 -211.085824) (xy 242.751212 -211.070469)
			(xy 242.701635 -211.047827) (xy 242.655785 -211.018361) (xy 242.614594 -210.98267) (xy 242.578903 -210.941479)
			(xy 242.549437 -210.895629) (xy 242.526795 -210.846052) (xy 242.51144 -210.793757) (xy 242.503684 -210.739809)
			(xy 242.503198 -210.712558) (xy 242.503587 -210.687653) (xy 242.510079 -210.638269) (xy 242.522934 -210.590147)
			(xy 242.541935 -210.544104) (xy 242.553998 -210.522312) (xy 242.560602 -210.510882) (xy 242.56111 -210.485228)
			(xy 242.509548 -210.385914) (xy 242.487958 -210.37169) (xy 242.475004 -210.37042) (xy 242.446898 -210.367321)
			(xy 242.391942 -210.354026) (xy 242.33955 -210.332764) (xy 242.290871 -210.304002) (xy 242.246971 -210.268369)
			(xy 242.208811 -210.226647) (xy 242.177227 -210.17975) (xy 242.152912 -210.128704) (xy 242.136398 -210.074628)
			(xy 242.128047 -210.018707) (xy 242.127532 -209.990436) (xy 230.2764 -209.990436) (xy 230.695246 -210.409282)
			(xy 230.699304 -210.413174) (xy 230.708795 -210.419199) (xy 230.714042 -210.42122) (xy 230.715058 -210.421474)
			(xy 230.74068 -210.42987) (xy 230.789446 -210.452866) (xy 230.834489 -210.482497) (xy 230.845747 -210.492433)
			(xy 235.785717 -210.492433) (xy 235.785719 -210.437939) (xy 235.793476 -210.383999) (xy 235.80883 -210.331713)
			(xy 235.831469 -210.282143) (xy 235.860931 -210.2363) (xy 235.896618 -210.195116) (xy 235.937802 -210.15943)
			(xy 235.983645 -210.129968) (xy 236.033215 -210.107329) (xy 236.085501 -210.091976) (xy 236.139441 -210.084219)
			(xy 236.193935 -210.084217) (xy 236.247875 -210.091971) (xy 236.300163 -210.107321) (xy 236.349734 -210.129956)
			(xy 236.395579 -210.159416) (xy 236.436765 -210.195099) (xy 236.472454 -210.236281) (xy 236.50192 -210.282122)
			(xy 236.524561 -210.33169) (xy 236.539919 -210.383976) (xy 236.547679 -210.437915) (xy 236.548168 -210.465162)
			(xy 236.547721 -210.492332) (xy 236.540066 -210.54613) (xy 236.532928 -210.57235) (xy 236.529271 -210.586855)
			(xy 236.529568 -210.616752) (xy 236.538505 -210.645283) (xy 236.555318 -210.670006) (xy 236.578567 -210.688804)
			(xy 236.606261 -210.700069) (xy 236.636031 -210.702835) (xy 236.650784 -210.700366) (xy 236.669876 -210.696687)
			(xy 236.708558 -210.692743) (xy 236.728 -210.692492) (xy 236.755251 -210.692978) (xy 236.809199 -210.700734)
			(xy 236.861494 -210.716089) (xy 236.911071 -210.738731) (xy 236.956921 -210.768197) (xy 236.998112 -210.803888)
			(xy 237.033803 -210.845079) (xy 237.063269 -210.890929) (xy 237.085911 -210.940506) (xy 237.101266 -210.992801)
			(xy 237.101985 -210.9978) (xy 238.403382 -210.9978) (xy 238.407453 -210.942178) (xy 238.419579 -210.887741)
			(xy 238.439502 -210.83565) (xy 238.466798 -210.787015) (xy 238.500884 -210.742872) (xy 238.541033 -210.704163)
			(xy 238.586391 -210.671712) (xy 238.635991 -210.646211) (xy 238.688775 -210.628204) (xy 238.743618 -210.618074)
			(xy 238.799352 -210.616037) (xy 238.854789 -210.622137) (xy 238.908746 -210.636243) (xy 238.960075 -210.658055)
			(xy 239.007681 -210.687109) (xy 239.050549 -210.722784) (xy 239.087766 -210.764321) (xy 239.118539 -210.810834)
			(xy 239.142211 -210.861331) (xy 239.158279 -210.914738) (xy 239.166399 -210.969914) (xy 239.166908 -210.9978)
			(xy 239.166399 -211.025686) (xy 239.158279 -211.080862) (xy 239.142211 -211.134269) (xy 239.118539 -211.184766)
			(xy 239.087766 -211.231279) (xy 239.050549 -211.272816) (xy 239.007681 -211.308491) (xy 238.960075 -211.337545)
			(xy 238.908746 -211.359357) (xy 238.854789 -211.373463) (xy 238.799352 -211.379563) (xy 238.743618 -211.377526)
			(xy 238.688775 -211.367396) (xy 238.635991 -211.349389) (xy 238.586391 -211.323888) (xy 238.541033 -211.291437)
			(xy 238.500884 -211.252728) (xy 238.466798 -211.208585) (xy 238.439502 -211.15995) (xy 238.419579 -211.107859)
			(xy 238.407453 -211.053422) (xy 238.403382 -210.9978) (xy 237.101985 -210.9978) (xy 237.109022 -211.046749)
			(xy 237.109022 -211.101251) (xy 237.101266 -211.155199) (xy 237.085911 -211.207494) (xy 237.063269 -211.257071)
			(xy 237.033803 -211.302921) (xy 236.998112 -211.344112) (xy 236.956921 -211.379803) (xy 236.911071 -211.409269)
			(xy 236.861494 -211.431911) (xy 236.809199 -211.447266) (xy 236.755251 -211.455022) (xy 236.700749 -211.455022)
			(xy 236.646801 -211.447266) (xy 236.594506 -211.431911) (xy 236.544929 -211.409269) (xy 236.499079 -211.379803)
			(xy 236.457888 -211.344112) (xy 236.422197 -211.302921) (xy 236.392731 -211.257071) (xy 236.370089 -211.207494)
			(xy 236.354734 -211.155199) (xy 236.346978 -211.101251) (xy 236.346492 -211.074) (xy 236.346949 -211.04683)
			(xy 236.354597 -210.993032) (xy 236.361732 -210.966812) (xy 236.365368 -210.952299) (xy 236.365087 -210.922401)
			(xy 236.356159 -210.893865) (xy 236.33935 -210.869138) (xy 236.3161 -210.850338) (xy 236.288401 -210.839077)
			(xy 236.258629 -210.83632) (xy 236.243876 -210.838796) (xy 236.224786 -210.842488) (xy 236.186102 -210.846429)
			(xy 236.16666 -210.84667) (xy 236.139413 -210.846179) (xy 236.085474 -210.838418) (xy 236.033188 -210.823061)
			(xy 235.983621 -210.800419) (xy 235.937779 -210.770953) (xy 235.896598 -210.735264) (xy 235.860914 -210.694077)
			(xy 235.831455 -210.648232) (xy 235.80882 -210.598661) (xy 235.79347 -210.546373) (xy 235.785717 -210.492433)
			(xy 230.845747 -210.492433) (xy 230.874913 -210.518173) (xy 230.909914 -210.559185) (xy 230.938793 -210.604714)
			(xy 230.960976 -210.653855) (xy 230.976021 -210.70563) (xy 230.983629 -210.759006) (xy 230.984044 -210.785964)
			(xy 230.983561 -210.813218) (xy 230.975809 -210.867171) (xy 230.960457 -210.919473) (xy 230.937818 -210.969057)
			(xy 230.908354 -211.014914) (xy 230.872663 -211.056112) (xy 230.831472 -211.09181) (xy 230.78562 -211.121284)
			(xy 230.73604 -211.143932) (xy 230.683742 -211.159293) (xy 230.62979 -211.167056) (xy 230.602536 -211.167472)
			(xy 230.575633 -211.167014) (xy 230.52236 -211.15946) (xy 230.470676 -211.144497) (xy 230.421607 -211.122422)
			(xy 230.376126 -211.093673) (xy 230.335134 -211.058819) (xy 230.299445 -211.018553) (xy 230.269767 -210.973672)
			(xy 230.246688 -210.925067) (xy 230.2383 -210.899502) (xy 230.238046 -210.898486) (xy 230.237792 -210.89747)
			(xy 230.235728 -210.892245) (xy 230.229707 -210.882762) (xy 230.225854 -210.878674) (xy 229.566216 -210.219036)
			(xy 229.548183 -210.200265) (xy 229.517601 -210.158149) (xy 229.493973 -210.111773) (xy 229.477877 -210.062276)
			(xy 229.469709 -210.010872) (xy 229.469188 -209.984848) (xy 229.469188 -207.005174) (xy 229.469713 -206.979149)
			(xy 229.477876 -206.927743) (xy 229.493965 -206.878241) (xy 229.517586 -206.831859) (xy 229.54816 -206.789734)
			(xy 229.566216 -206.770986) (xy 229.967536 -206.369666) (xy 229.975582 -206.360665) (xy 229.983018 -206.33773)
			(xy 229.98176 -206.325724) (xy 229.979982 -206.313786) (xy 229.965504 -206.293974) (xy 229.861364 -206.241396)
			(xy 229.832916 -206.243682) (xy 229.821232 -206.252318) (xy 229.796483 -206.269888) (xy 229.74258 -206.297783)
			(xy 229.684937 -206.316779) (xy 229.62501 -206.326396) (xy 229.594664 -206.326994) (xy 229.566456 -206.326483)
			(xy 229.510657 -206.318167) (xy 229.456692 -206.301722) (xy 229.405737 -206.277507) (xy 229.358906 -206.24605)
			(xy 229.317219 -206.208038) (xy 229.281587 -206.1643) (xy 229.26675 -206.140304) (xy 229.261953 -206.132923)
			(xy 229.248402 -206.121709) (xy 229.231856 -206.11574) (xy 229.223062 -206.115412) (xy 220.58249 -206.115412)
			(xy 220.572504 -206.115952) (xy 220.554075 -206.123669) (xy 220.546676 -206.130398) (xy 220.501972 -206.175102)
			(xy 220.501718 -206.175102) (xy 220.445076 -206.231744) (xy 220.439783 -206.238227) (xy 220.433315 -206.253652)
			(xy 220.432376 -206.26197) (xy 220.432376 -207.136238) (xy 220.43183 -207.169516) (xy 220.423142 -207.235501)
			(xy 220.405918 -207.299789) (xy 220.380454 -207.361281) (xy 220.347185 -207.418924) (xy 220.346199 -207.42021)
			(xy 221.283782 -207.42021) (xy 221.287853 -207.364588) (xy 221.299979 -207.310151) (xy 221.319902 -207.25806)
			(xy 221.347198 -207.209425) (xy 221.381284 -207.165282) (xy 221.421433 -207.126573) (xy 221.466791 -207.094122)
			(xy 221.516391 -207.068621) (xy 221.569175 -207.050614) (xy 221.624018 -207.040484) (xy 221.679752 -207.038447)
			(xy 221.735189 -207.044547) (xy 221.789146 -207.058653) (xy 221.840475 -207.080465) (xy 221.888081 -207.109519)
			(xy 221.930949 -207.145194) (xy 221.968166 -207.186731) (xy 221.998939 -207.233244) (xy 222.022611 -207.283741)
			(xy 222.038679 -207.337148) (xy 222.046799 -207.392324) (xy 222.047308 -207.42021) (xy 222.046799 -207.448096)
			(xy 222.038679 -207.503272) (xy 222.022611 -207.556679) (xy 221.998939 -207.607176) (xy 221.968166 -207.653689)
			(xy 221.930949 -207.695226) (xy 221.888081 -207.730901) (xy 221.840475 -207.759955) (xy 221.789146 -207.781767)
			(xy 221.735189 -207.795873) (xy 221.679752 -207.801973) (xy 221.624018 -207.799936) (xy 221.569175 -207.789806)
			(xy 221.516391 -207.771799) (xy 221.466791 -207.746298) (xy 221.421433 -207.713847) (xy 221.381284 -207.675138)
			(xy 221.347198 -207.630995) (xy 221.319902 -207.58236) (xy 221.299979 -207.530269) (xy 221.287853 -207.475832)
			(xy 221.283782 -207.42021) (xy 220.346199 -207.42021) (xy 220.306679 -207.471734) (xy 220.283532 -207.495648)
			(xy 219.322904 -208.456276) (xy 219.317599 -208.462755) (xy 219.311108 -208.478178) (xy 219.310204 -208.486502)
			(xy 219.310204 -208.978754) (xy 219.310868 -208.991403) (xy 219.322852 -209.013682) (xy 219.333064 -209.021172)
			(xy 219.397834 -209.063844) (xy 219.404165 -209.067704) (xy 219.418363 -209.071957) (xy 219.425774 -209.072226)
			(xy 219.443046 -209.072226) (xy 219.461334 -209.06867) (xy 219.465144 -209.067146) (xy 219.487057 -209.059068)
			(xy 219.532354 -209.047687) (xy 219.578699 -209.041902) (xy 219.60205 -209.041492) (xy 219.606622 -209.041492)
			(xy 219.633662 -209.042284) (xy 219.687121 -209.050559) (xy 219.738876 -209.066302) (xy 219.787887 -209.089198)
			(xy 219.833174 -209.118786) (xy 219.873827 -209.154475) (xy 219.909031 -209.195548) (xy 219.938081 -209.241182)
			(xy 219.960394 -209.290462) (xy 219.975523 -209.342399) (xy 219.976658 -209.350356) (xy 222.583754 -209.350356)
			(xy 222.587825 -209.294734) (xy 222.599951 -209.240297) (xy 222.619874 -209.188206) (xy 222.64717 -209.139571)
			(xy 222.681256 -209.095428) (xy 222.721405 -209.056719) (xy 222.766763 -209.024268) (xy 222.816363 -208.998767)
			(xy 222.869147 -208.98076) (xy 222.92399 -208.97063) (xy 222.979724 -208.968593) (xy 223.035161 -208.974693)
			(xy 223.089118 -208.988799) (xy 223.140447 -209.010611) (xy 223.188053 -209.039665) (xy 223.230921 -209.07534)
			(xy 223.268138 -209.116877) (xy 223.298911 -209.16339) (xy 223.322583 -209.213887) (xy 223.338651 -209.267294)
			(xy 223.346771 -209.32247) (xy 223.34728 -209.350356) (xy 223.346771 -209.378242) (xy 223.338651 -209.433418)
			(xy 223.322583 -209.486825) (xy 223.298911 -209.537322) (xy 223.268138 -209.583835) (xy 223.230921 -209.625372)
			(xy 223.188053 -209.661047) (xy 223.140447 -209.690101) (xy 223.089118 -209.711913) (xy 223.035161 -209.726019)
			(xy 222.979724 -209.732119) (xy 222.92399 -209.730082) (xy 222.869147 -209.719952) (xy 222.816363 -209.701945)
			(xy 222.766763 -209.676444) (xy 222.721405 -209.643993) (xy 222.681256 -209.605284) (xy 222.64717 -209.561141)
			(xy 222.619874 -209.512506) (xy 222.599951 -209.460415) (xy 222.587825 -209.405978) (xy 222.583754 -209.350356)
			(xy 219.976658 -209.350356) (xy 219.983164 -209.395952) (xy 219.983558 -209.423) (xy 219.983095 -209.450252)
			(xy 219.975337 -209.5042) (xy 219.959981 -209.556495) (xy 219.937338 -209.606072) (xy 219.907869 -209.651921)
			(xy 219.872174 -209.69311) (xy 219.830981 -209.728799) (xy 219.785128 -209.758262) (xy 219.735548 -209.780898)
			(xy 219.683251 -209.796248) (xy 219.629302 -209.803998) (xy 219.60205 -209.804508) (xy 219.575115 -209.804046)
			(xy 219.52178 -209.796467) (xy 219.470044 -209.781453) (xy 219.420938 -209.759303) (xy 219.37544 -209.730458)
			(xy 219.354654 -209.713322) (xy 219.346526 -209.706464) (xy 219.336366 -209.703416) (xy 219.32646 -209.700114)
			(xy 219.232226 -209.710782) (xy 219.214192 -209.720942) (xy 219.207842 -209.729324) (xy 219.207334 -209.729832)
			(xy 219.205302 -209.732626) (xy 219.184601 -209.758696) (xy 219.137517 -209.805757) (xy 219.084697 -209.846273)
			(xy 219.027041 -209.879551) (xy 218.965537 -209.905022) (xy 218.901235 -209.922251) (xy 218.835235 -209.930943)
			(xy 218.80195 -209.931508) (xy 218.763762 -209.930804) (xy 218.688255 -209.919321) (xy 218.651582 -209.908648)
			(xy 218.620881 -209.898596) (xy 218.562103 -209.871793) (xy 218.507192 -209.837763) (xy 218.457032 -209.797052)
			(xy 218.412432 -209.750318) (xy 218.374108 -209.698312) (xy 218.342679 -209.641872) (xy 218.31865 -209.581906)
			(xy 218.302409 -209.51938) (xy 218.294215 -209.4553) (xy 218.293696 -209.423) (xy 218.293696 -208.255362)
			(xy 218.293266 -208.245295) (xy 218.285541 -208.226701) (xy 218.27871 -208.219294) (xy 218.227656 -208.168748)
			(xy 218.227148 -208.16824) (xy 218.22029 -208.161382) (xy 218.201748 -208.153508) (xy 218.186 -208.153508)
			(xy 218.158749 -208.153022) (xy 218.104801 -208.145266) (xy 218.052506 -208.129911) (xy 218.002929 -208.107269)
			(xy 217.957079 -208.077803) (xy 217.915888 -208.042112) (xy 217.880197 -208.000921) (xy 217.850731 -207.955071)
			(xy 217.828089 -207.905494) (xy 217.812734 -207.853199) (xy 217.804978 -207.799251) (xy 217.804978 -207.744749)
			(xy 217.812734 -207.690801) (xy 217.828089 -207.638506) (xy 217.850731 -207.588929) (xy 217.880197 -207.543079)
			(xy 217.915888 -207.501888) (xy 217.957079 -207.466197) (xy 218.002929 -207.436731) (xy 218.052506 -207.414089)
			(xy 218.104801 -207.398734) (xy 218.158749 -207.390978) (xy 218.186 -207.390492) (xy 218.213298 -207.390957)
			(xy 218.267339 -207.398731) (xy 218.319721 -207.414122) (xy 218.369378 -207.436816) (xy 218.415297 -207.466349)
			(xy 218.456543 -207.502121) (xy 218.492274 -207.543401) (xy 218.521763 -207.589349) (xy 218.533472 -207.614012)
			(xy 218.538806 -207.625442) (xy 218.55811 -207.640682) (xy 218.652344 -207.657954) (xy 218.664577 -207.659454)
			(xy 218.688073 -207.652152) (xy 218.697302 -207.643984) (xy 219.015056 -207.32623) (xy 219.403168 -206.938372)
			(xy 219.40846 -206.931888) (xy 219.414927 -206.916463) (xy 219.415868 -206.908146) (xy 219.415868 -206.166212)
			(xy 219.41545 -206.156191) (xy 219.407781 -206.137676) (xy 219.393607 -206.123508) (xy 219.375089 -206.115846)
			(xy 219.365068 -206.115412) (xy 218.254072 -206.115412) (xy 218.249754 -206.116174) (xy 218.233997 -206.118666)
			(xy 218.202206 -206.121339) (xy 218.186254 -206.121508) (xy 218.186 -206.121508) (xy 218.170048 -206.121349)
			(xy 218.138255 -206.118681) (xy 218.1225 -206.116174) (xy 218.117928 -206.115412) (xy 216.229438 -206.115412)
			(xy 216.217282 -206.116116) (xy 216.195677 -206.127266) (xy 216.188036 -206.136748) (xy 216.142824 -206.200502)
			(xy 216.138252 -206.207106) (xy 216.133426 -206.221838) (xy 216.133426 -206.238094) (xy 216.134188 -206.246222)
			(xy 216.135966 -206.257652) (xy 216.136982 -206.260954) (xy 216.145152 -206.288756) (xy 216.153959 -206.346028)
			(xy 216.154508 -206.375) (xy 216.154036 -206.40237) (xy 216.146213 -206.456548) (xy 216.130726 -206.509052)
			(xy 216.107894 -206.558804) (xy 216.078186 -206.604781) (xy 216.060528 -206.625698) (xy 216.054432 -206.63281)
			(xy 216.048082 -206.649574) (xy 216.048082 -206.735426) (xy 216.054432 -206.75219) (xy 216.057698 -206.756)
			(xy 217.803982 -206.756) (xy 217.808053 -206.700378) (xy 217.820179 -206.645941) (xy 217.840102 -206.59385)
			(xy 217.867398 -206.545215) (xy 217.901484 -206.501072) (xy 217.941633 -206.462363) (xy 217.986991 -206.429912)
			(xy 218.036591 -206.404411) (xy 218.089375 -206.386404) (xy 218.144218 -206.376274) (xy 218.199952 -206.374237)
			(xy 218.255389 -206.380337) (xy 218.309346 -206.394443) (xy 218.360675 -206.416255) (xy 218.408281 -206.445309)
			(xy 218.451149 -206.480984) (xy 218.488366 -206.522521) (xy 218.519139 -206.569034) (xy 218.542811 -206.619531)
			(xy 218.558879 -206.672938) (xy 218.566999 -206.728114) (xy 218.567508 -206.756) (xy 218.566999 -206.783886)
			(xy 218.558879 -206.839062) (xy 218.542811 -206.892469) (xy 218.519139 -206.942966) (xy 218.488366 -206.989479)
			(xy 218.451149 -207.031016) (xy 218.408281 -207.066691) (xy 218.360675 -207.095745) (xy 218.309346 -207.117557)
			(xy 218.255389 -207.131663) (xy 218.199952 -207.137763) (xy 218.144218 -207.135726) (xy 218.089375 -207.125596)
			(xy 218.036591 -207.107589) (xy 217.986991 -207.082088) (xy 217.941633 -207.049637) (xy 217.901484 -207.010928)
			(xy 217.867398 -206.966785) (xy 217.840102 -206.91815) (xy 217.820179 -206.866059) (xy 217.808053 -206.811622)
			(xy 217.803982 -206.756) (xy 216.057698 -206.756) (xy 216.060528 -206.759302) (xy 216.078171 -206.780234)
			(xy 216.107899 -206.826201) (xy 216.130747 -206.875947) (xy 216.146245 -206.928449) (xy 216.154075 -206.982629)
			(xy 216.154075 -207.037371) (xy 216.146245 -207.091551) (xy 216.130747 -207.144053) (xy 216.107899 -207.193799)
			(xy 216.078171 -207.239766) (xy 216.060528 -207.260698) (xy 216.054432 -207.26781) (xy 216.048082 -207.284574)
			(xy 216.048082 -207.370426) (xy 216.054432 -207.38719) (xy 216.060528 -207.394302) (xy 216.078169 -207.415234)
			(xy 216.107892 -207.461201) (xy 216.130734 -207.510948) (xy 216.146222 -207.563451) (xy 216.15404 -207.61763)
			(xy 216.154508 -207.645) (xy 216.154022 -207.672251) (xy 216.146266 -207.726199) (xy 216.130911 -207.778494)
			(xy 216.108269 -207.828071) (xy 216.078803 -207.873921) (xy 216.043112 -207.915112) (xy 216.001921 -207.950803)
			(xy 215.956071 -207.980269) (xy 215.906494 -208.002911) (xy 215.854199 -208.018266) (xy 215.800251 -208.026022)
			(xy 215.745749 -208.026022) (xy 215.691801 -208.018266) (xy 215.639506 -208.002911) (xy 215.589929 -207.980269)
			(xy 215.544079 -207.950803) (xy 215.502888 -207.915112) (xy 215.467197 -207.873921) (xy 215.437731 -207.828071)
			(xy 215.415089 -207.778494) (xy 215.399734 -207.726199) (xy 215.391978 -207.672251) (xy 215.391492 -207.645)
			(xy 215.391964 -207.61763) (xy 215.399787 -207.563452) (xy 215.415274 -207.510948) (xy 215.438106 -207.461196)
			(xy 215.467814 -207.415219) (xy 215.485472 -207.394302) (xy 215.491568 -207.38719) (xy 215.497918 -207.370426)
			(xy 215.497918 -207.284574) (xy 215.491568 -207.26781) (xy 215.485472 -207.260698) (xy 215.467829 -207.239766)
			(xy 215.438101 -207.193799) (xy 215.415253 -207.144053) (xy 215.399755 -207.091551) (xy 215.391925 -207.037371)
			(xy 215.391925 -206.982629) (xy 215.399755 -206.928449) (xy 215.415253 -206.875947) (xy 215.438101 -206.826201)
			(xy 215.467829 -206.780234) (xy 215.485472 -206.759302) (xy 215.491568 -206.75219) (xy 215.497918 -206.735426)
			(xy 215.497918 -206.649574) (xy 215.491568 -206.63281) (xy 215.485472 -206.625698) (xy 215.467831 -206.604766)
			(xy 215.438108 -206.558799) (xy 215.415266 -206.509052) (xy 215.399778 -206.456549) (xy 215.39196 -206.40237)
			(xy 215.391492 -206.375) (xy 215.392161 -206.343275) (xy 215.402754 -206.280714) (xy 215.412574 -206.25054)
			(xy 215.416638 -206.238856) (xy 215.413336 -206.214726) (xy 215.357964 -206.136748) (xy 215.350344 -206.127245)
			(xy 215.328723 -206.116108) (xy 215.316562 -206.115412) (xy 214.723726 -206.115412) (xy 214.713661 -206.114976)
			(xy 214.695075 -206.107244) (xy 214.687658 -206.100426) (xy 212.824314 -204.237082) (xy 212.817469 -204.229683)
			(xy 212.809739 -204.211085) (xy 212.809328 -204.201014) (xy 212.809328 -192.820544) (xy 212.801708 -192.801748)
			(xy 212.794342 -192.794636) (xy 211.481924 -191.482218) (xy 211.474812 -191.474852) (xy 211.456016 -191.467232)
			(xy 209.35188 -191.467232) (xy 209.333084 -191.474852) (xy 209.325972 -191.482218) (xy 209.219292 -191.588898)
			(xy 209.211954 -191.596886) (xy 209.204232 -191.617134) (xy 209.205548 -191.638764) (xy 209.210148 -191.648588)
			(xy 209.21572 -191.658034) (xy 209.233071 -191.671412) (xy 209.254414 -191.67636) (xy 209.265266 -191.67475)
			(xy 209.273648 -191.672972) (xy 209.27822 -191.671194) (xy 209.301269 -191.662124) (xy 209.349125 -191.64935)
			(xy 209.398234 -191.642895) (xy 209.423 -191.642492) (xy 209.450251 -191.642978) (xy 209.504199 -191.650734)
			(xy 209.556494 -191.666089) (xy 209.606071 -191.688731) (xy 209.651921 -191.718197) (xy 209.693112 -191.753888)
			(xy 209.728803 -191.795079) (xy 209.758269 -191.840929) (xy 209.780911 -191.890506) (xy 209.796266 -191.942801)
			(xy 209.804022 -191.996749) (xy 209.804022 -192.051251) (xy 209.796266 -192.105199) (xy 209.780911 -192.157494)
			(xy 209.758269 -192.207071) (xy 209.728803 -192.252921) (xy 209.693112 -192.294112) (xy 209.651921 -192.329803)
			(xy 209.606071 -192.359269) (xy 209.556494 -192.381911) (xy 209.504199 -192.397266) (xy 209.450251 -192.405022)
			(xy 209.395749 -192.405022) (xy 209.341801 -192.397266) (xy 209.289506 -192.381911) (xy 209.239929 -192.359269)
			(xy 209.194079 -192.329803) (xy 209.152888 -192.294112) (xy 209.117197 -192.252921) (xy 209.087731 -192.207071)
			(xy 209.065089 -192.157494) (xy 209.049734 -192.105199) (xy 209.041978 -192.051251) (xy 209.041492 -192.024)
			(xy 209.041492 -192.014348) (xy 209.042 -191.998854) (xy 209.025236 -191.972692) (xy 208.924144 -191.929258)
			(xy 208.914683 -191.925669) (xy 208.894466 -191.925479) (xy 208.875743 -191.93311) (xy 208.868264 -191.939926)
			(xy 207.996282 -192.811908) (xy 207.989123 -192.819783) (xy 207.981405 -192.839589) (xy 207.982382 -192.860823)
			(xy 207.98663 -192.870582) (xy 207.988408 -192.873884) (xy 207.991202 -192.880234) (xy 207.991456 -192.880742)
			(xy 208.002499 -192.905825) (xy 208.018085 -192.958367) (xy 208.025989 -193.012598) (xy 208.026508 -193.04)
			(xy 208.026508 -193.040254) (xy 208.025843 -193.0717) (xy 208.015506 -193.133737) (xy 208.005934 -193.163698)
			(xy 208.004664 -193.167508) (xy 208.00314 -193.17589) (xy 208.00314 -193.195448) (xy 208.005426 -193.202814)
			(xy 208.013042 -193.229734) (xy 208.021207 -193.285078) (xy 208.021682 -193.31305) (xy 208.021682 -193.313812)
			(xy 208.021124 -193.343393) (xy 208.011989 -193.401845) (xy 207.993939 -193.458187) (xy 207.967408 -193.511066)
			(xy 207.933031 -193.559215) (xy 207.891634 -193.601481) (xy 207.868266 -193.619628) (xy 207.865472 -193.62166)
			(xy 207.85963 -193.627502) (xy 207.852578 -193.635225) (xy 207.844856 -193.654637) (xy 207.844644 -193.665094)
			(xy 207.847692 -193.760852) (xy 207.859884 -193.782696) (xy 207.870806 -193.7893) (xy 207.893684 -193.804415)
			(xy 207.935266 -193.840157) (xy 207.971311 -193.881477) (xy 208.001081 -193.927524) (xy 208.023963 -193.977354)
			(xy 208.039487 -194.029942) (xy 208.047335 -194.08421) (xy 208.047844 -194.111626) (xy 208.047356 -194.138877)
			(xy 208.039597 -194.192824) (xy 208.02424 -194.245117) (xy 208.001598 -194.294694) (xy 207.972132 -194.340543)
			(xy 207.936441 -194.381734) (xy 207.895251 -194.417426) (xy 207.849403 -194.446893) (xy 207.799827 -194.469537)
			(xy 207.747534 -194.484895) (xy 207.693587 -194.492656) (xy 207.666336 -194.493134) (xy 207.642386 -194.492697)
			(xy 207.594873 -194.486588) (xy 207.571594 -194.480942) (xy 207.55991 -194.477894) (xy 207.53705 -194.482466)
			(xy 207.463644 -194.539616) (xy 207.454811 -194.547206) (xy 207.444614 -194.568115) (xy 207.444086 -194.579748)
			(xy 207.444086 -195.326) (xy 209.656932 -195.326) (xy 209.661003 -195.270378) (xy 209.673129 -195.215941)
			(xy 209.693052 -195.16385) (xy 209.720348 -195.115215) (xy 209.754434 -195.071072) (xy 209.794583 -195.032363)
			(xy 209.839941 -194.999912) (xy 209.889541 -194.974411) (xy 209.942325 -194.956404) (xy 209.997168 -194.946274)
			(xy 210.052902 -194.944237) (xy 210.108339 -194.950337) (xy 210.162296 -194.964443) (xy 210.213625 -194.986255)
			(xy 210.261231 -195.015309) (xy 210.304099 -195.050984) (xy 210.341316 -195.092521) (xy 210.372089 -195.139034)
			(xy 210.395761 -195.189531) (xy 210.411829 -195.242938) (xy 210.419949 -195.298114) (xy 210.420458 -195.326)
			(xy 210.419949 -195.353886) (xy 210.411829 -195.409062) (xy 210.395761 -195.462469) (xy 210.372089 -195.512966)
			(xy 210.341316 -195.559479) (xy 210.304099 -195.601016) (xy 210.261231 -195.636691) (xy 210.213625 -195.665745)
			(xy 210.162296 -195.687557) (xy 210.108339 -195.701663) (xy 210.052902 -195.707763) (xy 209.997168 -195.705726)
			(xy 209.942325 -195.695596) (xy 209.889541 -195.677589) (xy 209.839941 -195.652088) (xy 209.794583 -195.619637)
			(xy 209.754434 -195.580928) (xy 209.720348 -195.536785) (xy 209.693052 -195.48815) (xy 209.673129 -195.436059)
			(xy 209.661003 -195.381622) (xy 209.656932 -195.326) (xy 207.444086 -195.326) (xy 207.444086 -196.596)
			(xy 209.040982 -196.596) (xy 209.045053 -196.540378) (xy 209.057179 -196.485941) (xy 209.077102 -196.43385)
			(xy 209.104398 -196.385215) (xy 209.138484 -196.341072) (xy 209.178633 -196.302363) (xy 209.223991 -196.269912)
			(xy 209.273591 -196.244411) (xy 209.326375 -196.226404) (xy 209.381218 -196.216274) (xy 209.436952 -196.214237)
			(xy 209.492389 -196.220337) (xy 209.546346 -196.234443) (xy 209.597675 -196.256255) (xy 209.645281 -196.285309)
			(xy 209.688149 -196.320984) (xy 209.725366 -196.362521) (xy 209.756139 -196.409034) (xy 209.779811 -196.459531)
			(xy 209.795879 -196.512938) (xy 209.803999 -196.568114) (xy 209.804508 -196.596) (xy 209.803999 -196.623886)
			(xy 209.795879 -196.679062) (xy 209.779811 -196.732469) (xy 209.756139 -196.782966) (xy 209.725366 -196.829479)
			(xy 209.688149 -196.871016) (xy 209.645281 -196.906691) (xy 209.597675 -196.935745) (xy 209.546346 -196.957557)
			(xy 209.492389 -196.971663) (xy 209.436952 -196.977763) (xy 209.381218 -196.975726) (xy 209.326375 -196.965596)
			(xy 209.273591 -196.947589) (xy 209.223991 -196.922088) (xy 209.178633 -196.889637) (xy 209.138484 -196.850928)
			(xy 209.104398 -196.806785) (xy 209.077102 -196.75815) (xy 209.057179 -196.706059) (xy 209.045053 -196.651622)
			(xy 209.040982 -196.596) (xy 207.444086 -196.596) (xy 207.444086 -197.485) (xy 208.025492 -197.485)
			(xy 208.025978 -197.457749) (xy 208.033734 -197.403801) (xy 208.049089 -197.351506) (xy 208.071731 -197.301929)
			(xy 208.101197 -197.256079) (xy 208.136888 -197.214888) (xy 208.178079 -197.179197) (xy 208.223929 -197.149731)
			(xy 208.273506 -197.127089) (xy 208.325801 -197.111734) (xy 208.379749 -197.103978) (xy 208.434251 -197.103978)
			(xy 208.488199 -197.111734) (xy 208.540494 -197.127089) (xy 208.590071 -197.149731) (xy 208.635921 -197.179197)
			(xy 208.677112 -197.214888) (xy 208.712803 -197.256079) (xy 208.742269 -197.301929) (xy 208.764911 -197.351506)
			(xy 208.780266 -197.403801) (xy 208.788022 -197.457749) (xy 208.788508 -197.485) (xy 208.788078 -197.510952)
			(xy 208.78103 -197.562375) (xy 208.767077 -197.612369) (xy 208.746477 -197.66001) (xy 208.719609 -197.704419)
			(xy 208.686971 -197.744777) (xy 208.668366 -197.762876) (xy 208.660492 -197.770242) (xy 208.65211 -197.790054)
			(xy 208.653888 -197.886828) (xy 208.662778 -197.906132) (xy 208.670906 -197.913244) (xy 208.690885 -197.931439)
			(xy 208.72601 -197.972505) (xy 208.754992 -198.018113) (xy 208.777253 -198.067353) (xy 208.792348 -198.11924)
			(xy 208.799974 -198.172737) (xy 208.800446 -198.199756) (xy 208.79996 -198.227007) (xy 208.792204 -198.280955)
			(xy 208.776849 -198.33325) (xy 208.754207 -198.382827) (xy 208.724741 -198.428677) (xy 208.68905 -198.469868)
			(xy 208.647859 -198.505559) (xy 208.602009 -198.535025) (xy 208.552432 -198.557667) (xy 208.500137 -198.573022)
			(xy 208.446189 -198.580778) (xy 208.391687 -198.580778) (xy 208.337739 -198.573022) (xy 208.285444 -198.557667)
			(xy 208.235867 -198.535025) (xy 208.190017 -198.505559) (xy 208.148826 -198.469868) (xy 208.113135 -198.428677)
			(xy 208.083669 -198.382827) (xy 208.061027 -198.33325) (xy 208.045672 -198.280955) (xy 208.037916 -198.227007)
			(xy 208.03743 -198.199756) (xy 208.03785 -198.173804) (xy 208.044903 -198.122381) (xy 208.058859 -198.072388)
			(xy 208.079462 -198.024747) (xy 208.10633 -197.980338) (xy 208.138968 -197.93998) (xy 208.157572 -197.92188)
			(xy 208.165446 -197.914514) (xy 208.173828 -197.894702) (xy 208.17205 -197.797928) (xy 208.16316 -197.778624)
			(xy 208.155032 -197.771512) (xy 208.135039 -197.753331) (xy 208.099914 -197.712264) (xy 208.070933 -197.666652)
			(xy 208.048674 -197.61741) (xy 208.033583 -197.56552) (xy 208.025961 -197.51202) (xy 208.025492 -197.485)
			(xy 207.444086 -197.485) (xy 207.444086 -198.755) (xy 209.040982 -198.755) (xy 209.045053 -198.699378)
			(xy 209.057179 -198.644941) (xy 209.077102 -198.59285) (xy 209.104398 -198.544215) (xy 209.138484 -198.500072)
			(xy 209.178633 -198.461363) (xy 209.223991 -198.428912) (xy 209.273591 -198.403411) (xy 209.326375 -198.385404)
			(xy 209.381218 -198.375274) (xy 209.436952 -198.373237) (xy 209.492389 -198.379337) (xy 209.546346 -198.393443)
			(xy 209.597675 -198.415255) (xy 209.645281 -198.444309) (xy 209.688149 -198.479984) (xy 209.725366 -198.521521)
			(xy 209.756139 -198.568034) (xy 209.779811 -198.618531) (xy 209.795879 -198.671938) (xy 209.803999 -198.727114)
			(xy 209.804508 -198.755) (xy 209.803999 -198.782886) (xy 209.795879 -198.838062) (xy 209.779811 -198.891469)
			(xy 209.756139 -198.941966) (xy 209.725366 -198.988479) (xy 209.688149 -199.030016) (xy 209.645281 -199.065691)
			(xy 209.597675 -199.094745) (xy 209.546346 -199.116557) (xy 209.492389 -199.130663) (xy 209.436952 -199.136763)
			(xy 209.381218 -199.134726) (xy 209.326375 -199.124596) (xy 209.273591 -199.106589) (xy 209.223991 -199.081088)
			(xy 209.178633 -199.048637) (xy 209.138484 -199.009928) (xy 209.104398 -198.965785) (xy 209.077102 -198.91715)
			(xy 209.057179 -198.865059) (xy 209.045053 -198.810622) (xy 209.040982 -198.755) (xy 207.444086 -198.755)
			(xy 207.444086 -199.898) (xy 209.656932 -199.898) (xy 209.661003 -199.842378) (xy 209.673129 -199.787941)
			(xy 209.693052 -199.73585) (xy 209.720348 -199.687215) (xy 209.754434 -199.643072) (xy 209.794583 -199.604363)
			(xy 209.839941 -199.571912) (xy 209.889541 -199.546411) (xy 209.942325 -199.528404) (xy 209.997168 -199.518274)
			(xy 210.052902 -199.516237) (xy 210.108339 -199.522337) (xy 210.162296 -199.536443) (xy 210.213625 -199.558255)
			(xy 210.261231 -199.587309) (xy 210.304099 -199.622984) (xy 210.341316 -199.664521) (xy 210.372089 -199.711034)
			(xy 210.395761 -199.761531) (xy 210.411829 -199.814938) (xy 210.419949 -199.870114) (xy 210.420458 -199.898)
			(xy 210.419949 -199.925886) (xy 210.411829 -199.981062) (xy 210.395761 -200.034469) (xy 210.372089 -200.084966)
			(xy 210.341316 -200.131479) (xy 210.304099 -200.173016) (xy 210.261231 -200.208691) (xy 210.213625 -200.237745)
			(xy 210.162296 -200.259557) (xy 210.108339 -200.273663) (xy 210.052902 -200.279763) (xy 209.997168 -200.277726)
			(xy 209.942325 -200.267596) (xy 209.889541 -200.249589) (xy 209.839941 -200.224088) (xy 209.794583 -200.191637)
			(xy 209.754434 -200.152928) (xy 209.720348 -200.108785) (xy 209.693052 -200.06015) (xy 209.673129 -200.008059)
			(xy 209.661003 -199.953622) (xy 209.656932 -199.898) (xy 207.444086 -199.898) (xy 207.444086 -201.168)
			(xy 208.024982 -201.168) (xy 208.029053 -201.112378) (xy 208.041179 -201.057941) (xy 208.061102 -201.00585)
			(xy 208.088398 -200.957215) (xy 208.122484 -200.913072) (xy 208.162633 -200.874363) (xy 208.207991 -200.841912)
			(xy 208.257591 -200.816411) (xy 208.310375 -200.798404) (xy 208.365218 -200.788274) (xy 208.420952 -200.786237)
			(xy 208.476389 -200.792337) (xy 208.530346 -200.806443) (xy 208.581675 -200.828255) (xy 208.629281 -200.857309)
			(xy 208.672149 -200.892984) (xy 208.709366 -200.934521) (xy 208.740139 -200.981034) (xy 208.763811 -201.031531)
			(xy 208.779879 -201.084938) (xy 208.787999 -201.140114) (xy 208.788508 -201.168) (xy 208.787999 -201.195886)
			(xy 208.780328 -201.24801) (xy 209.00085 -201.24801) (xy 209.004921 -201.192388) (xy 209.017047 -201.137951)
			(xy 209.03697 -201.08586) (xy 209.064266 -201.037225) (xy 209.098352 -200.993082) (xy 209.138501 -200.954373)
			(xy 209.183859 -200.921922) (xy 209.233459 -200.896421) (xy 209.286243 -200.878414) (xy 209.341086 -200.868284)
			(xy 209.39682 -200.866247) (xy 209.452257 -200.872347) (xy 209.506214 -200.886453) (xy 209.557543 -200.908265)
			(xy 209.605149 -200.937319) (xy 209.648017 -200.972994) (xy 209.685234 -201.014531) (xy 209.716007 -201.061044)
			(xy 209.739679 -201.111541) (xy 209.755747 -201.164948) (xy 209.763867 -201.220124) (xy 209.764376 -201.24801)
			(xy 209.763867 -201.275896) (xy 209.755747 -201.331072) (xy 209.739679 -201.384479) (xy 209.716007 -201.434976)
			(xy 209.685234 -201.481489) (xy 209.648017 -201.523026) (xy 209.605149 -201.558701) (xy 209.557543 -201.587755)
			(xy 209.506214 -201.609567) (xy 209.452257 -201.623673) (xy 209.39682 -201.629773) (xy 209.341086 -201.627736)
			(xy 209.286243 -201.617606) (xy 209.233459 -201.599599) (xy 209.183859 -201.574098) (xy 209.138501 -201.541647)
			(xy 209.098352 -201.502938) (xy 209.064266 -201.458795) (xy 209.03697 -201.41016) (xy 209.017047 -201.358069)
			(xy 209.004921 -201.303632) (xy 209.00085 -201.24801) (xy 208.780328 -201.24801) (xy 208.779879 -201.251062)
			(xy 208.763811 -201.304469) (xy 208.740139 -201.354966) (xy 208.709366 -201.401479) (xy 208.672149 -201.443016)
			(xy 208.629281 -201.478691) (xy 208.581675 -201.507745) (xy 208.530346 -201.529557) (xy 208.476389 -201.543663)
			(xy 208.420952 -201.549763) (xy 208.365218 -201.547726) (xy 208.310375 -201.537596) (xy 208.257591 -201.519589)
			(xy 208.207991 -201.494088) (xy 208.162633 -201.461637) (xy 208.122484 -201.422928) (xy 208.088398 -201.378785)
			(xy 208.061102 -201.33015) (xy 208.041179 -201.278059) (xy 208.029053 -201.223622) (xy 208.024982 -201.168)
			(xy 207.444086 -201.168) (xy 207.444086 -202.773026) (xy 207.443658 -202.783094) (xy 207.435935 -202.80169)
			(xy 207.4291 -202.809094) (xy 207.329532 -202.908662) (xy 207.322692 -202.916062) (xy 207.314975 -202.934661)
			(xy 207.314546 -202.94473) (xy 207.314546 -203.334366) (xy 208.00771 -203.334366) (xy 208.011781 -203.278744)
			(xy 208.023907 -203.224307) (xy 208.04383 -203.172216) (xy 208.071126 -203.123581) (xy 208.105212 -203.079438)
			(xy 208.145361 -203.040729) (xy 208.190719 -203.008278) (xy 208.240319 -202.982777) (xy 208.293103 -202.96477)
			(xy 208.347946 -202.95464) (xy 208.40368 -202.952603) (xy 208.459117 -202.958703) (xy 208.513074 -202.972809)
			(xy 208.564403 -202.994621) (xy 208.612009 -203.023675) (xy 208.654877 -203.05935) (xy 208.692094 -203.100887)
			(xy 208.722867 -203.1474) (xy 208.746539 -203.197897) (xy 208.762607 -203.251304) (xy 208.770727 -203.30648)
			(xy 208.771102 -203.327) (xy 209.040982 -203.327) (xy 209.045053 -203.271378) (xy 209.057179 -203.216941)
			(xy 209.077102 -203.16485) (xy 209.104398 -203.116215) (xy 209.138484 -203.072072) (xy 209.178633 -203.033363)
			(xy 209.223991 -203.000912) (xy 209.273591 -202.975411) (xy 209.326375 -202.957404) (xy 209.381218 -202.947274)
			(xy 209.436952 -202.945237) (xy 209.492389 -202.951337) (xy 209.546346 -202.965443) (xy 209.597675 -202.987255)
			(xy 209.645281 -203.016309) (xy 209.688149 -203.051984) (xy 209.725366 -203.093521) (xy 209.756139 -203.140034)
			(xy 209.779811 -203.190531) (xy 209.795879 -203.243938) (xy 209.803999 -203.299114) (xy 209.804508 -203.327)
			(xy 209.803999 -203.354886) (xy 209.795879 -203.410062) (xy 209.779811 -203.463469) (xy 209.756139 -203.513966)
			(xy 209.725366 -203.560479) (xy 209.688149 -203.602016) (xy 209.645281 -203.637691) (xy 209.597675 -203.666745)
			(xy 209.546346 -203.688557) (xy 209.492389 -203.702663) (xy 209.436952 -203.708763) (xy 209.381218 -203.706726)
			(xy 209.326375 -203.696596) (xy 209.273591 -203.678589) (xy 209.223991 -203.653088) (xy 209.178633 -203.620637)
			(xy 209.138484 -203.581928) (xy 209.104398 -203.537785) (xy 209.077102 -203.48915) (xy 209.057179 -203.437059)
			(xy 209.045053 -203.382622) (xy 209.040982 -203.327) (xy 208.771102 -203.327) (xy 208.771236 -203.334366)
			(xy 208.770727 -203.362252) (xy 208.762607 -203.417428) (xy 208.746539 -203.470835) (xy 208.722867 -203.521332)
			(xy 208.692094 -203.567845) (xy 208.654877 -203.609382) (xy 208.612009 -203.645057) (xy 208.564403 -203.674111)
			(xy 208.513074 -203.695923) (xy 208.459117 -203.710029) (xy 208.40368 -203.716129) (xy 208.347946 -203.714092)
			(xy 208.293103 -203.703962) (xy 208.240319 -203.685955) (xy 208.190719 -203.660454) (xy 208.145361 -203.628003)
			(xy 208.105212 -203.589294) (xy 208.071126 -203.545151) (xy 208.04383 -203.496516) (xy 208.023907 -203.444425)
			(xy 208.011781 -203.389988) (xy 208.00771 -203.334366) (xy 207.314546 -203.334366) (xy 207.314546 -204.47)
			(xy 209.656932 -204.47) (xy 209.661003 -204.414378) (xy 209.673129 -204.359941) (xy 209.693052 -204.30785)
			(xy 209.720348 -204.259215) (xy 209.754434 -204.215072) (xy 209.794583 -204.176363) (xy 209.839941 -204.143912)
			(xy 209.889541 -204.118411) (xy 209.942325 -204.100404) (xy 209.997168 -204.090274) (xy 210.052902 -204.088237)
			(xy 210.108339 -204.094337) (xy 210.162296 -204.108443) (xy 210.213625 -204.130255) (xy 210.261231 -204.159309)
			(xy 210.304099 -204.194984) (xy 210.341316 -204.236521) (xy 210.372089 -204.283034) (xy 210.395761 -204.333531)
			(xy 210.411829 -204.386938) (xy 210.419949 -204.442114) (xy 210.420458 -204.47) (xy 210.419949 -204.497886)
			(xy 210.411829 -204.553062) (xy 210.395761 -204.606469) (xy 210.372089 -204.656966) (xy 210.341316 -204.703479)
			(xy 210.304099 -204.745016) (xy 210.261231 -204.780691) (xy 210.213625 -204.809745) (xy 210.162296 -204.831557)
			(xy 210.108339 -204.845663) (xy 210.052902 -204.851763) (xy 209.997168 -204.849726) (xy 209.942325 -204.839596)
			(xy 209.889541 -204.821589) (xy 209.839941 -204.796088) (xy 209.794583 -204.763637) (xy 209.754434 -204.724928)
			(xy 209.720348 -204.680785) (xy 209.693052 -204.63215) (xy 209.673129 -204.580059) (xy 209.661003 -204.525622)
			(xy 209.656932 -204.47) (xy 207.314546 -204.47) (xy 207.314546 -205.77429) (xy 207.516982 -205.77429)
			(xy 207.521053 -205.718668) (xy 207.533179 -205.664231) (xy 207.553102 -205.61214) (xy 207.580398 -205.563505)
			(xy 207.614484 -205.519362) (xy 207.654633 -205.480653) (xy 207.699991 -205.448202) (xy 207.749591 -205.422701)
			(xy 207.802375 -205.404694) (xy 207.857218 -205.394564) (xy 207.912952 -205.392527) (xy 207.968389 -205.398627)
			(xy 208.022346 -205.412733) (xy 208.073675 -205.434545) (xy 208.121281 -205.463599) (xy 208.164149 -205.499274)
			(xy 208.201366 -205.540811) (xy 208.232139 -205.587324) (xy 208.255811 -205.637821) (xy 208.271879 -205.691228)
			(xy 208.279999 -205.746404) (xy 208.280508 -205.77429) (xy 208.279999 -205.802176) (xy 208.271879 -205.857352)
			(xy 208.255811 -205.910759) (xy 208.232139 -205.961256) (xy 208.201366 -206.007769) (xy 208.164149 -206.049306)
			(xy 208.121281 -206.084981) (xy 208.073675 -206.114035) (xy 208.022346 -206.135847) (xy 207.968389 -206.149953)
			(xy 207.912952 -206.156053) (xy 207.857218 -206.154016) (xy 207.802375 -206.143886) (xy 207.749591 -206.125879)
			(xy 207.699991 -206.100378) (xy 207.654633 -206.067927) (xy 207.614484 -206.029218) (xy 207.580398 -205.985075)
			(xy 207.553102 -205.93644) (xy 207.533179 -205.884349) (xy 207.521053 -205.829912) (xy 207.516982 -205.77429)
			(xy 207.314546 -205.77429) (xy 207.314546 -206.288894) (xy 213.358982 -206.288894) (xy 213.363053 -206.233272)
			(xy 213.375179 -206.178835) (xy 213.395102 -206.126744) (xy 213.422398 -206.078109) (xy 213.456484 -206.033966)
			(xy 213.496633 -205.995257) (xy 213.541991 -205.962806) (xy 213.591591 -205.937305) (xy 213.644375 -205.919298)
			(xy 213.699218 -205.909168) (xy 213.754952 -205.907131) (xy 213.810389 -205.913231) (xy 213.864346 -205.927337)
			(xy 213.915675 -205.949149) (xy 213.963281 -205.978203) (xy 214.006149 -206.013878) (xy 214.043366 -206.055415)
			(xy 214.074139 -206.101928) (xy 214.097811 -206.152425) (xy 214.113879 -206.205832) (xy 214.121999 -206.261008)
			(xy 214.122508 -206.288894) (xy 214.121999 -206.31678) (xy 214.113879 -206.371956) (xy 214.097811 -206.425363)
			(xy 214.074139 -206.47586) (xy 214.043366 -206.522373) (xy 214.006149 -206.56391) (xy 213.963281 -206.599585)
			(xy 213.915675 -206.628639) (xy 213.864346 -206.650451) (xy 213.810389 -206.664557) (xy 213.754952 -206.670657)
			(xy 213.699218 -206.66862) (xy 213.644375 -206.65849) (xy 213.591591 -206.640483) (xy 213.541991 -206.614982)
			(xy 213.496633 -206.582531) (xy 213.456484 -206.543822) (xy 213.422398 -206.499679) (xy 213.395102 -206.451044)
			(xy 213.375179 -206.398953) (xy 213.363053 -206.344516) (xy 213.358982 -206.288894) (xy 207.314546 -206.288894)
			(xy 207.314546 -206.756) (xy 207.516982 -206.756) (xy 207.521053 -206.700378) (xy 207.533179 -206.645941)
			(xy 207.553102 -206.59385) (xy 207.580398 -206.545215) (xy 207.614484 -206.501072) (xy 207.654633 -206.462363)
			(xy 207.699991 -206.429912) (xy 207.749591 -206.404411) (xy 207.802375 -206.386404) (xy 207.857218 -206.376274)
			(xy 207.912952 -206.374237) (xy 207.968389 -206.380337) (xy 208.022346 -206.394443) (xy 208.073675 -206.416255)
			(xy 208.121281 -206.445309) (xy 208.164149 -206.480984) (xy 208.201366 -206.522521) (xy 208.232139 -206.569034)
			(xy 208.255811 -206.619531) (xy 208.271879 -206.672938) (xy 208.279999 -206.728114) (xy 208.280508 -206.756)
			(xy 208.279999 -206.783886) (xy 208.271879 -206.839062) (xy 208.255811 -206.892469) (xy 208.232139 -206.942966)
			(xy 208.201366 -206.989479) (xy 208.164149 -207.031016) (xy 208.121281 -207.066691) (xy 208.073675 -207.095745)
			(xy 208.022346 -207.117557) (xy 207.968389 -207.131663) (xy 207.912952 -207.137763) (xy 207.857218 -207.135726)
			(xy 207.802375 -207.125596) (xy 207.749591 -207.107589) (xy 207.699991 -207.082088) (xy 207.654633 -207.049637)
			(xy 207.614484 -207.010928) (xy 207.580398 -206.966785) (xy 207.553102 -206.91815) (xy 207.533179 -206.866059)
			(xy 207.521053 -206.811622) (xy 207.516982 -206.756) (xy 207.314546 -206.756) (xy 207.314546 -207.376268)
			(xy 207.315049 -207.387105) (xy 207.324003 -207.406843) (xy 207.331818 -207.414368) (xy 207.337406 -207.419448)
			(xy 207.428084 -207.46085) (xy 207.437129 -207.464567) (xy 207.45664 -207.46555) (xy 207.475088 -207.459119)
			(xy 207.482694 -207.452976) (xy 207.50362 -207.435498) (xy 207.549493 -207.406032) (xy 207.59909 -207.38339)
			(xy 207.651404 -207.368031) (xy 207.705369 -207.360268) (xy 207.73263 -207.359758) (xy 207.759882 -207.360246)
			(xy 207.813832 -207.368007) (xy 207.866127 -207.383366) (xy 207.915705 -207.406011) (xy 207.961556 -207.43548)
			(xy 208.002746 -207.471175) (xy 208.038438 -207.512368) (xy 208.067904 -207.558221) (xy 208.090545 -207.607801)
			(xy 208.1059 -207.660098) (xy 208.113656 -207.714048) (xy 208.113656 -207.768552) (xy 208.1059 -207.822502)
			(xy 208.090545 -207.874799) (xy 208.067904 -207.924379) (xy 208.038438 -207.970232) (xy 208.002746 -208.011425)
			(xy 207.961556 -208.04712) (xy 207.915705 -208.076589) (xy 207.866127 -208.099234) (xy 207.813832 -208.114593)
			(xy 207.759882 -208.122354) (xy 207.73263 -208.122774) (xy 207.732376 -208.122774) (xy 207.705111 -208.122316)
			(xy 207.651135 -208.114564) (xy 207.598811 -208.099208) (xy 207.549207 -208.076559) (xy 207.503332 -208.04708)
			(xy 207.48244 -208.029556) (xy 207.47101 -208.01965) (xy 207.4418 -208.015332) (xy 207.344264 -208.060036)
			(xy 207.335605 -208.064457) (xy 207.322198 -208.078513) (xy 207.314989 -208.096551) (xy 207.314546 -208.106264)
			(xy 207.314546 -208.928716) (xy 207.31517 -208.940559) (xy 207.325776 -208.961737) (xy 207.334866 -208.969356)
			(xy 207.3402 -208.97342) (xy 207.341724 -208.974436) (xy 207.364555 -208.989509) (xy 207.40605 -209.02516)
			(xy 207.420746 -209.042) (xy 209.656932 -209.042) (xy 209.661003 -208.986378) (xy 209.673129 -208.931941)
			(xy 209.693052 -208.87985) (xy 209.720348 -208.831215) (xy 209.754434 -208.787072) (xy 209.794583 -208.748363)
			(xy 209.839941 -208.715912) (xy 209.889541 -208.690411) (xy 209.942325 -208.672404) (xy 209.997168 -208.662274)
			(xy 210.052902 -208.660237) (xy 210.108339 -208.666337) (xy 210.162296 -208.680443) (xy 210.213625 -208.702255)
			(xy 210.261231 -208.731309) (xy 210.304099 -208.766984) (xy 210.341316 -208.808521) (xy 210.372089 -208.855034)
			(xy 210.395761 -208.905531) (xy 210.411829 -208.958938) (xy 210.419949 -209.014114) (xy 210.420458 -209.042)
			(xy 210.419949 -209.069886) (xy 210.411829 -209.125062) (xy 210.395761 -209.178469) (xy 210.372089 -209.228966)
			(xy 210.341316 -209.275479) (xy 210.304099 -209.317016) (xy 210.261231 -209.352691) (xy 210.213625 -209.381745)
			(xy 210.175717 -209.397854) (xy 212.189058 -209.397854) (xy 212.193129 -209.342232) (xy 212.205255 -209.287795)
			(xy 212.225178 -209.235704) (xy 212.252474 -209.187069) (xy 212.28656 -209.142926) (xy 212.326709 -209.104217)
			(xy 212.372067 -209.071766) (xy 212.421667 -209.046265) (xy 212.474451 -209.028258) (xy 212.529294 -209.018128)
			(xy 212.585028 -209.016091) (xy 212.640465 -209.022191) (xy 212.694422 -209.036297) (xy 212.745751 -209.058109)
			(xy 212.793357 -209.087163) (xy 212.836225 -209.122838) (xy 212.873442 -209.164375) (xy 212.876838 -209.169508)
			(xy 215.066878 -209.169508) (xy 215.070949 -209.113886) (xy 215.083075 -209.059449) (xy 215.102998 -209.007358)
			(xy 215.130294 -208.958723) (xy 215.16438 -208.91458) (xy 215.204529 -208.875871) (xy 215.249887 -208.84342)
			(xy 215.299487 -208.817919) (xy 215.352271 -208.799912) (xy 215.407114 -208.789782) (xy 215.462848 -208.787745)
			(xy 215.518285 -208.793845) (xy 215.572242 -208.807951) (xy 215.623571 -208.829763) (xy 215.671177 -208.858817)
			(xy 215.714045 -208.894492) (xy 215.751262 -208.936029) (xy 215.782035 -208.982542) (xy 215.805707 -209.033039)
			(xy 215.821775 -209.086446) (xy 215.829895 -209.141622) (xy 215.830404 -209.169508) (xy 215.829895 -209.197394)
			(xy 215.82585 -209.22488) (xy 215.97061 -209.22488) (xy 215.974681 -209.169258) (xy 215.986807 -209.114821)
			(xy 216.00673 -209.06273) (xy 216.034026 -209.014095) (xy 216.068112 -208.969952) (xy 216.108261 -208.931243)
			(xy 216.153619 -208.898792) (xy 216.203219 -208.873291) (xy 216.256003 -208.855284) (xy 216.310846 -208.845154)
			(xy 216.36658 -208.843117) (xy 216.422017 -208.849217) (xy 216.475974 -208.863323) (xy 216.527303 -208.885135)
			(xy 216.574909 -208.914189) (xy 216.617777 -208.949864) (xy 216.654994 -208.991401) (xy 216.685767 -209.037914)
			(xy 216.709439 -209.088411) (xy 216.725507 -209.141818) (xy 216.733627 -209.196994) (xy 216.734136 -209.22488)
			(xy 216.733627 -209.252766) (xy 216.725507 -209.307942) (xy 216.709439 -209.361349) (xy 216.685767 -209.411846)
			(xy 216.654994 -209.458359) (xy 216.617777 -209.499896) (xy 216.574909 -209.535571) (xy 216.527303 -209.564625)
			(xy 216.475974 -209.586437) (xy 216.422017 -209.600543) (xy 216.36658 -209.606643) (xy 216.310846 -209.604606)
			(xy 216.256003 -209.594476) (xy 216.203219 -209.576469) (xy 216.153619 -209.550968) (xy 216.108261 -209.518517)
			(xy 216.068112 -209.479808) (xy 216.034026 -209.435665) (xy 216.00673 -209.38703) (xy 215.986807 -209.334939)
			(xy 215.974681 -209.280502) (xy 215.97061 -209.22488) (xy 215.82585 -209.22488) (xy 215.821775 -209.25257)
			(xy 215.805707 -209.305977) (xy 215.782035 -209.356474) (xy 215.751262 -209.402987) (xy 215.714045 -209.444524)
			(xy 215.671177 -209.480199) (xy 215.623571 -209.509253) (xy 215.572242 -209.531065) (xy 215.518285 -209.545171)
			(xy 215.462848 -209.551271) (xy 215.407114 -209.549234) (xy 215.352271 -209.539104) (xy 215.299487 -209.521097)
			(xy 215.249887 -209.495596) (xy 215.204529 -209.463145) (xy 215.16438 -209.424436) (xy 215.130294 -209.380293)
			(xy 215.102998 -209.331658) (xy 215.083075 -209.279567) (xy 215.070949 -209.22513) (xy 215.066878 -209.169508)
			(xy 212.876838 -209.169508) (xy 212.904215 -209.210888) (xy 212.927887 -209.261385) (xy 212.943955 -209.314792)
			(xy 212.952075 -209.369968) (xy 212.952584 -209.397854) (xy 212.952075 -209.42574) (xy 212.943955 -209.480916)
			(xy 212.927887 -209.534323) (xy 212.904215 -209.58482) (xy 212.873442 -209.631333) (xy 212.836225 -209.67287)
			(xy 212.793357 -209.708545) (xy 212.745751 -209.737599) (xy 212.694422 -209.759411) (xy 212.640465 -209.773517)
			(xy 212.585028 -209.779617) (xy 212.529294 -209.77758) (xy 212.474451 -209.76745) (xy 212.421667 -209.749443)
			(xy 212.372067 -209.723942) (xy 212.326709 -209.691491) (xy 212.28656 -209.652782) (xy 212.252474 -209.608639)
			(xy 212.225178 -209.560004) (xy 212.205255 -209.507913) (xy 212.193129 -209.453476) (xy 212.189058 -209.397854)
			(xy 210.175717 -209.397854) (xy 210.162296 -209.403557) (xy 210.108339 -209.417663) (xy 210.052902 -209.423763)
			(xy 209.997168 -209.421726) (xy 209.942325 -209.411596) (xy 209.889541 -209.393589) (xy 209.839941 -209.368088)
			(xy 209.794583 -209.335637) (xy 209.754434 -209.296928) (xy 209.720348 -209.252785) (xy 209.693052 -209.20415)
			(xy 209.673129 -209.152059) (xy 209.661003 -209.097622) (xy 209.656932 -209.042) (xy 207.420746 -209.042)
			(xy 207.442021 -209.066378) (xy 207.471728 -209.112317) (xy 207.494559 -209.162032) (xy 207.510045 -209.214502)
			(xy 207.517869 -209.268646) (xy 207.517869 -209.323354) (xy 207.510045 -209.377498) (xy 207.494559 -209.429968)
			(xy 207.471728 -209.479683) (xy 207.442021 -209.525622) (xy 207.40605 -209.56684) (xy 207.364555 -209.602491)
			(xy 207.341724 -209.617564) (xy 207.3402 -209.61858) (xy 207.334866 -209.622644) (xy 207.325751 -209.630242)
			(xy 207.315139 -209.651434) (xy 207.314546 -209.663284) (xy 207.314546 -210.450938) (xy 207.333596 -210.477354)
			(xy 207.349344 -210.482434) (xy 207.375837 -210.491752) (xy 207.425968 -210.517062) (xy 207.47185 -210.549444)
			(xy 207.512492 -210.588199) (xy 207.547017 -210.632491) (xy 207.574679 -210.681363) (xy 207.594882 -210.733762)
			(xy 207.602158 -210.766152) (xy 210.424776 -210.766152) (xy 210.425262 -210.738901) (xy 210.433018 -210.684953)
			(xy 210.448373 -210.632658) (xy 210.471015 -210.583081) (xy 210.500481 -210.537231) (xy 210.536172 -210.49604)
			(xy 210.577363 -210.460349) (xy 210.623213 -210.430883) (xy 210.67279 -210.408241) (xy 210.725085 -210.392886)
			(xy 210.779033 -210.38513) (xy 210.833535 -210.38513) (xy 210.887483 -210.392886) (xy 210.939778 -210.408241)
			(xy 210.989355 -210.430883) (xy 211.003171 -210.439762) (xy 219.192348 -210.439762) (xy 219.192834 -210.412511)
			(xy 219.20059 -210.358563) (xy 219.215945 -210.306268) (xy 219.238587 -210.256691) (xy 219.268053 -210.210841)
			(xy 219.303744 -210.16965) (xy 219.344935 -210.133959) (xy 219.390785 -210.104493) (xy 219.440362 -210.081851)
			(xy 219.492657 -210.066496) (xy 219.546605 -210.05874) (xy 219.601107 -210.05874) (xy 219.655055 -210.066496)
			(xy 219.70735 -210.081851) (xy 219.756927 -210.104493) (xy 219.802777 -210.133959) (xy 219.843968 -210.16965)
			(xy 219.879659 -210.210841) (xy 219.909125 -210.256691) (xy 219.931767 -210.306268) (xy 219.947122 -210.358563)
			(xy 219.954878 -210.412511) (xy 219.955364 -210.439762) (xy 219.954731 -210.470454) (xy 219.944914 -210.531049)
			(xy 219.925528 -210.589291) (xy 219.89707 -210.643681) (xy 219.879164 -210.668616) (xy 219.87256 -210.677252)
			(xy 219.867734 -210.69808) (xy 219.886276 -210.793584) (xy 219.898722 -210.810856) (xy 219.907866 -210.816698)
			(xy 219.931649 -210.831553) (xy 219.974939 -210.867195) (xy 220.012542 -210.908794) (xy 220.016338 -210.914488)
			(xy 222.243142 -210.914488) (xy 222.243559 -210.888123) (xy 222.250846 -210.835898) (xy 222.265253 -210.785174)
			(xy 222.286505 -210.736915) (xy 222.314197 -210.692041) (xy 222.347803 -210.651406) (xy 222.386682 -210.615784)
			(xy 222.430094 -210.585853) (xy 222.453454 -210.57362) (xy 222.461836 -210.569302) (xy 222.474282 -210.555586)
			(xy 222.506286 -210.475068) (xy 222.50654 -210.456526) (xy 222.503238 -210.447636) (xy 222.492342 -210.415906)
			(xy 222.480594 -210.349859) (xy 222.47987 -210.316318) (xy 222.480356 -210.289067) (xy 222.488112 -210.235119)
			(xy 222.503467 -210.182824) (xy 222.526109 -210.133247) (xy 222.555575 -210.087397) (xy 222.591266 -210.046206)
			(xy 222.632457 -210.010515) (xy 222.678307 -209.981049) (xy 222.727884 -209.958407) (xy 222.780179 -209.943052)
			(xy 222.834127 -209.935296) (xy 222.888629 -209.935296) (xy 222.942577 -209.943052) (xy 222.994872 -209.958407)
			(xy 223.044449 -209.981049) (xy 223.090299 -210.010515) (xy 223.13149 -210.046206) (xy 223.167181 -210.087397)
			(xy 223.196647 -210.133247) (xy 223.219289 -210.182824) (xy 223.234644 -210.235119) (xy 223.2424 -210.289067)
			(xy 223.242886 -210.316318) (xy 223.242376 -210.34268) (xy 223.235102 -210.3949) (xy 223.220709 -210.445621)
			(xy 223.218257 -210.451192) (xy 225.760786 -210.451192) (xy 225.764857 -210.39557) (xy 225.776983 -210.341133)
			(xy 225.796906 -210.289042) (xy 225.824202 -210.240407) (xy 225.858288 -210.196264) (xy 225.898437 -210.157555)
			(xy 225.943795 -210.125104) (xy 225.993395 -210.099603) (xy 226.046179 -210.081596) (xy 226.101022 -210.071466)
			(xy 226.156756 -210.069429) (xy 226.212193 -210.075529) (xy 226.26615 -210.089635) (xy 226.317479 -210.111447)
			(xy 226.365085 -210.140501) (xy 226.407953 -210.176176) (xy 226.44517 -210.217713) (xy 226.475943 -210.264226)
			(xy 226.499615 -210.314723) (xy 226.515683 -210.36813) (xy 226.523803 -210.423306) (xy 226.524312 -210.451192)
			(xy 226.960682 -210.451192) (xy 226.964753 -210.39557) (xy 226.976879 -210.341133) (xy 226.996802 -210.289042)
			(xy 227.024098 -210.240407) (xy 227.058184 -210.196264) (xy 227.098333 -210.157555) (xy 227.143691 -210.125104)
			(xy 227.193291 -210.099603) (xy 227.246075 -210.081596) (xy 227.300918 -210.071466) (xy 227.356652 -210.069429)
			(xy 227.412089 -210.075529) (xy 227.466046 -210.089635) (xy 227.517375 -210.111447) (xy 227.564981 -210.140501)
			(xy 227.607849 -210.176176) (xy 227.645066 -210.217713) (xy 227.675839 -210.264226) (xy 227.699511 -210.314723)
			(xy 227.715579 -210.36813) (xy 227.723699 -210.423306) (xy 227.724208 -210.451192) (xy 227.723699 -210.479078)
			(xy 227.715579 -210.534254) (xy 227.699511 -210.587661) (xy 227.675839 -210.638158) (xy 227.645066 -210.684671)
			(xy 227.607849 -210.726208) (xy 227.564981 -210.761883) (xy 227.517375 -210.790937) (xy 227.466046 -210.812749)
			(xy 227.412089 -210.826855) (xy 227.356652 -210.832955) (xy 227.300918 -210.830918) (xy 227.246075 -210.820788)
			(xy 227.193291 -210.802781) (xy 227.143691 -210.77728) (xy 227.098333 -210.744829) (xy 227.058184 -210.70612)
			(xy 227.024098 -210.661977) (xy 226.996802 -210.613342) (xy 226.976879 -210.561251) (xy 226.964753 -210.506814)
			(xy 226.960682 -210.451192) (xy 226.524312 -210.451192) (xy 226.523803 -210.479078) (xy 226.515683 -210.534254)
			(xy 226.499615 -210.587661) (xy 226.475943 -210.638158) (xy 226.44517 -210.684671) (xy 226.407953 -210.726208)
			(xy 226.365085 -210.761883) (xy 226.317479 -210.790937) (xy 226.26615 -210.812749) (xy 226.212193 -210.826855)
			(xy 226.156756 -210.832955) (xy 226.101022 -210.830918) (xy 226.046179 -210.820788) (xy 225.993395 -210.802781)
			(xy 225.943795 -210.77728) (xy 225.898437 -210.744829) (xy 225.858288 -210.70612) (xy 225.824202 -210.661977)
			(xy 225.796906 -210.613342) (xy 225.776983 -210.561251) (xy 225.764857 -210.506814) (xy 225.760786 -210.451192)
			(xy 223.218257 -210.451192) (xy 223.19947 -210.493879) (xy 223.171791 -210.538753) (xy 223.138198 -210.579389)
			(xy 223.09933 -210.615015) (xy 223.055929 -210.644951) (xy 223.032574 -210.657186) (xy 223.024192 -210.661504)
			(xy 223.011746 -210.67522) (xy 222.979742 -210.755738) (xy 222.979488 -210.77428) (xy 222.98279 -210.78317)
			(xy 222.993689 -210.814899) (xy 223.005434 -210.880947) (xy 223.006158 -210.914488) (xy 223.005672 -210.941739)
			(xy 222.997916 -210.995687) (xy 222.982561 -211.047982) (xy 222.959919 -211.097559) (xy 222.930453 -211.143409)
			(xy 222.894762 -211.1846) (xy 222.853571 -211.220291) (xy 222.807721 -211.249757) (xy 222.758144 -211.272399)
			(xy 222.705849 -211.287754) (xy 222.651901 -211.29551) (xy 222.597399 -211.29551) (xy 222.543451 -211.287754)
			(xy 222.491156 -211.272399) (xy 222.441579 -211.249757) (xy 222.395729 -211.220291) (xy 222.354538 -211.1846)
			(xy 222.318847 -211.143409) (xy 222.289381 -211.097559) (xy 222.266739 -211.047982) (xy 222.251384 -210.995687)
			(xy 222.243628 -210.941739) (xy 222.243142 -210.914488) (xy 220.016338 -210.914488) (xy 220.043644 -210.955452)
			(xy 220.067577 -211.006164) (xy 220.083822 -211.059834) (xy 220.092031 -211.115305) (xy 220.092524 -211.143342)
			(xy 220.092038 -211.170593) (xy 220.084282 -211.224541) (xy 220.068927 -211.276836) (xy 220.046285 -211.326413)
			(xy 220.016819 -211.372263) (xy 219.981128 -211.413454) (xy 219.939937 -211.449145) (xy 219.894087 -211.478611)
			(xy 219.84451 -211.501253) (xy 219.792215 -211.516608) (xy 219.738267 -211.524364) (xy 219.683765 -211.524364)
			(xy 219.629817 -211.516608) (xy 219.577522 -211.501253) (xy 219.527945 -211.478611) (xy 219.482095 -211.449145)
			(xy 219.440904 -211.413454) (xy 219.405213 -211.372263) (xy 219.375747 -211.326413) (xy 219.353105 -211.276836)
			(xy 219.33775 -211.224541) (xy 219.329994 -211.170593) (xy 219.329508 -211.143342) (xy 219.330148 -211.11265)
			(xy 219.339964 -211.052056) (xy 219.359349 -210.993814) (xy 219.387803 -210.939423) (xy 219.405708 -210.914488)
			(xy 219.412312 -210.905852) (xy 219.417138 -210.885024) (xy 219.398596 -210.78952) (xy 219.38615 -210.772248)
			(xy 219.377006 -210.766406) (xy 219.353218 -210.751558) (xy 219.309929 -210.715914) (xy 219.272329 -210.674313)
			(xy 219.241227 -210.627654) (xy 219.217295 -210.576942) (xy 219.20105 -210.523271) (xy 219.192842 -210.4678)
			(xy 219.192348 -210.439762) (xy 211.003171 -210.439762) (xy 211.035205 -210.460349) (xy 211.076396 -210.49604)
			(xy 211.112087 -210.537231) (xy 211.141553 -210.583081) (xy 211.164195 -210.632658) (xy 211.17955 -210.684953)
			(xy 211.187306 -210.738901) (xy 211.187792 -210.766152) (xy 211.187292 -210.793621) (xy 211.179418 -210.847991)
			(xy 211.163826 -210.900669) (xy 211.140838 -210.950566) (xy 211.110931 -210.996649) (xy 211.074722 -211.037965)
			(xy 211.032961 -211.07366) (xy 211.009992 -211.088732) (xy 210.997643 -211.097198) (xy 210.978014 -211.119779)
			(xy 210.96578 -211.147084) (xy 210.96535 -211.150454) (xy 212.175598 -211.150454) (xy 212.176035 -211.123201)
			(xy 212.183798 -211.069252) (xy 212.199159 -211.016956) (xy 212.221806 -210.967378) (xy 212.251278 -210.921527)
			(xy 212.286974 -210.880337) (xy 212.328169 -210.844647) (xy 212.374023 -210.815181) (xy 212.423604 -210.792541)
			(xy 212.475902 -210.777187) (xy 212.529853 -210.769431) (xy 212.557106 -210.768946) (xy 212.582771 -210.769352)
			(xy 212.633637 -210.776228) (xy 212.68312 -210.789868) (xy 212.730325 -210.810026) (xy 212.774398 -210.836336)
			(xy 212.814541 -210.868323) (xy 212.850029 -210.905408) (xy 212.865462 -210.925918) (xy 212.87359 -210.937094)
			(xy 212.89899 -210.948016) (xy 213.014306 -210.934046) (xy 213.036404 -210.917282) (xy 213.041484 -210.904582)
			(xy 213.052671 -210.8787) (xy 213.081514 -210.830253) (xy 213.117173 -210.786578) (xy 213.15887 -210.748627)
			(xy 213.2057 -210.717225) (xy 213.25664 -210.693057) (xy 213.310583 -210.676648) (xy 213.366352 -210.668357)
			(xy 213.394544 -210.667854) (xy 213.421795 -210.668337) (xy 213.47574 -210.676098) (xy 213.528033 -210.691457)
			(xy 213.577608 -210.714101) (xy 213.623456 -210.743568) (xy 213.664645 -210.779259) (xy 213.700336 -210.820449)
			(xy 213.729802 -210.866297) (xy 213.752445 -210.915873) (xy 213.767803 -210.968165) (xy 213.775564 -211.022111)
			(xy 213.776052 -211.049362) (xy 213.775578 -211.077761) (xy 213.767163 -211.133931) (xy 213.750513 -211.188233)
			(xy 213.748172 -211.193126) (xy 215.643966 -211.193126) (xy 215.648037 -211.137504) (xy 215.660163 -211.083067)
			(xy 215.680086 -211.030976) (xy 215.707382 -210.982341) (xy 215.741468 -210.938198) (xy 215.781617 -210.899489)
			(xy 215.826975 -210.867038) (xy 215.876575 -210.841537) (xy 215.929359 -210.82353) (xy 215.984202 -210.8134)
			(xy 216.039936 -210.811363) (xy 216.095373 -210.817463) (xy 216.14933 -210.831569) (xy 216.200659 -210.853381)
			(xy 216.248265 -210.882435) (xy 216.291133 -210.91811) (xy 216.32835 -210.959647) (xy 216.359123 -211.00616)
			(xy 216.382795 -211.056657) (xy 216.398863 -211.110064) (xy 216.406983 -211.16524) (xy 216.407492 -211.193126)
			(xy 216.406983 -211.221012) (xy 216.398863 -211.276188) (xy 216.382795 -211.329595) (xy 216.359123 -211.380092)
			(xy 216.32835 -211.426605) (xy 216.291133 -211.468142) (xy 216.248265 -211.503817) (xy 216.200659 -211.532871)
			(xy 216.14933 -211.554683) (xy 216.095373 -211.568789) (xy 216.039936 -211.574889) (xy 215.984202 -211.572852)
			(xy 215.929359 -211.562722) (xy 215.876575 -211.544715) (xy 215.826975 -211.519214) (xy 215.781617 -211.486763)
			(xy 215.741468 -211.448054) (xy 215.707382 -211.403911) (xy 215.680086 -211.355276) (xy 215.660163 -211.303185)
			(xy 215.648037 -211.248748) (xy 215.643966 -211.193126) (xy 213.748172 -211.193126) (xy 213.725996 -211.239466)
			(xy 213.694155 -211.286499) (xy 213.655692 -211.32829) (xy 213.611458 -211.363918) (xy 213.562431 -211.392593)
			(xy 213.509694 -211.413683) (xy 213.482174 -211.42071) (xy 213.472776 -211.422742) (xy 213.457536 -211.433156)
			(xy 213.408006 -211.50453) (xy 213.403434 -211.522564) (xy 213.404704 -211.531962) (xy 213.406039 -211.543599)
			(xy 213.407436 -211.566984) (xy 213.407498 -211.578698) (xy 213.407043 -211.605951) (xy 213.399286 -211.659903)
			(xy 213.38393 -211.712202) (xy 213.361287 -211.761782) (xy 213.331818 -211.807636) (xy 213.296123 -211.848829)
			(xy 213.25493 -211.884523) (xy 213.209075 -211.91399) (xy 213.159494 -211.936632) (xy 213.107195 -211.951988)
			(xy 213.053243 -211.959743) (xy 213.02599 -211.960206) (xy 212.998183 -211.959722) (xy 212.943161 -211.951619)
			(xy 212.889899 -211.935616) (xy 212.839523 -211.912052) (xy 212.7931 -211.881426) (xy 212.751615 -211.844385)
			(xy 212.715945 -211.801716) (xy 212.686846 -211.754321) (xy 212.664935 -211.703205) (xy 212.650675 -211.649449)
			(xy 212.647022 -211.621878) (xy 212.645752 -211.61248) (xy 212.637624 -211.596478) (xy 212.574378 -211.53882)
			(xy 212.557614 -211.531962) (xy 212.548216 -211.531962) (xy 212.521384 -211.530898) (xy 212.468408 -211.522108)
			(xy 212.417186 -211.50598) (xy 212.368731 -211.482832) (xy 212.323999 -211.45312) (xy 212.283873 -211.417433)
			(xy 212.249145 -211.376473) (xy 212.2205 -211.331051) (xy 212.198505 -211.282062) (xy 212.183593 -211.230473)
			(xy 212.176059 -211.177304) (xy 212.175598 -211.150454) (xy 210.96535 -211.150454) (xy 210.961992 -211.176764)
			(xy 210.966977 -211.206266) (xy 210.980306 -211.233054) (xy 211.000832 -211.254823) (xy 211.013548 -211.262722)
			(xy 211.038087 -211.277463) (xy 211.082906 -211.31307) (xy 211.121905 -211.354971) (xy 211.154209 -211.402227)
			(xy 211.179093 -211.453776) (xy 211.196001 -211.508464) (xy 211.204551 -211.565063) (xy 211.205064 -211.593684)
			(xy 211.204578 -211.620935) (xy 211.196822 -211.674883) (xy 211.181467 -211.727178) (xy 211.158825 -211.776755)
			(xy 211.129359 -211.822605) (xy 211.093668 -211.863796) (xy 211.052477 -211.899487) (xy 211.006627 -211.928953)
			(xy 210.95705 -211.951595) (xy 210.904755 -211.96695) (xy 210.850807 -211.974706) (xy 210.796305 -211.974706)
			(xy 210.742357 -211.96695) (xy 210.690062 -211.951595) (xy 210.640485 -211.928953) (xy 210.594635 -211.899487)
			(xy 210.553444 -211.863796) (xy 210.517753 -211.822605) (xy 210.488287 -211.776755) (xy 210.465645 -211.727178)
			(xy 210.45029 -211.674883) (xy 210.442534 -211.620935) (xy 210.442048 -211.593684) (xy 210.44248 -211.566213)
			(xy 210.450364 -211.511839) (xy 210.465967 -211.459158) (xy 210.488965 -211.409261) (xy 210.518883 -211.363178)
			(xy 210.555103 -211.321865) (xy 210.596874 -211.286174) (xy 210.619848 -211.271104) (xy 210.632266 -211.262728)
			(xy 210.65191 -211.24013) (xy 210.66415 -211.212804) (xy 210.667933 -211.183102) (xy 210.662932 -211.15358)
			(xy 210.649579 -211.12678) (xy 210.629023 -211.105009) (xy 210.616292 -211.097114) (xy 210.591711 -211.08244)
			(xy 210.546895 -211.04682) (xy 210.507901 -211.004906) (xy 210.475602 -210.957639) (xy 210.450725 -210.90608)
			(xy 210.433826 -210.851383) (xy 210.425284 -210.794776) (xy 210.424776 -210.766152) (xy 207.602158 -210.766152)
			(xy 207.60719 -210.788555) (xy 207.611335 -210.84456) (xy 207.607231 -210.900568) (xy 207.594964 -210.95537)
			(xy 207.574799 -211.007783) (xy 207.547173 -211.056676) (xy 207.51268 -211.100993) (xy 207.472067 -211.139778)
			(xy 207.426209 -211.172194) (xy 207.376096 -211.19754) (xy 207.349598 -211.206842) (xy 207.34909 -211.206842)
			(xy 207.339198 -211.210723) (xy 207.32353 -211.22504) (xy 207.315026 -211.244487) (xy 207.314546 -211.255102)
			(xy 207.314546 -212.440012) (xy 207.314546 -212.441028) (xy 207.31541 -212.453405) (xy 207.327395 -212.475099)
			(xy 207.337406 -212.48243) (xy 207.34528 -212.48751) (xy 207.35417 -212.489796) (xy 207.354678 -212.489796)
			(xy 207.382187 -212.496736) (xy 207.434924 -212.517645) (xy 207.483982 -212.546136) (xy 207.528278 -212.581581)
			(xy 207.566834 -212.623197) (xy 207.598798 -212.670066) (xy 207.623467 -212.721154) (xy 207.640294 -212.775332)
			(xy 207.648909 -212.831406) (xy 207.649122 -212.888137) (xy 207.640928 -212.944273) (xy 207.624508 -212.998576)
			(xy 207.600223 -213.049847) (xy 207.568611 -213.096955) (xy 207.530369 -213.138859) (xy 207.48634 -213.174636)
			(xy 207.437498 -213.203495) (xy 207.384918 -213.224799) (xy 207.357472 -213.231984) (xy 207.353662 -213.232746)
			(xy 207.346042 -213.236048) (xy 207.336909 -213.240255) (xy 207.322672 -213.254433) (xy 207.314971 -213.272991)
			(xy 207.314546 -213.283038) (xy 207.314546 -213.313264) (xy 209.351626 -213.313264) (xy 209.352112 -213.286661)
			(xy 209.359486 -213.233969) (xy 209.374113 -213.182814) (xy 209.395709 -213.134189) (xy 209.423855 -213.089038)
			(xy 209.458004 -213.048238) (xy 209.497494 -213.012581) (xy 209.519266 -212.997288) (xy 209.530736 -212.988938)
			(xy 209.548945 -212.9672) (xy 209.560467 -212.941289) (xy 209.56441 -212.913208) (xy 209.560471 -212.885126)
			(xy 209.548953 -212.859213) (xy 209.530747 -212.837472) (xy 209.519266 -212.82914) (xy 209.497511 -212.813824)
			(xy 209.458031 -212.778162) (xy 209.423885 -212.737362) (xy 209.395738 -212.692216) (xy 209.374133 -212.643598)
			(xy 209.359489 -212.592451) (xy 209.352091 -212.539765) (xy 209.351626 -212.513164) (xy 209.352112 -212.485913)
			(xy 209.359868 -212.431965) (xy 209.375223 -212.37967) (xy 209.397865 -212.330093) (xy 209.427331 -212.284243)
			(xy 209.463022 -212.243052) (xy 209.504213 -212.207361) (xy 209.550063 -212.177895) (xy 209.59964 -212.155253)
			(xy 209.651935 -212.139898) (xy 209.705883 -212.132142) (xy 209.760385 -212.132142) (xy 209.814333 -212.139898)
			(xy 209.83993 -212.147414) (xy 211.849514 -212.147414) (xy 211.849519 -212.092918) (xy 211.857279 -212.038976)
			(xy 211.872637 -211.986689) (xy 211.89528 -211.937119) (xy 211.924747 -211.891276) (xy 211.960438 -211.850093)
			(xy 212.001627 -211.814409) (xy 212.047475 -211.784949) (xy 212.097049 -211.762315) (xy 212.149339 -211.746965)
			(xy 212.203282 -211.739214) (xy 212.257778 -211.739218) (xy 212.31172 -211.746978) (xy 212.364008 -211.762336)
			(xy 212.413578 -211.784978) (xy 212.459421 -211.814445) (xy 212.500604 -211.850135) (xy 212.536289 -211.891324)
			(xy 212.565749 -211.937171) (xy 212.588384 -211.986745) (xy 212.603734 -212.039035) (xy 212.611486 -212.092978)
			(xy 212.61197 -212.120226) (xy 212.611462 -212.138514) (xy 212.611227 -212.153217) (xy 212.618247 -212.181762)
			(xy 212.63309 -212.207135) (xy 212.654533 -212.227243) (xy 212.680806 -212.240427) (xy 212.709743 -212.2456)
			(xy 212.738957 -212.242335) (xy 212.752686 -212.237066) (xy 212.776281 -212.227514) (xy 212.825377 -212.214073)
			(xy 212.875825 -212.207277) (xy 212.901276 -212.20684) (xy 212.928529 -212.207252) (xy 212.98248 -212.215005)
			(xy 213.034778 -212.230358) (xy 213.042439 -212.233856) (xy 215.108441 -212.233856) (xy 215.108441 -212.179344)
			(xy 215.116199 -212.125388) (xy 215.131558 -212.073086) (xy 215.154204 -212.023501) (xy 215.183676 -211.977645)
			(xy 215.219375 -211.936449) (xy 215.260574 -211.900754) (xy 215.306433 -211.871286) (xy 215.356019 -211.848645)
			(xy 215.408324 -211.833292) (xy 215.46228 -211.825538) (xy 215.489536 -211.825078) (xy 215.515852 -211.825534)
			(xy 215.567985 -211.832755) (xy 215.618633 -211.847068) (xy 215.666835 -211.868202) (xy 215.711677 -211.895756)
			(xy 215.75231 -211.929208) (xy 215.77046 -211.948268) (xy 215.777999 -211.955649) (xy 215.797266 -211.964187)
			(xy 215.807798 -211.964778) (xy 215.882474 -211.964778) (xy 215.893025 -211.964255) (xy 215.91232 -211.955716)
			(xy 215.919812 -211.948268) (xy 215.937954 -211.929196) (xy 215.978572 -211.895714) (xy 216.02341 -211.868141)
			(xy 216.071616 -211.847001) (xy 216.122273 -211.832696) (xy 216.174417 -211.825498) (xy 216.200736 -211.825078)
			(xy 216.227985 -211.825595) (xy 216.279125 -211.832952) (xy 242.36883 -211.832952) (xy 242.372901 -211.77733)
			(xy 242.385027 -211.722893) (xy 242.40495 -211.670802) (xy 242.432246 -211.622167) (xy 242.466332 -211.578024)
			(xy 242.506481 -211.539315) (xy 242.551839 -211.506864) (xy 242.601439 -211.481363) (xy 242.654223 -211.463356)
			(xy 242.709066 -211.453226) (xy 242.7648 -211.451189) (xy 242.820237 -211.457289) (xy 242.874194 -211.471395)
			(xy 242.925523 -211.493207) (xy 242.973129 -211.522261) (xy 243.015997 -211.557936) (xy 243.053214 -211.599473)
			(xy 243.083987 -211.645986) (xy 243.107659 -211.696483) (xy 243.123727 -211.74989) (xy 243.131847 -211.805066)
			(xy 243.132356 -211.832952) (xy 243.131847 -211.860838) (xy 243.123727 -211.916014) (xy 243.107659 -211.969421)
			(xy 243.083987 -212.019918) (xy 243.053214 -212.066431) (xy 243.034145 -212.087714) (xy 246.890032 -212.087714)
			(xy 246.890468 -212.06046) (xy 246.898225 -212.006506) (xy 246.913581 -211.954205) (xy 246.936225 -211.904622)
			(xy 246.965695 -211.858767) (xy 247.001392 -211.817573) (xy 247.042588 -211.781879) (xy 247.088445 -211.752412)
			(xy 247.138029 -211.729772) (xy 247.190331 -211.714419) (xy 247.244286 -211.706667) (xy 247.27154 -211.706206)
			(xy 247.298049 -211.706686) (xy 247.350556 -211.714031) (xy 247.40154 -211.728575) (xy 247.45002 -211.750037)
			(xy 247.495062 -211.778004) (xy 247.535798 -211.811938) (xy 247.571444 -211.851185) (xy 247.586754 -211.87283)
			(xy 247.593866 -211.883244) (xy 247.61571 -211.894928) (xy 247.724422 -211.895944) (xy 247.74652 -211.884768)
			(xy 247.753632 -211.874354) (xy 247.769051 -211.853347) (xy 247.804649 -211.815293) (xy 247.845092 -211.782435)
			(xy 247.889629 -211.755385) (xy 247.937432 -211.734643) (xy 247.987612 -211.720597) (xy 248.039236 -211.713508)
			(xy 248.06529 -211.713064) (xy 248.09254 -211.713587) (xy 248.146485 -211.721342) (xy 248.198777 -211.736694)
			(xy 248.248352 -211.759332) (xy 248.294201 -211.788795) (xy 248.335391 -211.824482) (xy 248.371082 -211.865668)
			(xy 248.40055 -211.911515) (xy 248.423192 -211.961087) (xy 248.43855 -212.013378) (xy 248.44631 -212.067322)
			(xy 248.446798 -212.094572) (xy 248.446595 -212.11343) (xy 248.442901 -212.150965) (xy 248.439432 -212.169502)
			(xy 248.436638 -212.183218) (xy 248.445782 -212.209634) (xy 248.535952 -212.284564) (xy 248.563638 -212.289136)
			(xy 248.576592 -212.283802) (xy 248.599094 -212.275243) (xy 248.645722 -212.263247) (xy 248.693489 -212.257224)
			(xy 248.717562 -212.256878) (xy 248.744816 -212.257367) (xy 248.798769 -212.265119) (xy 248.851069 -212.280471)
			(xy 248.900652 -212.303111) (xy 248.946508 -212.332577) (xy 248.987704 -212.368269) (xy 249.023401 -212.409461)
			(xy 249.052871 -212.455314) (xy 249.075516 -212.504895) (xy 249.090873 -212.557194) (xy 249.098631 -212.611146)
			(xy 249.098631 -212.638386) (xy 250.494544 -212.638386) (xy 250.498615 -212.582764) (xy 250.510741 -212.528327)
			(xy 250.530664 -212.476236) (xy 250.55796 -212.427601) (xy 250.592046 -212.383458) (xy 250.632195 -212.344749)
			(xy 250.677553 -212.312298) (xy 250.727153 -212.286797) (xy 250.779937 -212.26879) (xy 250.83478 -212.25866)
			(xy 250.890514 -212.256623) (xy 250.945951 -212.262723) (xy 250.999908 -212.276829) (xy 251.051237 -212.298641)
			(xy 251.098843 -212.327695) (xy 251.141711 -212.36337) (xy 251.178928 -212.404907) (xy 251.209701 -212.45142)
			(xy 251.233373 -212.501917) (xy 251.249441 -212.555324) (xy 251.257561 -212.6105) (xy 251.25807 -212.638386)
			(xy 251.257561 -212.666272) (xy 251.249441 -212.721448) (xy 251.233373 -212.774855) (xy 251.209701 -212.825352)
			(xy 251.178928 -212.871865) (xy 251.141711 -212.913402) (xy 251.098843 -212.949077) (xy 251.051237 -212.978131)
			(xy 250.999908 -212.999943) (xy 250.945951 -213.014049) (xy 250.890514 -213.020149) (xy 250.83478 -213.018112)
			(xy 250.779937 -213.007982) (xy 250.727153 -212.989975) (xy 250.677553 -212.964474) (xy 250.632195 -212.932023)
			(xy 250.592046 -212.893314) (xy 250.55796 -212.849171) (xy 250.530664 -212.800536) (xy 250.510741 -212.748445)
			(xy 250.498615 -212.694008) (xy 250.494544 -212.638386) (xy 249.098631 -212.638386) (xy 249.098631 -212.665654)
			(xy 249.090873 -212.719606) (xy 249.075516 -212.771905) (xy 249.052871 -212.821486) (xy 249.023401 -212.867339)
			(xy 248.987704 -212.908531) (xy 248.946508 -212.944223) (xy 248.900652 -212.973689) (xy 248.851069 -212.996329)
			(xy 248.798769 -213.011681) (xy 248.744816 -213.019433) (xy 248.717562 -213.019894) (xy 248.692527 -213.019478)
			(xy 248.642891 -213.012901) (xy 248.594537 -212.999904) (xy 248.571258 -212.990684) (xy 248.562368 -212.986874)
			(xy 248.543826 -212.98662) (xy 248.46153 -213.015576) (xy 248.447306 -213.027768) (xy 248.442734 -213.03615)
			(xy 248.428366 -213.061709) (xy 248.392932 -213.108425) (xy 248.350766 -213.149167) (xy 248.302861 -213.182976)
			(xy 248.250347 -213.209056) (xy 248.19446 -213.226791) (xy 248.136517 -213.235765) (xy 248.1072 -213.236302)
			(xy 248.079598 -213.235783) (xy 248.024969 -213.227827) (xy 247.972057 -213.212083) (xy 247.921967 -213.188878)
			(xy 247.875743 -213.158696) (xy 247.854724 -213.140798) (xy 247.847612 -213.134702) (xy 247.83034 -213.128098)
			(xy 247.744488 -213.128098) (xy 247.727216 -213.134702) (xy 247.720104 -213.140798) (xy 247.699067 -213.158676)
			(xy 247.652853 -213.188873) (xy 247.602768 -213.212092) (xy 247.549859 -213.227848) (xy 247.495231 -213.235811)
			(xy 247.467628 -213.236302) (xy 247.440376 -213.235819) (xy 247.386425 -213.228065) (xy 247.334127 -213.212713)
			(xy 247.284547 -213.190073) (xy 247.238693 -213.160607) (xy 247.1975 -213.124916) (xy 247.161806 -213.083724)
			(xy 247.132338 -213.037873) (xy 247.109695 -212.988293) (xy 247.094339 -212.935996) (xy 247.086583 -212.882046)
			(xy 247.08612 -212.854794) (xy 247.086595 -212.827696) (xy 247.094276 -212.774048) (xy 247.109468 -212.722025)
			(xy 247.131866 -212.672675) (xy 247.16102 -212.626989) (xy 247.178322 -212.606128) (xy 247.18645 -212.596476)
			(xy 247.192038 -212.572346) (xy 247.165368 -212.467698) (xy 247.148858 -212.449156) (xy 247.137174 -212.444838)
			(xy 247.110313 -212.434188) (xy 247.059928 -212.405901) (xy 247.014383 -212.370344) (xy 246.974718 -212.328327)
			(xy 246.94184 -212.280811) (xy 246.9165 -212.228882) (xy 246.899277 -212.173726) (xy 246.890565 -212.116605)
			(xy 246.890032 -212.087714) (xy 243.034145 -212.087714) (xy 243.015997 -212.107968) (xy 242.973129 -212.143643)
			(xy 242.925523 -212.172697) (xy 242.874194 -212.194509) (xy 242.820237 -212.208615) (xy 242.7648 -212.214715)
			(xy 242.709066 -212.212678) (xy 242.654223 -212.202548) (xy 242.601439 -212.184541) (xy 242.551839 -212.15904)
			(xy 242.506481 -212.126589) (xy 242.466332 -212.08788) (xy 242.432246 -212.043737) (xy 242.40495 -211.995102)
			(xy 242.385027 -211.943011) (xy 242.372901 -211.888574) (xy 242.36883 -211.832952) (xy 216.279125 -211.832952)
			(xy 216.281926 -211.833355) (xy 216.334215 -211.848713) (xy 216.383786 -211.871355) (xy 216.42963 -211.900821)
			(xy 216.470814 -211.936511) (xy 216.5065 -211.977699) (xy 216.535962 -212.023546) (xy 216.5586 -212.073119)
			(xy 216.573953 -212.125409) (xy 216.581708 -212.179351) (xy 216.581708 -212.233849) (xy 216.573953 -212.287791)
			(xy 216.561453 -212.330363) (xy 222.737682 -212.330363) (xy 222.737682 -212.278389) (xy 222.745812 -212.227054)
			(xy 222.761873 -212.177624) (xy 222.785469 -212.131314) (xy 222.816019 -212.089266) (xy 222.85277 -212.052515)
			(xy 222.894818 -212.021965) (xy 222.941128 -211.998369) (xy 222.990558 -211.982308) (xy 223.041893 -211.974178)
			(xy 223.093867 -211.974178) (xy 223.145202 -211.982308) (xy 223.194632 -211.998369) (xy 223.240942 -212.021965)
			(xy 223.28299 -212.052515) (xy 223.319741 -212.089266) (xy 223.350291 -212.131314) (xy 223.373887 -212.177624)
			(xy 223.389948 -212.227054) (xy 223.398078 -212.278389) (xy 223.398588 -212.304376) (xy 223.398078 -212.330363)
			(xy 223.537782 -212.330363) (xy 223.537782 -212.278389) (xy 223.545912 -212.227054) (xy 223.561973 -212.177624)
			(xy 223.585569 -212.131314) (xy 223.616119 -212.089266) (xy 223.65287 -212.052515) (xy 223.694918 -212.021965)
			(xy 223.741228 -211.998369) (xy 223.790658 -211.982308) (xy 223.841993 -211.974178) (xy 223.893967 -211.974178)
			(xy 223.945302 -211.982308) (xy 223.994732 -211.998369) (xy 224.041042 -212.021965) (xy 224.08309 -212.052515)
			(xy 224.119841 -212.089266) (xy 224.150391 -212.131314) (xy 224.173987 -212.177624) (xy 224.180204 -212.196759)
			(xy 224.737424 -212.196759) (xy 224.737424 -212.144785) (xy 224.745554 -212.09345) (xy 224.761615 -212.04402)
			(xy 224.785211 -211.99771) (xy 224.815761 -211.955662) (xy 224.852512 -211.918911) (xy 224.89456 -211.888361)
			(xy 224.94087 -211.864765) (xy 224.9903 -211.848704) (xy 225.041635 -211.840574) (xy 225.093609 -211.840574)
			(xy 225.144944 -211.848704) (xy 225.194374 -211.864765) (xy 225.240684 -211.888361) (xy 225.282732 -211.918911)
			(xy 225.319483 -211.955662) (xy 225.350033 -211.99771) (xy 225.373629 -212.04402) (xy 225.38969 -212.09345)
			(xy 225.39782 -212.144785) (xy 225.39833 -212.170772) (xy 225.39782 -212.196759) (xy 225.38969 -212.248094)
			(xy 225.373629 -212.297524) (xy 225.356638 -212.330871) (xy 226.737674 -212.330871) (xy 226.737674 -212.278897)
			(xy 226.745804 -212.227562) (xy 226.761865 -212.178132) (xy 226.785461 -212.131822) (xy 226.816011 -212.089774)
			(xy 226.852762 -212.053023) (xy 226.89481 -212.022473) (xy 226.94112 -211.998877) (xy 226.99055 -211.982816)
			(xy 227.041885 -211.974686) (xy 227.093859 -211.974686) (xy 227.145194 -211.982816) (xy 227.194624 -211.998877)
			(xy 227.240934 -212.022473) (xy 227.282982 -212.053023) (xy 227.319733 -212.089774) (xy 227.350283 -212.131822)
			(xy 227.373879 -212.178132) (xy 227.38994 -212.227562) (xy 227.39807 -212.278897) (xy 227.39858 -212.304884)
			(xy 227.39808 -212.330363) (xy 228.337366 -212.330363) (xy 228.337366 -212.278389) (xy 228.345496 -212.227054)
			(xy 228.361557 -212.177624) (xy 228.385153 -212.131314) (xy 228.415703 -212.089266) (xy 228.452454 -212.052515)
			(xy 228.494502 -212.021965) (xy 228.540812 -211.998369) (xy 228.590242 -211.982308) (xy 228.641577 -211.974178)
			(xy 228.693551 -211.974178) (xy 228.744886 -211.982308) (xy 228.794316 -211.998369) (xy 228.840626 -212.021965)
			(xy 228.882674 -212.052515) (xy 228.919425 -212.089266) (xy 228.949975 -212.131314) (xy 228.973571 -212.177624)
			(xy 228.989632 -212.227054) (xy 228.997762 -212.278389) (xy 228.998272 -212.304376) (xy 228.997762 -212.330363)
			(xy 233.137204 -212.330363) (xy 233.137204 -212.278389) (xy 233.145334 -212.227054) (xy 233.161395 -212.177624)
			(xy 233.184991 -212.131314) (xy 233.215541 -212.089266) (xy 233.252292 -212.052515) (xy 233.29434 -212.021965)
			(xy 233.34065 -211.998369) (xy 233.39008 -211.982308) (xy 233.441415 -211.974178) (xy 233.493389 -211.974178)
			(xy 233.544724 -211.982308) (xy 233.594154 -211.998369) (xy 233.640464 -212.021965) (xy 233.682512 -212.052515)
			(xy 233.719263 -212.089266) (xy 233.749813 -212.131314) (xy 233.773409 -212.177624) (xy 233.78947 -212.227054)
			(xy 233.7976 -212.278389) (xy 233.79811 -212.304376) (xy 233.7976 -212.330363) (xy 235.53725 -212.330363)
			(xy 235.53725 -212.278389) (xy 235.54538 -212.227054) (xy 235.561441 -212.177624) (xy 235.585037 -212.131314)
			(xy 235.615587 -212.089266) (xy 235.652338 -212.052515) (xy 235.694386 -212.021965) (xy 235.740696 -211.998369)
			(xy 235.790126 -211.982308) (xy 235.841461 -211.974178) (xy 235.893435 -211.974178) (xy 235.94477 -211.982308)
			(xy 235.9942 -211.998369) (xy 236.04051 -212.021965) (xy 236.082558 -212.052515) (xy 236.119309 -212.089266)
			(xy 236.149859 -212.131314) (xy 236.173455 -212.177624) (xy 236.189516 -212.227054) (xy 236.197646 -212.278389)
			(xy 236.197937 -212.2932) (xy 240.647472 -212.2932) (xy 240.651543 -212.237578) (xy 240.663669 -212.183141)
			(xy 240.683592 -212.13105) (xy 240.710888 -212.082415) (xy 240.744974 -212.038272) (xy 240.785123 -211.999563)
			(xy 240.830481 -211.967112) (xy 240.880081 -211.941611) (xy 240.932865 -211.923604) (xy 240.987708 -211.913474)
			(xy 241.043442 -211.911437) (xy 241.098879 -211.917537) (xy 241.152836 -211.931643) (xy 241.204165 -211.953455)
			(xy 241.251771 -211.982509) (xy 241.294639 -212.018184) (xy 241.331856 -212.059721) (xy 241.362629 -212.106234)
			(xy 241.386301 -212.156731) (xy 241.402369 -212.210138) (xy 241.410489 -212.265314) (xy 241.410998 -212.2932)
			(xy 241.410489 -212.321086) (xy 241.402369 -212.376262) (xy 241.386301 -212.429669) (xy 241.362629 -212.480166)
			(xy 241.331856 -212.526679) (xy 241.294639 -212.568216) (xy 241.251771 -212.603891) (xy 241.204165 -212.632945)
			(xy 241.152836 -212.654757) (xy 241.098879 -212.668863) (xy 241.043442 -212.674963) (xy 240.987708 -212.672926)
			(xy 240.932865 -212.662796) (xy 240.880081 -212.644789) (xy 240.830481 -212.619288) (xy 240.785123 -212.586837)
			(xy 240.744974 -212.548128) (xy 240.710888 -212.503985) (xy 240.683592 -212.45535) (xy 240.663669 -212.403259)
			(xy 240.651543 -212.348822) (xy 240.647472 -212.2932) (xy 236.197937 -212.2932) (xy 236.198156 -212.304376)
			(xy 236.197646 -212.330363) (xy 236.189516 -212.381698) (xy 236.173455 -212.431128) (xy 236.149859 -212.477438)
			(xy 236.119309 -212.519486) (xy 236.082558 -212.556237) (xy 236.04051 -212.586787) (xy 235.9942 -212.610383)
			(xy 235.94477 -212.626444) (xy 235.893435 -212.634574) (xy 235.841461 -212.634574) (xy 235.790126 -212.626444)
			(xy 235.740696 -212.610383) (xy 235.694386 -212.586787) (xy 235.652338 -212.556237) (xy 235.615587 -212.519486)
			(xy 235.585037 -212.477438) (xy 235.561441 -212.431128) (xy 235.54538 -212.381698) (xy 235.53725 -212.330363)
			(xy 233.7976 -212.330363) (xy 233.78947 -212.381698) (xy 233.773409 -212.431128) (xy 233.749813 -212.477438)
			(xy 233.719263 -212.519486) (xy 233.682512 -212.556237) (xy 233.640464 -212.586787) (xy 233.594154 -212.610383)
			(xy 233.544724 -212.626444) (xy 233.493389 -212.634574) (xy 233.441415 -212.634574) (xy 233.39008 -212.626444)
			(xy 233.34065 -212.610383) (xy 233.29434 -212.586787) (xy 233.252292 -212.556237) (xy 233.215541 -212.519486)
			(xy 233.184991 -212.477438) (xy 233.161395 -212.431128) (xy 233.145334 -212.381698) (xy 233.137204 -212.330363)
			(xy 228.997762 -212.330363) (xy 228.989632 -212.381698) (xy 228.973571 -212.431128) (xy 228.949975 -212.477438)
			(xy 228.919425 -212.519486) (xy 228.882674 -212.556237) (xy 228.840626 -212.586787) (xy 228.794316 -212.610383)
			(xy 228.744886 -212.626444) (xy 228.693551 -212.634574) (xy 228.641577 -212.634574) (xy 228.590242 -212.626444)
			(xy 228.540812 -212.610383) (xy 228.494502 -212.586787) (xy 228.452454 -212.556237) (xy 228.415703 -212.519486)
			(xy 228.385153 -212.477438) (xy 228.361557 -212.431128) (xy 228.345496 -212.381698) (xy 228.337366 -212.330363)
			(xy 227.39808 -212.330363) (xy 227.39807 -212.330871) (xy 227.38994 -212.382206) (xy 227.373879 -212.431636)
			(xy 227.350283 -212.477946) (xy 227.319733 -212.519994) (xy 227.282982 -212.556745) (xy 227.240934 -212.587295)
			(xy 227.194624 -212.610891) (xy 227.145194 -212.626952) (xy 227.093859 -212.635082) (xy 227.041885 -212.635082)
			(xy 226.99055 -212.626952) (xy 226.94112 -212.610891) (xy 226.89481 -212.587295) (xy 226.852762 -212.556745)
			(xy 226.816011 -212.519994) (xy 226.785461 -212.477946) (xy 226.761865 -212.431636) (xy 226.745804 -212.382206)
			(xy 226.737674 -212.330871) (xy 225.356638 -212.330871) (xy 225.350033 -212.343834) (xy 225.319483 -212.385882)
			(xy 225.282732 -212.422633) (xy 225.240684 -212.453183) (xy 225.194374 -212.476779) (xy 225.144944 -212.49284)
			(xy 225.093609 -212.50097) (xy 225.041635 -212.50097) (xy 224.9903 -212.49284) (xy 224.94087 -212.476779)
			(xy 224.89456 -212.453183) (xy 224.852512 -212.422633) (xy 224.815761 -212.385882) (xy 224.785211 -212.343834)
			(xy 224.761615 -212.297524) (xy 224.745554 -212.248094) (xy 224.737424 -212.196759) (xy 224.180204 -212.196759)
			(xy 224.190048 -212.227054) (xy 224.198178 -212.278389) (xy 224.198688 -212.304376) (xy 224.198178 -212.330363)
			(xy 224.190048 -212.381698) (xy 224.173987 -212.431128) (xy 224.150391 -212.477438) (xy 224.119841 -212.519486)
			(xy 224.08309 -212.556237) (xy 224.041042 -212.586787) (xy 223.994732 -212.610383) (xy 223.945302 -212.626444)
			(xy 223.893967 -212.634574) (xy 223.841993 -212.634574) (xy 223.790658 -212.626444) (xy 223.741228 -212.610383)
			(xy 223.694918 -212.586787) (xy 223.65287 -212.556237) (xy 223.616119 -212.519486) (xy 223.585569 -212.477438)
			(xy 223.561973 -212.431128) (xy 223.545912 -212.381698) (xy 223.537782 -212.330363) (xy 223.398078 -212.330363)
			(xy 223.389948 -212.381698) (xy 223.373887 -212.431128) (xy 223.350291 -212.477438) (xy 223.319741 -212.519486)
			(xy 223.28299 -212.556237) (xy 223.240942 -212.586787) (xy 223.194632 -212.610383) (xy 223.145202 -212.626444)
			(xy 223.093867 -212.634574) (xy 223.041893 -212.634574) (xy 222.990558 -212.626444) (xy 222.941128 -212.610383)
			(xy 222.894818 -212.586787) (xy 222.85277 -212.556237) (xy 222.816019 -212.519486) (xy 222.785469 -212.477438)
			(xy 222.761873 -212.431128) (xy 222.745812 -212.381698) (xy 222.737682 -212.330363) (xy 216.561453 -212.330363)
			(xy 216.5586 -212.340081) (xy 216.535962 -212.389654) (xy 216.5065 -212.435501) (xy 216.470814 -212.476689)
			(xy 216.42963 -212.512379) (xy 216.383786 -212.541845) (xy 216.334215 -212.564487) (xy 216.281926 -212.579845)
			(xy 216.227985 -212.587605) (xy 216.200736 -212.588094) (xy 216.174419 -212.587665) (xy 216.122284 -212.58044)
			(xy 216.071635 -212.566123) (xy 216.023433 -212.544984) (xy 215.978592 -212.517424) (xy 215.937961 -212.483966)
			(xy 215.919812 -212.464904) (xy 215.912287 -212.457506) (xy 215.89301 -212.44898) (xy 215.882474 -212.448394)
			(xy 215.807798 -212.448394) (xy 215.797247 -212.44891) (xy 215.777952 -212.457455) (xy 215.77046 -212.464904)
			(xy 215.752346 -212.484004) (xy 215.711721 -212.51748) (xy 215.666876 -212.545047) (xy 215.618664 -212.566182)
			(xy 215.568004 -212.580483) (xy 215.515857 -212.587676) (xy 215.489536 -212.588094) (xy 215.46228 -212.587662)
			(xy 215.408324 -212.579908) (xy 215.356019 -212.564555) (xy 215.306433 -212.541914) (xy 215.260574 -212.512446)
			(xy 215.219375 -212.476751) (xy 215.183676 -212.435555) (xy 215.154204 -212.389699) (xy 215.131558 -212.340114)
			(xy 215.116199 -212.287812) (xy 215.108441 -212.233856) (xy 213.042439 -212.233856) (xy 213.084359 -212.252997)
			(xy 213.130214 -212.282461) (xy 213.171409 -212.318152) (xy 213.207105 -212.359341) (xy 213.236576 -212.405192)
			(xy 213.259223 -212.45477) (xy 213.274583 -212.507066) (xy 213.282344 -212.561015) (xy 213.282348 -212.615521)
			(xy 213.274596 -212.669472) (xy 213.259245 -212.72177) (xy 213.236607 -212.771352) (xy 213.207144 -212.817207)
			(xy 213.171454 -212.858403) (xy 213.130265 -212.8941) (xy 213.084415 -212.923573) (xy 213.034838 -212.94622)
			(xy 212.982542 -212.961581) (xy 212.928593 -212.969343) (xy 212.874087 -212.969349) (xy 212.820136 -212.961598)
			(xy 212.767837 -212.946248) (xy 212.718255 -212.923611) (xy 212.672399 -212.894148) (xy 212.631203 -212.85846)
			(xy 212.595504 -212.817272) (xy 212.566031 -212.771422) (xy 212.543383 -212.721845) (xy 212.528021 -212.66955)
			(xy 212.520257 -212.615601) (xy 212.519768 -212.588348) (xy 212.520276 -212.57006) (xy 212.520535 -212.555353)
			(xy 212.513528 -212.526794) (xy 212.498687 -212.501408) (xy 212.477238 -212.481291) (xy 212.450954 -212.468107)
			(xy 212.422005 -212.462943) (xy 212.392782 -212.466227) (xy 212.379052 -212.471508) (xy 212.355454 -212.481052)
			(xy 212.306359 -212.494495) (xy 212.255913 -212.501295) (xy 212.230462 -212.501734) (xy 212.203214 -212.501181)
			(xy 212.149273 -212.49342) (xy 212.096985 -212.478062) (xy 212.047415 -212.455418) (xy 212.001573 -212.425951)
			(xy 211.96039 -212.390259) (xy 211.924706 -212.34907) (xy 211.895247 -212.303222) (xy 211.872613 -212.253648)
			(xy 211.857265 -212.201357) (xy 211.849514 -212.147414) (xy 209.83993 -212.147414) (xy 209.866628 -212.155253)
			(xy 209.916205 -212.177895) (xy 209.962055 -212.207361) (xy 210.003246 -212.243052) (xy 210.038937 -212.284243)
			(xy 210.068403 -212.330093) (xy 210.091045 -212.37967) (xy 210.1064 -212.431965) (xy 210.114156 -212.485913)
			(xy 210.114642 -212.513164) (xy 210.114191 -212.539768) (xy 210.106813 -212.592462) (xy 210.092181 -212.643619)
			(xy 210.070579 -212.692245) (xy 210.042428 -212.737396) (xy 210.008272 -212.778194) (xy 209.968777 -212.813848)
			(xy 209.947002 -212.82914) (xy 209.935508 -212.837457) (xy 209.917304 -212.859204) (xy 209.905788 -212.885122)
			(xy 209.901849 -212.913208) (xy 209.905792 -212.941293) (xy 209.917312 -212.967209) (xy 209.93552 -212.988954)
			(xy 209.947002 -212.997288) (xy 209.968763 -213.012597) (xy 210.008245 -213.048259) (xy 210.04239 -213.089059)
			(xy 210.05612 -213.11108) (xy 210.384896 -213.11108) (xy 210.388967 -213.055458) (xy 210.401093 -213.001021)
			(xy 210.421016 -212.94893) (xy 210.448312 -212.900295) (xy 210.482398 -212.856152) (xy 210.522547 -212.817443)
			(xy 210.567905 -212.784992) (xy 210.617505 -212.759491) (xy 210.670289 -212.741484) (xy 210.725132 -212.731354)
			(xy 210.780866 -212.729317) (xy 210.836303 -212.735417) (xy 210.89026 -212.749523) (xy 210.941589 -212.771335)
			(xy 210.989195 -212.800389) (xy 211.032063 -212.836064) (xy 211.06928 -212.877601) (xy 211.100053 -212.924114)
			(xy 211.123725 -212.974611) (xy 211.139793 -213.028018) (xy 211.147913 -213.083194) (xy 211.148422 -213.11108)
			(xy 211.147913 -213.138966) (xy 211.139793 -213.194142) (xy 211.123725 -213.247549) (xy 211.122644 -213.249856)
			(xy 215.108441 -213.249856) (xy 215.108441 -213.195344) (xy 215.116199 -213.141388) (xy 215.131558 -213.089086)
			(xy 215.154204 -213.039501) (xy 215.183676 -212.993645) (xy 215.219375 -212.952449) (xy 215.260574 -212.916754)
			(xy 215.306433 -212.887286) (xy 215.356019 -212.864645) (xy 215.408324 -212.849292) (xy 215.46228 -212.841538)
			(xy 215.489536 -212.841078) (xy 215.515852 -212.841534) (xy 215.567985 -212.848755) (xy 215.618633 -212.863068)
			(xy 215.666835 -212.884202) (xy 215.711677 -212.911756) (xy 215.75231 -212.945208) (xy 215.77046 -212.964268)
			(xy 215.777999 -212.971649) (xy 215.797266 -212.980187) (xy 215.807798 -212.980778) (xy 215.882474 -212.980778)
			(xy 215.893025 -212.980255) (xy 215.91232 -212.971716) (xy 215.919812 -212.964268) (xy 215.937954 -212.945196)
			(xy 215.978572 -212.911714) (xy 216.02341 -212.884141) (xy 216.071616 -212.863001) (xy 216.122273 -212.848696)
			(xy 216.174417 -212.841498) (xy 216.200736 -212.841078) (xy 216.227985 -212.841595) (xy 216.281926 -212.849355)
			(xy 216.334215 -212.864713) (xy 216.383786 -212.887355) (xy 216.42963 -212.916821) (xy 216.470814 -212.952511)
			(xy 216.5065 -212.993699) (xy 216.535962 -213.039546) (xy 216.5586 -213.089119) (xy 216.570739 -213.130463)
			(xy 226.737674 -213.130463) (xy 226.737674 -213.078489) (xy 226.745804 -213.027154) (xy 226.761865 -212.977724)
			(xy 226.785461 -212.931414) (xy 226.816011 -212.889366) (xy 226.852762 -212.852615) (xy 226.89481 -212.822065)
			(xy 226.94112 -212.798469) (xy 226.99055 -212.782408) (xy 227.041885 -212.774278) (xy 227.093859 -212.774278)
			(xy 227.145194 -212.782408) (xy 227.194624 -212.798469) (xy 227.240934 -212.822065) (xy 227.282982 -212.852615)
			(xy 227.319733 -212.889366) (xy 227.350283 -212.931414) (xy 227.373879 -212.977724) (xy 227.38994 -213.027154)
			(xy 227.39807 -213.078489) (xy 227.39858 -213.104476) (xy 227.39808 -213.129955) (xy 228.33762 -213.129955)
			(xy 228.33762 -213.077981) (xy 228.34575 -213.026646) (xy 228.361811 -212.977216) (xy 228.385407 -212.930906)
			(xy 228.415957 -212.888858) (xy 228.452708 -212.852107) (xy 228.494756 -212.821557) (xy 228.541066 -212.797961)
			(xy 228.590496 -212.7819) (xy 228.641831 -212.77377) (xy 228.693805 -212.77377) (xy 228.74514 -212.7819)
			(xy 228.79457 -212.797961) (xy 228.84088 -212.821557) (xy 228.882928 -212.852107) (xy 228.919679 -212.888858)
			(xy 228.950229 -212.930906) (xy 228.973825 -212.977216) (xy 228.989886 -213.026646) (xy 228.998016 -213.077981)
			(xy 228.998526 -213.103968) (xy 228.998016 -213.129955) (xy 228.997936 -213.130463) (xy 229.937312 -213.130463)
			(xy 229.937312 -213.078489) (xy 229.945442 -213.027154) (xy 229.961503 -212.977724) (xy 229.985099 -212.931414)
			(xy 230.015649 -212.889366) (xy 230.0524 -212.852615) (xy 230.094448 -212.822065) (xy 230.140758 -212.798469)
			(xy 230.190188 -212.782408) (xy 230.241523 -212.774278) (xy 230.293497 -212.774278) (xy 230.344832 -212.782408)
			(xy 230.394262 -212.798469) (xy 230.440572 -212.822065) (xy 230.48262 -212.852615) (xy 230.519371 -212.889366)
			(xy 230.549921 -212.931414) (xy 230.573517 -212.977724) (xy 230.589578 -213.027154) (xy 230.597708 -213.078489)
			(xy 230.598218 -213.104476) (xy 230.597708 -213.130463) (xy 230.737158 -213.130463) (xy 230.737158 -213.078489)
			(xy 230.745288 -213.027154) (xy 230.761349 -212.977724) (xy 230.784945 -212.931414) (xy 230.815495 -212.889366)
			(xy 230.852246 -212.852615) (xy 230.894294 -212.822065) (xy 230.940604 -212.798469) (xy 230.990034 -212.782408)
			(xy 231.041369 -212.774278) (xy 231.093343 -212.774278) (xy 231.144678 -212.782408) (xy 231.194108 -212.798469)
			(xy 231.240418 -212.822065) (xy 231.282466 -212.852615) (xy 231.319217 -212.889366) (xy 231.349767 -212.931414)
			(xy 231.373363 -212.977724) (xy 231.389424 -213.027154) (xy 231.397554 -213.078489) (xy 231.398064 -213.104476)
			(xy 231.397554 -213.130463) (xy 233.137204 -213.130463) (xy 233.137204 -213.078489) (xy 233.145334 -213.027154)
			(xy 233.161395 -212.977724) (xy 233.184991 -212.931414) (xy 233.215541 -212.889366) (xy 233.252292 -212.852615)
			(xy 233.29434 -212.822065) (xy 233.34065 -212.798469) (xy 233.39008 -212.782408) (xy 233.441415 -212.774278)
			(xy 233.493389 -212.774278) (xy 233.502999 -212.7758) (xy 242.111782 -212.7758) (xy 242.115853 -212.720178)
			(xy 242.127979 -212.665741) (xy 242.147902 -212.61365) (xy 242.175198 -212.565015) (xy 242.209284 -212.520872)
			(xy 242.249433 -212.482163) (xy 242.294791 -212.449712) (xy 242.344391 -212.424211) (xy 242.397175 -212.406204)
			(xy 242.452018 -212.396074) (xy 242.507752 -212.394037) (xy 242.563189 -212.400137) (xy 242.617146 -212.414243)
			(xy 242.668475 -212.436055) (xy 242.716081 -212.465109) (xy 242.758949 -212.500784) (xy 242.796166 -212.542321)
			(xy 242.826939 -212.588834) (xy 242.850611 -212.639331) (xy 242.866679 -212.692738) (xy 242.874799 -212.747914)
			(xy 242.875308 -212.7758) (xy 242.874799 -212.803686) (xy 242.866679 -212.858862) (xy 242.850611 -212.912269)
			(xy 242.826939 -212.962766) (xy 242.811997 -212.98535) (xy 243.756432 -212.98535) (xy 243.760503 -212.929728)
			(xy 243.772629 -212.875291) (xy 243.792552 -212.8232) (xy 243.819848 -212.774565) (xy 243.853934 -212.730422)
			(xy 243.894083 -212.691713) (xy 243.939441 -212.659262) (xy 243.989041 -212.633761) (xy 244.041825 -212.615754)
			(xy 244.096668 -212.605624) (xy 244.152402 -212.603587) (xy 244.207839 -212.609687) (xy 244.261796 -212.623793)
			(xy 244.313125 -212.645605) (xy 244.360731 -212.674659) (xy 244.403599 -212.710334) (xy 244.440816 -212.751871)
			(xy 244.471589 -212.798384) (xy 244.495261 -212.848881) (xy 244.511329 -212.902288) (xy 244.519449 -212.957464)
			(xy 244.519958 -212.98535) (xy 244.519449 -213.013236) (xy 244.511329 -213.068412) (xy 244.495261 -213.121819)
			(xy 244.471589 -213.172316) (xy 244.459336 -213.190836) (xy 245.822468 -213.190836) (xy 245.826539 -213.135214)
			(xy 245.838665 -213.080777) (xy 245.858588 -213.028686) (xy 245.885884 -212.980051) (xy 245.91997 -212.935908)
			(xy 245.960119 -212.897199) (xy 246.005477 -212.864748) (xy 246.055077 -212.839247) (xy 246.107861 -212.82124)
			(xy 246.162704 -212.81111) (xy 246.218438 -212.809073) (xy 246.273875 -212.815173) (xy 246.327832 -212.829279)
			(xy 246.379161 -212.851091) (xy 246.426767 -212.880145) (xy 246.469635 -212.91582) (xy 246.506852 -212.957357)
			(xy 246.537625 -213.00387) (xy 246.561297 -213.054367) (xy 246.577365 -213.107774) (xy 246.585485 -213.16295)
			(xy 246.585994 -213.190836) (xy 246.585485 -213.218722) (xy 246.577365 -213.273898) (xy 246.561297 -213.327305)
			(xy 246.537625 -213.377802) (xy 246.506852 -213.424315) (xy 246.469635 -213.465852) (xy 246.426767 -213.501527)
			(xy 246.379161 -213.530581) (xy 246.327832 -213.552393) (xy 246.273875 -213.566499) (xy 246.218438 -213.572599)
			(xy 246.162704 -213.570562) (xy 246.107861 -213.560432) (xy 246.055077 -213.542425) (xy 246.005477 -213.516924)
			(xy 245.960119 -213.484473) (xy 245.91997 -213.445764) (xy 245.885884 -213.401621) (xy 245.858588 -213.352986)
			(xy 245.838665 -213.300895) (xy 245.826539 -213.246458) (xy 245.822468 -213.190836) (xy 244.459336 -213.190836)
			(xy 244.440816 -213.218829) (xy 244.403599 -213.260366) (xy 244.360731 -213.296041) (xy 244.313125 -213.325095)
			(xy 244.261796 -213.346907) (xy 244.207839 -213.361013) (xy 244.152402 -213.367113) (xy 244.096668 -213.365076)
			(xy 244.041825 -213.354946) (xy 243.989041 -213.336939) (xy 243.939441 -213.311438) (xy 243.894083 -213.278987)
			(xy 243.853934 -213.240278) (xy 243.819848 -213.196135) (xy 243.792552 -213.1475) (xy 243.772629 -213.095409)
			(xy 243.760503 -213.040972) (xy 243.756432 -212.98535) (xy 242.811997 -212.98535) (xy 242.796166 -213.009279)
			(xy 242.758949 -213.050816) (xy 242.716081 -213.086491) (xy 242.668475 -213.115545) (xy 242.617146 -213.137357)
			(xy 242.563189 -213.151463) (xy 242.507752 -213.157563) (xy 242.452018 -213.155526) (xy 242.397175 -213.145396)
			(xy 242.344391 -213.127389) (xy 242.294791 -213.101888) (xy 242.249433 -213.069437) (xy 242.209284 -213.030728)
			(xy 242.175198 -212.986585) (xy 242.147902 -212.93795) (xy 242.127979 -212.885859) (xy 242.115853 -212.831422)
			(xy 242.111782 -212.7758) (xy 233.502999 -212.7758) (xy 233.544724 -212.782408) (xy 233.594154 -212.798469)
			(xy 233.640464 -212.822065) (xy 233.682512 -212.852615) (xy 233.719263 -212.889366) (xy 233.749813 -212.931414)
			(xy 233.773409 -212.977724) (xy 233.78947 -213.027154) (xy 233.7976 -213.078489) (xy 233.79811 -213.104476)
			(xy 233.7976 -213.130463) (xy 233.78947 -213.181798) (xy 233.773409 -213.231228) (xy 233.749813 -213.277538)
			(xy 233.719263 -213.319586) (xy 233.682512 -213.356337) (xy 233.640464 -213.386887) (xy 233.594154 -213.410483)
			(xy 233.544724 -213.426544) (xy 233.493389 -213.434674) (xy 233.441415 -213.434674) (xy 233.39008 -213.426544)
			(xy 233.34065 -213.410483) (xy 233.29434 -213.386887) (xy 233.252292 -213.356337) (xy 233.215541 -213.319586)
			(xy 233.184991 -213.277538) (xy 233.161395 -213.231228) (xy 233.145334 -213.181798) (xy 233.137204 -213.130463)
			(xy 231.397554 -213.130463) (xy 231.389424 -213.181798) (xy 231.373363 -213.231228) (xy 231.349767 -213.277538)
			(xy 231.319217 -213.319586) (xy 231.282466 -213.356337) (xy 231.240418 -213.386887) (xy 231.194108 -213.410483)
			(xy 231.144678 -213.426544) (xy 231.093343 -213.434674) (xy 231.041369 -213.434674) (xy 230.990034 -213.426544)
			(xy 230.940604 -213.410483) (xy 230.894294 -213.386887) (xy 230.852246 -213.356337) (xy 230.815495 -213.319586)
			(xy 230.784945 -213.277538) (xy 230.761349 -213.231228) (xy 230.745288 -213.181798) (xy 230.737158 -213.130463)
			(xy 230.597708 -213.130463) (xy 230.589578 -213.181798) (xy 230.573517 -213.231228) (xy 230.549921 -213.277538)
			(xy 230.519371 -213.319586) (xy 230.48262 -213.356337) (xy 230.440572 -213.386887) (xy 230.394262 -213.410483)
			(xy 230.344832 -213.426544) (xy 230.293497 -213.434674) (xy 230.241523 -213.434674) (xy 230.190188 -213.426544)
			(xy 230.140758 -213.410483) (xy 230.094448 -213.386887) (xy 230.0524 -213.356337) (xy 230.015649 -213.319586)
			(xy 229.985099 -213.277538) (xy 229.961503 -213.231228) (xy 229.945442 -213.181798) (xy 229.937312 -213.130463)
			(xy 228.997936 -213.130463) (xy 228.989886 -213.18129) (xy 228.973825 -213.23072) (xy 228.950229 -213.27703)
			(xy 228.919679 -213.319078) (xy 228.882928 -213.355829) (xy 228.84088 -213.386379) (xy 228.79457 -213.409975)
			(xy 228.74514 -213.426036) (xy 228.693805 -213.434166) (xy 228.641831 -213.434166) (xy 228.590496 -213.426036)
			(xy 228.541066 -213.409975) (xy 228.494756 -213.386379) (xy 228.452708 -213.355829) (xy 228.415957 -213.319078)
			(xy 228.385407 -213.27703) (xy 228.361811 -213.23072) (xy 228.34575 -213.18129) (xy 228.33762 -213.129955)
			(xy 227.39808 -213.129955) (xy 227.39807 -213.130463) (xy 227.38994 -213.181798) (xy 227.373879 -213.231228)
			(xy 227.350283 -213.277538) (xy 227.319733 -213.319586) (xy 227.282982 -213.356337) (xy 227.240934 -213.386887)
			(xy 227.194624 -213.410483) (xy 227.145194 -213.426544) (xy 227.093859 -213.434674) (xy 227.041885 -213.434674)
			(xy 226.99055 -213.426544) (xy 226.94112 -213.410483) (xy 226.89481 -213.386887) (xy 226.852762 -213.356337)
			(xy 226.816011 -213.319586) (xy 226.785461 -213.277538) (xy 226.761865 -213.231228) (xy 226.745804 -213.181798)
			(xy 226.737674 -213.130463) (xy 216.570739 -213.130463) (xy 216.573953 -213.141409) (xy 216.581708 -213.195351)
			(xy 216.581708 -213.249849) (xy 216.573953 -213.303791) (xy 216.5586 -213.356081) (xy 216.535962 -213.405654)
			(xy 216.5065 -213.451501) (xy 216.470814 -213.492689) (xy 216.42963 -213.528379) (xy 216.383786 -213.557845)
			(xy 216.334215 -213.580487) (xy 216.281926 -213.595845) (xy 216.227985 -213.603605) (xy 216.200736 -213.604094)
			(xy 216.174419 -213.603665) (xy 216.122284 -213.59644) (xy 216.071635 -213.582123) (xy 216.023433 -213.560984)
			(xy 215.978592 -213.533424) (xy 215.937961 -213.499966) (xy 215.919812 -213.480904) (xy 215.912287 -213.473506)
			(xy 215.89301 -213.46498) (xy 215.882474 -213.464394) (xy 215.807798 -213.464394) (xy 215.797247 -213.46491)
			(xy 215.777952 -213.473455) (xy 215.77046 -213.480904) (xy 215.752346 -213.500004) (xy 215.711721 -213.53348)
			(xy 215.666876 -213.561047) (xy 215.618664 -213.582182) (xy 215.568004 -213.596483) (xy 215.515857 -213.603676)
			(xy 215.489536 -213.604094) (xy 215.46228 -213.603662) (xy 215.408324 -213.595908) (xy 215.356019 -213.580555)
			(xy 215.306433 -213.557914) (xy 215.260574 -213.528446) (xy 215.219375 -213.492751) (xy 215.183676 -213.451555)
			(xy 215.154204 -213.405699) (xy 215.131558 -213.356114) (xy 215.116199 -213.303812) (xy 215.108441 -213.249856)
			(xy 211.122644 -213.249856) (xy 211.100053 -213.298046) (xy 211.06928 -213.344559) (xy 211.032063 -213.386096)
			(xy 210.989195 -213.421771) (xy 210.941589 -213.450825) (xy 210.89026 -213.472637) (xy 210.836303 -213.486743)
			(xy 210.780866 -213.492843) (xy 210.725132 -213.490806) (xy 210.670289 -213.480676) (xy 210.617505 -213.462669)
			(xy 210.567905 -213.437168) (xy 210.522547 -213.404717) (xy 210.482398 -213.366008) (xy 210.448312 -213.321865)
			(xy 210.421016 -213.27323) (xy 210.401093 -213.221139) (xy 210.388967 -213.166702) (xy 210.384896 -213.11108)
			(xy 210.05612 -213.11108) (xy 210.070538 -213.134206) (xy 210.092142 -213.182826) (xy 210.106784 -213.233975)
			(xy 210.114178 -213.286662) (xy 210.114642 -213.313264) (xy 210.114156 -213.340515) (xy 210.1064 -213.394463)
			(xy 210.091045 -213.446758) (xy 210.068403 -213.496335) (xy 210.038937 -213.542185) (xy 210.003246 -213.583376)
			(xy 209.962055 -213.619067) (xy 209.916205 -213.648533) (xy 209.866628 -213.671175) (xy 209.814333 -213.68653)
			(xy 209.760385 -213.694286) (xy 209.705883 -213.694286) (xy 209.651935 -213.68653) (xy 209.59964 -213.671175)
			(xy 209.550063 -213.648533) (xy 209.504213 -213.619067) (xy 209.463022 -213.583376) (xy 209.427331 -213.542185)
			(xy 209.397865 -213.496335) (xy 209.375223 -213.446758) (xy 209.359868 -213.394463) (xy 209.352112 -213.340515)
			(xy 209.351626 -213.313264) (xy 207.314546 -213.313264) (xy 207.314546 -214.038688) (xy 210.37626 -214.038688)
			(xy 210.380331 -213.983066) (xy 210.392457 -213.928629) (xy 210.41238 -213.876538) (xy 210.439676 -213.827903)
			(xy 210.473762 -213.78376) (xy 210.513911 -213.745051) (xy 210.559269 -213.7126) (xy 210.608869 -213.687099)
			(xy 210.661653 -213.669092) (xy 210.716496 -213.658962) (xy 210.77223 -213.656925) (xy 210.827667 -213.663025)
			(xy 210.881624 -213.677131) (xy 210.932953 -213.698943) (xy 210.980559 -213.727997) (xy 211.023427 -213.763672)
			(xy 211.060644 -213.805209) (xy 211.091417 -213.851722) (xy 211.115089 -213.902219) (xy 211.131157 -213.955626)
			(xy 211.139277 -214.010802) (xy 211.139786 -214.038688) (xy 211.139277 -214.066574) (xy 211.131157 -214.12175)
			(xy 211.115089 -214.175157) (xy 211.091417 -214.225654) (xy 211.060644 -214.272167) (xy 211.027592 -214.309055)
			(xy 211.867921 -214.309055) (xy 211.867921 -214.254545) (xy 211.875679 -214.200588) (xy 211.891036 -214.148285)
			(xy 211.913681 -214.098701) (xy 211.943152 -214.052843) (xy 211.97885 -214.011647) (xy 212.020046 -213.97595)
			(xy 212.065904 -213.946479) (xy 212.115489 -213.923835) (xy 212.167792 -213.908478) (xy 212.221749 -213.900721)
			(xy 212.249004 -213.900258) (xy 212.274773 -213.900681) (xy 212.325844 -213.907591) (xy 212.375521 -213.921311)
			(xy 212.4229 -213.941592) (xy 212.467119 -213.968064) (xy 212.48751 -213.983824) (xy 212.494876 -213.98992)
			(xy 212.51291 -213.995508) (xy 212.60054 -213.98992) (xy 212.617812 -213.981792) (xy 212.624416 -213.974934)
			(xy 212.642453 -213.956652) (xy 212.682618 -213.924644) (xy 212.72671 -213.898307) (xy 212.773933 -213.878117)
			(xy 212.823437 -213.864437) (xy 212.874327 -213.857515) (xy 212.900006 -213.857078) (xy 212.927256 -213.857593)
			(xy 212.981201 -213.86535) (xy 213.033493 -213.880705) (xy 213.083068 -213.903345) (xy 213.128916 -213.932811)
			(xy 213.170103 -213.968501) (xy 213.205793 -214.009689) (xy 213.235258 -214.055538) (xy 213.257897 -214.105113)
			(xy 213.273252 -214.157405) (xy 213.281008 -214.21135) (xy 213.281008 -214.26585) (xy 213.281007 -214.265856)
			(xy 215.108441 -214.265856) (xy 215.108441 -214.211344) (xy 215.116199 -214.157388) (xy 215.131558 -214.105086)
			(xy 215.154204 -214.055501) (xy 215.183676 -214.009645) (xy 215.219375 -213.968449) (xy 215.260574 -213.932754)
			(xy 215.306433 -213.903286) (xy 215.356019 -213.880645) (xy 215.408324 -213.865292) (xy 215.46228 -213.857538)
			(xy 215.489536 -213.857078) (xy 215.515852 -213.857534) (xy 215.567985 -213.864755) (xy 215.618633 -213.879068)
			(xy 215.666835 -213.900202) (xy 215.711677 -213.927756) (xy 215.75231 -213.961208) (xy 215.77046 -213.980268)
			(xy 215.777999 -213.987649) (xy 215.797266 -213.996187) (xy 215.807798 -213.996778) (xy 215.882474 -213.996778)
			(xy 215.893025 -213.996255) (xy 215.91232 -213.987716) (xy 215.919812 -213.980268) (xy 215.937954 -213.961196)
			(xy 215.978572 -213.927714) (xy 216.02341 -213.900141) (xy 216.071616 -213.879001) (xy 216.122273 -213.864696)
			(xy 216.174417 -213.857498) (xy 216.200736 -213.857078) (xy 216.227985 -213.857595) (xy 216.281926 -213.865355)
			(xy 216.334215 -213.880713) (xy 216.383786 -213.903355) (xy 216.425722 -213.930309) (xy 224.337628 -213.930309)
			(xy 224.337628 -213.878335) (xy 224.345758 -213.827) (xy 224.361819 -213.77757) (xy 224.385415 -213.73126)
			(xy 224.415965 -213.689212) (xy 224.452716 -213.652461) (xy 224.494764 -213.621911) (xy 224.541074 -213.598315)
			(xy 224.590504 -213.582254) (xy 224.641839 -213.574124) (xy 224.693813 -213.574124) (xy 224.745148 -213.582254)
			(xy 224.794578 -213.598315) (xy 224.840888 -213.621911) (xy 224.882936 -213.652461) (xy 224.919687 -213.689212)
			(xy 224.950237 -213.73126) (xy 224.973833 -213.77757) (xy 224.989894 -213.827) (xy 224.998024 -213.878335)
			(xy 224.998534 -213.904322) (xy 224.998024 -213.930309) (xy 225.137728 -213.930309) (xy 225.137728 -213.878335)
			(xy 225.145858 -213.827) (xy 225.161919 -213.77757) (xy 225.185515 -213.73126) (xy 225.216065 -213.689212)
			(xy 225.252816 -213.652461) (xy 225.294864 -213.621911) (xy 225.341174 -213.598315) (xy 225.390604 -213.582254)
			(xy 225.441939 -213.574124) (xy 225.493913 -213.574124) (xy 225.545248 -213.582254) (xy 225.594678 -213.598315)
			(xy 225.640988 -213.621911) (xy 225.683036 -213.652461) (xy 225.719787 -213.689212) (xy 225.750337 -213.73126)
			(xy 225.773933 -213.77757) (xy 225.789994 -213.827) (xy 225.798124 -213.878335) (xy 225.798634 -213.904322)
			(xy 225.798124 -213.930309) (xy 225.937574 -213.930309) (xy 225.937574 -213.878335) (xy 225.945704 -213.827)
			(xy 225.961765 -213.77757) (xy 225.985361 -213.73126) (xy 226.015911 -213.689212) (xy 226.052662 -213.652461)
			(xy 226.09471 -213.621911) (xy 226.14102 -213.598315) (xy 226.19045 -213.582254) (xy 226.241785 -213.574124)
			(xy 226.293759 -213.574124) (xy 226.345094 -213.582254) (xy 226.394524 -213.598315) (xy 226.440834 -213.621911)
			(xy 226.482882 -213.652461) (xy 226.519633 -213.689212) (xy 226.550183 -213.73126) (xy 226.573779 -213.77757)
			(xy 226.58984 -213.827) (xy 226.59797 -213.878335) (xy 226.59848 -213.904322) (xy 226.59797 -213.930309)
			(xy 226.737674 -213.930309) (xy 226.737674 -213.878335) (xy 226.745804 -213.827) (xy 226.761865 -213.77757)
			(xy 226.785461 -213.73126) (xy 226.816011 -213.689212) (xy 226.852762 -213.652461) (xy 226.89481 -213.621911)
			(xy 226.94112 -213.598315) (xy 226.99055 -213.582254) (xy 227.041885 -213.574124) (xy 227.093859 -213.574124)
			(xy 227.145194 -213.582254) (xy 227.194624 -213.598315) (xy 227.240934 -213.621911) (xy 227.282982 -213.652461)
			(xy 227.319733 -213.689212) (xy 227.350283 -213.73126) (xy 227.373879 -213.77757) (xy 227.38994 -213.827)
			(xy 227.39807 -213.878335) (xy 227.39858 -213.904322) (xy 227.39807 -213.930309) (xy 227.537774 -213.930309)
			(xy 227.537774 -213.878335) (xy 227.545904 -213.827) (xy 227.561965 -213.77757) (xy 227.585561 -213.73126)
			(xy 227.616111 -213.689212) (xy 227.652862 -213.652461) (xy 227.69491 -213.621911) (xy 227.74122 -213.598315)
			(xy 227.79065 -213.582254) (xy 227.841985 -213.574124) (xy 227.893959 -213.574124) (xy 227.945294 -213.582254)
			(xy 227.994724 -213.598315) (xy 228.041034 -213.621911) (xy 228.083082 -213.652461) (xy 228.119833 -213.689212)
			(xy 228.150383 -213.73126) (xy 228.173979 -213.77757) (xy 228.19004 -213.827) (xy 228.19817 -213.878335)
			(xy 228.19868 -213.904322) (xy 228.19817 -213.930309) (xy 228.33762 -213.930309) (xy 228.33762 -213.878335)
			(xy 228.34575 -213.827) (xy 228.361811 -213.77757) (xy 228.385407 -213.73126) (xy 228.415957 -213.689212)
			(xy 228.452708 -213.652461) (xy 228.494756 -213.621911) (xy 228.541066 -213.598315) (xy 228.590496 -213.582254)
			(xy 228.641831 -213.574124) (xy 228.693805 -213.574124) (xy 228.74514 -213.582254) (xy 228.79457 -213.598315)
			(xy 228.84088 -213.621911) (xy 228.882928 -213.652461) (xy 228.919679 -213.689212) (xy 228.950229 -213.73126)
			(xy 228.973825 -213.77757) (xy 228.989886 -213.827) (xy 228.998016 -213.878335) (xy 228.998526 -213.904322)
			(xy 228.998016 -213.930309) (xy 229.937312 -213.930309) (xy 229.937312 -213.878335) (xy 229.945442 -213.827)
			(xy 229.961503 -213.77757) (xy 229.985099 -213.73126) (xy 230.015649 -213.689212) (xy 230.0524 -213.652461)
			(xy 230.094448 -213.621911) (xy 230.140758 -213.598315) (xy 230.190188 -213.582254) (xy 230.241523 -213.574124)
			(xy 230.293497 -213.574124) (xy 230.344832 -213.582254) (xy 230.394262 -213.598315) (xy 230.440572 -213.621911)
			(xy 230.48262 -213.652461) (xy 230.519371 -213.689212) (xy 230.549921 -213.73126) (xy 230.573517 -213.77757)
			(xy 230.589578 -213.827) (xy 230.597708 -213.878335) (xy 230.598218 -213.904322) (xy 230.597708 -213.930309)
			(xy 230.737158 -213.930309) (xy 230.737158 -213.878335) (xy 230.745288 -213.827) (xy 230.761349 -213.77757)
			(xy 230.784945 -213.73126) (xy 230.815495 -213.689212) (xy 230.852246 -213.652461) (xy 230.894294 -213.621911)
			(xy 230.940604 -213.598315) (xy 230.990034 -213.582254) (xy 231.041369 -213.574124) (xy 231.093343 -213.574124)
			(xy 231.144678 -213.582254) (xy 231.194108 -213.598315) (xy 231.240418 -213.621911) (xy 231.282466 -213.652461)
			(xy 231.319217 -213.689212) (xy 231.349767 -213.73126) (xy 231.373363 -213.77757) (xy 231.389424 -213.827)
			(xy 231.397554 -213.878335) (xy 231.398064 -213.904322) (xy 231.397554 -213.930309) (xy 231.537258 -213.930309)
			(xy 231.537258 -213.878335) (xy 231.545388 -213.827) (xy 231.561449 -213.77757) (xy 231.585045 -213.73126)
			(xy 231.615595 -213.689212) (xy 231.652346 -213.652461) (xy 231.694394 -213.621911) (xy 231.740704 -213.598315)
			(xy 231.790134 -213.582254) (xy 231.841469 -213.574124) (xy 231.893443 -213.574124) (xy 231.944778 -213.582254)
			(xy 231.994208 -213.598315) (xy 232.040518 -213.621911) (xy 232.082566 -213.652461) (xy 232.119317 -213.689212)
			(xy 232.149867 -213.73126) (xy 232.173463 -213.77757) (xy 232.189524 -213.827) (xy 232.197654 -213.878335)
			(xy 232.198164 -213.904322) (xy 232.197654 -213.930309) (xy 232.337358 -213.930309) (xy 232.337358 -213.878335)
			(xy 232.345488 -213.827) (xy 232.361549 -213.77757) (xy 232.385145 -213.73126) (xy 232.415695 -213.689212)
			(xy 232.452446 -213.652461) (xy 232.494494 -213.621911) (xy 232.540804 -213.598315) (xy 232.590234 -213.582254)
			(xy 232.641569 -213.574124) (xy 232.693543 -213.574124) (xy 232.744878 -213.582254) (xy 232.794308 -213.598315)
			(xy 232.840618 -213.621911) (xy 232.882666 -213.652461) (xy 232.919417 -213.689212) (xy 232.949967 -213.73126)
			(xy 232.973563 -213.77757) (xy 232.989624 -213.827) (xy 232.997754 -213.878335) (xy 232.998264 -213.904322)
			(xy 232.997754 -213.930309) (xy 233.137204 -213.930309) (xy 233.137204 -213.878335) (xy 233.145334 -213.827)
			(xy 233.161395 -213.77757) (xy 233.184991 -213.73126) (xy 233.215541 -213.689212) (xy 233.252292 -213.652461)
			(xy 233.29434 -213.621911) (xy 233.34065 -213.598315) (xy 233.39008 -213.582254) (xy 233.441415 -213.574124)
			(xy 233.493389 -213.574124) (xy 233.544724 -213.582254) (xy 233.594154 -213.598315) (xy 233.640464 -213.621911)
			(xy 233.682512 -213.652461) (xy 233.719263 -213.689212) (xy 233.749813 -213.73126) (xy 233.773409 -213.77757)
			(xy 233.78947 -213.827) (xy 233.7976 -213.878335) (xy 233.79811 -213.904322) (xy 233.7976 -213.930309)
			(xy 233.937304 -213.930309) (xy 233.937304 -213.878335) (xy 233.945434 -213.827) (xy 233.961495 -213.77757)
			(xy 233.985091 -213.73126) (xy 234.015641 -213.689212) (xy 234.052392 -213.652461) (xy 234.09444 -213.621911)
			(xy 234.14075 -213.598315) (xy 234.19018 -213.582254) (xy 234.241515 -213.574124) (xy 234.293489 -213.574124)
			(xy 234.344824 -213.582254) (xy 234.358883 -213.586822) (xy 236.605826 -213.586822) (xy 236.606312 -213.559571)
			(xy 236.614068 -213.505623) (xy 236.629423 -213.453328) (xy 236.652065 -213.403751) (xy 236.681531 -213.357901)
			(xy 236.717222 -213.31671) (xy 236.758413 -213.281019) (xy 236.804263 -213.251553) (xy 236.85384 -213.228911)
			(xy 236.906135 -213.213556) (xy 236.960083 -213.2058) (xy 237.014585 -213.2058) (xy 237.068533 -213.213556)
			(xy 237.120828 -213.228911) (xy 237.170405 -213.251553) (xy 237.216255 -213.281019) (xy 237.257446 -213.31671)
			(xy 237.293137 -213.357901) (xy 237.322603 -213.403751) (xy 237.345245 -213.453328) (xy 237.3606 -213.505623)
			(xy 237.368356 -213.559571) (xy 237.368842 -213.586822) (xy 237.368365 -213.614) (xy 237.666782 -213.614)
			(xy 237.670853 -213.558378) (xy 237.682979 -213.503941) (xy 237.702902 -213.45185) (xy 237.730198 -213.403215)
			(xy 237.764284 -213.359072) (xy 237.804433 -213.320363) (xy 237.849791 -213.287912) (xy 237.899391 -213.262411)
			(xy 237.952175 -213.244404) (xy 238.007018 -213.234274) (xy 238.062752 -213.232237) (xy 238.118189 -213.238337)
			(xy 238.172146 -213.252443) (xy 238.223475 -213.274255) (xy 238.271081 -213.303309) (xy 238.313949 -213.338984)
			(xy 238.351166 -213.380521) (xy 238.381939 -213.427034) (xy 238.405611 -213.477531) (xy 238.421679 -213.530938)
			(xy 238.429799 -213.586114) (xy 238.430308 -213.614) (xy 238.429799 -213.641886) (xy 238.421679 -213.697062)
			(xy 238.405611 -213.750469) (xy 238.381939 -213.800966) (xy 238.351166 -213.847479) (xy 238.313949 -213.889016)
			(xy 238.271081 -213.924691) (xy 238.223475 -213.953745) (xy 238.172146 -213.975557) (xy 238.118189 -213.989663)
			(xy 238.062752 -213.995763) (xy 238.007018 -213.993726) (xy 237.952175 -213.983596) (xy 237.899391 -213.965589)
			(xy 237.849791 -213.940088) (xy 237.804433 -213.907637) (xy 237.764284 -213.868928) (xy 237.730198 -213.824785)
			(xy 237.702902 -213.77615) (xy 237.682979 -213.724059) (xy 237.670853 -213.669622) (xy 237.666782 -213.614)
			(xy 237.368365 -213.614) (xy 237.368362 -213.614172) (xy 237.360566 -213.668313) (xy 237.345107 -213.720783)
			(xy 237.322304 -213.770502) (xy 237.292626 -213.81645) (xy 237.256682 -213.857682) (xy 237.236254 -213.875874)
			(xy 237.227618 -213.883494) (xy 237.218474 -213.90356) (xy 237.21949 -214.004398) (xy 237.229142 -214.02421)
			(xy 237.238032 -214.031576) (xy 237.254727 -214.0458) (xy 242.111782 -214.0458) (xy 242.115853 -213.990178)
			(xy 242.127979 -213.935741) (xy 242.147902 -213.88365) (xy 242.175198 -213.835015) (xy 242.209284 -213.790872)
			(xy 242.249433 -213.752163) (xy 242.294791 -213.719712) (xy 242.344391 -213.694211) (xy 242.397175 -213.676204)
			(xy 242.452018 -213.666074) (xy 242.507752 -213.664037) (xy 242.563189 -213.670137) (xy 242.617146 -213.684243)
			(xy 242.668475 -213.706055) (xy 242.716081 -213.735109) (xy 242.758949 -213.770784) (xy 242.796166 -213.812321)
			(xy 242.826939 -213.858834) (xy 242.850611 -213.909331) (xy 242.866679 -213.962738) (xy 242.874799 -214.017914)
			(xy 242.875308 -214.0458) (xy 242.874799 -214.073686) (xy 242.871315 -214.097362) (xy 246.008142 -214.097362)
			(xy 246.012213 -214.04174) (xy 246.024339 -213.987303) (xy 246.044262 -213.935212) (xy 246.071558 -213.886577)
			(xy 246.105644 -213.842434) (xy 246.145793 -213.803725) (xy 246.191151 -213.771274) (xy 246.240751 -213.745773)
			(xy 246.293535 -213.727766) (xy 246.348378 -213.717636) (xy 246.404112 -213.715599) (xy 246.459549 -213.721699)
			(xy 246.513506 -213.735805) (xy 246.564835 -213.757617) (xy 246.612441 -213.786671) (xy 246.655309 -213.822346)
			(xy 246.692526 -213.863883) (xy 246.723299 -213.910396) (xy 246.746971 -213.960893) (xy 246.763039 -214.0143)
			(xy 246.771159 -214.069476) (xy 246.771668 -214.097362) (xy 246.771159 -214.125248) (xy 246.763039 -214.180424)
			(xy 246.746971 -214.233831) (xy 246.723299 -214.284328) (xy 246.692526 -214.330841) (xy 246.655309 -214.372378)
			(xy 246.612441 -214.408053) (xy 246.564835 -214.437107) (xy 246.513506 -214.458919) (xy 246.459549 -214.473025)
			(xy 246.404112 -214.479125) (xy 246.348378 -214.477088) (xy 246.293535 -214.466958) (xy 246.240751 -214.448951)
			(xy 246.191151 -214.42345) (xy 246.145793 -214.390999) (xy 246.105644 -214.35229) (xy 246.071558 -214.308147)
			(xy 246.044262 -214.259512) (xy 246.024339 -214.207421) (xy 246.012213 -214.152984) (xy 246.008142 -214.097362)
			(xy 242.871315 -214.097362) (xy 242.866679 -214.128862) (xy 242.850611 -214.182269) (xy 242.826939 -214.232766)
			(xy 242.796166 -214.279279) (xy 242.758949 -214.320816) (xy 242.716081 -214.356491) (xy 242.668475 -214.385545)
			(xy 242.617146 -214.407357) (xy 242.563189 -214.421463) (xy 242.507752 -214.427563) (xy 242.452018 -214.425526)
			(xy 242.397175 -214.415396) (xy 242.344391 -214.397389) (xy 242.294791 -214.371888) (xy 242.249433 -214.339437)
			(xy 242.209284 -214.300728) (xy 242.175198 -214.256585) (xy 242.147902 -214.20795) (xy 242.127979 -214.155859)
			(xy 242.115853 -214.101422) (xy 242.111782 -214.0458) (xy 237.254727 -214.0458) (xy 237.259403 -214.049784)
			(xy 237.297076 -214.091412) (xy 237.328239 -214.138112) (xy 237.352219 -214.188876) (xy 237.3685 -214.242607)
			(xy 237.376727 -214.298144) (xy 237.377224 -214.326216) (xy 237.376738 -214.353467) (xy 237.368982 -214.407415)
			(xy 237.353627 -214.45971) (xy 237.330985 -214.509287) (xy 237.301519 -214.555137) (xy 237.265828 -214.596328)
			(xy 237.224637 -214.632019) (xy 237.178787 -214.661485) (xy 237.12921 -214.684127) (xy 237.076915 -214.699482)
			(xy 237.022967 -214.707238) (xy 236.968465 -214.707238) (xy 236.914517 -214.699482) (xy 236.862222 -214.684127)
			(xy 236.812645 -214.661485) (xy 236.766795 -214.632019) (xy 236.725604 -214.596328) (xy 236.689913 -214.555137)
			(xy 236.660447 -214.509287) (xy 236.637805 -214.45971) (xy 236.62245 -214.407415) (xy 236.614694 -214.353467)
			(xy 236.614208 -214.326216) (xy 236.614662 -214.298865) (xy 236.622467 -214.244724) (xy 236.637931 -214.192255)
			(xy 236.660739 -214.142535) (xy 236.690421 -214.096588) (xy 236.726368 -214.055356) (xy 236.746796 -214.037164)
			(xy 236.755432 -214.029544) (xy 236.764576 -214.009478) (xy 236.76356 -213.90864) (xy 236.753908 -213.888828)
			(xy 236.745018 -213.881462) (xy 236.723627 -213.863276) (xy 236.685954 -213.821645) (xy 236.654792 -213.77494)
			(xy 236.630815 -213.724172) (xy 236.61454 -213.670436) (xy 236.606319 -213.614895) (xy 236.605826 -213.586822)
			(xy 234.358883 -213.586822) (xy 234.394254 -213.598315) (xy 234.440564 -213.621911) (xy 234.482612 -213.652461)
			(xy 234.519363 -213.689212) (xy 234.549913 -213.73126) (xy 234.573509 -213.77757) (xy 234.58957 -213.827)
			(xy 234.5977 -213.878335) (xy 234.59821 -213.904322) (xy 234.5977 -213.930309) (xy 234.58957 -213.981644)
			(xy 234.573509 -214.031074) (xy 234.549913 -214.077384) (xy 234.519363 -214.119432) (xy 234.482612 -214.156183)
			(xy 234.440564 -214.186733) (xy 234.394254 -214.210329) (xy 234.344824 -214.22639) (xy 234.293489 -214.23452)
			(xy 234.241515 -214.23452) (xy 234.19018 -214.22639) (xy 234.14075 -214.210329) (xy 234.09444 -214.186733)
			(xy 234.052392 -214.156183) (xy 234.015641 -214.119432) (xy 233.985091 -214.077384) (xy 233.961495 -214.031074)
			(xy 233.945434 -213.981644) (xy 233.937304 -213.930309) (xy 233.7976 -213.930309) (xy 233.78947 -213.981644)
			(xy 233.773409 -214.031074) (xy 233.749813 -214.077384) (xy 233.719263 -214.119432) (xy 233.682512 -214.156183)
			(xy 233.640464 -214.186733) (xy 233.594154 -214.210329) (xy 233.544724 -214.22639) (xy 233.493389 -214.23452)
			(xy 233.441415 -214.23452) (xy 233.39008 -214.22639) (xy 233.34065 -214.210329) (xy 233.29434 -214.186733)
			(xy 233.252292 -214.156183) (xy 233.215541 -214.119432) (xy 233.184991 -214.077384) (xy 233.161395 -214.031074)
			(xy 233.145334 -213.981644) (xy 233.137204 -213.930309) (xy 232.997754 -213.930309) (xy 232.989624 -213.981644)
			(xy 232.973563 -214.031074) (xy 232.949967 -214.077384) (xy 232.919417 -214.119432) (xy 232.882666 -214.156183)
			(xy 232.840618 -214.186733) (xy 232.794308 -214.210329) (xy 232.744878 -214.22639) (xy 232.693543 -214.23452)
			(xy 232.641569 -214.23452) (xy 232.590234 -214.22639) (xy 232.540804 -214.210329) (xy 232.494494 -214.186733)
			(xy 232.452446 -214.156183) (xy 232.415695 -214.119432) (xy 232.385145 -214.077384) (xy 232.361549 -214.031074)
			(xy 232.345488 -213.981644) (xy 232.337358 -213.930309) (xy 232.197654 -213.930309) (xy 232.189524 -213.981644)
			(xy 232.173463 -214.031074) (xy 232.149867 -214.077384) (xy 232.119317 -214.119432) (xy 232.082566 -214.156183)
			(xy 232.040518 -214.186733) (xy 231.994208 -214.210329) (xy 231.944778 -214.22639) (xy 231.893443 -214.23452)
			(xy 231.841469 -214.23452) (xy 231.790134 -214.22639) (xy 231.740704 -214.210329) (xy 231.694394 -214.186733)
			(xy 231.652346 -214.156183) (xy 231.615595 -214.119432) (xy 231.585045 -214.077384) (xy 231.561449 -214.031074)
			(xy 231.545388 -213.981644) (xy 231.537258 -213.930309) (xy 231.397554 -213.930309) (xy 231.389424 -213.981644)
			(xy 231.373363 -214.031074) (xy 231.349767 -214.077384) (xy 231.319217 -214.119432) (xy 231.282466 -214.156183)
			(xy 231.240418 -214.186733) (xy 231.194108 -214.210329) (xy 231.144678 -214.22639) (xy 231.093343 -214.23452)
			(xy 231.041369 -214.23452) (xy 230.990034 -214.22639) (xy 230.940604 -214.210329) (xy 230.894294 -214.186733)
			(xy 230.852246 -214.156183) (xy 230.815495 -214.119432) (xy 230.784945 -214.077384) (xy 230.761349 -214.031074)
			(xy 230.745288 -213.981644) (xy 230.737158 -213.930309) (xy 230.597708 -213.930309) (xy 230.589578 -213.981644)
			(xy 230.573517 -214.031074) (xy 230.549921 -214.077384) (xy 230.519371 -214.119432) (xy 230.48262 -214.156183)
			(xy 230.440572 -214.186733) (xy 230.394262 -214.210329) (xy 230.344832 -214.22639) (xy 230.293497 -214.23452)
			(xy 230.241523 -214.23452) (xy 230.190188 -214.22639) (xy 230.140758 -214.210329) (xy 230.094448 -214.186733)
			(xy 230.0524 -214.156183) (xy 230.015649 -214.119432) (xy 229.985099 -214.077384) (xy 229.961503 -214.031074)
			(xy 229.945442 -213.981644) (xy 229.937312 -213.930309) (xy 228.998016 -213.930309) (xy 228.989886 -213.981644)
			(xy 228.973825 -214.031074) (xy 228.950229 -214.077384) (xy 228.919679 -214.119432) (xy 228.882928 -214.156183)
			(xy 228.84088 -214.186733) (xy 228.79457 -214.210329) (xy 228.74514 -214.22639) (xy 228.693805 -214.23452)
			(xy 228.641831 -214.23452) (xy 228.590496 -214.22639) (xy 228.541066 -214.210329) (xy 228.494756 -214.186733)
			(xy 228.452708 -214.156183) (xy 228.415957 -214.119432) (xy 228.385407 -214.077384) (xy 228.361811 -214.031074)
			(xy 228.34575 -213.981644) (xy 228.33762 -213.930309) (xy 228.19817 -213.930309) (xy 228.19004 -213.981644)
			(xy 228.173979 -214.031074) (xy 228.150383 -214.077384) (xy 228.119833 -214.119432) (xy 228.083082 -214.156183)
			(xy 228.041034 -214.186733) (xy 227.994724 -214.210329) (xy 227.945294 -214.22639) (xy 227.893959 -214.23452)
			(xy 227.841985 -214.23452) (xy 227.79065 -214.22639) (xy 227.74122 -214.210329) (xy 227.69491 -214.186733)
			(xy 227.652862 -214.156183) (xy 227.616111 -214.119432) (xy 227.585561 -214.077384) (xy 227.561965 -214.031074)
			(xy 227.545904 -213.981644) (xy 227.537774 -213.930309) (xy 227.39807 -213.930309) (xy 227.38994 -213.981644)
			(xy 227.373879 -214.031074) (xy 227.350283 -214.077384) (xy 227.319733 -214.119432) (xy 227.282982 -214.156183)
			(xy 227.240934 -214.186733) (xy 227.194624 -214.210329) (xy 227.145194 -214.22639) (xy 227.093859 -214.23452)
			(xy 227.041885 -214.23452) (xy 226.99055 -214.22639) (xy 226.94112 -214.210329) (xy 226.89481 -214.186733)
			(xy 226.852762 -214.156183) (xy 226.816011 -214.119432) (xy 226.785461 -214.077384) (xy 226.761865 -214.031074)
			(xy 226.745804 -213.981644) (xy 226.737674 -213.930309) (xy 226.59797 -213.930309) (xy 226.58984 -213.981644)
			(xy 226.573779 -214.031074) (xy 226.550183 -214.077384) (xy 226.519633 -214.119432) (xy 226.482882 -214.156183)
			(xy 226.440834 -214.186733) (xy 226.394524 -214.210329) (xy 226.345094 -214.22639) (xy 226.293759 -214.23452)
			(xy 226.241785 -214.23452) (xy 226.19045 -214.22639) (xy 226.14102 -214.210329) (xy 226.09471 -214.186733)
			(xy 226.052662 -214.156183) (xy 226.015911 -214.119432) (xy 225.985361 -214.077384) (xy 225.961765 -214.031074)
			(xy 225.945704 -213.981644) (xy 225.937574 -213.930309) (xy 225.798124 -213.930309) (xy 225.789994 -213.981644)
			(xy 225.773933 -214.031074) (xy 225.750337 -214.077384) (xy 225.719787 -214.119432) (xy 225.683036 -214.156183)
			(xy 225.640988 -214.186733) (xy 225.594678 -214.210329) (xy 225.545248 -214.22639) (xy 225.493913 -214.23452)
			(xy 225.441939 -214.23452) (xy 225.390604 -214.22639) (xy 225.341174 -214.210329) (xy 225.294864 -214.186733)
			(xy 225.252816 -214.156183) (xy 225.216065 -214.119432) (xy 225.185515 -214.077384) (xy 225.161919 -214.031074)
			(xy 225.145858 -213.981644) (xy 225.137728 -213.930309) (xy 224.998024 -213.930309) (xy 224.989894 -213.981644)
			(xy 224.973833 -214.031074) (xy 224.950237 -214.077384) (xy 224.919687 -214.119432) (xy 224.882936 -214.156183)
			(xy 224.840888 -214.186733) (xy 224.794578 -214.210329) (xy 224.745148 -214.22639) (xy 224.693813 -214.23452)
			(xy 224.641839 -214.23452) (xy 224.590504 -214.22639) (xy 224.541074 -214.210329) (xy 224.494764 -214.186733)
			(xy 224.452716 -214.156183) (xy 224.415965 -214.119432) (xy 224.385415 -214.077384) (xy 224.361819 -214.031074)
			(xy 224.345758 -213.981644) (xy 224.337628 -213.930309) (xy 216.425722 -213.930309) (xy 216.42963 -213.932821)
			(xy 216.470814 -213.968511) (xy 216.5065 -214.009699) (xy 216.535962 -214.055546) (xy 216.5586 -214.105119)
			(xy 216.573953 -214.157409) (xy 216.581708 -214.211351) (xy 216.581708 -214.265849) (xy 216.573953 -214.319791)
			(xy 216.5586 -214.372081) (xy 216.535962 -214.421654) (xy 216.5065 -214.467501) (xy 216.470814 -214.508689)
			(xy 216.42963 -214.544379) (xy 216.383786 -214.573845) (xy 216.334215 -214.596487) (xy 216.281926 -214.611845)
			(xy 216.227985 -214.619605) (xy 216.200736 -214.620094) (xy 216.174419 -214.619665) (xy 216.122284 -214.61244)
			(xy 216.071635 -214.598123) (xy 216.023433 -214.576984) (xy 215.978592 -214.549424) (xy 215.937961 -214.515966)
			(xy 215.919812 -214.496904) (xy 215.912287 -214.489506) (xy 215.89301 -214.48098) (xy 215.882474 -214.480394)
			(xy 215.807798 -214.480394) (xy 215.797247 -214.48091) (xy 215.777952 -214.489455) (xy 215.77046 -214.496904)
			(xy 215.752346 -214.516004) (xy 215.711721 -214.54948) (xy 215.666876 -214.577047) (xy 215.618664 -214.598182)
			(xy 215.568004 -214.612483) (xy 215.515857 -214.619676) (xy 215.489536 -214.620094) (xy 215.46228 -214.619662)
			(xy 215.408324 -214.611908) (xy 215.356019 -214.596555) (xy 215.306433 -214.573914) (xy 215.260574 -214.544446)
			(xy 215.219375 -214.508751) (xy 215.183676 -214.467555) (xy 215.154204 -214.421699) (xy 215.131558 -214.372114)
			(xy 215.116199 -214.319812) (xy 215.108441 -214.265856) (xy 213.281007 -214.265856) (xy 213.273252 -214.319795)
			(xy 213.257897 -214.372087) (xy 213.235258 -214.421662) (xy 213.205793 -214.467511) (xy 213.170103 -214.508699)
			(xy 213.128916 -214.544389) (xy 213.083068 -214.573855) (xy 213.033493 -214.596495) (xy 212.981201 -214.61185)
			(xy 212.927256 -214.619607) (xy 212.900006 -214.620094) (xy 212.874238 -214.619654) (xy 212.823168 -214.612747)
			(xy 212.773491 -214.59903) (xy 212.726112 -214.578753) (xy 212.681893 -214.552286) (xy 212.6615 -214.536528)
			(xy 212.654134 -214.530432) (xy 212.6361 -214.524844) (xy 212.54847 -214.530432) (xy 212.531198 -214.53856)
			(xy 212.524594 -214.545418) (xy 212.506562 -214.563705) (xy 212.466395 -214.595711) (xy 212.422302 -214.622046)
			(xy 212.375077 -214.642235) (xy 212.325574 -214.655914) (xy 212.274683 -214.662837) (xy 212.249004 -214.663274)
			(xy 212.221749 -214.662879) (xy 212.167792 -214.655122) (xy 212.115489 -214.639765) (xy 212.065904 -214.617121)
			(xy 212.020046 -214.58765) (xy 211.97885 -214.551953) (xy 211.943152 -214.510757) (xy 211.913681 -214.464899)
			(xy 211.891036 -214.415315) (xy 211.875679 -214.363012) (xy 211.867921 -214.309055) (xy 211.027592 -214.309055)
			(xy 211.023427 -214.313704) (xy 210.980559 -214.349379) (xy 210.932953 -214.378433) (xy 210.881624 -214.400245)
			(xy 210.827667 -214.414351) (xy 210.77223 -214.420451) (xy 210.716496 -214.418414) (xy 210.661653 -214.408284)
			(xy 210.608869 -214.390277) (xy 210.559269 -214.364776) (xy 210.513911 -214.332325) (xy 210.473762 -214.293616)
			(xy 210.439676 -214.249473) (xy 210.41238 -214.200838) (xy 210.392457 -214.148747) (xy 210.380331 -214.09431)
			(xy 210.37626 -214.038688) (xy 207.314546 -214.038688) (xy 207.314546 -214.372444) (xy 207.336898 -214.40013)
			(xy 207.354424 -214.40394) (xy 207.380965 -214.410182) (xy 207.432054 -214.429225) (xy 207.479912 -214.455347)
			(xy 207.523564 -214.488014) (xy 207.562123 -214.526563) (xy 207.594801 -214.570207) (xy 207.620935 -214.618059)
			(xy 207.639991 -214.669143) (xy 207.651582 -214.722419) (xy 207.652154 -214.730409) (xy 222.737682 -214.730409)
			(xy 222.737682 -214.678435) (xy 222.745812 -214.6271) (xy 222.761873 -214.57767) (xy 222.785469 -214.53136)
			(xy 222.816019 -214.489312) (xy 222.85277 -214.452561) (xy 222.894818 -214.422011) (xy 222.941128 -214.398415)
			(xy 222.990558 -214.382354) (xy 223.041893 -214.374224) (xy 223.093867 -214.374224) (xy 223.145202 -214.382354)
			(xy 223.194632 -214.398415) (xy 223.240942 -214.422011) (xy 223.28299 -214.452561) (xy 223.319741 -214.489312)
			(xy 223.350291 -214.53136) (xy 223.373887 -214.57767) (xy 223.389948 -214.6271) (xy 223.398078 -214.678435)
			(xy 223.398588 -214.704422) (xy 223.398078 -214.730409) (xy 223.537782 -214.730409) (xy 223.537782 -214.678435)
			(xy 223.545912 -214.6271) (xy 223.561973 -214.57767) (xy 223.585569 -214.53136) (xy 223.616119 -214.489312)
			(xy 223.65287 -214.452561) (xy 223.694918 -214.422011) (xy 223.741228 -214.398415) (xy 223.790658 -214.382354)
			(xy 223.841993 -214.374224) (xy 223.893967 -214.374224) (xy 223.945302 -214.382354) (xy 223.994732 -214.398415)
			(xy 224.041042 -214.422011) (xy 224.08309 -214.452561) (xy 224.119841 -214.489312) (xy 224.150391 -214.53136)
			(xy 224.173987 -214.57767) (xy 224.190048 -214.6271) (xy 224.198178 -214.678435) (xy 224.198688 -214.704422)
			(xy 224.198178 -214.730409) (xy 224.337628 -214.730409) (xy 224.337628 -214.678435) (xy 224.345758 -214.6271)
			(xy 224.361819 -214.57767) (xy 224.385415 -214.53136) (xy 224.415965 -214.489312) (xy 224.452716 -214.452561)
			(xy 224.494764 -214.422011) (xy 224.541074 -214.398415) (xy 224.590504 -214.382354) (xy 224.641839 -214.374224)
			(xy 224.693813 -214.374224) (xy 224.745148 -214.382354) (xy 224.794578 -214.398415) (xy 224.840888 -214.422011)
			(xy 224.882936 -214.452561) (xy 224.919687 -214.489312) (xy 224.950237 -214.53136) (xy 224.973833 -214.57767)
			(xy 224.989894 -214.6271) (xy 224.998024 -214.678435) (xy 224.998534 -214.704422) (xy 224.998024 -214.730409)
			(xy 225.137728 -214.730409) (xy 225.137728 -214.678435) (xy 225.145858 -214.6271) (xy 225.161919 -214.57767)
			(xy 225.185515 -214.53136) (xy 225.216065 -214.489312) (xy 225.252816 -214.452561) (xy 225.294864 -214.422011)
			(xy 225.341174 -214.398415) (xy 225.390604 -214.382354) (xy 225.441939 -214.374224) (xy 225.493913 -214.374224)
			(xy 225.545248 -214.382354) (xy 225.594678 -214.398415) (xy 225.640988 -214.422011) (xy 225.683036 -214.452561)
			(xy 225.719787 -214.489312) (xy 225.750337 -214.53136) (xy 225.773933 -214.57767) (xy 225.789994 -214.6271)
			(xy 225.798124 -214.678435) (xy 225.798634 -214.704422) (xy 225.798124 -214.730409) (xy 225.937574 -214.730409)
			(xy 225.937574 -214.678435) (xy 225.945704 -214.6271) (xy 225.961765 -214.57767) (xy 225.985361 -214.53136)
			(xy 226.015911 -214.489312) (xy 226.052662 -214.452561) (xy 226.09471 -214.422011) (xy 226.14102 -214.398415)
			(xy 226.19045 -214.382354) (xy 226.241785 -214.374224) (xy 226.293759 -214.374224) (xy 226.345094 -214.382354)
			(xy 226.394524 -214.398415) (xy 226.440834 -214.422011) (xy 226.482882 -214.452561) (xy 226.519633 -214.489312)
			(xy 226.550183 -214.53136) (xy 226.573779 -214.57767) (xy 226.58984 -214.6271) (xy 226.59797 -214.678435)
			(xy 226.59848 -214.704422) (xy 226.59797 -214.730409) (xy 226.737674 -214.730409) (xy 226.737674 -214.678435)
			(xy 226.745804 -214.6271) (xy 226.761865 -214.57767) (xy 226.785461 -214.53136) (xy 226.816011 -214.489312)
			(xy 226.852762 -214.452561) (xy 226.89481 -214.422011) (xy 226.94112 -214.398415) (xy 226.99055 -214.382354)
			(xy 227.041885 -214.374224) (xy 227.093859 -214.374224) (xy 227.145194 -214.382354) (xy 227.194624 -214.398415)
			(xy 227.240934 -214.422011) (xy 227.282982 -214.452561) (xy 227.319733 -214.489312) (xy 227.350283 -214.53136)
			(xy 227.373879 -214.57767) (xy 227.38994 -214.6271) (xy 227.39807 -214.678435) (xy 227.39858 -214.704422)
			(xy 227.39807 -214.730409) (xy 227.537774 -214.730409) (xy 227.537774 -214.678435) (xy 227.545904 -214.6271)
			(xy 227.561965 -214.57767) (xy 227.585561 -214.53136) (xy 227.616111 -214.489312) (xy 227.652862 -214.452561)
			(xy 227.69491 -214.422011) (xy 227.74122 -214.398415) (xy 227.79065 -214.382354) (xy 227.841985 -214.374224)
			(xy 227.893959 -214.374224) (xy 227.945294 -214.382354) (xy 227.994724 -214.398415) (xy 228.041034 -214.422011)
			(xy 228.083082 -214.452561) (xy 228.119833 -214.489312) (xy 228.150383 -214.53136) (xy 228.173979 -214.57767)
			(xy 228.19004 -214.6271) (xy 228.19817 -214.678435) (xy 228.19868 -214.704422) (xy 228.19817 -214.730409)
			(xy 228.33762 -214.730409) (xy 228.33762 -214.678435) (xy 228.34575 -214.6271) (xy 228.361811 -214.57767)
			(xy 228.385407 -214.53136) (xy 228.415957 -214.489312) (xy 228.452708 -214.452561) (xy 228.494756 -214.422011)
			(xy 228.541066 -214.398415) (xy 228.590496 -214.382354) (xy 228.641831 -214.374224) (xy 228.693805 -214.374224)
			(xy 228.74514 -214.382354) (xy 228.79457 -214.398415) (xy 228.84088 -214.422011) (xy 228.882928 -214.452561)
			(xy 228.919679 -214.489312) (xy 228.950229 -214.53136) (xy 228.973825 -214.57767) (xy 228.989886 -214.6271)
			(xy 228.998016 -214.678435) (xy 228.998526 -214.704422) (xy 228.998016 -214.730409) (xy 229.937312 -214.730409)
			(xy 229.937312 -214.678435) (xy 229.945442 -214.6271) (xy 229.961503 -214.57767) (xy 229.985099 -214.53136)
			(xy 230.015649 -214.489312) (xy 230.0524 -214.452561) (xy 230.094448 -214.422011) (xy 230.140758 -214.398415)
			(xy 230.190188 -214.382354) (xy 230.241523 -214.374224) (xy 230.293497 -214.374224) (xy 230.344832 -214.382354)
			(xy 230.394262 -214.398415) (xy 230.440572 -214.422011) (xy 230.48262 -214.452561) (xy 230.519371 -214.489312)
			(xy 230.549921 -214.53136) (xy 230.573517 -214.57767) (xy 230.589578 -214.6271) (xy 230.597708 -214.678435)
			(xy 230.598218 -214.704422) (xy 230.597708 -214.730409) (xy 230.737158 -214.730409) (xy 230.737158 -214.678435)
			(xy 230.745288 -214.6271) (xy 230.761349 -214.57767) (xy 230.784945 -214.53136) (xy 230.815495 -214.489312)
			(xy 230.852246 -214.452561) (xy 230.894294 -214.422011) (xy 230.940604 -214.398415) (xy 230.990034 -214.382354)
			(xy 231.041369 -214.374224) (xy 231.093343 -214.374224) (xy 231.144678 -214.382354) (xy 231.194108 -214.398415)
			(xy 231.240418 -214.422011) (xy 231.282466 -214.452561) (xy 231.319217 -214.489312) (xy 231.349767 -214.53136)
			(xy 231.373363 -214.57767) (xy 231.389424 -214.6271) (xy 231.397554 -214.678435) (xy 231.398064 -214.704422)
			(xy 231.397554 -214.730409) (xy 231.537258 -214.730409) (xy 231.537258 -214.678435) (xy 231.545388 -214.6271)
			(xy 231.561449 -214.57767) (xy 231.585045 -214.53136) (xy 231.615595 -214.489312) (xy 231.652346 -214.452561)
			(xy 231.694394 -214.422011) (xy 231.740704 -214.398415) (xy 231.790134 -214.382354) (xy 231.841469 -214.374224)
			(xy 231.893443 -214.374224) (xy 231.944778 -214.382354) (xy 231.994208 -214.398415) (xy 232.040518 -214.422011)
			(xy 232.082566 -214.452561) (xy 232.119317 -214.489312) (xy 232.149867 -214.53136) (xy 232.173463 -214.57767)
			(xy 232.189524 -214.6271) (xy 232.197654 -214.678435) (xy 232.198164 -214.704422) (xy 232.197654 -214.730409)
			(xy 232.337358 -214.730409) (xy 232.337358 -214.678435) (xy 232.345488 -214.6271) (xy 232.361549 -214.57767)
			(xy 232.385145 -214.53136) (xy 232.415695 -214.489312) (xy 232.452446 -214.452561) (xy 232.494494 -214.422011)
			(xy 232.540804 -214.398415) (xy 232.590234 -214.382354) (xy 232.641569 -214.374224) (xy 232.693543 -214.374224)
			(xy 232.744878 -214.382354) (xy 232.794308 -214.398415) (xy 232.840618 -214.422011) (xy 232.882666 -214.452561)
			(xy 232.919417 -214.489312) (xy 232.949967 -214.53136) (xy 232.973563 -214.57767) (xy 232.989624 -214.6271)
			(xy 232.997754 -214.678435) (xy 232.998264 -214.704422) (xy 232.997754 -214.730409) (xy 233.137204 -214.730409)
			(xy 233.137204 -214.678435) (xy 233.145334 -214.6271) (xy 233.161395 -214.57767) (xy 233.184991 -214.53136)
			(xy 233.215541 -214.489312) (xy 233.252292 -214.452561) (xy 233.29434 -214.422011) (xy 233.34065 -214.398415)
			(xy 233.39008 -214.382354) (xy 233.441415 -214.374224) (xy 233.493389 -214.374224) (xy 233.544724 -214.382354)
			(xy 233.594154 -214.398415) (xy 233.640464 -214.422011) (xy 233.682512 -214.452561) (xy 233.719263 -214.489312)
			(xy 233.749813 -214.53136) (xy 233.773409 -214.57767) (xy 233.78947 -214.6271) (xy 233.7976 -214.678435)
			(xy 233.79811 -214.704422) (xy 233.7976 -214.730409) (xy 233.937304 -214.730409) (xy 233.937304 -214.678435)
			(xy 233.945434 -214.6271) (xy 233.961495 -214.57767) (xy 233.985091 -214.53136) (xy 234.015641 -214.489312)
			(xy 234.052392 -214.452561) (xy 234.09444 -214.422011) (xy 234.14075 -214.398415) (xy 234.19018 -214.382354)
			(xy 234.241515 -214.374224) (xy 234.293489 -214.374224) (xy 234.344824 -214.382354) (xy 234.394254 -214.398415)
			(xy 234.440564 -214.422011) (xy 234.482612 -214.452561) (xy 234.519363 -214.489312) (xy 234.549913 -214.53136)
			(xy 234.573509 -214.57767) (xy 234.58957 -214.6271) (xy 234.5977 -214.678435) (xy 234.59821 -214.704422)
			(xy 234.5977 -214.730409) (xy 234.73715 -214.730409) (xy 234.73715 -214.678435) (xy 234.74528 -214.6271)
			(xy 234.761341 -214.57767) (xy 234.784937 -214.53136) (xy 234.815487 -214.489312) (xy 234.852238 -214.452561)
			(xy 234.894286 -214.422011) (xy 234.940596 -214.398415) (xy 234.990026 -214.382354) (xy 235.041361 -214.374224)
			(xy 235.093335 -214.374224) (xy 235.14467 -214.382354) (xy 235.1941 -214.398415) (xy 235.24041 -214.422011)
			(xy 235.282458 -214.452561) (xy 235.319209 -214.489312) (xy 235.349759 -214.53136) (xy 235.373355 -214.57767)
			(xy 235.389416 -214.6271) (xy 235.397546 -214.678435) (xy 235.398056 -214.704422) (xy 235.397546 -214.730409)
			(xy 235.389416 -214.781744) (xy 235.373355 -214.831174) (xy 235.349759 -214.877484) (xy 235.319209 -214.919532)
			(xy 235.282458 -214.956283) (xy 235.24041 -214.986833) (xy 235.1941 -215.010429) (xy 235.14467 -215.02649)
			(xy 235.093335 -215.03462) (xy 235.041361 -215.03462) (xy 234.990026 -215.02649) (xy 234.940596 -215.010429)
			(xy 234.894286 -214.986833) (xy 234.852238 -214.956283) (xy 234.815487 -214.919532) (xy 234.784937 -214.877484)
			(xy 234.761341 -214.831174) (xy 234.74528 -214.781744) (xy 234.73715 -214.730409) (xy 234.5977 -214.730409)
			(xy 234.58957 -214.781744) (xy 234.573509 -214.831174) (xy 234.549913 -214.877484) (xy 234.519363 -214.919532)
			(xy 234.482612 -214.956283) (xy 234.440564 -214.986833) (xy 234.394254 -215.010429) (xy 234.344824 -215.02649)
			(xy 234.293489 -215.03462) (xy 234.241515 -215.03462) (xy 234.19018 -215.02649) (xy 234.14075 -215.010429)
			(xy 234.09444 -214.986833) (xy 234.052392 -214.956283) (xy 234.015641 -214.919532) (xy 233.985091 -214.877484)
			(xy 233.961495 -214.831174) (xy 233.945434 -214.781744) (xy 233.937304 -214.730409) (xy 233.7976 -214.730409)
			(xy 233.78947 -214.781744) (xy 233.773409 -214.831174) (xy 233.749813 -214.877484) (xy 233.719263 -214.919532)
			(xy 233.682512 -214.956283) (xy 233.640464 -214.986833) (xy 233.594154 -215.010429) (xy 233.544724 -215.02649)
			(xy 233.493389 -215.03462) (xy 233.441415 -215.03462) (xy 233.39008 -215.02649) (xy 233.34065 -215.010429)
			(xy 233.29434 -214.986833) (xy 233.252292 -214.956283) (xy 233.215541 -214.919532) (xy 233.184991 -214.877484)
			(xy 233.161395 -214.831174) (xy 233.145334 -214.781744) (xy 233.137204 -214.730409) (xy 232.997754 -214.730409)
			(xy 232.989624 -214.781744) (xy 232.973563 -214.831174) (xy 232.949967 -214.877484) (xy 232.919417 -214.919532)
			(xy 232.882666 -214.956283) (xy 232.840618 -214.986833) (xy 232.794308 -215.010429) (xy 232.744878 -215.02649)
			(xy 232.693543 -215.03462) (xy 232.641569 -215.03462) (xy 232.590234 -215.02649) (xy 232.540804 -215.010429)
			(xy 232.494494 -214.986833) (xy 232.452446 -214.956283) (xy 232.415695 -214.919532) (xy 232.385145 -214.877484)
			(xy 232.361549 -214.831174) (xy 232.345488 -214.781744) (xy 232.337358 -214.730409) (xy 232.197654 -214.730409)
			(xy 232.189524 -214.781744) (xy 232.173463 -214.831174) (xy 232.149867 -214.877484) (xy 232.119317 -214.919532)
			(xy 232.082566 -214.956283) (xy 232.040518 -214.986833) (xy 231.994208 -215.010429) (xy 231.944778 -215.02649)
			(xy 231.893443 -215.03462) (xy 231.841469 -215.03462) (xy 231.790134 -215.02649) (xy 231.740704 -215.010429)
			(xy 231.694394 -214.986833) (xy 231.652346 -214.956283) (xy 231.615595 -214.919532) (xy 231.585045 -214.877484)
			(xy 231.561449 -214.831174) (xy 231.545388 -214.781744) (xy 231.537258 -214.730409) (xy 231.397554 -214.730409)
			(xy 231.389424 -214.781744) (xy 231.373363 -214.831174) (xy 231.349767 -214.877484) (xy 231.319217 -214.919532)
			(xy 231.282466 -214.956283) (xy 231.240418 -214.986833) (xy 231.194108 -215.010429) (xy 231.144678 -215.02649)
			(xy 231.093343 -215.03462) (xy 231.041369 -215.03462) (xy 230.990034 -215.02649) (xy 230.940604 -215.010429)
			(xy 230.894294 -214.986833) (xy 230.852246 -214.956283) (xy 230.815495 -214.919532) (xy 230.784945 -214.877484)
			(xy 230.761349 -214.831174) (xy 230.745288 -214.781744) (xy 230.737158 -214.730409) (xy 230.597708 -214.730409)
			(xy 230.589578 -214.781744) (xy 230.573517 -214.831174) (xy 230.549921 -214.877484) (xy 230.519371 -214.919532)
			(xy 230.48262 -214.956283) (xy 230.440572 -214.986833) (xy 230.394262 -215.010429) (xy 230.344832 -215.02649)
			(xy 230.293497 -215.03462) (xy 230.241523 -215.03462) (xy 230.190188 -215.02649) (xy 230.140758 -215.010429)
			(xy 230.094448 -214.986833) (xy 230.0524 -214.956283) (xy 230.015649 -214.919532) (xy 229.985099 -214.877484)
			(xy 229.961503 -214.831174) (xy 229.945442 -214.781744) (xy 229.937312 -214.730409) (xy 228.998016 -214.730409)
			(xy 228.989886 -214.781744) (xy 228.973825 -214.831174) (xy 228.950229 -214.877484) (xy 228.919679 -214.919532)
			(xy 228.882928 -214.956283) (xy 228.84088 -214.986833) (xy 228.79457 -215.010429) (xy 228.74514 -215.02649)
			(xy 228.693805 -215.03462) (xy 228.641831 -215.03462) (xy 228.590496 -215.02649) (xy 228.541066 -215.010429)
			(xy 228.494756 -214.986833) (xy 228.452708 -214.956283) (xy 228.415957 -214.919532) (xy 228.385407 -214.877484)
			(xy 228.361811 -214.831174) (xy 228.34575 -214.781744) (xy 228.33762 -214.730409) (xy 228.19817 -214.730409)
			(xy 228.19004 -214.781744) (xy 228.173979 -214.831174) (xy 228.150383 -214.877484) (xy 228.119833 -214.919532)
			(xy 228.083082 -214.956283) (xy 228.041034 -214.986833) (xy 227.994724 -215.010429) (xy 227.945294 -215.02649)
			(xy 227.893959 -215.03462) (xy 227.841985 -215.03462) (xy 227.79065 -215.02649) (xy 227.74122 -215.010429)
			(xy 227.69491 -214.986833) (xy 227.652862 -214.956283) (xy 227.616111 -214.919532) (xy 227.585561 -214.877484)
			(xy 227.561965 -214.831174) (xy 227.545904 -214.781744) (xy 227.537774 -214.730409) (xy 227.39807 -214.730409)
			(xy 227.38994 -214.781744) (xy 227.373879 -214.831174) (xy 227.350283 -214.877484) (xy 227.319733 -214.919532)
			(xy 227.282982 -214.956283) (xy 227.240934 -214.986833) (xy 227.194624 -215.010429) (xy 227.145194 -215.02649)
			(xy 227.093859 -215.03462) (xy 227.041885 -215.03462) (xy 226.99055 -215.02649) (xy 226.94112 -215.010429)
			(xy 226.89481 -214.986833) (xy 226.852762 -214.956283) (xy 226.816011 -214.919532) (xy 226.785461 -214.877484)
			(xy 226.761865 -214.831174) (xy 226.745804 -214.781744) (xy 226.737674 -214.730409) (xy 226.59797 -214.730409)
			(xy 226.58984 -214.781744) (xy 226.573779 -214.831174) (xy 226.550183 -214.877484) (xy 226.519633 -214.919532)
			(xy 226.482882 -214.956283) (xy 226.440834 -214.986833) (xy 226.394524 -215.010429) (xy 226.345094 -215.02649)
			(xy 226.293759 -215.03462) (xy 226.241785 -215.03462) (xy 226.19045 -215.02649) (xy 226.14102 -215.010429)
			(xy 226.09471 -214.986833) (xy 226.052662 -214.956283) (xy 226.015911 -214.919532) (xy 225.985361 -214.877484)
			(xy 225.961765 -214.831174) (xy 225.945704 -214.781744) (xy 225.937574 -214.730409) (xy 225.798124 -214.730409)
			(xy 225.789994 -214.781744) (xy 225.773933 -214.831174) (xy 225.750337 -214.877484) (xy 225.719787 -214.919532)
			(xy 225.683036 -214.956283) (xy 225.640988 -214.986833) (xy 225.594678 -215.010429) (xy 225.545248 -215.02649)
			(xy 225.493913 -215.03462) (xy 225.441939 -215.03462) (xy 225.390604 -215.02649) (xy 225.341174 -215.010429)
			(xy 225.294864 -214.986833) (xy 225.252816 -214.956283) (xy 225.216065 -214.919532) (xy 225.185515 -214.877484)
			(xy 225.161919 -214.831174) (xy 225.145858 -214.781744) (xy 225.137728 -214.730409) (xy 224.998024 -214.730409)
			(xy 224.989894 -214.781744) (xy 224.973833 -214.831174) (xy 224.950237 -214.877484) (xy 224.919687 -214.919532)
			(xy 224.882936 -214.956283) (xy 224.840888 -214.986833) (xy 224.794578 -215.010429) (xy 224.745148 -215.02649)
			(xy 224.693813 -215.03462) (xy 224.641839 -215.03462) (xy 224.590504 -215.02649) (xy 224.541074 -215.010429)
			(xy 224.494764 -214.986833) (xy 224.452716 -214.956283) (xy 224.415965 -214.919532) (xy 224.385415 -214.877484)
			(xy 224.361819 -214.831174) (xy 224.345758 -214.781744) (xy 224.337628 -214.730409) (xy 224.198178 -214.730409)
			(xy 224.190048 -214.781744) (xy 224.173987 -214.831174) (xy 224.150391 -214.877484) (xy 224.119841 -214.919532)
			(xy 224.08309 -214.956283) (xy 224.041042 -214.986833) (xy 223.994732 -215.010429) (xy 223.945302 -215.02649)
			(xy 223.893967 -215.03462) (xy 223.841993 -215.03462) (xy 223.790658 -215.02649) (xy 223.741228 -215.010429)
			(xy 223.694918 -214.986833) (xy 223.65287 -214.956283) (xy 223.616119 -214.919532) (xy 223.585569 -214.877484)
			(xy 223.561973 -214.831174) (xy 223.545912 -214.781744) (xy 223.537782 -214.730409) (xy 223.398078 -214.730409)
			(xy 223.389948 -214.781744) (xy 223.373887 -214.831174) (xy 223.350291 -214.877484) (xy 223.319741 -214.919532)
			(xy 223.28299 -214.956283) (xy 223.240942 -214.986833) (xy 223.194632 -215.010429) (xy 223.145202 -215.02649)
			(xy 223.093867 -215.03462) (xy 223.041893 -215.03462) (xy 222.990558 -215.02649) (xy 222.941128 -215.010429)
			(xy 222.894818 -214.986833) (xy 222.85277 -214.956283) (xy 222.816019 -214.919532) (xy 222.785469 -214.877484)
			(xy 222.761873 -214.831174) (xy 222.745812 -214.781744) (xy 222.737682 -214.730409) (xy 207.652154 -214.730409)
			(xy 207.655472 -214.776803) (xy 207.651582 -214.831186) (xy 207.63999 -214.884462) (xy 207.620933 -214.935546)
			(xy 207.594798 -214.983397) (xy 207.562119 -215.027041) (xy 207.523561 -215.065589) (xy 207.479908 -215.098256)
			(xy 207.432049 -215.124377) (xy 207.38096 -215.14342) (xy 207.354424 -215.149684) (xy 207.336898 -215.153494)
			(xy 207.314546 -215.18118) (xy 207.314546 -215.410288) (xy 207.314968 -215.420358) (xy 207.322685 -215.438961)
			(xy 207.329532 -215.446356) (xy 207.40878 -215.525604) (xy 208.560414 -215.525604) (xy 208.564485 -215.469982)
			(xy 208.576611 -215.415545) (xy 208.596534 -215.363454) (xy 208.62383 -215.314819) (xy 208.657916 -215.270676)
			(xy 208.698065 -215.231967) (xy 208.743423 -215.199516) (xy 208.793023 -215.174015) (xy 208.845807 -215.156008)
			(xy 208.90065 -215.145878) (xy 208.956384 -215.143841) (xy 209.011821 -215.149941) (xy 209.065778 -215.164047)
			(xy 209.117107 -215.185859) (xy 209.164713 -215.214913) (xy 209.207581 -215.250588) (xy 209.244798 -215.292125)
			(xy 209.263654 -215.320626) (xy 211.762592 -215.320626) (xy 211.766663 -215.265004) (xy 211.778789 -215.210567)
			(xy 211.798712 -215.158476) (xy 211.826008 -215.109841) (xy 211.860094 -215.065698) (xy 211.900243 -215.026989)
			(xy 211.945601 -214.994538) (xy 211.995201 -214.969037) (xy 212.047985 -214.95103) (xy 212.102828 -214.9409)
			(xy 212.158562 -214.938863) (xy 212.213999 -214.944963) (xy 212.267956 -214.959069) (xy 212.319285 -214.980881)
			(xy 212.366891 -215.009935) (xy 212.409759 -215.04561) (xy 212.446976 -215.087147) (xy 212.477749 -215.13366)
			(xy 212.501421 -215.184157) (xy 212.517489 -215.237564) (xy 212.52517 -215.289756) (xy 214.563615 -215.289756)
			(xy 214.563615 -215.235244) (xy 214.571373 -215.181287) (xy 214.586731 -215.128983) (xy 214.609376 -215.079397)
			(xy 214.638848 -215.033539) (xy 214.674546 -214.992342) (xy 214.715744 -214.956644) (xy 214.761602 -214.927173)
			(xy 214.811189 -214.904529) (xy 214.863493 -214.889172) (xy 214.91745 -214.881415) (xy 214.944706 -214.880952)
			(xy 214.971606 -214.881428) (xy 215.024872 -214.888981) (xy 215.076546 -214.903949) (xy 215.125602 -214.926035)
			(xy 215.171065 -214.9548) (xy 215.191848 -214.971884) (xy 215.19896 -214.97798) (xy 215.215978 -214.984076)
			(xy 215.301576 -214.98306) (xy 215.31834 -214.976456) (xy 215.325452 -214.970106) (xy 215.346563 -214.951952)
			(xy 215.393028 -214.921279) (xy 215.443459 -214.897687) (xy 215.496783 -214.881674) (xy 215.551868 -214.873583)
			(xy 215.579706 -214.873078) (xy 215.607077 -214.873522) (xy 215.661258 -214.881342) (xy 215.713762 -214.896835)
			(xy 215.763509 -214.919682) (xy 215.809474 -214.949413) (xy 215.830404 -214.967058) (xy 215.837516 -214.973154)
			(xy 215.854534 -214.979504) (xy 215.939878 -214.979504) (xy 215.956896 -214.973154) (xy 215.964008 -214.967058)
			(xy 215.984921 -214.949395) (xy 216.030899 -214.919688) (xy 216.080652 -214.896857) (xy 216.133157 -214.881372)
			(xy 216.187336 -214.873549) (xy 216.214706 -214.873078) (xy 216.241956 -214.873593) (xy 216.295901 -214.88135)
			(xy 216.348193 -214.896705) (xy 216.397768 -214.919345) (xy 216.443616 -214.948811) (xy 216.484803 -214.984501)
			(xy 216.520493 -215.025689) (xy 216.537987 -215.05291) (xy 243.483382 -215.05291) (xy 243.487453 -214.997288)
			(xy 243.499579 -214.942851) (xy 243.519502 -214.89076) (xy 243.546798 -214.842125) (xy 243.580884 -214.797982)
			(xy 243.621033 -214.759273) (xy 243.666391 -214.726822) (xy 243.715991 -214.701321) (xy 243.768775 -214.683314)
			(xy 243.823618 -214.673184) (xy 243.879352 -214.671147) (xy 243.934789 -214.677247) (xy 243.988746 -214.691353)
			(xy 244.040075 -214.713165) (xy 244.087681 -214.742219) (xy 244.130549 -214.777894) (xy 244.167766 -214.819431)
			(xy 244.198539 -214.865944) (xy 244.222211 -214.916441) (xy 244.238279 -214.969848) (xy 244.246399 -215.025024)
			(xy 244.246908 -215.05291) (xy 244.246399 -215.080796) (xy 244.238279 -215.135972) (xy 244.222211 -215.189379)
			(xy 244.198539 -215.239876) (xy 244.167766 -215.286389) (xy 244.130549 -215.327926) (xy 244.087681 -215.363601)
			(xy 244.040075 -215.392655) (xy 243.988746 -215.414467) (xy 243.934789 -215.428573) (xy 243.879352 -215.434673)
			(xy 243.823618 -215.432636) (xy 243.768775 -215.422506) (xy 243.715991 -215.404499) (xy 243.666391 -215.378998)
			(xy 243.621033 -215.346547) (xy 243.580884 -215.307838) (xy 243.546798 -215.263695) (xy 243.519502 -215.21506)
			(xy 243.499579 -215.162969) (xy 243.487453 -215.108532) (xy 243.483382 -215.05291) (xy 216.537987 -215.05291)
			(xy 216.549958 -215.071538) (xy 216.572597 -215.121113) (xy 216.587952 -215.173405) (xy 216.595708 -215.22735)
			(xy 216.595708 -215.28185) (xy 216.587952 -215.335795) (xy 216.572597 -215.388087) (xy 216.549958 -215.437662)
			(xy 216.520493 -215.483511) (xy 216.484803 -215.524699) (xy 216.443616 -215.560389) (xy 216.417907 -215.576912)
			(xy 217.845892 -215.576912) (xy 217.849963 -215.52129) (xy 217.862089 -215.466853) (xy 217.882012 -215.414762)
			(xy 217.909308 -215.366127) (xy 217.943394 -215.321984) (xy 217.983543 -215.283275) (xy 218.028901 -215.250824)
			(xy 218.078501 -215.225323) (xy 218.131285 -215.207316) (xy 218.186128 -215.197186) (xy 218.241862 -215.195149)
			(xy 218.297299 -215.201249) (xy 218.351256 -215.215355) (xy 218.402585 -215.237167) (xy 218.450191 -215.266221)
			(xy 218.493059 -215.301896) (xy 218.530276 -215.343433) (xy 218.561049 -215.389946) (xy 218.584721 -215.440443)
			(xy 218.600789 -215.49385) (xy 218.606147 -215.530255) (xy 222.737682 -215.530255) (xy 222.737682 -215.478281)
			(xy 222.745812 -215.426946) (xy 222.761873 -215.377516) (xy 222.785469 -215.331206) (xy 222.816019 -215.289158)
			(xy 222.85277 -215.252407) (xy 222.894818 -215.221857) (xy 222.941128 -215.198261) (xy 222.990558 -215.1822)
			(xy 223.041893 -215.17407) (xy 223.093867 -215.17407) (xy 223.145202 -215.1822) (xy 223.194632 -215.198261)
			(xy 223.240942 -215.221857) (xy 223.28299 -215.252407) (xy 223.319741 -215.289158) (xy 223.350291 -215.331206)
			(xy 223.373887 -215.377516) (xy 223.389948 -215.426946) (xy 223.398078 -215.478281) (xy 223.398588 -215.504268)
			(xy 223.398078 -215.530255) (xy 223.537782 -215.530255) (xy 223.537782 -215.478281) (xy 223.545912 -215.426946)
			(xy 223.561973 -215.377516) (xy 223.585569 -215.331206) (xy 223.616119 -215.289158) (xy 223.65287 -215.252407)
			(xy 223.694918 -215.221857) (xy 223.741228 -215.198261) (xy 223.790658 -215.1822) (xy 223.841993 -215.17407)
			(xy 223.893967 -215.17407) (xy 223.945302 -215.1822) (xy 223.994732 -215.198261) (xy 224.041042 -215.221857)
			(xy 224.08309 -215.252407) (xy 224.119841 -215.289158) (xy 224.150391 -215.331206) (xy 224.173987 -215.377516)
			(xy 224.190048 -215.426946) (xy 224.198178 -215.478281) (xy 224.198688 -215.504268) (xy 224.198178 -215.530255)
			(xy 224.337628 -215.530255) (xy 224.337628 -215.478281) (xy 224.345758 -215.426946) (xy 224.361819 -215.377516)
			(xy 224.385415 -215.331206) (xy 224.415965 -215.289158) (xy 224.452716 -215.252407) (xy 224.494764 -215.221857)
			(xy 224.541074 -215.198261) (xy 224.590504 -215.1822) (xy 224.641839 -215.17407) (xy 224.693813 -215.17407)
			(xy 224.745148 -215.1822) (xy 224.794578 -215.198261) (xy 224.840888 -215.221857) (xy 224.882936 -215.252407)
			(xy 224.919687 -215.289158) (xy 224.950237 -215.331206) (xy 224.973833 -215.377516) (xy 224.989894 -215.426946)
			(xy 224.998024 -215.478281) (xy 224.998534 -215.504268) (xy 224.998024 -215.530255) (xy 225.137728 -215.530255)
			(xy 225.137728 -215.478281) (xy 225.145858 -215.426946) (xy 225.161919 -215.377516) (xy 225.185515 -215.331206)
			(xy 225.216065 -215.289158) (xy 225.252816 -215.252407) (xy 225.294864 -215.221857) (xy 225.341174 -215.198261)
			(xy 225.390604 -215.1822) (xy 225.441939 -215.17407) (xy 225.493913 -215.17407) (xy 225.545248 -215.1822)
			(xy 225.594678 -215.198261) (xy 225.640988 -215.221857) (xy 225.683036 -215.252407) (xy 225.719787 -215.289158)
			(xy 225.750337 -215.331206) (xy 225.773933 -215.377516) (xy 225.789994 -215.426946) (xy 225.798124 -215.478281)
			(xy 225.798634 -215.504268) (xy 225.798124 -215.530255) (xy 225.937574 -215.530255) (xy 225.937574 -215.478281)
			(xy 225.945704 -215.426946) (xy 225.961765 -215.377516) (xy 225.985361 -215.331206) (xy 226.015911 -215.289158)
			(xy 226.052662 -215.252407) (xy 226.09471 -215.221857) (xy 226.14102 -215.198261) (xy 226.19045 -215.1822)
			(xy 226.241785 -215.17407) (xy 226.293759 -215.17407) (xy 226.345094 -215.1822) (xy 226.394524 -215.198261)
			(xy 226.440834 -215.221857) (xy 226.482882 -215.252407) (xy 226.519633 -215.289158) (xy 226.550183 -215.331206)
			(xy 226.573779 -215.377516) (xy 226.58984 -215.426946) (xy 226.59797 -215.478281) (xy 226.59848 -215.504268)
			(xy 226.59797 -215.530255) (xy 226.737674 -215.530255) (xy 226.737674 -215.478281) (xy 226.745804 -215.426946)
			(xy 226.761865 -215.377516) (xy 226.785461 -215.331206) (xy 226.816011 -215.289158) (xy 226.852762 -215.252407)
			(xy 226.89481 -215.221857) (xy 226.94112 -215.198261) (xy 226.99055 -215.1822) (xy 227.041885 -215.17407)
			(xy 227.093859 -215.17407) (xy 227.145194 -215.1822) (xy 227.194624 -215.198261) (xy 227.240934 -215.221857)
			(xy 227.282982 -215.252407) (xy 227.319733 -215.289158) (xy 227.350283 -215.331206) (xy 227.373879 -215.377516)
			(xy 227.38994 -215.426946) (xy 227.39807 -215.478281) (xy 227.39858 -215.504268) (xy 227.39807 -215.530255)
			(xy 227.537774 -215.530255) (xy 227.537774 -215.478281) (xy 227.545904 -215.426946) (xy 227.561965 -215.377516)
			(xy 227.585561 -215.331206) (xy 227.616111 -215.289158) (xy 227.652862 -215.252407) (xy 227.69491 -215.221857)
			(xy 227.74122 -215.198261) (xy 227.79065 -215.1822) (xy 227.841985 -215.17407) (xy 227.893959 -215.17407)
			(xy 227.945294 -215.1822) (xy 227.994724 -215.198261) (xy 228.041034 -215.221857) (xy 228.083082 -215.252407)
			(xy 228.119833 -215.289158) (xy 228.150383 -215.331206) (xy 228.173979 -215.377516) (xy 228.19004 -215.426946)
			(xy 228.19817 -215.478281) (xy 228.19868 -215.504268) (xy 228.19817 -215.530255) (xy 228.33762 -215.530255)
			(xy 228.33762 -215.478281) (xy 228.34575 -215.426946) (xy 228.361811 -215.377516) (xy 228.385407 -215.331206)
			(xy 228.415957 -215.289158) (xy 228.452708 -215.252407) (xy 228.494756 -215.221857) (xy 228.541066 -215.198261)
			(xy 228.590496 -215.1822) (xy 228.641831 -215.17407) (xy 228.693805 -215.17407) (xy 228.74514 -215.1822)
			(xy 228.79457 -215.198261) (xy 228.84088 -215.221857) (xy 228.882928 -215.252407) (xy 228.919679 -215.289158)
			(xy 228.950229 -215.331206) (xy 228.973825 -215.377516) (xy 228.989886 -215.426946) (xy 228.998016 -215.478281)
			(xy 228.998526 -215.504268) (xy 228.998016 -215.530255) (xy 229.937312 -215.530255) (xy 229.937312 -215.478281)
			(xy 229.945442 -215.426946) (xy 229.961503 -215.377516) (xy 229.985099 -215.331206) (xy 230.015649 -215.289158)
			(xy 230.0524 -215.252407) (xy 230.094448 -215.221857) (xy 230.140758 -215.198261) (xy 230.190188 -215.1822)
			(xy 230.241523 -215.17407) (xy 230.293497 -215.17407) (xy 230.344832 -215.1822) (xy 230.394262 -215.198261)
			(xy 230.440572 -215.221857) (xy 230.48262 -215.252407) (xy 230.519371 -215.289158) (xy 230.549921 -215.331206)
			(xy 230.573517 -215.377516) (xy 230.589578 -215.426946) (xy 230.597708 -215.478281) (xy 230.598218 -215.504268)
			(xy 230.597708 -215.530255) (xy 230.737158 -215.530255) (xy 230.737158 -215.478281) (xy 230.745288 -215.426946)
			(xy 230.761349 -215.377516) (xy 230.784945 -215.331206) (xy 230.815495 -215.289158) (xy 230.852246 -215.252407)
			(xy 230.894294 -215.221857) (xy 230.940604 -215.198261) (xy 230.990034 -215.1822) (xy 231.041369 -215.17407)
			(xy 231.093343 -215.17407) (xy 231.144678 -215.1822) (xy 231.194108 -215.198261) (xy 231.240418 -215.221857)
			(xy 231.282466 -215.252407) (xy 231.319217 -215.289158) (xy 231.349767 -215.331206) (xy 231.373363 -215.377516)
			(xy 231.389424 -215.426946) (xy 231.397554 -215.478281) (xy 231.398064 -215.504268) (xy 231.397554 -215.530255)
			(xy 231.537258 -215.530255) (xy 231.537258 -215.478281) (xy 231.545388 -215.426946) (xy 231.561449 -215.377516)
			(xy 231.585045 -215.331206) (xy 231.615595 -215.289158) (xy 231.652346 -215.252407) (xy 231.694394 -215.221857)
			(xy 231.740704 -215.198261) (xy 231.790134 -215.1822) (xy 231.841469 -215.17407) (xy 231.893443 -215.17407)
			(xy 231.944778 -215.1822) (xy 231.994208 -215.198261) (xy 232.040518 -215.221857) (xy 232.082566 -215.252407)
			(xy 232.119317 -215.289158) (xy 232.149867 -215.331206) (xy 232.173463 -215.377516) (xy 232.189524 -215.426946)
			(xy 232.197654 -215.478281) (xy 232.198164 -215.504268) (xy 232.197654 -215.530255) (xy 232.337358 -215.530255)
			(xy 232.337358 -215.478281) (xy 232.345488 -215.426946) (xy 232.361549 -215.377516) (xy 232.385145 -215.331206)
			(xy 232.415695 -215.289158) (xy 232.452446 -215.252407) (xy 232.494494 -215.221857) (xy 232.540804 -215.198261)
			(xy 232.590234 -215.1822) (xy 232.641569 -215.17407) (xy 232.693543 -215.17407) (xy 232.744878 -215.1822)
			(xy 232.794308 -215.198261) (xy 232.840618 -215.221857) (xy 232.882666 -215.252407) (xy 232.919417 -215.289158)
			(xy 232.949967 -215.331206) (xy 232.973563 -215.377516) (xy 232.989624 -215.426946) (xy 232.997754 -215.478281)
			(xy 232.998264 -215.504268) (xy 232.997754 -215.530255) (xy 232.989624 -215.58159) (xy 232.973563 -215.63102)
			(xy 232.949967 -215.67733) (xy 232.919417 -215.719378) (xy 232.882666 -215.756129) (xy 232.840618 -215.786679)
			(xy 232.794308 -215.810275) (xy 232.744878 -215.826336) (xy 232.693543 -215.834466) (xy 232.641569 -215.834466)
			(xy 232.590234 -215.826336) (xy 232.540804 -215.810275) (xy 232.494494 -215.786679) (xy 232.452446 -215.756129)
			(xy 232.415695 -215.719378) (xy 232.385145 -215.67733) (xy 232.361549 -215.63102) (xy 232.345488 -215.58159)
			(xy 232.337358 -215.530255) (xy 232.197654 -215.530255) (xy 232.189524 -215.58159) (xy 232.173463 -215.63102)
			(xy 232.149867 -215.67733) (xy 232.119317 -215.719378) (xy 232.082566 -215.756129) (xy 232.040518 -215.786679)
			(xy 231.994208 -215.810275) (xy 231.944778 -215.826336) (xy 231.893443 -215.834466) (xy 231.841469 -215.834466)
			(xy 231.790134 -215.826336) (xy 231.740704 -215.810275) (xy 231.694394 -215.786679) (xy 231.652346 -215.756129)
			(xy 231.615595 -215.719378) (xy 231.585045 -215.67733) (xy 231.561449 -215.63102) (xy 231.545388 -215.58159)
			(xy 231.537258 -215.530255) (xy 231.397554 -215.530255) (xy 231.389424 -215.58159) (xy 231.373363 -215.63102)
			(xy 231.349767 -215.67733) (xy 231.319217 -215.719378) (xy 231.282466 -215.756129) (xy 231.240418 -215.786679)
			(xy 231.194108 -215.810275) (xy 231.144678 -215.826336) (xy 231.093343 -215.834466) (xy 231.041369 -215.834466)
			(xy 230.990034 -215.826336) (xy 230.940604 -215.810275) (xy 230.894294 -215.786679) (xy 230.852246 -215.756129)
			(xy 230.815495 -215.719378) (xy 230.784945 -215.67733) (xy 230.761349 -215.63102) (xy 230.745288 -215.58159)
			(xy 230.737158 -215.530255) (xy 230.597708 -215.530255) (xy 230.589578 -215.58159) (xy 230.573517 -215.63102)
			(xy 230.549921 -215.67733) (xy 230.519371 -215.719378) (xy 230.48262 -215.756129) (xy 230.440572 -215.786679)
			(xy 230.394262 -215.810275) (xy 230.344832 -215.826336) (xy 230.293497 -215.834466) (xy 230.241523 -215.834466)
			(xy 230.190188 -215.826336) (xy 230.140758 -215.810275) (xy 230.094448 -215.786679) (xy 230.0524 -215.756129)
			(xy 230.015649 -215.719378) (xy 229.985099 -215.67733) (xy 229.961503 -215.63102) (xy 229.945442 -215.58159)
			(xy 229.937312 -215.530255) (xy 228.998016 -215.530255) (xy 228.989886 -215.58159) (xy 228.973825 -215.63102)
			(xy 228.950229 -215.67733) (xy 228.919679 -215.719378) (xy 228.882928 -215.756129) (xy 228.84088 -215.786679)
			(xy 228.79457 -215.810275) (xy 228.74514 -215.826336) (xy 228.693805 -215.834466) (xy 228.641831 -215.834466)
			(xy 228.590496 -215.826336) (xy 228.541066 -215.810275) (xy 228.494756 -215.786679) (xy 228.452708 -215.756129)
			(xy 228.415957 -215.719378) (xy 228.385407 -215.67733) (xy 228.361811 -215.63102) (xy 228.34575 -215.58159)
			(xy 228.33762 -215.530255) (xy 228.19817 -215.530255) (xy 228.19004 -215.58159) (xy 228.173979 -215.63102)
			(xy 228.150383 -215.67733) (xy 228.119833 -215.719378) (xy 228.083082 -215.756129) (xy 228.041034 -215.786679)
			(xy 227.994724 -215.810275) (xy 227.945294 -215.826336) (xy 227.893959 -215.834466) (xy 227.841985 -215.834466)
			(xy 227.79065 -215.826336) (xy 227.74122 -215.810275) (xy 227.69491 -215.786679) (xy 227.652862 -215.756129)
			(xy 227.616111 -215.719378) (xy 227.585561 -215.67733) (xy 227.561965 -215.63102) (xy 227.545904 -215.58159)
			(xy 227.537774 -215.530255) (xy 227.39807 -215.530255) (xy 227.38994 -215.58159) (xy 227.373879 -215.63102)
			(xy 227.350283 -215.67733) (xy 227.319733 -215.719378) (xy 227.282982 -215.756129) (xy 227.240934 -215.786679)
			(xy 227.194624 -215.810275) (xy 227.145194 -215.826336) (xy 227.093859 -215.834466) (xy 227.041885 -215.834466)
			(xy 226.99055 -215.826336) (xy 226.94112 -215.810275) (xy 226.89481 -215.786679) (xy 226.852762 -215.756129)
			(xy 226.816011 -215.719378) (xy 226.785461 -215.67733) (xy 226.761865 -215.63102) (xy 226.745804 -215.58159)
			(xy 226.737674 -215.530255) (xy 226.59797 -215.530255) (xy 226.58984 -215.58159) (xy 226.573779 -215.63102)
			(xy 226.550183 -215.67733) (xy 226.519633 -215.719378) (xy 226.482882 -215.756129) (xy 226.440834 -215.786679)
			(xy 226.394524 -215.810275) (xy 226.345094 -215.826336) (xy 226.293759 -215.834466) (xy 226.241785 -215.834466)
			(xy 226.19045 -215.826336) (xy 226.14102 -215.810275) (xy 226.09471 -215.786679) (xy 226.052662 -215.756129)
			(xy 226.015911 -215.719378) (xy 225.985361 -215.67733) (xy 225.961765 -215.63102) (xy 225.945704 -215.58159)
			(xy 225.937574 -215.530255) (xy 225.798124 -215.530255) (xy 225.789994 -215.58159) (xy 225.773933 -215.63102)
			(xy 225.750337 -215.67733) (xy 225.719787 -215.719378) (xy 225.683036 -215.756129) (xy 225.640988 -215.786679)
			(xy 225.594678 -215.810275) (xy 225.545248 -215.826336) (xy 225.493913 -215.834466) (xy 225.441939 -215.834466)
			(xy 225.390604 -215.826336) (xy 225.341174 -215.810275) (xy 225.294864 -215.786679) (xy 225.252816 -215.756129)
			(xy 225.216065 -215.719378) (xy 225.185515 -215.67733) (xy 225.161919 -215.63102) (xy 225.145858 -215.58159)
			(xy 225.137728 -215.530255) (xy 224.998024 -215.530255) (xy 224.989894 -215.58159) (xy 224.973833 -215.63102)
			(xy 224.950237 -215.67733) (xy 224.919687 -215.719378) (xy 224.882936 -215.756129) (xy 224.840888 -215.786679)
			(xy 224.794578 -215.810275) (xy 224.745148 -215.826336) (xy 224.693813 -215.834466) (xy 224.641839 -215.834466)
			(xy 224.590504 -215.826336) (xy 224.541074 -215.810275) (xy 224.494764 -215.786679) (xy 224.452716 -215.756129)
			(xy 224.415965 -215.719378) (xy 224.385415 -215.67733) (xy 224.361819 -215.63102) (xy 224.345758 -215.58159)
			(xy 224.337628 -215.530255) (xy 224.198178 -215.530255) (xy 224.190048 -215.58159) (xy 224.173987 -215.63102)
			(xy 224.150391 -215.67733) (xy 224.119841 -215.719378) (xy 224.08309 -215.756129) (xy 224.041042 -215.786679)
			(xy 223.994732 -215.810275) (xy 223.945302 -215.826336) (xy 223.893967 -215.834466) (xy 223.841993 -215.834466)
			(xy 223.790658 -215.826336) (xy 223.741228 -215.810275) (xy 223.694918 -215.786679) (xy 223.65287 -215.756129)
			(xy 223.616119 -215.719378) (xy 223.585569 -215.67733) (xy 223.561973 -215.63102) (xy 223.545912 -215.58159)
			(xy 223.537782 -215.530255) (xy 223.398078 -215.530255) (xy 223.389948 -215.58159) (xy 223.373887 -215.63102)
			(xy 223.350291 -215.67733) (xy 223.319741 -215.719378) (xy 223.28299 -215.756129) (xy 223.240942 -215.786679)
			(xy 223.194632 -215.810275) (xy 223.145202 -215.826336) (xy 223.093867 -215.834466) (xy 223.041893 -215.834466)
			(xy 222.990558 -215.826336) (xy 222.941128 -215.810275) (xy 222.894818 -215.786679) (xy 222.85277 -215.756129)
			(xy 222.816019 -215.719378) (xy 222.785469 -215.67733) (xy 222.761873 -215.63102) (xy 222.745812 -215.58159)
			(xy 222.737682 -215.530255) (xy 218.606147 -215.530255) (xy 218.608909 -215.549026) (xy 218.609418 -215.576912)
			(xy 218.608909 -215.604798) (xy 218.600789 -215.659974) (xy 218.584721 -215.713381) (xy 218.561049 -215.763878)
			(xy 218.530276 -215.810391) (xy 218.493059 -215.851928) (xy 218.450191 -215.887603) (xy 218.402585 -215.916657)
			(xy 218.351256 -215.938469) (xy 218.297299 -215.952575) (xy 218.241862 -215.958675) (xy 218.186128 -215.956638)
			(xy 218.131285 -215.946508) (xy 218.078501 -215.928501) (xy 218.028901 -215.903) (xy 217.983543 -215.870549)
			(xy 217.943394 -215.83184) (xy 217.909308 -215.787697) (xy 217.882012 -215.739062) (xy 217.862089 -215.686971)
			(xy 217.849963 -215.632534) (xy 217.845892 -215.576912) (xy 216.417907 -215.576912) (xy 216.397768 -215.589855)
			(xy 216.348193 -215.612495) (xy 216.295901 -215.62785) (xy 216.241956 -215.635607) (xy 216.214706 -215.636094)
			(xy 216.187336 -215.635626) (xy 216.133157 -215.627809) (xy 216.080654 -215.61232) (xy 216.030907 -215.589479)
			(xy 215.98494 -215.559755) (xy 215.964008 -215.542114) (xy 215.956896 -215.536018) (xy 215.939878 -215.529668)
			(xy 215.854534 -215.529668) (xy 215.837516 -215.536018) (xy 215.830404 -215.542114) (xy 215.809483 -215.559767)
			(xy 215.763507 -215.589476) (xy 215.713757 -215.612309) (xy 215.661254 -215.627797) (xy 215.607076 -215.635622)
			(xy 215.579706 -215.636094) (xy 215.552806 -215.635623) (xy 215.499539 -215.628071) (xy 215.447864 -215.613103)
			(xy 215.398808 -215.591015) (xy 215.353346 -215.562247) (xy 215.332564 -215.545162) (xy 215.325452 -215.539066)
			(xy 215.308434 -215.53297) (xy 215.222836 -215.533986) (xy 215.206072 -215.54059) (xy 215.19896 -215.54694)
			(xy 215.177851 -215.565096) (xy 215.131384 -215.595766) (xy 215.080953 -215.619358) (xy 215.027629 -215.63537)
			(xy 214.972544 -215.643463) (xy 214.944706 -215.643968) (xy 214.91745 -215.643585) (xy 214.863493 -215.635828)
			(xy 214.811189 -215.620471) (xy 214.761602 -215.597827) (xy 214.715744 -215.568356) (xy 214.674546 -215.532658)
			(xy 214.638848 -215.491461) (xy 214.609376 -215.445603) (xy 214.586731 -215.396017) (xy 214.571373 -215.343713)
			(xy 214.563615 -215.289756) (xy 212.52517 -215.289756) (xy 212.525609 -215.29274) (xy 212.526118 -215.320626)
			(xy 212.525609 -215.348512) (xy 212.517489 -215.403688) (xy 212.501421 -215.457095) (xy 212.477749 -215.507592)
			(xy 212.446976 -215.554105) (xy 212.409759 -215.595642) (xy 212.366891 -215.631317) (xy 212.319285 -215.660371)
			(xy 212.267956 -215.682183) (xy 212.213999 -215.696289) (xy 212.158562 -215.702389) (xy 212.102828 -215.700352)
			(xy 212.047985 -215.690222) (xy 211.995201 -215.672215) (xy 211.945601 -215.646714) (xy 211.900243 -215.614263)
			(xy 211.860094 -215.575554) (xy 211.826008 -215.531411) (xy 211.798712 -215.482776) (xy 211.778789 -215.430685)
			(xy 211.766663 -215.376248) (xy 211.762592 -215.320626) (xy 209.263654 -215.320626) (xy 209.275571 -215.338638)
			(xy 209.299243 -215.389135) (xy 209.315311 -215.442542) (xy 209.323431 -215.497718) (xy 209.32394 -215.525604)
			(xy 209.323431 -215.55349) (xy 209.315311 -215.608666) (xy 209.299243 -215.662073) (xy 209.275571 -215.71257)
			(xy 209.244798 -215.759083) (xy 209.207581 -215.80062) (xy 209.164713 -215.836295) (xy 209.117107 -215.865349)
			(xy 209.065778 -215.887161) (xy 209.011821 -215.901267) (xy 208.956384 -215.907367) (xy 208.90065 -215.90533)
			(xy 208.845807 -215.8952) (xy 208.793023 -215.877193) (xy 208.743423 -215.851692) (xy 208.698065 -215.819241)
			(xy 208.657916 -215.780532) (xy 208.62383 -215.736389) (xy 208.596534 -215.687754) (xy 208.576611 -215.635663)
			(xy 208.564485 -215.581226) (xy 208.560414 -215.525604) (xy 207.40878 -215.525604) (xy 207.4291 -215.545924)
			(xy 207.435943 -215.553324) (xy 207.443668 -215.571922) (xy 207.444086 -215.581992) (xy 207.444086 -216.554304)
			(xy 208.638646 -216.554304) (xy 208.642717 -216.498682) (xy 208.654843 -216.444245) (xy 208.674766 -216.392154)
			(xy 208.702062 -216.343519) (xy 208.736148 -216.299376) (xy 208.776297 -216.260667) (xy 208.821655 -216.228216)
			(xy 208.871255 -216.202715) (xy 208.924039 -216.184708) (xy 208.978882 -216.174578) (xy 209.034616 -216.172541)
			(xy 209.090053 -216.178641) (xy 209.14401 -216.192747) (xy 209.195339 -216.214559) (xy 209.242945 -216.243613)
			(xy 209.285813 -216.279288) (xy 209.32303 -216.320825) (xy 209.353803 -216.367338) (xy 209.377475 -216.417835)
			(xy 209.382715 -216.435251) (xy 210.184978 -216.435251) (xy 210.184978 -216.380749) (xy 210.192734 -216.326801)
			(xy 210.208089 -216.274506) (xy 210.230731 -216.224929) (xy 210.260197 -216.179079) (xy 210.295888 -216.137888)
			(xy 210.337079 -216.102197) (xy 210.382929 -216.072731) (xy 210.432506 -216.050089) (xy 210.484801 -216.034734)
			(xy 210.538749 -216.026978) (xy 210.566 -216.026492) (xy 210.592844 -216.026887) (xy 210.646003 -216.034401)
			(xy 210.697584 -216.049294) (xy 210.746567 -216.071273) (xy 210.791984 -216.099902) (xy 210.832939 -216.134617)
			(xy 210.868621 -216.174732) (xy 210.898326 -216.219453) (xy 210.921467 -216.267898) (xy 210.922313 -216.270586)
			(xy 212.326218 -216.270586) (xy 212.330289 -216.214964) (xy 212.342415 -216.160527) (xy 212.362338 -216.108436)
			(xy 212.389634 -216.059801) (xy 212.42372 -216.015658) (xy 212.463869 -215.976949) (xy 212.509227 -215.944498)
			(xy 212.558827 -215.918997) (xy 212.611611 -215.90099) (xy 212.666454 -215.89086) (xy 212.722188 -215.888823)
			(xy 212.777625 -215.894923) (xy 212.831582 -215.909029) (xy 212.882911 -215.930841) (xy 212.930517 -215.959895)
			(xy 212.973385 -215.99557) (xy 213.010602 -216.037107) (xy 213.041375 -216.08362) (xy 213.065047 -216.134117)
			(xy 213.081115 -216.187524) (xy 213.089235 -216.2427) (xy 213.089744 -216.270586) (xy 213.089246 -216.297856)
			(xy 215.108441 -216.297856) (xy 215.108441 -216.243344) (xy 215.116199 -216.189388) (xy 215.131558 -216.137086)
			(xy 215.154204 -216.087501) (xy 215.183676 -216.041645) (xy 215.219375 -216.000449) (xy 215.260574 -215.964754)
			(xy 215.306433 -215.935286) (xy 215.356019 -215.912645) (xy 215.408324 -215.897292) (xy 215.46228 -215.889538)
			(xy 215.489536 -215.889078) (xy 215.515852 -215.889534) (xy 215.567985 -215.896755) (xy 215.618633 -215.911068)
			(xy 215.666835 -215.932202) (xy 215.711677 -215.959756) (xy 215.75231 -215.993208) (xy 215.77046 -216.012268)
			(xy 215.777999 -216.019649) (xy 215.797266 -216.028187) (xy 215.807798 -216.028778) (xy 215.882474 -216.028778)
			(xy 215.893025 -216.028255) (xy 215.91232 -216.019716) (xy 215.919812 -216.012268) (xy 215.937954 -215.993196)
			(xy 215.978572 -215.959714) (xy 216.02341 -215.932141) (xy 216.071616 -215.911001) (xy 216.122273 -215.896696)
			(xy 216.174417 -215.889498) (xy 216.200736 -215.889078) (xy 216.227985 -215.889595) (xy 216.281926 -215.897355)
			(xy 216.334215 -215.912713) (xy 216.383786 -215.935355) (xy 216.42963 -215.964821) (xy 216.470814 -216.000511)
			(xy 216.5065 -216.041699) (xy 216.535962 -216.087546) (xy 216.5586 -216.137119) (xy 216.573953 -216.189409)
			(xy 216.581708 -216.243351) (xy 216.581708 -216.297849) (xy 216.577035 -216.330355) (xy 222.737682 -216.330355)
			(xy 222.737682 -216.278381) (xy 222.745812 -216.227046) (xy 222.761873 -216.177616) (xy 222.785469 -216.131306)
			(xy 222.816019 -216.089258) (xy 222.85277 -216.052507) (xy 222.894818 -216.021957) (xy 222.941128 -215.998361)
			(xy 222.990558 -215.9823) (xy 223.041893 -215.97417) (xy 223.093867 -215.97417) (xy 223.145202 -215.9823)
			(xy 223.194632 -215.998361) (xy 223.240942 -216.021957) (xy 223.28299 -216.052507) (xy 223.319741 -216.089258)
			(xy 223.350291 -216.131306) (xy 223.373887 -216.177616) (xy 223.389948 -216.227046) (xy 223.398078 -216.278381)
			(xy 223.398588 -216.304368) (xy 223.398078 -216.330355) (xy 223.537782 -216.330355) (xy 223.537782 -216.278381)
			(xy 223.545912 -216.227046) (xy 223.561973 -216.177616) (xy 223.585569 -216.131306) (xy 223.616119 -216.089258)
			(xy 223.65287 -216.052507) (xy 223.694918 -216.021957) (xy 223.741228 -215.998361) (xy 223.790658 -215.9823)
			(xy 223.841993 -215.97417) (xy 223.893967 -215.97417) (xy 223.945302 -215.9823) (xy 223.994732 -215.998361)
			(xy 224.041042 -216.021957) (xy 224.08309 -216.052507) (xy 224.119841 -216.089258) (xy 224.150391 -216.131306)
			(xy 224.173987 -216.177616) (xy 224.190048 -216.227046) (xy 224.198178 -216.278381) (xy 224.198688 -216.304368)
			(xy 224.198178 -216.330355) (xy 224.337628 -216.330355) (xy 224.337628 -216.278381) (xy 224.345758 -216.227046)
			(xy 224.361819 -216.177616) (xy 224.385415 -216.131306) (xy 224.415965 -216.089258) (xy 224.452716 -216.052507)
			(xy 224.494764 -216.021957) (xy 224.541074 -215.998361) (xy 224.590504 -215.9823) (xy 224.641839 -215.97417)
			(xy 224.693813 -215.97417) (xy 224.745148 -215.9823) (xy 224.794578 -215.998361) (xy 224.840888 -216.021957)
			(xy 224.882936 -216.052507) (xy 224.919687 -216.089258) (xy 224.950237 -216.131306) (xy 224.973833 -216.177616)
			(xy 224.989894 -216.227046) (xy 224.998024 -216.278381) (xy 224.998534 -216.304368) (xy 224.998024 -216.330355)
			(xy 225.137728 -216.330355) (xy 225.137728 -216.278381) (xy 225.145858 -216.227046) (xy 225.161919 -216.177616)
			(xy 225.185515 -216.131306) (xy 225.216065 -216.089258) (xy 225.252816 -216.052507) (xy 225.294864 -216.021957)
			(xy 225.341174 -215.998361) (xy 225.390604 -215.9823) (xy 225.441939 -215.97417) (xy 225.493913 -215.97417)
			(xy 225.545248 -215.9823) (xy 225.594678 -215.998361) (xy 225.640988 -216.021957) (xy 225.683036 -216.052507)
			(xy 225.719787 -216.089258) (xy 225.750337 -216.131306) (xy 225.773933 -216.177616) (xy 225.789994 -216.227046)
			(xy 225.798124 -216.278381) (xy 225.798634 -216.304368) (xy 225.798124 -216.330355) (xy 225.937574 -216.330355)
			(xy 225.937574 -216.278381) (xy 225.945704 -216.227046) (xy 225.961765 -216.177616) (xy 225.985361 -216.131306)
			(xy 226.015911 -216.089258) (xy 226.052662 -216.052507) (xy 226.09471 -216.021957) (xy 226.14102 -215.998361)
			(xy 226.19045 -215.9823) (xy 226.241785 -215.97417) (xy 226.293759 -215.97417) (xy 226.345094 -215.9823)
			(xy 226.394524 -215.998361) (xy 226.440834 -216.021957) (xy 226.482882 -216.052507) (xy 226.519633 -216.089258)
			(xy 226.550183 -216.131306) (xy 226.573779 -216.177616) (xy 226.58984 -216.227046) (xy 226.59797 -216.278381)
			(xy 226.59848 -216.304368) (xy 226.597975 -216.330101) (xy 226.73742 -216.330101) (xy 226.73742 -216.278127)
			(xy 226.74555 -216.226792) (xy 226.761611 -216.177362) (xy 226.785207 -216.131052) (xy 226.815757 -216.089004)
			(xy 226.852508 -216.052253) (xy 226.894556 -216.021703) (xy 226.940866 -215.998107) (xy 226.990296 -215.982046)
			(xy 227.041631 -215.973916) (xy 227.093605 -215.973916) (xy 227.14494 -215.982046) (xy 227.19437 -215.998107)
			(xy 227.24068 -216.021703) (xy 227.282728 -216.052253) (xy 227.319479 -216.089004) (xy 227.350029 -216.131052)
			(xy 227.373625 -216.177362) (xy 227.389686 -216.226792) (xy 227.397816 -216.278127) (xy 227.398326 -216.304114)
			(xy 227.397816 -216.330101) (xy 227.397776 -216.330355) (xy 230.737158 -216.330355) (xy 230.737158 -216.278381)
			(xy 230.745288 -216.227046) (xy 230.761349 -216.177616) (xy 230.784945 -216.131306) (xy 230.815495 -216.089258)
			(xy 230.852246 -216.052507) (xy 230.894294 -216.021957) (xy 230.940604 -215.998361) (xy 230.990034 -215.9823)
			(xy 231.041369 -215.97417) (xy 231.093343 -215.97417) (xy 231.144678 -215.9823) (xy 231.194108 -215.998361)
			(xy 231.240418 -216.021957) (xy 231.282466 -216.052507) (xy 231.319217 -216.089258) (xy 231.349767 -216.131306)
			(xy 231.373363 -216.177616) (xy 231.389424 -216.227046) (xy 231.397554 -216.278381) (xy 231.398064 -216.304368)
			(xy 231.397554 -216.330355) (xy 231.537258 -216.330355) (xy 231.537258 -216.278381) (xy 231.545388 -216.227046)
			(xy 231.561449 -216.177616) (xy 231.585045 -216.131306) (xy 231.615595 -216.089258) (xy 231.652346 -216.052507)
			(xy 231.694394 -216.021957) (xy 231.740704 -215.998361) (xy 231.790134 -215.9823) (xy 231.841469 -215.97417)
			(xy 231.893443 -215.97417) (xy 231.944778 -215.9823) (xy 231.994208 -215.998361) (xy 232.040518 -216.021957)
			(xy 232.082566 -216.052507) (xy 232.119317 -216.089258) (xy 232.149867 -216.131306) (xy 232.173463 -216.177616)
			(xy 232.189524 -216.227046) (xy 232.197654 -216.278381) (xy 232.198164 -216.304368) (xy 232.197654 -216.330355)
			(xy 232.337358 -216.330355) (xy 232.337358 -216.278381) (xy 232.345488 -216.227046) (xy 232.361549 -216.177616)
			(xy 232.385145 -216.131306) (xy 232.415695 -216.089258) (xy 232.452446 -216.052507) (xy 232.494494 -216.021957)
			(xy 232.540804 -215.998361) (xy 232.590234 -215.9823) (xy 232.641569 -215.97417) (xy 232.693543 -215.97417)
			(xy 232.744878 -215.9823) (xy 232.794308 -215.998361) (xy 232.840618 -216.021957) (xy 232.882666 -216.052507)
			(xy 232.919417 -216.089258) (xy 232.949967 -216.131306) (xy 232.973563 -216.177616) (xy 232.989624 -216.227046)
			(xy 232.997754 -216.278381) (xy 232.998264 -216.304368) (xy 233.115104 -216.304368) (xy 233.11553 -216.277203)
			(xy 233.123844 -216.223513) (xy 233.1403 -216.171735) (xy 233.164509 -216.123097) (xy 233.195896 -216.078751)
			(xy 233.233719 -216.039749) (xy 233.27708 -216.007014) (xy 233.300778 -215.993726) (xy 233.312621 -215.986828)
			(xy 233.332439 -215.967916) (xy 233.346505 -215.944409) (xy 233.353803 -215.918005) (xy 233.353805 -215.890612)
			(xy 233.346512 -215.864206) (xy 233.33245 -215.840697) (xy 233.312635 -215.821782) (xy 233.300778 -215.81491)
			(xy 233.277086 -215.801615) (xy 233.233733 -215.768879) (xy 233.195918 -215.729875) (xy 233.164539 -215.68553)
			(xy 233.140339 -215.636893) (xy 233.123893 -215.585117) (xy 233.115589 -215.531431) (xy 233.115104 -215.504268)
			(xy 233.115596 -215.477904) (xy 233.123455 -215.425764) (xy 233.138997 -215.375379) (xy 233.161875 -215.327872)
			(xy 233.191578 -215.284306) (xy 233.227442 -215.245653) (xy 233.268667 -215.212778) (xy 233.314331 -215.186413)
			(xy 233.363415 -215.16715) (xy 233.414821 -215.155416) (xy 233.467402 -215.151476) (xy 233.519983 -215.155416)
			(xy 233.571389 -215.16715) (xy 233.620473 -215.186413) (xy 233.666137 -215.212778) (xy 233.707362 -215.245653)
			(xy 233.743226 -215.284306) (xy 233.772929 -215.327872) (xy 233.795807 -215.375379) (xy 233.811349 -215.425764)
			(xy 233.819208 -215.477904) (xy 233.8197 -215.504268) (xy 233.81922 -215.531431) (xy 233.810916 -215.585118)
			(xy 233.794469 -215.636895) (xy 233.770269 -215.685533) (xy 233.762297 -215.6968) (xy 240.079782 -215.6968)
			(xy 240.083853 -215.641178) (xy 240.095979 -215.586741) (xy 240.115902 -215.53465) (xy 240.143198 -215.486015)
			(xy 240.177284 -215.441872) (xy 240.217433 -215.403163) (xy 240.262791 -215.370712) (xy 240.312391 -215.345211)
			(xy 240.365175 -215.327204) (xy 240.420018 -215.317074) (xy 240.475752 -215.315037) (xy 240.531189 -215.321137)
			(xy 240.585146 -215.335243) (xy 240.636475 -215.357055) (xy 240.684081 -215.386109) (xy 240.726949 -215.421784)
			(xy 240.764166 -215.463321) (xy 240.794939 -215.509834) (xy 240.818611 -215.560331) (xy 240.834679 -215.613738)
			(xy 240.842799 -215.668914) (xy 240.843308 -215.6968) (xy 240.842799 -215.724686) (xy 240.834679 -215.779862)
			(xy 240.818611 -215.833269) (xy 240.794939 -215.883766) (xy 240.764166 -215.930279) (xy 240.726949 -215.971816)
			(xy 240.684081 -216.007491) (xy 240.636475 -216.036545) (xy 240.585146 -216.058357) (xy 240.531189 -216.072463)
			(xy 240.475752 -216.078563) (xy 240.420018 -216.076526) (xy 240.365175 -216.066396) (xy 240.312391 -216.048389)
			(xy 240.262791 -216.022888) (xy 240.217433 -215.990437) (xy 240.177284 -215.951728) (xy 240.143198 -215.907585)
			(xy 240.115902 -215.85895) (xy 240.095979 -215.806859) (xy 240.083853 -215.752422) (xy 240.079782 -215.6968)
			(xy 233.762297 -215.6968) (xy 233.73889 -215.729879) (xy 233.701075 -215.768883) (xy 233.657721 -215.80162)
			(xy 233.634026 -215.81491) (xy 233.62215 -215.821756) (xy 233.602328 -215.840677) (xy 233.588261 -215.864193)
			(xy 233.580965 -215.890607) (xy 233.580967 -215.91801) (xy 233.588268 -215.944422) (xy 233.602339 -215.967937)
			(xy 233.622164 -215.986854) (xy 233.634026 -215.993726) (xy 233.657711 -216.007034) (xy 233.70107 -216.039763)
			(xy 233.738888 -216.078762) (xy 233.77027 -216.123106) (xy 233.794471 -216.171742) (xy 233.810917 -216.223518)
			(xy 233.819218 -216.277205) (xy 233.8197 -216.304368) (xy 233.819215 -216.330355) (xy 233.937304 -216.330355)
			(xy 233.937304 -216.278381) (xy 233.945434 -216.227046) (xy 233.961495 -216.177616) (xy 233.985091 -216.131306)
			(xy 234.015641 -216.089258) (xy 234.052392 -216.052507) (xy 234.09444 -216.021957) (xy 234.14075 -215.998361)
			(xy 234.19018 -215.9823) (xy 234.241515 -215.97417) (xy 234.293489 -215.97417) (xy 234.344824 -215.9823)
			(xy 234.394254 -215.998361) (xy 234.440564 -216.021957) (xy 234.482612 -216.052507) (xy 234.519363 -216.089258)
			(xy 234.549913 -216.131306) (xy 234.573509 -216.177616) (xy 234.58957 -216.227046) (xy 234.5977 -216.278381)
			(xy 234.59821 -216.304368) (xy 234.5977 -216.330355) (xy 234.73715 -216.330355) (xy 234.73715 -216.278381)
			(xy 234.74528 -216.227046) (xy 234.761341 -216.177616) (xy 234.784937 -216.131306) (xy 234.815487 -216.089258)
			(xy 234.852238 -216.052507) (xy 234.894286 -216.021957) (xy 234.940596 -215.998361) (xy 234.990026 -215.9823)
			(xy 235.041361 -215.97417) (xy 235.093335 -215.97417) (xy 235.14467 -215.9823) (xy 235.1941 -215.998361)
			(xy 235.24041 -216.021957) (xy 235.282458 -216.052507) (xy 235.319209 -216.089258) (xy 235.349759 -216.131306)
			(xy 235.373355 -216.177616) (xy 235.389416 -216.227046) (xy 235.397546 -216.278381) (xy 235.398056 -216.304368)
			(xy 235.397546 -216.330355) (xy 235.389416 -216.38169) (xy 235.373355 -216.43112) (xy 235.349759 -216.47743)
			(xy 235.319209 -216.519478) (xy 235.282458 -216.556229) (xy 235.24041 -216.586779) (xy 235.1941 -216.610375)
			(xy 235.14467 -216.626436) (xy 235.093335 -216.634566) (xy 235.041361 -216.634566) (xy 234.990026 -216.626436)
			(xy 234.940596 -216.610375) (xy 234.894286 -216.586779) (xy 234.852238 -216.556229) (xy 234.815487 -216.519478)
			(xy 234.784937 -216.47743) (xy 234.761341 -216.43112) (xy 234.74528 -216.38169) (xy 234.73715 -216.330355)
			(xy 234.5977 -216.330355) (xy 234.58957 -216.38169) (xy 234.573509 -216.43112) (xy 234.549913 -216.47743)
			(xy 234.519363 -216.519478) (xy 234.482612 -216.556229) (xy 234.440564 -216.586779) (xy 234.394254 -216.610375)
			(xy 234.344824 -216.626436) (xy 234.293489 -216.634566) (xy 234.241515 -216.634566) (xy 234.19018 -216.626436)
			(xy 234.14075 -216.610375) (xy 234.09444 -216.586779) (xy 234.052392 -216.556229) (xy 234.015641 -216.519478)
			(xy 233.985091 -216.47743) (xy 233.961495 -216.43112) (xy 233.945434 -216.38169) (xy 233.937304 -216.330355)
			(xy 233.819215 -216.330355) (xy 233.819208 -216.330732) (xy 233.811349 -216.382872) (xy 233.795807 -216.433257)
			(xy 233.772929 -216.480764) (xy 233.743226 -216.52433) (xy 233.707362 -216.562983) (xy 233.666137 -216.595858)
			(xy 233.620473 -216.622223) (xy 233.571389 -216.641486) (xy 233.519983 -216.65322) (xy 233.467402 -216.65716)
			(xy 233.414821 -216.65322) (xy 233.363415 -216.641486) (xy 233.314331 -216.622223) (xy 233.268667 -216.595858)
			(xy 233.227442 -216.562983) (xy 233.191578 -216.52433) (xy 233.161875 -216.480764) (xy 233.138997 -216.433257)
			(xy 233.123455 -216.382872) (xy 233.115596 -216.330732) (xy 233.115104 -216.304368) (xy 232.998264 -216.304368)
			(xy 232.997754 -216.330355) (xy 232.989624 -216.38169) (xy 232.973563 -216.43112) (xy 232.949967 -216.47743)
			(xy 232.919417 -216.519478) (xy 232.882666 -216.556229) (xy 232.840618 -216.586779) (xy 232.794308 -216.610375)
			(xy 232.744878 -216.626436) (xy 232.693543 -216.634566) (xy 232.641569 -216.634566) (xy 232.590234 -216.626436)
			(xy 232.540804 -216.610375) (xy 232.494494 -216.586779) (xy 232.452446 -216.556229) (xy 232.415695 -216.519478)
			(xy 232.385145 -216.47743) (xy 232.361549 -216.43112) (xy 232.345488 -216.38169) (xy 232.337358 -216.330355)
			(xy 232.197654 -216.330355) (xy 232.189524 -216.38169) (xy 232.173463 -216.43112) (xy 232.149867 -216.47743)
			(xy 232.119317 -216.519478) (xy 232.082566 -216.556229) (xy 232.040518 -216.586779) (xy 231.994208 -216.610375)
			(xy 231.944778 -216.626436) (xy 231.893443 -216.634566) (xy 231.841469 -216.634566) (xy 231.790134 -216.626436)
			(xy 231.740704 -216.610375) (xy 231.694394 -216.586779) (xy 231.652346 -216.556229) (xy 231.615595 -216.519478)
			(xy 231.585045 -216.47743) (xy 231.561449 -216.43112) (xy 231.545388 -216.38169) (xy 231.537258 -216.330355)
			(xy 231.397554 -216.330355) (xy 231.389424 -216.38169) (xy 231.373363 -216.43112) (xy 231.349767 -216.47743)
			(xy 231.319217 -216.519478) (xy 231.282466 -216.556229) (xy 231.240418 -216.586779) (xy 231.194108 -216.610375)
			(xy 231.144678 -216.626436) (xy 231.093343 -216.634566) (xy 231.041369 -216.634566) (xy 230.990034 -216.626436)
			(xy 230.940604 -216.610375) (xy 230.894294 -216.586779) (xy 230.852246 -216.556229) (xy 230.815495 -216.519478)
			(xy 230.784945 -216.47743) (xy 230.761349 -216.43112) (xy 230.745288 -216.38169) (xy 230.737158 -216.330355)
			(xy 227.397776 -216.330355) (xy 227.389686 -216.381436) (xy 227.373625 -216.430866) (xy 227.350029 -216.477176)
			(xy 227.319479 -216.519224) (xy 227.282728 -216.555975) (xy 227.24068 -216.586525) (xy 227.19437 -216.610121)
			(xy 227.14494 -216.626182) (xy 227.093605 -216.634312) (xy 227.041631 -216.634312) (xy 226.990296 -216.626182)
			(xy 226.940866 -216.610121) (xy 226.894556 -216.586525) (xy 226.852508 -216.555975) (xy 226.815757 -216.519224)
			(xy 226.785207 -216.477176) (xy 226.761611 -216.430866) (xy 226.74555 -216.381436) (xy 226.73742 -216.330101)
			(xy 226.597975 -216.330101) (xy 226.59797 -216.330355) (xy 226.58984 -216.38169) (xy 226.573779 -216.43112)
			(xy 226.550183 -216.47743) (xy 226.519633 -216.519478) (xy 226.482882 -216.556229) (xy 226.440834 -216.586779)
			(xy 226.394524 -216.610375) (xy 226.345094 -216.626436) (xy 226.293759 -216.634566) (xy 226.241785 -216.634566)
			(xy 226.19045 -216.626436) (xy 226.14102 -216.610375) (xy 226.09471 -216.586779) (xy 226.052662 -216.556229)
			(xy 226.015911 -216.519478) (xy 225.985361 -216.47743) (xy 225.961765 -216.43112) (xy 225.945704 -216.38169)
			(xy 225.937574 -216.330355) (xy 225.798124 -216.330355) (xy 225.789994 -216.38169) (xy 225.773933 -216.43112)
			(xy 225.750337 -216.47743) (xy 225.719787 -216.519478) (xy 225.683036 -216.556229) (xy 225.640988 -216.586779)
			(xy 225.594678 -216.610375) (xy 225.545248 -216.626436) (xy 225.493913 -216.634566) (xy 225.441939 -216.634566)
			(xy 225.390604 -216.626436) (xy 225.341174 -216.610375) (xy 225.294864 -216.586779) (xy 225.252816 -216.556229)
			(xy 225.216065 -216.519478) (xy 225.185515 -216.47743) (xy 225.161919 -216.43112) (xy 225.145858 -216.38169)
			(xy 225.137728 -216.330355) (xy 224.998024 -216.330355) (xy 224.989894 -216.38169) (xy 224.973833 -216.43112)
			(xy 224.950237 -216.47743) (xy 224.919687 -216.519478) (xy 224.882936 -216.556229) (xy 224.840888 -216.586779)
			(xy 224.794578 -216.610375) (xy 224.745148 -216.626436) (xy 224.693813 -216.634566) (xy 224.641839 -216.634566)
			(xy 224.590504 -216.626436) (xy 224.541074 -216.610375) (xy 224.494764 -216.586779) (xy 224.452716 -216.556229)
			(xy 224.415965 -216.519478) (xy 224.385415 -216.47743) (xy 224.361819 -216.43112) (xy 224.345758 -216.38169)
			(xy 224.337628 -216.330355) (xy 224.198178 -216.330355) (xy 224.190048 -216.38169) (xy 224.173987 -216.43112)
			(xy 224.150391 -216.47743) (xy 224.119841 -216.519478) (xy 224.08309 -216.556229) (xy 224.041042 -216.586779)
			(xy 223.994732 -216.610375) (xy 223.945302 -216.626436) (xy 223.893967 -216.634566) (xy 223.841993 -216.634566)
			(xy 223.790658 -216.626436) (xy 223.741228 -216.610375) (xy 223.694918 -216.586779) (xy 223.65287 -216.556229)
			(xy 223.616119 -216.519478) (xy 223.585569 -216.47743) (xy 223.561973 -216.43112) (xy 223.545912 -216.38169)
			(xy 223.537782 -216.330355) (xy 223.398078 -216.330355) (xy 223.389948 -216.38169) (xy 223.373887 -216.43112)
			(xy 223.350291 -216.47743) (xy 223.319741 -216.519478) (xy 223.28299 -216.556229) (xy 223.240942 -216.586779)
			(xy 223.194632 -216.610375) (xy 223.145202 -216.626436) (xy 223.093867 -216.634566) (xy 223.041893 -216.634566)
			(xy 222.990558 -216.626436) (xy 222.941128 -216.610375) (xy 222.894818 -216.586779) (xy 222.85277 -216.556229)
			(xy 222.816019 -216.519478) (xy 222.785469 -216.47743) (xy 222.761873 -216.43112) (xy 222.745812 -216.38169)
			(xy 222.737682 -216.330355) (xy 216.577035 -216.330355) (xy 216.573953 -216.351791) (xy 216.5586 -216.404081)
			(xy 216.535962 -216.453654) (xy 216.5065 -216.499501) (xy 216.470814 -216.540689) (xy 216.42963 -216.576379)
			(xy 216.383786 -216.605845) (xy 216.334215 -216.628487) (xy 216.281926 -216.643845) (xy 216.227985 -216.651605)
			(xy 216.200736 -216.652094) (xy 216.174419 -216.651665) (xy 216.122284 -216.64444) (xy 216.071635 -216.630123)
			(xy 216.023433 -216.608984) (xy 215.978592 -216.581424) (xy 215.937961 -216.547966) (xy 215.919812 -216.528904)
			(xy 215.912287 -216.521506) (xy 215.89301 -216.51298) (xy 215.882474 -216.512394) (xy 215.807798 -216.512394)
			(xy 215.797247 -216.51291) (xy 215.777952 -216.521455) (xy 215.77046 -216.528904) (xy 215.752346 -216.548004)
			(xy 215.711721 -216.58148) (xy 215.666876 -216.609047) (xy 215.618664 -216.630182) (xy 215.568004 -216.644483)
			(xy 215.515857 -216.651676) (xy 215.489536 -216.652094) (xy 215.46228 -216.651662) (xy 215.408324 -216.643908)
			(xy 215.356019 -216.628555) (xy 215.306433 -216.605914) (xy 215.260574 -216.576446) (xy 215.219375 -216.540751)
			(xy 215.183676 -216.499555) (xy 215.154204 -216.453699) (xy 215.131558 -216.404114) (xy 215.116199 -216.351812)
			(xy 215.108441 -216.297856) (xy 213.089246 -216.297856) (xy 213.089235 -216.298472) (xy 213.081115 -216.353648)
			(xy 213.065047 -216.407055) (xy 213.041375 -216.457552) (xy 213.010602 -216.504065) (xy 212.973385 -216.545602)
			(xy 212.930517 -216.581277) (xy 212.882911 -216.610331) (xy 212.831582 -216.632143) (xy 212.777625 -216.646249)
			(xy 212.722188 -216.652349) (xy 212.666454 -216.650312) (xy 212.611611 -216.640182) (xy 212.558827 -216.622175)
			(xy 212.509227 -216.596674) (xy 212.463869 -216.564223) (xy 212.42372 -216.525514) (xy 212.389634 -216.481371)
			(xy 212.362338 -216.432736) (xy 212.342415 -216.380645) (xy 212.330289 -216.326208) (xy 212.326218 -216.270586)
			(xy 210.922313 -216.270586) (xy 210.937587 -216.319108) (xy 210.942428 -216.345516) (xy 210.944206 -216.356946)
			(xy 210.957414 -216.375742) (xy 211.046568 -216.426034) (xy 211.069428 -216.427558) (xy 211.08035 -216.42324)
			(xy 211.102966 -216.414577) (xy 211.149832 -216.402368) (xy 211.197867 -216.3962) (xy 211.222082 -216.395808)
			(xy 211.249335 -216.396272) (xy 211.303287 -216.404027) (xy 211.355586 -216.419382) (xy 211.405167 -216.442023)
			(xy 211.451021 -216.471491) (xy 211.492214 -216.507185) (xy 211.527908 -216.548378) (xy 211.557376 -216.594231)
			(xy 211.580018 -216.643812) (xy 211.595373 -216.696111) (xy 211.603128 -216.750063) (xy 211.60359 -216.777316)
			(xy 211.603526 -216.787879) (xy 211.602383 -216.808973) (xy 211.601304 -216.81948) (xy 211.600034 -216.82964)
			(xy 211.60613 -216.849452) (xy 211.66582 -216.921588) (xy 211.684108 -216.930986) (xy 211.694522 -216.931748)
			(xy 211.722899 -216.934511) (xy 211.778452 -216.94733) (xy 211.831478 -216.968272) (xy 211.880799 -216.996871)
			(xy 211.925315 -217.03249) (xy 211.964035 -217.074337) (xy 211.996099 -217.121478) (xy 212.020791 -217.172866)
			(xy 212.037562 -217.227355) (xy 212.046039 -217.283734) (xy 212.046092 -217.286586) (xy 214.587326 -217.286586)
			(xy 214.591397 -217.230964) (xy 214.603523 -217.176527) (xy 214.623446 -217.124436) (xy 214.650742 -217.075801)
			(xy 214.684828 -217.031658) (xy 214.724977 -216.992949) (xy 214.770335 -216.960498) (xy 214.819935 -216.934997)
			(xy 214.872719 -216.91699) (xy 214.927562 -216.90686) (xy 214.983296 -216.904823) (xy 215.038733 -216.910923)
			(xy 215.09269 -216.925029) (xy 215.144019 -216.946841) (xy 215.191625 -216.975895) (xy 215.234493 -217.01157)
			(xy 215.27171 -217.053107) (xy 215.302483 -217.09962) (xy 215.326155 -217.150117) (xy 215.342223 -217.203524)
			(xy 215.344952 -217.22207) (xy 215.812876 -217.22207) (xy 215.816947 -217.166448) (xy 215.829073 -217.112011)
			(xy 215.848996 -217.05992) (xy 215.876292 -217.011285) (xy 215.910378 -216.967142) (xy 215.950527 -216.928433)
			(xy 215.995885 -216.895982) (xy 216.045485 -216.870481) (xy 216.098269 -216.852474) (xy 216.153112 -216.842344)
			(xy 216.208846 -216.840307) (xy 216.264283 -216.846407) (xy 216.31824 -216.860513) (xy 216.369569 -216.882325)
			(xy 216.417175 -216.911379) (xy 216.460043 -216.947054) (xy 216.49726 -216.988591) (xy 216.528033 -217.035104)
			(xy 216.551705 -217.085601) (xy 216.5652 -217.130455) (xy 224.337628 -217.130455) (xy 224.337628 -217.078481)
			(xy 224.345758 -217.027146) (xy 224.361819 -216.977716) (xy 224.385415 -216.931406) (xy 224.415965 -216.889358)
			(xy 224.452716 -216.852607) (xy 224.494764 -216.822057) (xy 224.541074 -216.798461) (xy 224.590504 -216.7824)
			(xy 224.641839 -216.77427) (xy 224.693813 -216.77427) (xy 224.745148 -216.7824) (xy 224.794578 -216.798461)
			(xy 224.840888 -216.822057) (xy 224.882936 -216.852607) (xy 224.919687 -216.889358) (xy 224.950237 -216.931406)
			(xy 224.973833 -216.977716) (xy 224.989894 -217.027146) (xy 224.998024 -217.078481) (xy 224.998534 -217.104468)
			(xy 224.998024 -217.130455) (xy 225.137728 -217.130455) (xy 225.137728 -217.078481) (xy 225.145858 -217.027146)
			(xy 225.161919 -216.977716) (xy 225.185515 -216.931406) (xy 225.216065 -216.889358) (xy 225.252816 -216.852607)
			(xy 225.294864 -216.822057) (xy 225.341174 -216.798461) (xy 225.390604 -216.7824) (xy 225.441939 -216.77427)
			(xy 225.493913 -216.77427) (xy 225.545248 -216.7824) (xy 225.594678 -216.798461) (xy 225.640988 -216.822057)
			(xy 225.683036 -216.852607) (xy 225.719787 -216.889358) (xy 225.750337 -216.931406) (xy 225.773933 -216.977716)
			(xy 225.789994 -217.027146) (xy 225.798124 -217.078481) (xy 225.798634 -217.104468) (xy 225.798124 -217.130455)
			(xy 225.937574 -217.130455) (xy 225.937574 -217.078481) (xy 225.945704 -217.027146) (xy 225.961765 -216.977716)
			(xy 225.985361 -216.931406) (xy 226.015911 -216.889358) (xy 226.052662 -216.852607) (xy 226.09471 -216.822057)
			(xy 226.14102 -216.798461) (xy 226.19045 -216.7824) (xy 226.241785 -216.77427) (xy 226.293759 -216.77427)
			(xy 226.345094 -216.7824) (xy 226.394524 -216.798461) (xy 226.440834 -216.822057) (xy 226.482882 -216.852607)
			(xy 226.519633 -216.889358) (xy 226.550183 -216.931406) (xy 226.573779 -216.977716) (xy 226.58984 -217.027146)
			(xy 226.59797 -217.078481) (xy 226.59848 -217.104468) (xy 226.59797 -217.130455) (xy 226.737674 -217.130455)
			(xy 226.737674 -217.078481) (xy 226.745804 -217.027146) (xy 226.761865 -216.977716) (xy 226.785461 -216.931406)
			(xy 226.816011 -216.889358) (xy 226.852762 -216.852607) (xy 226.89481 -216.822057) (xy 226.94112 -216.798461)
			(xy 226.99055 -216.7824) (xy 227.041885 -216.77427) (xy 227.093859 -216.77427) (xy 227.145194 -216.7824)
			(xy 227.194624 -216.798461) (xy 227.240934 -216.822057) (xy 227.282982 -216.852607) (xy 227.319733 -216.889358)
			(xy 227.350283 -216.931406) (xy 227.373879 -216.977716) (xy 227.38994 -217.027146) (xy 227.39807 -217.078481)
			(xy 227.39858 -217.104468) (xy 227.39807 -217.130455) (xy 227.537774 -217.130455) (xy 227.537774 -217.078481)
			(xy 227.545904 -217.027146) (xy 227.561965 -216.977716) (xy 227.585561 -216.931406) (xy 227.616111 -216.889358)
			(xy 227.652862 -216.852607) (xy 227.69491 -216.822057) (xy 227.74122 -216.798461) (xy 227.79065 -216.7824)
			(xy 227.841985 -216.77427) (xy 227.893959 -216.77427) (xy 227.945294 -216.7824) (xy 227.994724 -216.798461)
			(xy 228.041034 -216.822057) (xy 228.083082 -216.852607) (xy 228.119833 -216.889358) (xy 228.150383 -216.931406)
			(xy 228.173979 -216.977716) (xy 228.19004 -217.027146) (xy 228.19817 -217.078481) (xy 228.19868 -217.104468)
			(xy 228.19817 -217.130455) (xy 228.33762 -217.130455) (xy 228.33762 -217.078481) (xy 228.34575 -217.027146)
			(xy 228.361811 -216.977716) (xy 228.385407 -216.931406) (xy 228.415957 -216.889358) (xy 228.452708 -216.852607)
			(xy 228.494756 -216.822057) (xy 228.541066 -216.798461) (xy 228.590496 -216.7824) (xy 228.641831 -216.77427)
			(xy 228.693805 -216.77427) (xy 228.74514 -216.7824) (xy 228.79457 -216.798461) (xy 228.84088 -216.822057)
			(xy 228.882928 -216.852607) (xy 228.919679 -216.889358) (xy 228.950229 -216.931406) (xy 228.973825 -216.977716)
			(xy 228.989886 -217.027146) (xy 228.998016 -217.078481) (xy 228.998526 -217.104468) (xy 228.998016 -217.130455)
			(xy 229.937312 -217.130455) (xy 229.937312 -217.078481) (xy 229.945442 -217.027146) (xy 229.961503 -216.977716)
			(xy 229.985099 -216.931406) (xy 230.015649 -216.889358) (xy 230.0524 -216.852607) (xy 230.094448 -216.822057)
			(xy 230.140758 -216.798461) (xy 230.190188 -216.7824) (xy 230.241523 -216.77427) (xy 230.293497 -216.77427)
			(xy 230.344832 -216.7824) (xy 230.394262 -216.798461) (xy 230.440572 -216.822057) (xy 230.48262 -216.852607)
			(xy 230.519371 -216.889358) (xy 230.549921 -216.931406) (xy 230.573517 -216.977716) (xy 230.589578 -217.027146)
			(xy 230.597708 -217.078481) (xy 230.598218 -217.104468) (xy 230.597708 -217.130455) (xy 230.737158 -217.130455)
			(xy 230.737158 -217.078481) (xy 230.745288 -217.027146) (xy 230.761349 -216.977716) (xy 230.784945 -216.931406)
			(xy 230.815495 -216.889358) (xy 230.852246 -216.852607) (xy 230.894294 -216.822057) (xy 230.940604 -216.798461)
			(xy 230.990034 -216.7824) (xy 231.041369 -216.77427) (xy 231.093343 -216.77427) (xy 231.144678 -216.7824)
			(xy 231.194108 -216.798461) (xy 231.240418 -216.822057) (xy 231.282466 -216.852607) (xy 231.319217 -216.889358)
			(xy 231.349767 -216.931406) (xy 231.373363 -216.977716) (xy 231.389424 -217.027146) (xy 231.397554 -217.078481)
			(xy 231.398064 -217.104468) (xy 231.397554 -217.130455) (xy 231.537258 -217.130455) (xy 231.537258 -217.078481)
			(xy 231.545388 -217.027146) (xy 231.561449 -216.977716) (xy 231.585045 -216.931406) (xy 231.615595 -216.889358)
			(xy 231.652346 -216.852607) (xy 231.694394 -216.822057) (xy 231.740704 -216.798461) (xy 231.790134 -216.7824)
			(xy 231.841469 -216.77427) (xy 231.893443 -216.77427) (xy 231.944778 -216.7824) (xy 231.994208 -216.798461)
			(xy 232.040518 -216.822057) (xy 232.082566 -216.852607) (xy 232.119317 -216.889358) (xy 232.149867 -216.931406)
			(xy 232.173463 -216.977716) (xy 232.189524 -217.027146) (xy 232.197654 -217.078481) (xy 232.198164 -217.104468)
			(xy 232.197654 -217.130455) (xy 233.137204 -217.130455) (xy 233.137204 -217.078481) (xy 233.145334 -217.027146)
			(xy 233.161395 -216.977716) (xy 233.184991 -216.931406) (xy 233.215541 -216.889358) (xy 233.252292 -216.852607)
			(xy 233.29434 -216.822057) (xy 233.34065 -216.798461) (xy 233.39008 -216.7824) (xy 233.441415 -216.77427)
			(xy 233.493389 -216.77427) (xy 233.544724 -216.7824) (xy 233.594154 -216.798461) (xy 233.640464 -216.822057)
			(xy 233.682512 -216.852607) (xy 233.719263 -216.889358) (xy 233.749813 -216.931406) (xy 233.773409 -216.977716)
			(xy 233.78947 -217.027146) (xy 233.7976 -217.078481) (xy 233.79811 -217.104468) (xy 233.7976 -217.130455)
			(xy 233.937304 -217.130455) (xy 233.937304 -217.078481) (xy 233.945434 -217.027146) (xy 233.961495 -216.977716)
			(xy 233.985091 -216.931406) (xy 234.015641 -216.889358) (xy 234.052392 -216.852607) (xy 234.09444 -216.822057)
			(xy 234.14075 -216.798461) (xy 234.19018 -216.7824) (xy 234.241515 -216.77427) (xy 234.293489 -216.77427)
			(xy 234.344824 -216.7824) (xy 234.394254 -216.798461) (xy 234.440564 -216.822057) (xy 234.482612 -216.852607)
			(xy 234.519363 -216.889358) (xy 234.549913 -216.931406) (xy 234.573509 -216.977716) (xy 234.58957 -217.027146)
			(xy 234.5977 -217.078481) (xy 234.59821 -217.104468) (xy 234.5977 -217.130455) (xy 234.594052 -217.15349)
			(xy 240.342672 -217.15349) (xy 240.346743 -217.097868) (xy 240.358869 -217.043431) (xy 240.378792 -216.99134)
			(xy 240.406088 -216.942705) (xy 240.440174 -216.898562) (xy 240.480323 -216.859853) (xy 240.525681 -216.827402)
			(xy 240.575281 -216.801901) (xy 240.628065 -216.783894) (xy 240.682908 -216.773764) (xy 240.738642 -216.771727)
			(xy 240.794079 -216.777827) (xy 240.848036 -216.791933) (xy 240.899365 -216.813745) (xy 240.946971 -216.842799)
			(xy 240.965648 -216.858342) (xy 246.074438 -216.858342) (xy 246.07496 -216.831169) (xy 246.082654 -216.77737)
			(xy 246.097907 -216.725209) (xy 246.120409 -216.67574) (xy 246.149705 -216.629967) (xy 246.185202 -216.588815)
			(xy 246.22618 -216.553118) (xy 246.271811 -216.5236) (xy 246.321169 -216.500858) (xy 246.373256 -216.485352)
			(xy 246.400066 -216.480898) (xy 246.411496 -216.47912) (xy 246.430292 -216.466674) (xy 246.482616 -216.379044)
			(xy 246.484648 -216.356692) (xy 246.480584 -216.34577) (xy 246.469906 -216.314259) (xy 246.458418 -216.248732)
			(xy 246.457724 -216.215468) (xy 246.458148 -216.188215) (xy 246.46591 -216.134263) (xy 246.481271 -216.081965)
			(xy 246.503918 -216.032386) (xy 246.53339 -215.986534) (xy 246.569088 -215.945343) (xy 246.610285 -215.909652)
			(xy 246.656142 -215.880187) (xy 246.705725 -215.857548) (xy 246.758026 -215.842196) (xy 246.811978 -215.834444)
			(xy 246.839232 -215.83396) (xy 246.865423 -215.834405) (xy 246.917307 -215.841622) (xy 246.967717 -215.855862)
			(xy 246.991886 -215.865964) (xy 247.00484 -215.871552) (xy 247.033034 -215.867742) (xy 247.125236 -215.794082)
			(xy 247.135142 -215.767412) (xy 247.132348 -215.753696) (xy 247.129146 -215.735834) (xy 247.125708 -215.699706)
			(xy 247.12549 -215.68156) (xy 247.125941 -215.654308) (xy 247.133703 -215.600359) (xy 247.149063 -215.548064)
			(xy 247.171708 -215.498486) (xy 247.201179 -215.452636) (xy 247.236874 -215.411447) (xy 247.278067 -215.375756)
			(xy 247.32392 -215.34629) (xy 247.373499 -215.323649) (xy 247.425796 -215.308294) (xy 247.479746 -215.300538)
			(xy 247.506998 -215.300052) (xy 247.536169 -215.30063) (xy 247.593826 -215.309561) (xy 247.621806 -215.317832)
			(xy 247.634252 -215.321642) (xy 247.659144 -215.316816) (xy 247.744996 -215.246966) (xy 247.754902 -215.223598)
			(xy 247.753632 -215.210644) (xy 247.7516 -215.17229) (xy 247.752089 -215.14504) (xy 247.759847 -215.091094)
			(xy 247.775202 -215.038802) (xy 247.797844 -214.989227) (xy 247.82731 -214.943379) (xy 247.863001 -214.902191)
			(xy 247.90419 -214.866501) (xy 247.950039 -214.837037) (xy 247.999615 -214.814397) (xy 248.051908 -214.799044)
			(xy 248.105854 -214.791288) (xy 248.160354 -214.791289) (xy 248.2143 -214.799045) (xy 248.266593 -214.8144)
			(xy 248.316168 -214.837041) (xy 248.362016 -214.866506) (xy 248.403205 -214.902197) (xy 248.438895 -214.943385)
			(xy 248.46836 -214.989234) (xy 248.491001 -215.038809) (xy 248.506355 -215.091102) (xy 248.514112 -215.145048)
			(xy 248.514112 -215.199548) (xy 248.506356 -215.253494) (xy 248.491002 -215.305787) (xy 248.468362 -215.355362)
			(xy 248.438897 -215.401212) (xy 248.403208 -215.442401) (xy 248.36202 -215.478091) (xy 248.316171 -215.507557)
			(xy 248.266596 -215.530198) (xy 248.214304 -215.545554) (xy 248.160358 -215.553311) (xy 248.133108 -215.553798)
			(xy 248.103937 -215.553216) (xy 248.046281 -215.544287) (xy 248.0183 -215.536018) (xy 248.005854 -215.532208)
			(xy 247.980962 -215.537034) (xy 247.89511 -215.606884) (xy 247.885204 -215.630252) (xy 247.886474 -215.643206)
			(xy 247.888506 -215.68156) (xy 247.888007 -215.708812) (xy 247.880256 -215.762762) (xy 247.864905 -215.815059)
			(xy 247.842267 -215.864639) (xy 247.812803 -215.910493) (xy 247.777113 -215.951686) (xy 247.735923 -215.98738)
			(xy 247.690073 -216.016849) (xy 247.640495 -216.039492) (xy 247.588199 -216.054848) (xy 247.53425 -216.062605)
			(xy 247.506998 -216.063068) (xy 247.480807 -216.062611) (xy 247.428924 -216.055398) (xy 247.378513 -216.041164)
			(xy 247.354344 -216.031064) (xy 247.34139 -216.025476) (xy 247.313196 -216.029286) (xy 247.220994 -216.102946)
			(xy 247.211088 -216.129616) (xy 247.213882 -216.143332) (xy 247.217086 -216.161194) (xy 247.220523 -216.197322)
			(xy 247.22074 -216.215468) (xy 247.220246 -216.242642) (xy 247.21255 -216.296443) (xy 247.197295 -216.348606)
			(xy 247.17479 -216.398076) (xy 247.161447 -216.418922) (xy 251.19406 -216.418922) (xy 251.198131 -216.3633)
			(xy 251.210257 -216.308863) (xy 251.23018 -216.256772) (xy 251.257476 -216.208137) (xy 251.291562 -216.163994)
			(xy 251.331711 -216.125285) (xy 251.377069 -216.092834) (xy 251.426669 -216.067333) (xy 251.479453 -216.049326)
			(xy 251.534296 -216.039196) (xy 251.59003 -216.037159) (xy 251.645467 -216.043259) (xy 251.699424 -216.057365)
			(xy 251.750753 -216.079177) (xy 251.798359 -216.108231) (xy 251.841227 -216.143906) (xy 251.878444 -216.185443)
			(xy 251.909217 -216.231956) (xy 251.932889 -216.282453) (xy 251.948957 -216.33586) (xy 251.957077 -216.391036)
			(xy 251.957586 -216.418922) (xy 251.957077 -216.446808) (xy 251.948957 -216.501984) (xy 251.932889 -216.555391)
			(xy 251.909217 -216.605888) (xy 251.878444 -216.652401) (xy 251.841227 -216.693938) (xy 251.798359 -216.729613)
			(xy 251.750753 -216.758667) (xy 251.699424 -216.780479) (xy 251.645467 -216.794585) (xy 251.59003 -216.800685)
			(xy 251.534296 -216.798648) (xy 251.479453 -216.788518) (xy 251.426669 -216.770511) (xy 251.377069 -216.74501)
			(xy 251.331711 -216.712559) (xy 251.291562 -216.67385) (xy 251.257476 -216.629707) (xy 251.23018 -216.581072)
			(xy 251.210257 -216.528981) (xy 251.198131 -216.474544) (xy 251.19406 -216.418922) (xy 247.161447 -216.418922)
			(xy 247.145491 -216.44385) (xy 247.109991 -216.485002) (xy 247.069009 -216.520698) (xy 247.023375 -216.550215)
			(xy 246.974013 -216.572956) (xy 246.921923 -216.58846) (xy 246.895112 -216.592912) (xy 246.883682 -216.59469)
			(xy 246.864886 -216.607136) (xy 246.812562 -216.694766) (xy 246.81053 -216.717118) (xy 246.814594 -216.72804)
			(xy 246.825249 -216.759558) (xy 246.836752 -216.82508) (xy 246.837454 -216.858342) (xy 246.836968 -216.885593)
			(xy 246.829212 -216.939541) (xy 246.813857 -216.991836) (xy 246.791215 -217.041413) (xy 246.761749 -217.087263)
			(xy 246.737818 -217.114882) (xy 247.502932 -217.114882) (xy 247.507003 -217.05926) (xy 247.519129 -217.004823)
			(xy 247.539052 -216.952732) (xy 247.566348 -216.904097) (xy 247.600434 -216.859954) (xy 247.640583 -216.821245)
			(xy 247.685941 -216.788794) (xy 247.735541 -216.763293) (xy 247.788325 -216.745286) (xy 247.843168 -216.735156)
			(xy 247.898902 -216.733119) (xy 247.954339 -216.739219) (xy 248.008296 -216.753325) (xy 248.059625 -216.775137)
			(xy 248.107231 -216.804191) (xy 248.150099 -216.839866) (xy 248.187316 -216.881403) (xy 248.218089 -216.927916)
			(xy 248.241761 -216.978413) (xy 248.257829 -217.03182) (xy 248.265949 -217.086996) (xy 248.266458 -217.114882)
			(xy 248.265949 -217.142768) (xy 248.257829 -217.197944) (xy 248.241761 -217.251351) (xy 248.218089 -217.301848)
			(xy 248.187316 -217.348361) (xy 248.150099 -217.389898) (xy 248.107231 -217.425573) (xy 248.059625 -217.454627)
			(xy 248.008296 -217.476439) (xy 247.954339 -217.490545) (xy 247.898902 -217.496645) (xy 247.843168 -217.494608)
			(xy 247.788325 -217.484478) (xy 247.735541 -217.466471) (xy 247.685941 -217.44097) (xy 247.640583 -217.408519)
			(xy 247.600434 -217.36981) (xy 247.566348 -217.325667) (xy 247.539052 -217.277032) (xy 247.519129 -217.224941)
			(xy 247.507003 -217.170504) (xy 247.502932 -217.114882) (xy 246.737818 -217.114882) (xy 246.726058 -217.128454)
			(xy 246.684867 -217.164145) (xy 246.639017 -217.193611) (xy 246.58944 -217.216253) (xy 246.537145 -217.231608)
			(xy 246.483197 -217.239364) (xy 246.428695 -217.239364) (xy 246.374747 -217.231608) (xy 246.322452 -217.216253)
			(xy 246.272875 -217.193611) (xy 246.227025 -217.164145) (xy 246.185834 -217.128454) (xy 246.150143 -217.087263)
			(xy 246.120677 -217.041413) (xy 246.098035 -216.991836) (xy 246.08268 -216.939541) (xy 246.074924 -216.885593)
			(xy 246.074438 -216.858342) (xy 240.965648 -216.858342) (xy 240.989839 -216.878474) (xy 241.027056 -216.920011)
			(xy 241.057829 -216.966524) (xy 241.081501 -217.017021) (xy 241.097569 -217.070428) (xy 241.105689 -217.125604)
			(xy 241.106198 -217.15349) (xy 241.105689 -217.181376) (xy 241.097569 -217.236552) (xy 241.081501 -217.289959)
			(xy 241.057829 -217.340456) (xy 241.027056 -217.386969) (xy 240.989839 -217.428506) (xy 240.946971 -217.464181)
			(xy 240.899365 -217.493235) (xy 240.848036 -217.515047) (xy 240.794079 -217.529153) (xy 240.738642 -217.535253)
			(xy 240.682908 -217.533216) (xy 240.628065 -217.523086) (xy 240.575281 -217.505079) (xy 240.525681 -217.479578)
			(xy 240.480323 -217.447127) (xy 240.440174 -217.408418) (xy 240.406088 -217.364275) (xy 240.378792 -217.31564)
			(xy 240.358869 -217.263549) (xy 240.346743 -217.209112) (xy 240.342672 -217.15349) (xy 234.594052 -217.15349)
			(xy 234.58957 -217.18179) (xy 234.573509 -217.23122) (xy 234.549913 -217.27753) (xy 234.519363 -217.319578)
			(xy 234.482612 -217.356329) (xy 234.440564 -217.386879) (xy 234.394254 -217.410475) (xy 234.344824 -217.426536)
			(xy 234.293489 -217.434666) (xy 234.241515 -217.434666) (xy 234.19018 -217.426536) (xy 234.14075 -217.410475)
			(xy 234.09444 -217.386879) (xy 234.052392 -217.356329) (xy 234.015641 -217.319578) (xy 233.985091 -217.27753)
			(xy 233.961495 -217.23122) (xy 233.945434 -217.18179) (xy 233.937304 -217.130455) (xy 233.7976 -217.130455)
			(xy 233.78947 -217.18179) (xy 233.773409 -217.23122) (xy 233.749813 -217.27753) (xy 233.719263 -217.319578)
			(xy 233.682512 -217.356329) (xy 233.640464 -217.386879) (xy 233.594154 -217.410475) (xy 233.544724 -217.426536)
			(xy 233.493389 -217.434666) (xy 233.441415 -217.434666) (xy 233.39008 -217.426536) (xy 233.34065 -217.410475)
			(xy 233.29434 -217.386879) (xy 233.252292 -217.356329) (xy 233.215541 -217.319578) (xy 233.184991 -217.27753)
			(xy 233.161395 -217.23122) (xy 233.145334 -217.18179) (xy 233.137204 -217.130455) (xy 232.197654 -217.130455)
			(xy 232.189524 -217.18179) (xy 232.173463 -217.23122) (xy 232.149867 -217.27753) (xy 232.119317 -217.319578)
			(xy 232.082566 -217.356329) (xy 232.040518 -217.386879) (xy 231.994208 -217.410475) (xy 231.944778 -217.426536)
			(xy 231.893443 -217.434666) (xy 231.841469 -217.434666) (xy 231.790134 -217.426536) (xy 231.740704 -217.410475)
			(xy 231.694394 -217.386879) (xy 231.652346 -217.356329) (xy 231.615595 -217.319578) (xy 231.585045 -217.27753)
			(xy 231.561449 -217.23122) (xy 231.545388 -217.18179) (xy 231.537258 -217.130455) (xy 231.397554 -217.130455)
			(xy 231.389424 -217.18179) (xy 231.373363 -217.23122) (xy 231.349767 -217.27753) (xy 231.319217 -217.319578)
			(xy 231.282466 -217.356329) (xy 231.240418 -217.386879) (xy 231.194108 -217.410475) (xy 231.144678 -217.426536)
			(xy 231.093343 -217.434666) (xy 231.041369 -217.434666) (xy 230.990034 -217.426536) (xy 230.940604 -217.410475)
			(xy 230.894294 -217.386879) (xy 230.852246 -217.356329) (xy 230.815495 -217.319578) (xy 230.784945 -217.27753)
			(xy 230.761349 -217.23122) (xy 230.745288 -217.18179) (xy 230.737158 -217.130455) (xy 230.597708 -217.130455)
			(xy 230.589578 -217.18179) (xy 230.573517 -217.23122) (xy 230.549921 -217.27753) (xy 230.519371 -217.319578)
			(xy 230.48262 -217.356329) (xy 230.440572 -217.386879) (xy 230.394262 -217.410475) (xy 230.344832 -217.426536)
			(xy 230.293497 -217.434666) (xy 230.241523 -217.434666) (xy 230.190188 -217.426536) (xy 230.140758 -217.410475)
			(xy 230.094448 -217.386879) (xy 230.0524 -217.356329) (xy 230.015649 -217.319578) (xy 229.985099 -217.27753)
			(xy 229.961503 -217.23122) (xy 229.945442 -217.18179) (xy 229.937312 -217.130455) (xy 228.998016 -217.130455)
			(xy 228.989886 -217.18179) (xy 228.973825 -217.23122) (xy 228.950229 -217.27753) (xy 228.919679 -217.319578)
			(xy 228.882928 -217.356329) (xy 228.84088 -217.386879) (xy 228.79457 -217.410475) (xy 228.74514 -217.426536)
			(xy 228.693805 -217.434666) (xy 228.641831 -217.434666) (xy 228.590496 -217.426536) (xy 228.541066 -217.410475)
			(xy 228.494756 -217.386879) (xy 228.452708 -217.356329) (xy 228.415957 -217.319578) (xy 228.385407 -217.27753)
			(xy 228.361811 -217.23122) (xy 228.34575 -217.18179) (xy 228.33762 -217.130455) (xy 228.19817 -217.130455)
			(xy 228.19004 -217.18179) (xy 228.173979 -217.23122) (xy 228.150383 -217.27753) (xy 228.119833 -217.319578)
			(xy 228.083082 -217.356329) (xy 228.041034 -217.386879) (xy 227.994724 -217.410475) (xy 227.945294 -217.426536)
			(xy 227.893959 -217.434666) (xy 227.841985 -217.434666) (xy 227.79065 -217.426536) (xy 227.74122 -217.410475)
			(xy 227.69491 -217.386879) (xy 227.652862 -217.356329) (xy 227.616111 -217.319578) (xy 227.585561 -217.27753)
			(xy 227.561965 -217.23122) (xy 227.545904 -217.18179) (xy 227.537774 -217.130455) (xy 227.39807 -217.130455)
			(xy 227.38994 -217.18179) (xy 227.373879 -217.23122) (xy 227.350283 -217.27753) (xy 227.319733 -217.319578)
			(xy 227.282982 -217.356329) (xy 227.240934 -217.386879) (xy 227.194624 -217.410475) (xy 227.145194 -217.426536)
			(xy 227.093859 -217.434666) (xy 227.041885 -217.434666) (xy 226.99055 -217.426536) (xy 226.94112 -217.410475)
			(xy 226.89481 -217.386879) (xy 226.852762 -217.356329) (xy 226.816011 -217.319578) (xy 226.785461 -217.27753)
			(xy 226.761865 -217.23122) (xy 226.745804 -217.18179) (xy 226.737674 -217.130455) (xy 226.59797 -217.130455)
			(xy 226.58984 -217.18179) (xy 226.573779 -217.23122) (xy 226.550183 -217.27753) (xy 226.519633 -217.319578)
			(xy 226.482882 -217.356329) (xy 226.440834 -217.386879) (xy 226.394524 -217.410475) (xy 226.345094 -217.426536)
			(xy 226.293759 -217.434666) (xy 226.241785 -217.434666) (xy 226.19045 -217.426536) (xy 226.14102 -217.410475)
			(xy 226.09471 -217.386879) (xy 226.052662 -217.356329) (xy 226.015911 -217.319578) (xy 225.985361 -217.27753)
			(xy 225.961765 -217.23122) (xy 225.945704 -217.18179) (xy 225.937574 -217.130455) (xy 225.798124 -217.130455)
			(xy 225.789994 -217.18179) (xy 225.773933 -217.23122) (xy 225.750337 -217.27753) (xy 225.719787 -217.319578)
			(xy 225.683036 -217.356329) (xy 225.640988 -217.386879) (xy 225.594678 -217.410475) (xy 225.545248 -217.426536)
			(xy 225.493913 -217.434666) (xy 225.441939 -217.434666) (xy 225.390604 -217.426536) (xy 225.341174 -217.410475)
			(xy 225.294864 -217.386879) (xy 225.252816 -217.356329) (xy 225.216065 -217.319578) (xy 225.185515 -217.27753)
			(xy 225.161919 -217.23122) (xy 225.145858 -217.18179) (xy 225.137728 -217.130455) (xy 224.998024 -217.130455)
			(xy 224.989894 -217.18179) (xy 224.973833 -217.23122) (xy 224.950237 -217.27753) (xy 224.919687 -217.319578)
			(xy 224.882936 -217.356329) (xy 224.840888 -217.386879) (xy 224.794578 -217.410475) (xy 224.745148 -217.426536)
			(xy 224.693813 -217.434666) (xy 224.641839 -217.434666) (xy 224.590504 -217.426536) (xy 224.541074 -217.410475)
			(xy 224.494764 -217.386879) (xy 224.452716 -217.356329) (xy 224.415965 -217.319578) (xy 224.385415 -217.27753)
			(xy 224.361819 -217.23122) (xy 224.345758 -217.18179) (xy 224.337628 -217.130455) (xy 216.5652 -217.130455)
			(xy 216.567773 -217.139008) (xy 216.575893 -217.194184) (xy 216.576402 -217.22207) (xy 216.575893 -217.249956)
			(xy 216.567773 -217.305132) (xy 216.551705 -217.358539) (xy 216.528033 -217.409036) (xy 216.49726 -217.455549)
			(xy 216.460043 -217.497086) (xy 216.417175 -217.532761) (xy 216.369569 -217.561815) (xy 216.31824 -217.583627)
			(xy 216.264283 -217.597733) (xy 216.208846 -217.603833) (xy 216.153112 -217.601796) (xy 216.098269 -217.591666)
			(xy 216.045485 -217.573659) (xy 215.995885 -217.548158) (xy 215.950527 -217.515707) (xy 215.910378 -217.476998)
			(xy 215.876292 -217.432855) (xy 215.848996 -217.38422) (xy 215.829073 -217.332129) (xy 215.816947 -217.277692)
			(xy 215.812876 -217.22207) (xy 215.344952 -217.22207) (xy 215.350343 -217.2587) (xy 215.350852 -217.286586)
			(xy 215.350343 -217.314472) (xy 215.342223 -217.369648) (xy 215.326155 -217.423055) (xy 215.302483 -217.473552)
			(xy 215.27171 -217.520065) (xy 215.234493 -217.561602) (xy 215.191625 -217.597277) (xy 215.144019 -217.626331)
			(xy 215.09269 -217.648143) (xy 215.038733 -217.662249) (xy 214.983296 -217.668349) (xy 214.927562 -217.666312)
			(xy 214.872719 -217.656182) (xy 214.819935 -217.638175) (xy 214.770335 -217.612674) (xy 214.724977 -217.580223)
			(xy 214.684828 -217.541514) (xy 214.650742 -217.497371) (xy 214.623446 -217.448736) (xy 214.603523 -217.396645)
			(xy 214.591397 -217.342208) (xy 214.587326 -217.286586) (xy 212.046092 -217.286586) (xy 212.046566 -217.31224)
			(xy 212.04608 -217.339491) (xy 212.038324 -217.393439) (xy 212.022969 -217.445734) (xy 212.000327 -217.495311)
			(xy 211.970861 -217.541161) (xy 211.93517 -217.582352) (xy 211.893979 -217.618043) (xy 211.848129 -217.647509)
			(xy 211.798552 -217.670151) (xy 211.746257 -217.685506) (xy 211.692309 -217.693262) (xy 211.637807 -217.693262)
			(xy 211.583859 -217.685506) (xy 211.531564 -217.670151) (xy 211.481987 -217.647509) (xy 211.436137 -217.618043)
			(xy 211.394946 -217.582352) (xy 211.359255 -217.541161) (xy 211.329789 -217.495311) (xy 211.307147 -217.445734)
			(xy 211.291792 -217.393439) (xy 211.284036 -217.339491) (xy 211.28355 -217.31224) (xy 211.283611 -217.301677)
			(xy 211.284756 -217.280583) (xy 211.285836 -217.270076) (xy 211.287106 -217.259916) (xy 211.28101 -217.240104)
			(xy 211.22132 -217.167968) (xy 211.203032 -217.15857) (xy 211.192618 -217.157808) (xy 211.164549 -217.15516)
			(xy 211.109592 -217.142569) (xy 211.057086 -217.122031) (xy 211.008172 -217.093992) (xy 210.963915 -217.059064)
			(xy 210.925277 -217.018005) (xy 210.8931 -216.971709) (xy 210.868082 -216.921183) (xy 210.850769 -216.867527)
			(xy 210.845654 -216.8398) (xy 210.843876 -216.82837) (xy 210.830668 -216.809574) (xy 210.741514 -216.759282)
			(xy 210.718654 -216.757758) (xy 210.707732 -216.762076) (xy 210.685118 -216.770745) (xy 210.638251 -216.782952)
			(xy 210.590215 -216.789117) (xy 210.566 -216.789508) (xy 210.538749 -216.789022) (xy 210.484801 -216.781266)
			(xy 210.432506 -216.765911) (xy 210.382929 -216.743269) (xy 210.337079 -216.713803) (xy 210.295888 -216.678112)
			(xy 210.260197 -216.636921) (xy 210.230731 -216.591071) (xy 210.208089 -216.541494) (xy 210.192734 -216.489199)
			(xy 210.184978 -216.435251) (xy 209.382715 -216.435251) (xy 209.393543 -216.471242) (xy 209.401663 -216.526418)
			(xy 209.402172 -216.554304) (xy 209.401663 -216.58219) (xy 209.393543 -216.637366) (xy 209.377475 -216.690773)
			(xy 209.353803 -216.74127) (xy 209.32303 -216.787783) (xy 209.285813 -216.82932) (xy 209.242945 -216.864995)
			(xy 209.195339 -216.894049) (xy 209.14401 -216.915861) (xy 209.090053 -216.929967) (xy 209.034616 -216.936067)
			(xy 208.978882 -216.93403) (xy 208.924039 -216.9239) (xy 208.871255 -216.905893) (xy 208.821655 -216.880392)
			(xy 208.776297 -216.847941) (xy 208.736148 -216.809232) (xy 208.702062 -216.765089) (xy 208.674766 -216.716454)
			(xy 208.654843 -216.664363) (xy 208.642717 -216.609926) (xy 208.638646 -216.554304) (xy 207.444086 -216.554304)
			(xy 207.444086 -217.920824) (xy 208.797142 -217.920824) (xy 208.801213 -217.865202) (xy 208.813339 -217.810765)
			(xy 208.833262 -217.758674) (xy 208.860558 -217.710039) (xy 208.894644 -217.665896) (xy 208.934793 -217.627187)
			(xy 208.980151 -217.594736) (xy 209.029751 -217.569235) (xy 209.082535 -217.551228) (xy 209.137378 -217.541098)
			(xy 209.193112 -217.539061) (xy 209.248549 -217.545161) (xy 209.302506 -217.559267) (xy 209.353835 -217.581079)
			(xy 209.401441 -217.610133) (xy 209.444309 -217.645808) (xy 209.481526 -217.687345) (xy 209.512299 -217.733858)
			(xy 209.535971 -217.784355) (xy 209.552039 -217.837762) (xy 209.560159 -217.892938) (xy 209.560668 -217.920824)
			(xy 209.560159 -217.94871) (xy 209.552039 -218.003886) (xy 209.535971 -218.057293) (xy 209.512299 -218.10779)
			(xy 209.481526 -218.154303) (xy 209.444309 -218.19584) (xy 209.401441 -218.231515) (xy 209.353835 -218.260569)
			(xy 209.302506 -218.282381) (xy 209.27477 -218.289632) (xy 212.858602 -218.289632) (xy 212.862673 -218.23401)
			(xy 212.874799 -218.179573) (xy 212.894722 -218.127482) (xy 212.922018 -218.078847) (xy 212.956104 -218.034704)
			(xy 212.996253 -217.995995) (xy 213.041611 -217.963544) (xy 213.091211 -217.938043) (xy 213.143995 -217.920036)
			(xy 213.198838 -217.909906) (xy 213.254572 -217.907869) (xy 213.310009 -217.913969) (xy 213.363966 -217.928075)
			(xy 213.415295 -217.949887) (xy 213.462901 -217.978941) (xy 213.505769 -218.014616) (xy 213.542986 -218.056153)
			(xy 213.573759 -218.102666) (xy 213.597431 -218.153163) (xy 213.613499 -218.20657) (xy 213.621619 -218.261746)
			(xy 213.622128 -218.289632) (xy 213.622058 -218.293442) (xy 213.885778 -218.293442) (xy 213.889849 -218.23782)
			(xy 213.901975 -218.183383) (xy 213.921898 -218.131292) (xy 213.949194 -218.082657) (xy 213.98328 -218.038514)
			(xy 214.023429 -217.999805) (xy 214.068787 -217.967354) (xy 214.118387 -217.941853) (xy 214.171171 -217.923846)
			(xy 214.226014 -217.913716) (xy 214.281748 -217.911679) (xy 214.337185 -217.917779) (xy 214.391142 -217.931885)
			(xy 214.442471 -217.953697) (xy 214.490077 -217.982751) (xy 214.532945 -218.018426) (xy 214.570162 -218.059963)
			(xy 214.600935 -218.106476) (xy 214.624607 -218.156973) (xy 214.640675 -218.21038) (xy 214.648795 -218.265556)
			(xy 214.649304 -218.293442) (xy 214.648795 -218.321328) (xy 214.640675 -218.376504) (xy 214.624607 -218.429911)
			(xy 214.600935 -218.480408) (xy 214.570162 -218.526921) (xy 214.532945 -218.568458) (xy 214.490077 -218.604133)
			(xy 214.442471 -218.633187) (xy 214.391142 -218.654999) (xy 214.337185 -218.669105) (xy 214.281748 -218.675205)
			(xy 214.226014 -218.673168) (xy 214.171171 -218.663038) (xy 214.118387 -218.645031) (xy 214.068787 -218.61953)
			(xy 214.023429 -218.587079) (xy 213.98328 -218.54837) (xy 213.949194 -218.504227) (xy 213.921898 -218.455592)
			(xy 213.901975 -218.403501) (xy 213.889849 -218.349064) (xy 213.885778 -218.293442) (xy 213.622058 -218.293442)
			(xy 213.621619 -218.317518) (xy 213.613499 -218.372694) (xy 213.597431 -218.426101) (xy 213.573759 -218.476598)
			(xy 213.542986 -218.523111) (xy 213.505769 -218.564648) (xy 213.462901 -218.600323) (xy 213.415295 -218.629377)
			(xy 213.363966 -218.651189) (xy 213.310009 -218.665295) (xy 213.254572 -218.671395) (xy 213.198838 -218.669358)
			(xy 213.143995 -218.659228) (xy 213.091211 -218.641221) (xy 213.041611 -218.61572) (xy 212.996253 -218.583269)
			(xy 212.956104 -218.54456) (xy 212.922018 -218.500417) (xy 212.894722 -218.451782) (xy 212.874799 -218.399691)
			(xy 212.862673 -218.345254) (xy 212.858602 -218.289632) (xy 209.27477 -218.289632) (xy 209.248549 -218.296487)
			(xy 209.193112 -218.302587) (xy 209.137378 -218.30055) (xy 209.082535 -218.29042) (xy 209.029751 -218.272413)
			(xy 208.980151 -218.246912) (xy 208.934793 -218.214461) (xy 208.894644 -218.175752) (xy 208.860558 -218.131609)
			(xy 208.833262 -218.082974) (xy 208.813339 -218.030883) (xy 208.801213 -217.976446) (xy 208.797142 -217.920824)
			(xy 207.444086 -217.920824) (xy 207.444086 -219.356178) (xy 207.678018 -219.356178) (xy 207.682089 -219.300556)
			(xy 207.694215 -219.246119) (xy 207.714138 -219.194028) (xy 207.741434 -219.145393) (xy 207.77552 -219.10125)
			(xy 207.815669 -219.062541) (xy 207.861027 -219.03009) (xy 207.910627 -219.004589) (xy 207.963411 -218.986582)
			(xy 208.018254 -218.976452) (xy 208.073988 -218.974415) (xy 208.129425 -218.980515) (xy 208.183382 -218.994621)
			(xy 208.234711 -219.016433) (xy 208.282317 -219.045487) (xy 208.325185 -219.081162) (xy 208.362402 -219.122699)
			(xy 208.393175 -219.169212) (xy 208.416847 -219.219709) (xy 208.432915 -219.273116) (xy 208.4376 -219.30495)
			(xy 208.64527 -219.30495) (xy 208.64527 -219.25045) (xy 208.653025 -219.196506) (xy 208.668378 -219.144214)
			(xy 208.691016 -219.094639) (xy 208.720479 -219.04879) (xy 208.756166 -219.0076) (xy 208.797351 -218.971907)
			(xy 208.843196 -218.942439) (xy 208.892769 -218.919795) (xy 208.945059 -218.904435) (xy 208.999002 -218.896673)
			(xy 209.026252 -218.896184) (xy 209.055757 -218.896736) (xy 209.114063 -218.905836) (xy 209.170275 -218.923795)
			(xy 209.223055 -218.950187) (xy 209.271148 -218.984383) (xy 209.313409 -219.025569) (xy 209.33156 -219.048838)
			(xy 209.339688 -219.059506) (xy 209.363564 -219.070174) (xy 209.47634 -219.05976) (xy 209.49793 -219.045028)
			(xy 209.503772 -219.032836) (xy 209.515942 -219.009268) (xy 209.545838 -218.965454) (xy 209.581511 -218.926199)
			(xy 209.622273 -218.89226) (xy 209.667342 -218.864291) (xy 209.715848 -218.842828) (xy 209.766857 -218.828287)
			(xy 209.819389 -218.820946) (xy 209.84591 -218.820492) (xy 209.873161 -218.820968) (xy 209.92711 -218.828726)
			(xy 209.979404 -218.844083) (xy 210.028982 -218.866725) (xy 210.074832 -218.896192) (xy 210.116022 -218.931885)
			(xy 210.151714 -218.973076) (xy 210.18118 -219.018927) (xy 210.203821 -219.068505) (xy 210.219176 -219.1208)
			(xy 210.226932 -219.174748) (xy 210.227418 -219.202) (xy 210.22685 -219.231157) (xy 210.217988 -219.288795)
			(xy 210.200455 -219.344411) (xy 210.17466 -219.396711) (xy 210.141204 -219.444474) (xy 210.100868 -219.486588)
			(xy 210.078066 -219.504768) (xy 210.068414 -219.512134) (xy 210.058 -219.533724) (xy 210.058689 -219.581476)
			(xy 210.858098 -219.581476) (xy 210.862169 -219.525854) (xy 210.874295 -219.471417) (xy 210.894218 -219.419326)
			(xy 210.921514 -219.370691) (xy 210.9556 -219.326548) (xy 210.995749 -219.287839) (xy 211.041107 -219.255388)
			(xy 211.090707 -219.229887) (xy 211.143491 -219.21188) (xy 211.198334 -219.20175) (xy 211.254068 -219.199713)
			(xy 211.309505 -219.205813) (xy 211.363462 -219.219919) (xy 211.414791 -219.241731) (xy 211.462397 -219.270785)
			(xy 211.505265 -219.30646) (xy 211.542482 -219.347997) (xy 211.573255 -219.39451) (xy 211.596927 -219.445007)
			(xy 211.612995 -219.498414) (xy 211.621115 -219.55359) (xy 211.621624 -219.581476) (xy 211.621115 -219.609362)
			(xy 211.612995 -219.664538) (xy 211.596927 -219.717945) (xy 211.573255 -219.768442) (xy 211.542482 -219.814955)
			(xy 211.505265 -219.856492) (xy 211.462397 -219.892167) (xy 211.414791 -219.921221) (xy 211.363462 -219.943033)
			(xy 211.309505 -219.957139) (xy 211.254068 -219.963239) (xy 211.198334 -219.961202) (xy 211.143491 -219.951072)
			(xy 211.090707 -219.933065) (xy 211.041107 -219.907564) (xy 210.995749 -219.875113) (xy 210.9556 -219.836404)
			(xy 210.921514 -219.792261) (xy 210.894218 -219.743626) (xy 210.874295 -219.691535) (xy 210.862169 -219.637098)
			(xy 210.858098 -219.581476) (xy 210.058689 -219.581476) (xy 210.059524 -219.639388) (xy 210.070446 -219.660724)
			(xy 210.080352 -219.667836) (xy 210.101023 -219.683249) (xy 210.138384 -219.718787) (xy 210.170619 -219.759032)
			(xy 210.197142 -219.803251) (xy 210.217468 -219.850639) (xy 210.231227 -219.900333) (xy 210.23817 -219.951426)
			(xy 210.238594 -219.977208) (xy 210.238152 -220.004462) (xy 210.230394 -220.058414) (xy 210.215036 -220.110713)
			(xy 210.192391 -220.160294) (xy 210.162921 -220.206148) (xy 210.127225 -220.247341) (xy 210.08603 -220.283034)
			(xy 210.040175 -220.312502) (xy 209.990593 -220.335144) (xy 209.938293 -220.350498) (xy 209.88434 -220.358254)
			(xy 209.857086 -220.358716) (xy 209.828464 -220.358202) (xy 209.771862 -220.349665) (xy 209.717169 -220.332769)
			(xy 209.665614 -220.307894) (xy 209.641694 -220.292168) (xy 209.629756 -220.28404) (xy 209.601308 -220.282516)
			(xy 209.496406 -220.33992) (xy 209.482436 -220.364558) (xy 209.48269 -220.379036) (xy 209.482944 -220.389704)
			(xy 209.482944 -220.401896) (xy 209.493866 -220.423232) (xy 209.578702 -220.486224) (xy 209.602324 -220.490288)
			(xy 209.614008 -220.486732) (xy 209.64093 -220.479127) (xy 209.696273 -220.470967) (xy 209.724244 -220.470476)
			(xy 209.751492 -220.470997) (xy 209.805433 -220.478759) (xy 209.85772 -220.494117) (xy 209.907289 -220.516759)
			(xy 209.953132 -220.546226) (xy 209.994316 -220.581916) (xy 210.030001 -220.623103) (xy 210.059462 -220.668949)
			(xy 210.082099 -220.718521) (xy 210.097451 -220.77081) (xy 210.105206 -220.824752) (xy 210.105206 -220.879248)
			(xy 210.097451 -220.93319) (xy 210.082099 -220.985479) (xy 210.059462 -221.035051) (xy 210.030001 -221.080897)
			(xy 209.994316 -221.122084) (xy 209.953132 -221.157774) (xy 209.907289 -221.187241) (xy 209.85772 -221.209883)
			(xy 209.805433 -221.225241) (xy 209.751492 -221.233003) (xy 209.724244 -221.233492) (xy 209.693134 -221.232887)
			(xy 209.631738 -221.222806) (xy 209.60207 -221.213426) (xy 209.59191 -221.20987) (xy 209.571082 -221.211902)
			(xy 209.486754 -221.257622) (xy 209.4738 -221.274386) (xy 209.47126 -221.2848) (xy 209.463854 -221.311842)
			(xy 209.447657 -221.350586) (xy 212.316566 -221.350586) (xy 212.320637 -221.294964) (xy 212.332763 -221.240527)
			(xy 212.352686 -221.188436) (xy 212.379982 -221.139801) (xy 212.414068 -221.095658) (xy 212.454217 -221.056949)
			(xy 212.499575 -221.024498) (xy 212.549175 -220.998997) (xy 212.601959 -220.98099) (xy 212.656802 -220.97086)
			(xy 212.712536 -220.968823) (xy 212.767973 -220.974923) (xy 212.82193 -220.989029) (xy 212.873259 -221.010841)
			(xy 212.920865 -221.039895) (xy 212.963733 -221.07557) (xy 213.00095 -221.117107) (xy 213.031723 -221.16362)
			(xy 213.055395 -221.214117) (xy 213.071463 -221.267524) (xy 213.079583 -221.3227) (xy 213.080092 -221.350586)
			(xy 213.079583 -221.378472) (xy 213.071463 -221.433648) (xy 213.055395 -221.487055) (xy 213.031723 -221.537552)
			(xy 213.00095 -221.584065) (xy 212.963733 -221.625602) (xy 212.920865 -221.661277) (xy 212.873259 -221.690331)
			(xy 212.82193 -221.712143) (xy 212.767973 -221.726249) (xy 212.712536 -221.732349) (xy 212.656802 -221.730312)
			(xy 212.601959 -221.720182) (xy 212.549175 -221.702175) (xy 212.499575 -221.676674) (xy 212.454217 -221.644223)
			(xy 212.414068 -221.605514) (xy 212.379982 -221.561371) (xy 212.352686 -221.512736) (xy 212.332763 -221.460645)
			(xy 212.320637 -221.406208) (xy 212.316566 -221.350586) (xy 209.447657 -221.350586) (xy 209.442229 -221.363571)
			(xy 209.413268 -221.411578) (xy 209.377594 -221.454832) (xy 209.335976 -221.4924) (xy 209.289308 -221.523475)
			(xy 209.238597 -221.547387) (xy 209.184932 -221.563622) (xy 209.129469 -221.571831) (xy 209.101436 -221.572328)
			(xy 209.074185 -221.571811) (xy 209.020237 -221.56406) (xy 208.967941 -221.548709) (xy 208.918363 -221.526072)
			(xy 208.87251 -221.49661) (xy 208.831318 -221.460922) (xy 208.795624 -221.419735) (xy 208.766154 -221.373887)
			(xy 208.74351 -221.324311) (xy 208.728152 -221.272018) (xy 208.720393 -221.218071) (xy 208.719928 -221.19082)
			(xy 208.72038 -221.164216) (xy 208.727759 -221.111522) (xy 208.742392 -221.060366) (xy 208.763994 -221.011741)
			(xy 208.792145 -220.96659) (xy 208.8263 -220.925792) (xy 208.865794 -220.890136) (xy 208.887568 -220.874844)
			(xy 208.897418 -220.867253) (xy 208.909097 -220.845343) (xy 208.90992 -220.832934) (xy 208.90992 -220.748606)
			(xy 208.909272 -220.736153) (xy 208.897546 -220.714176) (xy 208.887568 -220.706696) (xy 208.865793 -220.691407)
			(xy 208.826313 -220.655741) (xy 208.792169 -220.614936) (xy 208.764024 -220.569786) (xy 208.742422 -220.521163)
			(xy 208.727783 -220.470011) (xy 208.72039 -220.417323) (xy 208.719928 -220.39072) (xy 208.720374 -220.363466)
			(xy 208.728129 -220.309513) (xy 208.743485 -220.257212) (xy 208.766127 -220.20763) (xy 208.795597 -220.161775)
			(xy 208.831292 -220.120581) (xy 208.872488 -220.084887) (xy 208.918344 -220.05542) (xy 208.967927 -220.032779)
			(xy 209.020228 -220.017426) (xy 209.074182 -220.009673) (xy 209.101436 -220.009212) (xy 209.130058 -220.00971)
			(xy 209.186662 -220.018251) (xy 209.241355 -220.035151) (xy 209.292909 -220.060032) (xy 209.316828 -220.07576)
			(xy 209.328766 -220.083888) (xy 209.357214 -220.085412) (xy 209.462116 -220.028008) (xy 209.476086 -220.00337)
			(xy 209.475832 -219.988892) (xy 209.475578 -219.977208) (xy 209.476154 -219.948051) (xy 209.485014 -219.890414)
			(xy 209.502546 -219.834798) (xy 209.528339 -219.782498) (xy 209.561793 -219.734735) (xy 209.602129 -219.692621)
			(xy 209.62493 -219.67444) (xy 209.634582 -219.667074) (xy 209.644996 -219.645484) (xy 209.643472 -219.53982)
			(xy 209.63255 -219.518484) (xy 209.622644 -219.511372) (xy 209.599532 -219.494073) (xy 209.558335 -219.453635)
			(xy 209.540602 -219.430854) (xy 209.532474 -219.420186) (xy 209.508598 -219.409518) (xy 209.395822 -219.419932)
			(xy 209.374232 -219.434664) (xy 209.36839 -219.446856) (xy 209.356169 -219.470396) (xy 209.32628 -219.51421)
			(xy 209.290615 -219.553465) (xy 209.24986 -219.587406) (xy 209.204799 -219.615379) (xy 209.1563 -219.636846)
			(xy 209.105297 -219.651393) (xy 209.052771 -219.658741) (xy 209.026252 -219.6592) (xy 208.999002 -219.658727)
			(xy 208.945059 -219.650965) (xy 208.892769 -219.635605) (xy 208.843196 -219.612961) (xy 208.797351 -219.583493)
			(xy 208.756166 -219.5478) (xy 208.720479 -219.50661) (xy 208.691016 -219.460761) (xy 208.668378 -219.411186)
			(xy 208.653025 -219.358894) (xy 208.64527 -219.30495) (xy 208.4376 -219.30495) (xy 208.441035 -219.328292)
			(xy 208.441544 -219.356178) (xy 208.441035 -219.384064) (xy 208.432915 -219.43924) (xy 208.416847 -219.492647)
			(xy 208.393175 -219.543144) (xy 208.362402 -219.589657) (xy 208.325185 -219.631194) (xy 208.282317 -219.666869)
			(xy 208.234711 -219.695923) (xy 208.183382 -219.717735) (xy 208.129425 -219.731841) (xy 208.073988 -219.737941)
			(xy 208.018254 -219.735904) (xy 207.963411 -219.725774) (xy 207.910627 -219.707767) (xy 207.861027 -219.682266)
			(xy 207.815669 -219.649815) (xy 207.77552 -219.611106) (xy 207.741434 -219.566963) (xy 207.714138 -219.518328)
			(xy 207.694215 -219.466237) (xy 207.682089 -219.4118) (xy 207.678018 -219.356178) (xy 207.444086 -219.356178)
			(xy 207.444086 -221.240604) (xy 207.444543 -221.250482) (xy 207.451981 -221.268786) (xy 207.458564 -221.276164)
			(xy 207.458818 -221.276418) (xy 208.205578 -222.023178) (xy 209.92795 -222.023178) (xy 209.932021 -221.967556)
			(xy 209.944147 -221.913119) (xy 209.96407 -221.861028) (xy 209.991366 -221.812393) (xy 210.025452 -221.76825)
			(xy 210.065601 -221.729541) (xy 210.110959 -221.69709) (xy 210.160559 -221.671589) (xy 210.213343 -221.653582)
			(xy 210.268186 -221.643452) (xy 210.32392 -221.641415) (xy 210.379357 -221.647515) (xy 210.433314 -221.661621)
			(xy 210.484643 -221.683433) (xy 210.532249 -221.712487) (xy 210.575117 -221.748162) (xy 210.612334 -221.789699)
			(xy 210.643107 -221.836212) (xy 210.665741 -221.884494) (xy 211.249258 -221.884494) (xy 211.253329 -221.828872)
			(xy 211.265455 -221.774435) (xy 211.285378 -221.722344) (xy 211.312674 -221.673709) (xy 211.34676 -221.629566)
			(xy 211.386909 -221.590857) (xy 211.432267 -221.558406) (xy 211.481867 -221.532905) (xy 211.534651 -221.514898)
			(xy 211.589494 -221.504768) (xy 211.645228 -221.502731) (xy 211.700665 -221.508831) (xy 211.754622 -221.522937)
			(xy 211.805951 -221.544749) (xy 211.853557 -221.573803) (xy 211.896425 -221.609478) (xy 211.933642 -221.651015)
			(xy 211.964415 -221.697528) (xy 211.988087 -221.748025) (xy 212.004155 -221.801432) (xy 212.012275 -221.856608)
			(xy 212.012784 -221.884494) (xy 212.012275 -221.91238) (xy 212.004155 -221.967556) (xy 211.988087 -222.020963)
			(xy 211.964415 -222.07146) (xy 211.933642 -222.117973) (xy 211.896425 -222.15951) (xy 211.853557 -222.195185)
			(xy 211.805951 -222.224239) (xy 211.754622 -222.246051) (xy 211.700665 -222.260157) (xy 211.645228 -222.266257)
			(xy 211.589494 -222.26422) (xy 211.534651 -222.25409) (xy 211.481867 -222.236083) (xy 211.432267 -222.210582)
			(xy 211.386909 -222.178131) (xy 211.34676 -222.139422) (xy 211.312674 -222.095279) (xy 211.285378 -222.046644)
			(xy 211.265455 -221.994553) (xy 211.253329 -221.940116) (xy 211.249258 -221.884494) (xy 210.665741 -221.884494)
			(xy 210.666779 -221.886709) (xy 210.682847 -221.940116) (xy 210.690967 -221.995292) (xy 210.691476 -222.023178)
			(xy 210.690967 -222.051064) (xy 210.682847 -222.10624) (xy 210.666779 -222.159647) (xy 210.643107 -222.210144)
			(xy 210.612334 -222.256657) (xy 210.575117 -222.298194) (xy 210.532249 -222.333869) (xy 210.484643 -222.362923)
			(xy 210.476023 -222.366586) (xy 213.037418 -222.366586) (xy 213.041489 -222.310964) (xy 213.053615 -222.256527)
			(xy 213.073538 -222.204436) (xy 213.100834 -222.155801) (xy 213.13492 -222.111658) (xy 213.175069 -222.072949)
			(xy 213.220427 -222.040498) (xy 213.270027 -222.014997) (xy 213.322811 -221.99699) (xy 213.377654 -221.98686)
			(xy 213.433388 -221.984823) (xy 213.488825 -221.990923) (xy 213.542782 -222.005029) (xy 213.594111 -222.026841)
			(xy 213.641717 -222.055895) (xy 213.684585 -222.09157) (xy 213.721802 -222.133107) (xy 213.752575 -222.17962)
			(xy 213.776247 -222.230117) (xy 213.792315 -222.283524) (xy 213.800435 -222.3387) (xy 213.800944 -222.366586)
			(xy 213.800446 -222.393856) (xy 215.108441 -222.393856) (xy 215.108441 -222.339344) (xy 215.116199 -222.285388)
			(xy 215.131558 -222.233086) (xy 215.154204 -222.183501) (xy 215.183676 -222.137645) (xy 215.219375 -222.096449)
			(xy 215.260574 -222.060754) (xy 215.306433 -222.031286) (xy 215.356019 -222.008645) (xy 215.408324 -221.993292)
			(xy 215.46228 -221.985538) (xy 215.489536 -221.985078) (xy 215.515852 -221.985534) (xy 215.567985 -221.992755)
			(xy 215.618633 -222.007068) (xy 215.666835 -222.028202) (xy 215.711677 -222.055756) (xy 215.75231 -222.089208)
			(xy 215.77046 -222.108268) (xy 215.777999 -222.115649) (xy 215.797266 -222.124187) (xy 215.807798 -222.124778)
			(xy 215.882474 -222.124778) (xy 215.893025 -222.124255) (xy 215.91232 -222.115716) (xy 215.919812 -222.108268)
			(xy 215.937954 -222.089196) (xy 215.978572 -222.055714) (xy 216.02341 -222.028141) (xy 216.071616 -222.007001)
			(xy 216.122273 -221.992696) (xy 216.174417 -221.985498) (xy 216.200736 -221.985078) (xy 216.227985 -221.985595)
			(xy 216.281926 -221.993355) (xy 216.334215 -222.008713) (xy 216.383786 -222.031355) (xy 216.42963 -222.060821)
			(xy 216.470814 -222.096511) (xy 216.5065 -222.137699) (xy 216.535962 -222.183546) (xy 216.5586 -222.233119)
			(xy 216.573953 -222.285409) (xy 216.581708 -222.339351) (xy 216.581708 -222.393849) (xy 216.573953 -222.447791)
			(xy 216.5586 -222.500081) (xy 216.535962 -222.549654) (xy 216.5065 -222.595501) (xy 216.470814 -222.636689)
			(xy 216.42963 -222.672379) (xy 216.383786 -222.701845) (xy 216.334215 -222.724487) (xy 216.281926 -222.739845)
			(xy 216.227985 -222.747605) (xy 216.200736 -222.748094) (xy 216.174419 -222.747665) (xy 216.122284 -222.74044)
			(xy 216.071635 -222.726123) (xy 216.023433 -222.704984) (xy 215.978592 -222.677424) (xy 215.937961 -222.643966)
			(xy 215.919812 -222.624904) (xy 215.912287 -222.617506) (xy 215.89301 -222.60898) (xy 215.882474 -222.608394)
			(xy 215.807798 -222.608394) (xy 215.797247 -222.60891) (xy 215.777952 -222.617455) (xy 215.77046 -222.624904)
			(xy 215.752346 -222.644004) (xy 215.711721 -222.67748) (xy 215.666876 -222.705047) (xy 215.618664 -222.726182)
			(xy 215.568004 -222.740483) (xy 215.515857 -222.747676) (xy 215.489536 -222.748094) (xy 215.46228 -222.747662)
			(xy 215.408324 -222.739908) (xy 215.356019 -222.724555) (xy 215.306433 -222.701914) (xy 215.260574 -222.672446)
			(xy 215.219375 -222.636751) (xy 215.183676 -222.595555) (xy 215.154204 -222.549699) (xy 215.131558 -222.500114)
			(xy 215.116199 -222.447812) (xy 215.108441 -222.393856) (xy 213.800446 -222.393856) (xy 213.800435 -222.394472)
			(xy 213.792315 -222.449648) (xy 213.776247 -222.503055) (xy 213.752575 -222.553552) (xy 213.721802 -222.600065)
			(xy 213.684585 -222.641602) (xy 213.641717 -222.677277) (xy 213.594111 -222.706331) (xy 213.542782 -222.728143)
			(xy 213.488825 -222.742249) (xy 213.433388 -222.748349) (xy 213.377654 -222.746312) (xy 213.322811 -222.736182)
			(xy 213.270027 -222.718175) (xy 213.220427 -222.692674) (xy 213.175069 -222.660223) (xy 213.13492 -222.621514)
			(xy 213.100834 -222.577371) (xy 213.073538 -222.528736) (xy 213.053615 -222.476645) (xy 213.041489 -222.422208)
			(xy 213.037418 -222.366586) (xy 210.476023 -222.366586) (xy 210.433314 -222.384735) (xy 210.379357 -222.398841)
			(xy 210.32392 -222.404941) (xy 210.268186 -222.402904) (xy 210.213343 -222.392774) (xy 210.160559 -222.374767)
			(xy 210.110959 -222.349266) (xy 210.065601 -222.316815) (xy 210.025452 -222.278106) (xy 209.991366 -222.233963)
			(xy 209.96407 -222.185328) (xy 209.944147 -222.133237) (xy 209.932021 -222.0788) (xy 209.92795 -222.023178)
			(xy 208.205578 -222.023178) (xy 209.778854 -223.596454) (xy 209.779362 -223.596962) (xy 209.786744 -223.603542)
			(xy 209.805043 -223.610988) (xy 209.814922 -223.61144) (xy 211.789518 -223.61144)
		)
		(stroke
			(width 0)
			(type solid)
		)
		(fill yes)
		(layer "In9.Cu")
		(net "P1V2_AUX")
	)
	(gr_poly
		(pts
			(xy 417.538916 -124.605288) (xy 417.55147 -124.604642) (xy 417.573598 -124.592783) (xy 417.58108 -124.582682)
			(xy 417.635182 -124.501148) (xy 417.637468 -124.476256) (xy 417.632388 -124.464318) (xy 417.623034 -124.440982)
			(xy 417.609841 -124.392468) (xy 417.603126 -124.342643) (xy 417.60267 -124.317506) (xy 417.60267 -124.311918)
			(xy 417.603465 -124.28488) (xy 417.611746 -124.231426) (xy 417.627493 -124.179678) (xy 417.650392 -124.130673)
			(xy 417.679982 -124.085392) (xy 417.71567 -124.044745) (xy 417.756742 -124.009546) (xy 417.802374 -123.980501)
			(xy 417.85165 -123.958191) (xy 417.903583 -123.943065) (xy 417.957132 -123.935426) (xy 418.011224 -123.935426)
			(xy 418.064773 -123.943065) (xy 418.116706 -123.958191) (xy 418.165982 -123.980501) (xy 418.211614 -124.009546)
			(xy 418.252686 -124.044745) (xy 418.288374 -124.085392) (xy 418.317964 -124.130673) (xy 418.340863 -124.179678)
			(xy 418.35661 -124.231426) (xy 418.364891 -124.28488) (xy 418.365686 -124.311918) (xy 418.365686 -124.316998)
			(xy 418.365264 -124.342221) (xy 418.358581 -124.392222) (xy 418.345357 -124.440904) (xy 418.335968 -124.464318)
			(xy 418.330888 -124.476256) (xy 418.333174 -124.501148) (xy 418.387276 -124.582682) (xy 418.394794 -124.592742)
			(xy 418.4169 -124.6046) (xy 418.42944 -124.605288) (xy 431.504852 -124.605288) (xy 431.512266 -124.60504)
			(xy 431.52647 -124.600786) (xy 431.532792 -124.596906) (xy 431.546508 -124.588016) (xy 431.55616 -124.576586)
			(xy 431.559208 -124.56922) (xy 431.565812 -124.554488) (xy 431.569574 -124.544461) (xy 431.569433 -124.523071)
			(xy 431.565558 -124.513086) (xy 431.548514 -124.474297) (xy 431.520279 -124.394408) (xy 431.498915 -124.312414)
			(xy 431.484578 -124.228904) (xy 431.47737 -124.14448) (xy 431.476912 -124.102114) (xy 431.478944 -124.038868)
			(xy 431.479112 -124.034171) (xy 431.477955 -124.024844) (xy 431.476658 -124.020326) (xy 431.471812 -124.004496)
			(xy 431.46456 -123.972193) (xy 431.46218 -123.95581) (xy 431.460517 -123.946549) (xy 431.451491 -123.930058)
			(xy 431.437126 -123.917931) (xy 431.428398 -123.914408) (xy 431.398271 -123.903884) (xy 431.339298 -123.879479)
			(xy 431.310542 -123.86564) (xy 430.556924 -123.86564) (xy 430.547139 -123.866092) (xy 430.528989 -123.873412)
			(xy 430.521618 -123.879864) (xy 430.490751 -123.908784) (xy 430.424901 -123.961884) (xy 430.354793 -124.009218)
			(xy 430.280928 -124.050446) (xy 430.203838 -124.085272) (xy 430.124076 -124.113446) (xy 430.042215 -124.134765)
			(xy 429.958842 -124.149077) (xy 429.874558 -124.156278) (xy 429.832262 -124.156724) (xy 429.785606 -124.156179)
			(xy 429.692702 -124.147458) (xy 429.60102 -124.130095) (xy 429.51136 -124.104242) (xy 429.424509 -124.070125)
			(xy 429.341224 -124.028044) (xy 429.262235 -123.978365) (xy 429.188234 -123.921524) (xy 429.119866 -123.858018)
			(xy 429.057731 -123.788403) (xy 429.002371 -123.713286) (xy 428.977806 -123.673616) (xy 428.975305 -123.669568)
			(xy 428.969041 -123.662407) (xy 428.96536 -123.659392) (xy 428.942627 -123.641195) (xy 428.902424 -123.599076)
			(xy 428.869085 -123.551339) (xy 428.843384 -123.499091) (xy 428.825918 -123.443546) (xy 428.817091 -123.385992)
			(xy 428.816516 -123.356878) (xy 428.81677 -123.34748) (xy 428.81762 -123.325836) (xy 428.823601 -123.282932)
			(xy 428.828708 -123.261882) (xy 428.83455 -123.241308) (xy 428.835891 -123.236799) (xy 428.83705 -123.227465)
			(xy 428.836836 -123.222766) (xy 428.835881 -123.206908) (xy 428.834864 -123.175152) (xy 428.834804 -123.159266)
			(xy 428.83524 -123.116899) (xy 428.84243 -123.03247) (xy 428.856763 -122.948957) (xy 428.878136 -122.866963)
			(xy 428.906394 -122.787079) (xy 428.92345 -122.748294) (xy 428.927423 -122.738255) (xy 428.92741 -122.716684)
			(xy 428.92345 -122.706638) (xy 428.906408 -122.667849) (xy 428.878177 -122.587959) (xy 428.856817 -122.505965)
			(xy 428.842484 -122.422455) (xy 428.835281 -122.338031) (xy 428.834804 -122.295666) (xy 428.834872 -122.27978)
			(xy 428.835887 -122.248024) (xy 428.836836 -122.232166) (xy 428.837003 -122.227469) (xy 428.835846 -122.218142)
			(xy 428.83455 -122.213624) (xy 428.828591 -122.193923) (xy 428.820443 -122.153576) (xy 428.818294 -122.133106)
			(xy 428.818294 -122.132598) (xy 428.817532 -122.125994) (xy 428.816516 -122.098308) (xy 428.816516 -122.098054)
			(xy 428.817067 -122.068941) (xy 428.825913 -122.011392) (xy 428.843392 -121.955852) (xy 428.8691 -121.903609)
			(xy 428.902441 -121.855874) (xy 428.942642 -121.813754) (xy 428.96536 -121.79554) (xy 428.969034 -121.792519)
			(xy 428.975292 -121.785355) (xy 428.977806 -121.781316) (xy 429.002324 -121.741616) (xy 429.05769 -121.6665)
			(xy 429.119831 -121.596884) (xy 429.188204 -121.533379) (xy 429.26221 -121.476538) (xy 429.341204 -121.426861)
			(xy 429.424492 -121.38478) (xy 429.511348 -121.350664) (xy 429.601011 -121.324812) (xy 429.692697 -121.307449)
			(xy 429.785604 -121.298727) (xy 429.832262 -121.298208) (xy 429.874559 -121.298663) (xy 429.958848 -121.305844)
			(xy 430.042225 -121.32014) (xy 430.124091 -121.34145) (xy 430.203857 -121.369619) (xy 430.28095 -121.404445)
			(xy 430.354815 -121.445678) (xy 430.424921 -121.493021) (xy 430.490764 -121.546133) (xy 430.521618 -121.575068)
			(xy 430.528969 -121.581551) (xy 430.547132 -121.588873) (xy 430.556924 -121.589292) (xy 431.42916 -121.589292)
			(xy 431.45837 -121.561606) (xy 431.45964 -121.54154) (xy 431.461672 -121.518172) (xy 431.461672 -121.517918)
			(xy 431.466752 -121.486168) (xy 431.468792 -121.476535) (xy 431.473748 -121.457475) (xy 431.476658 -121.448068)
			(xy 431.477995 -121.443559) (xy 431.479147 -121.434225) (xy 431.478944 -121.429526) (xy 431.477986 -121.413605)
			(xy 431.476972 -121.381722) (xy 431.476912 -121.365772) (xy 431.477348 -121.323405) (xy 431.484537 -121.238976)
			(xy 431.49887 -121.155463) (xy 431.520243 -121.073468) (xy 431.548501 -120.993584) (xy 431.565558 -120.9548)
			(xy 431.569532 -120.944761) (xy 431.569521 -120.923189) (xy 431.565558 -120.913144) (xy 431.548516 -120.874355)
			(xy 431.520284 -120.794466) (xy 431.498924 -120.712471) (xy 431.48459 -120.628961) (xy 431.477386 -120.544537)
			(xy 431.476912 -120.502172) (xy 431.47869 -120.447816) (xy 431.478852 -120.442841) (xy 431.477443 -120.432989)
			(xy 431.475896 -120.428258) (xy 431.475388 -120.426734) (xy 431.472848 -120.419622) (xy 431.464212 -120.40743)
			(xy 431.434494 -120.384824) (xy 431.420016 -120.379744) (xy 431.411888 -120.379236) (xy 431.361909 -120.376779)
			(xy 431.262786 -120.363033) (xy 431.214022 -120.351804) (xy 431.173393 -120.341451) (xy 431.093909 -120.314745)
			(xy 431.055272 -120.298464) (xy 431.054002 -120.297956) (xy 431.002186 -120.275604) (xy 430.991772 -120.270778)
			(xy 430.991518 -120.270778) (xy 430.981358 -120.265952) (xy 430.55667 -120.265952) (xy 430.554892 -120.265952)
			(xy 430.547333 -120.266494) (xy 430.532999 -120.271394) (xy 430.526698 -120.275604) (xy 430.521364 -120.279922)
			(xy 430.490518 -120.308817) (xy 430.424714 -120.36187) (xy 430.354655 -120.409162) (xy 430.280844 -120.450352)
			(xy 430.203811 -120.485146) (xy 430.124108 -120.513293) (xy 430.042308 -120.534591) (xy 429.958999 -120.548887)
			(xy 429.874779 -120.556078) (xy 429.832516 -120.556528) (xy 429.832262 -120.556528) (xy 429.785613 -120.555984)
			(xy 429.692724 -120.547268) (xy 429.601055 -120.529916) (xy 429.511407 -120.504079) (xy 429.424563 -120.469983)
			(xy 429.341283 -120.427926) (xy 429.262294 -120.378276) (xy 429.188286 -120.321467) (xy 429.119908 -120.257995)
			(xy 429.057755 -120.188415) (xy 429.002372 -120.113335) (xy 428.977806 -120.073674) (xy 428.975302 -120.069628)
			(xy 428.969035 -120.062472) (xy 428.96536 -120.05945) (xy 428.942703 -120.041325) (xy 428.902616 -119.999383)
			(xy 428.869338 -119.951857) (xy 428.843636 -119.899842) (xy 428.826102 -119.844536) (xy 428.81714 -119.787213)
			(xy 428.816516 -119.758206) (xy 428.81677 -119.747538) (xy 428.817622 -119.725894) (xy 428.823607 -119.682992)
			(xy 428.828708 -119.66194) (xy 428.83455 -119.641366) (xy 428.835887 -119.636857) (xy 428.837039 -119.627523)
			(xy 428.836836 -119.622824) (xy 428.835882 -119.606966) (xy 428.834866 -119.57521) (xy 428.834804 -119.559324)
			(xy 428.835238 -119.516956) (xy 428.842423 -119.432526) (xy 428.856751 -119.349011) (xy 428.87812 -119.267015)
			(xy 428.906374 -119.187129) (xy 428.92345 -119.148352) (xy 428.927435 -119.138312) (xy 428.927445 -119.116731)
			(xy 428.92345 -119.106696) (xy 428.906406 -119.067907) (xy 428.87817 -118.988019) (xy 428.856806 -118.906024)
			(xy 428.842468 -118.822514) (xy 428.835259 -118.73809) (xy 428.834804 -118.695724) (xy 428.834873 -118.679838)
			(xy 428.835889 -118.648082) (xy 428.836836 -118.632224) (xy 428.837009 -118.627526) (xy 428.835861 -118.618196)
			(xy 428.83455 -118.613682) (xy 428.828593 -118.59398) (xy 428.820449 -118.553633) (xy 428.818294 -118.533164)
			(xy 428.818294 -118.532656) (xy 428.817532 -118.526052) (xy 428.816516 -118.498366) (xy 428.816516 -118.498112)
			(xy 428.817063 -118.468997) (xy 428.825901 -118.411443) (xy 428.843374 -118.355897) (xy 428.869078 -118.303648)
			(xy 428.902415 -118.255906) (xy 428.942614 -118.213779) (xy 428.96536 -118.195598) (xy 428.969037 -118.192579)
			(xy 428.975302 -118.18542) (xy 428.977806 -118.181374) (xy 429.002338 -118.141692) (xy 429.057725 -118.066612)
			(xy 429.119882 -117.997032) (xy 429.188265 -117.93356) (xy 429.262276 -117.876752) (xy 429.341268 -117.827102)
			(xy 429.424551 -117.785046) (xy 429.511398 -117.750951) (xy 429.601049 -117.725115) (xy 429.692721 -117.707763)
			(xy 429.785612 -117.699047) (xy 429.832262 -117.69852) (xy 429.832516 -117.69852) (xy 429.874778 -117.698988)
			(xy 429.958997 -117.706185) (xy 430.042304 -117.720484) (xy 430.124102 -117.741782) (xy 430.203804 -117.769927)
			(xy 430.280838 -117.804716) (xy 430.354651 -117.8459) (xy 430.424714 -117.893183) (xy 430.490524 -117.946226)
			(xy 430.521364 -117.975126) (xy 430.526698 -117.979444) (xy 430.532971 -117.983712) (xy 430.547319 -117.988626)
			(xy 430.554892 -117.989096) (xy 432.521868 -117.989096) (xy 432.56383 -117.98954) (xy 432.647456 -117.996614)
			(xy 432.730192 -118.010689) (xy 432.811452 -118.031667) (xy 432.890663 -118.059397) (xy 432.967264 -118.093686)
			(xy 433.040713 -118.134289) (xy 433.075842 -118.157244) (xy 434.179172 -118.894352) (xy 441.71616 -118.894352)
			(xy 441.716576 -118.868036) (xy 441.723819 -118.815905) (xy 441.738147 -118.76526) (xy 441.759289 -118.717061)
			(xy 441.786845 -118.672219) (xy 441.820293 -118.631582) (xy 441.83935 -118.613428) (xy 441.84677 -118.605838)
			(xy 441.855309 -118.586434) (xy 441.85586 -118.575836) (xy 441.85586 -118.501668) (xy 441.855442 -118.491037)
			(xy 441.846897 -118.471574) (xy 441.83935 -118.464076) (xy 441.82028 -118.445935) (xy 441.786826 -118.405301)
			(xy 441.75927 -118.360457) (xy 441.738135 -118.312254) (xy 441.72382 -118.261604) (xy 441.716598 -118.209469)
			(xy 441.71616 -118.183152) (xy 441.716646 -118.155901) (xy 441.724402 -118.101953) (xy 441.739757 -118.049658)
			(xy 441.762399 -118.000081) (xy 441.791865 -117.954231) (xy 441.827556 -117.91304) (xy 441.868747 -117.877349)
			(xy 441.914597 -117.847883) (xy 441.964174 -117.825241) (xy 442.016469 -117.809886) (xy 442.070417 -117.80213)
			(xy 442.124919 -117.80213) (xy 442.178867 -117.809886) (xy 442.231162 -117.825241) (xy 442.280739 -117.847883)
			(xy 442.326589 -117.877349) (xy 442.36778 -117.91304) (xy 442.403471 -117.954231) (xy 442.432937 -118.000081)
			(xy 442.455579 -118.049658) (xy 442.470934 -118.101953) (xy 442.47869 -118.155901) (xy 442.479176 -118.183152)
			(xy 442.478751 -118.209467) (xy 442.471508 -118.261598) (xy 442.457182 -118.312242) (xy 442.436041 -118.360441)
			(xy 442.408487 -118.405283) (xy 442.375041 -118.445921) (xy 442.355986 -118.464076) (xy 442.35225 -118.467886)
			(xy 445.782444 -118.467886) (xy 445.786515 -118.412264) (xy 445.798641 -118.357827) (xy 445.818564 -118.305736)
			(xy 445.84586 -118.257101) (xy 445.879946 -118.212958) (xy 445.920095 -118.174249) (xy 445.965453 -118.141798)
			(xy 446.015053 -118.116297) (xy 446.067837 -118.09829) (xy 446.12268 -118.08816) (xy 446.178414 -118.086123)
			(xy 446.233851 -118.092223) (xy 446.287808 -118.106329) (xy 446.339137 -118.128141) (xy 446.386743 -118.157195)
			(xy 446.429611 -118.19287) (xy 446.466828 -118.234407) (xy 446.497601 -118.28092) (xy 446.521273 -118.331417)
			(xy 446.537341 -118.384824) (xy 446.545461 -118.44) (xy 446.54597 -118.467886) (xy 447.95262 -118.467886)
			(xy 447.956691 -118.412264) (xy 447.968817 -118.357827) (xy 447.98874 -118.305736) (xy 448.016036 -118.257101)
			(xy 448.050122 -118.212958) (xy 448.090271 -118.174249) (xy 448.135629 -118.141798) (xy 448.185229 -118.116297)
			(xy 448.238013 -118.09829) (xy 448.292856 -118.08816) (xy 448.34859 -118.086123) (xy 448.404027 -118.092223)
			(xy 448.457984 -118.106329) (xy 448.509313 -118.128141) (xy 448.556919 -118.157195) (xy 448.599787 -118.19287)
			(xy 448.637004 -118.234407) (xy 448.667777 -118.28092) (xy 448.691449 -118.331417) (xy 448.707517 -118.384824)
			(xy 448.715637 -118.44) (xy 448.716146 -118.467886) (xy 448.715637 -118.495772) (xy 448.707517 -118.550948)
			(xy 448.691449 -118.604355) (xy 448.667777 -118.654852) (xy 448.637004 -118.701365) (xy 448.599787 -118.742902)
			(xy 448.578953 -118.76024) (xy 448.838826 -118.76024) (xy 448.842897 -118.704618) (xy 448.855023 -118.650181)
			(xy 448.874946 -118.59809) (xy 448.902242 -118.549455) (xy 448.936328 -118.505312) (xy 448.976477 -118.466603)
			(xy 449.021835 -118.434152) (xy 449.071435 -118.408651) (xy 449.124219 -118.390644) (xy 449.179062 -118.380514)
			(xy 449.234796 -118.378477) (xy 449.290233 -118.384577) (xy 449.34419 -118.398683) (xy 449.395519 -118.420495)
			(xy 449.443125 -118.449549) (xy 449.485993 -118.485224) (xy 449.52321 -118.526761) (xy 449.553983 -118.573274)
			(xy 449.577655 -118.623771) (xy 449.593723 -118.677178) (xy 449.601843 -118.732354) (xy 449.602352 -118.76024)
			(xy 450.864476 -118.76024) (xy 450.868547 -118.704618) (xy 450.880673 -118.650181) (xy 450.900596 -118.59809)
			(xy 450.927892 -118.549455) (xy 450.961978 -118.505312) (xy 451.002127 -118.466603) (xy 451.047485 -118.434152)
			(xy 451.097085 -118.408651) (xy 451.149869 -118.390644) (xy 451.204712 -118.380514) (xy 451.260446 -118.378477)
			(xy 451.315883 -118.384577) (xy 451.36984 -118.398683) (xy 451.421169 -118.420495) (xy 451.468775 -118.449549)
			(xy 451.511643 -118.485224) (xy 451.54886 -118.526761) (xy 451.579633 -118.573274) (xy 451.603305 -118.623771)
			(xy 451.619373 -118.677178) (xy 451.627493 -118.732354) (xy 451.628002 -118.76024) (xy 451.627493 -118.788126)
			(xy 451.619373 -118.843302) (xy 451.603305 -118.896709) (xy 451.579633 -118.947206) (xy 451.54886 -118.993719)
			(xy 451.511643 -119.035256) (xy 451.468775 -119.070931) (xy 451.421169 -119.099985) (xy 451.36984 -119.121797)
			(xy 451.315883 -119.135903) (xy 451.260446 -119.142003) (xy 451.204712 -119.139966) (xy 451.149869 -119.129836)
			(xy 451.097085 -119.111829) (xy 451.047485 -119.086328) (xy 451.002127 -119.053877) (xy 450.961978 -119.015168)
			(xy 450.927892 -118.971025) (xy 450.900596 -118.92239) (xy 450.880673 -118.870299) (xy 450.868547 -118.815862)
			(xy 450.864476 -118.76024) (xy 449.602352 -118.76024) (xy 449.601843 -118.788126) (xy 449.593723 -118.843302)
			(xy 449.577655 -118.896709) (xy 449.553983 -118.947206) (xy 449.52321 -118.993719) (xy 449.485993 -119.035256)
			(xy 449.443125 -119.070931) (xy 449.395519 -119.099985) (xy 449.34419 -119.121797) (xy 449.290233 -119.135903)
			(xy 449.234796 -119.142003) (xy 449.179062 -119.139966) (xy 449.124219 -119.129836) (xy 449.071435 -119.111829)
			(xy 449.021835 -119.086328) (xy 448.976477 -119.053877) (xy 448.936328 -119.015168) (xy 448.902242 -118.971025)
			(xy 448.874946 -118.92239) (xy 448.855023 -118.870299) (xy 448.842897 -118.815862) (xy 448.838826 -118.76024)
			(xy 448.578953 -118.76024) (xy 448.556919 -118.778577) (xy 448.509313 -118.807631) (xy 448.457984 -118.829443)
			(xy 448.404027 -118.843549) (xy 448.34859 -118.849649) (xy 448.292856 -118.847612) (xy 448.238013 -118.837482)
			(xy 448.185229 -118.819475) (xy 448.135629 -118.793974) (xy 448.090271 -118.761523) (xy 448.050122 -118.722814)
			(xy 448.016036 -118.678671) (xy 447.98874 -118.630036) (xy 447.968817 -118.577945) (xy 447.956691 -118.523508)
			(xy 447.95262 -118.467886) (xy 446.54597 -118.467886) (xy 446.545461 -118.495772) (xy 446.537341 -118.550948)
			(xy 446.521273 -118.604355) (xy 446.497601 -118.654852) (xy 446.466828 -118.701365) (xy 446.429611 -118.742902)
			(xy 446.386743 -118.778577) (xy 446.339137 -118.807631) (xy 446.287808 -118.829443) (xy 446.233851 -118.843549)
			(xy 446.178414 -118.849649) (xy 446.12268 -118.847612) (xy 446.067837 -118.837482) (xy 446.015053 -118.819475)
			(xy 445.965453 -118.793974) (xy 445.920095 -118.761523) (xy 445.879946 -118.722814) (xy 445.84586 -118.678671)
			(xy 445.818564 -118.630036) (xy 445.798641 -118.577945) (xy 445.786515 -118.523508) (xy 445.782444 -118.467886)
			(xy 442.35225 -118.467886) (xy 442.348554 -118.471656) (xy 442.340024 -118.491068) (xy 442.339476 -118.501668)
			(xy 442.339476 -118.575836) (xy 442.339881 -118.586468) (xy 442.348434 -118.605932) (xy 442.355986 -118.613428)
			(xy 442.375045 -118.63158) (xy 442.408503 -118.67221) (xy 442.436062 -118.717051) (xy 442.4572 -118.765252)
			(xy 442.471516 -118.815901) (xy 442.478739 -118.868036) (xy 442.479176 -118.894352) (xy 442.47869 -118.921603)
			(xy 442.470934 -118.975551) (xy 442.455579 -119.027846) (xy 442.432937 -119.077423) (xy 442.403471 -119.123273)
			(xy 442.36778 -119.164464) (xy 442.326589 -119.200155) (xy 442.280739 -119.229621) (xy 442.231162 -119.252263)
			(xy 442.178867 -119.267618) (xy 442.124919 -119.275374) (xy 442.070417 -119.275374) (xy 442.016469 -119.267618)
			(xy 441.964174 -119.252263) (xy 441.914597 -119.229621) (xy 441.868747 -119.200155) (xy 441.827556 -119.164464)
			(xy 441.791865 -119.123273) (xy 441.762399 -119.077423) (xy 441.739757 -119.027846) (xy 441.724402 -118.975551)
			(xy 441.716646 -118.921603) (xy 441.71616 -118.894352) (xy 434.179172 -118.894352) (xy 434.947356 -119.407557)
			(xy 442.799609 -119.407557) (xy 442.799609 -119.353043) (xy 442.807368 -119.299083) (xy 442.822727 -119.246777)
			(xy 442.845374 -119.197189) (xy 442.874848 -119.151329) (xy 442.910548 -119.110131) (xy 442.951749 -119.074433)
			(xy 442.99761 -119.044962) (xy 443.0472 -119.022318) (xy 443.099507 -119.006962) (xy 443.153467 -118.999207)
			(xy 443.180724 -118.998746) (xy 443.208095 -118.999187) (xy 443.262276 -119.007009) (xy 443.31478 -119.022503)
			(xy 443.364526 -119.045351) (xy 443.410492 -119.075082) (xy 443.431422 -119.092726) (xy 443.438534 -119.098822)
			(xy 443.455298 -119.105172) (xy 443.513972 -119.105172) (xy 443.513972 -119.092726) (xy 443.555628 -119.092726)
			(xy 443.571376 -119.087138) (xy 443.578234 -119.081804) (xy 443.598536 -119.06612) (xy 443.64259 -119.039825)
			(xy 443.689772 -119.019677) (xy 443.739231 -119.006041) (xy 443.790072 -118.999162) (xy 443.815724 -118.998746)
			(xy 443.842971 -118.999326) (xy 443.896909 -119.007084) (xy 443.949195 -119.022439) (xy 443.998763 -119.045079)
			(xy 444.044605 -119.074543) (xy 444.085787 -119.11023) (xy 444.121472 -119.151414) (xy 444.150932 -119.197258)
			(xy 444.173569 -119.246828) (xy 444.188921 -119.299114) (xy 444.196676 -119.353053) (xy 444.196676 -119.407547)
			(xy 444.188921 -119.461486) (xy 444.173569 -119.513772) (xy 444.150932 -119.563342) (xy 444.121472 -119.609186)
			(xy 444.085787 -119.65037) (xy 444.044605 -119.686057) (xy 443.998763 -119.715521) (xy 443.949195 -119.738161)
			(xy 443.896909 -119.753516) (xy 443.842971 -119.761274) (xy 443.815724 -119.761762) (xy 443.788354 -119.761291)
			(xy 443.734175 -119.753476) (xy 443.681671 -119.737988) (xy 443.631924 -119.715148) (xy 443.585957 -119.685423)
			(xy 443.565026 -119.667782) (xy 443.557914 -119.661686) (xy 443.54115 -119.655336) (xy 443.482476 -119.655336)
			(xy 443.482476 -119.667782) (xy 443.44082 -119.667782) (xy 443.425072 -119.67337) (xy 443.418214 -119.678704)
			(xy 443.397896 -119.694367) (xy 443.353847 -119.720665) (xy 443.306669 -119.740817) (xy 443.257213 -119.754458)
			(xy 443.206375 -119.761343) (xy 443.180724 -119.761762) (xy 443.153467 -119.761393) (xy 443.099507 -119.753638)
			(xy 443.0472 -119.738282) (xy 442.99761 -119.715638) (xy 442.951749 -119.686167) (xy 442.910548 -119.650469)
			(xy 442.874848 -119.609271) (xy 442.845374 -119.563411) (xy 442.822727 -119.513823) (xy 442.807368 -119.461517)
			(xy 442.799609 -119.407557) (xy 434.947356 -119.407557) (xy 435.738357 -119.936006) (xy 440.994544 -119.936006)
			(xy 440.998615 -119.880384) (xy 441.010741 -119.825947) (xy 441.030664 -119.773856) (xy 441.05796 -119.725221)
			(xy 441.092046 -119.681078) (xy 441.132195 -119.642369) (xy 441.177553 -119.609918) (xy 441.227153 -119.584417)
			(xy 441.279937 -119.56641) (xy 441.33478 -119.55628) (xy 441.390514 -119.554243) (xy 441.445951 -119.560343)
			(xy 441.499908 -119.574449) (xy 441.551237 -119.596261) (xy 441.598843 -119.625315) (xy 441.641711 -119.66099)
			(xy 441.678928 -119.702527) (xy 441.709701 -119.74904) (xy 441.733373 -119.799537) (xy 441.749441 -119.852944)
			(xy 441.755348 -119.89308) (xy 445.869058 -119.89308) (xy 445.873129 -119.837458) (xy 445.885255 -119.783021)
			(xy 445.905178 -119.73093) (xy 445.932474 -119.682295) (xy 445.96656 -119.638152) (xy 446.006709 -119.599443)
			(xy 446.052067 -119.566992) (xy 446.101667 -119.541491) (xy 446.154451 -119.523484) (xy 446.209294 -119.513354)
			(xy 446.265028 -119.511317) (xy 446.320465 -119.517417) (xy 446.374422 -119.531523) (xy 446.425751 -119.553335)
			(xy 446.473357 -119.582389) (xy 446.516225 -119.618064) (xy 446.553442 -119.659601) (xy 446.584215 -119.706114)
			(xy 446.607887 -119.756611) (xy 446.623955 -119.810018) (xy 446.632075 -119.865194) (xy 446.632584 -119.89308)
			(xy 446.632075 -119.920966) (xy 446.623955 -119.976142) (xy 446.607887 -120.029549) (xy 446.584215 -120.080046)
			(xy 446.553442 -120.126559) (xy 446.516225 -120.168096) (xy 446.473357 -120.203771) (xy 446.425751 -120.232825)
			(xy 446.374422 -120.254637) (xy 446.320465 -120.268743) (xy 446.265028 -120.274843) (xy 446.209294 -120.272806)
			(xy 446.154451 -120.262676) (xy 446.101667 -120.244669) (xy 446.052067 -120.219168) (xy 446.006709 -120.186717)
			(xy 445.96656 -120.148008) (xy 445.932474 -120.103865) (xy 445.905178 -120.05523) (xy 445.885255 -120.003139)
			(xy 445.873129 -119.948702) (xy 445.869058 -119.89308) (xy 441.755348 -119.89308) (xy 441.757561 -119.90812)
			(xy 441.75807 -119.936006) (xy 441.757561 -119.963892) (xy 441.749441 -120.019068) (xy 441.733373 -120.072475)
			(xy 441.709701 -120.122972) (xy 441.678928 -120.169485) (xy 441.641711 -120.211022) (xy 441.598843 -120.246697)
			(xy 441.551237 -120.275751) (xy 441.499908 -120.297563) (xy 441.445951 -120.311669) (xy 441.390514 -120.317769)
			(xy 441.33478 -120.315732) (xy 441.279937 -120.305602) (xy 441.227153 -120.287595) (xy 441.177553 -120.262094)
			(xy 441.132195 -120.229643) (xy 441.092046 -120.190934) (xy 441.05796 -120.146791) (xy 441.030664 -120.098156)
			(xy 441.010741 -120.046065) (xy 440.998615 -119.991628) (xy 440.994544 -119.936006) (xy 435.738357 -119.936006)
			(xy 436.019702 -120.123966) (xy 436.054379 -120.147628) (xy 436.120047 -120.199938) (xy 436.181081 -120.257587)
			(xy 436.23705 -120.320166) (xy 436.287556 -120.387232) (xy 436.33224 -120.458308) (xy 436.350184 -120.493028)
			(xy 447.904106 -120.493028) (xy 447.908177 -120.437406) (xy 447.920303 -120.382969) (xy 447.940226 -120.330878)
			(xy 447.967522 -120.282243) (xy 448.001608 -120.2381) (xy 448.041757 -120.199391) (xy 448.087115 -120.16694)
			(xy 448.136715 -120.141439) (xy 448.189499 -120.123432) (xy 448.244342 -120.113302) (xy 448.300076 -120.111265)
			(xy 448.355513 -120.117365) (xy 448.40947 -120.131471) (xy 448.460799 -120.153283) (xy 448.508405 -120.182337)
			(xy 448.551273 -120.218012) (xy 448.58849 -120.259549) (xy 448.619263 -120.306062) (xy 448.642935 -120.356559)
			(xy 448.659003 -120.409966) (xy 448.667123 -120.465142) (xy 448.667632 -120.493028) (xy 448.667123 -120.520914)
			(xy 448.659003 -120.57609) (xy 448.642935 -120.629497) (xy 448.619263 -120.679994) (xy 448.58849 -120.726507)
			(xy 448.551273 -120.768044) (xy 448.522198 -120.79224) (xy 450.991476 -120.79224) (xy 450.995547 -120.736618)
			(xy 451.007673 -120.682181) (xy 451.027596 -120.63009) (xy 451.054892 -120.581455) (xy 451.088978 -120.537312)
			(xy 451.129127 -120.498603) (xy 451.174485 -120.466152) (xy 451.224085 -120.440651) (xy 451.276869 -120.422644)
			(xy 451.331712 -120.412514) (xy 451.387446 -120.410477) (xy 451.442883 -120.416577) (xy 451.49684 -120.430683)
			(xy 451.548169 -120.452495) (xy 451.595775 -120.481549) (xy 451.638643 -120.517224) (xy 451.646777 -120.526302)
			(xy 452.503538 -120.526302) (xy 452.507609 -120.47068) (xy 452.519735 -120.416243) (xy 452.539658 -120.364152)
			(xy 452.566954 -120.315517) (xy 452.60104 -120.271374) (xy 452.641189 -120.232665) (xy 452.686547 -120.200214)
			(xy 452.736147 -120.174713) (xy 452.788931 -120.156706) (xy 452.843774 -120.146576) (xy 452.899508 -120.144539)
			(xy 452.954945 -120.150639) (xy 453.008902 -120.164745) (xy 453.060231 -120.186557) (xy 453.107837 -120.215611)
			(xy 453.150705 -120.251286) (xy 453.187922 -120.292823) (xy 453.218695 -120.339336) (xy 453.242367 -120.389833)
			(xy 453.258435 -120.44324) (xy 453.266555 -120.498416) (xy 453.267064 -120.526302) (xy 453.266555 -120.554188)
			(xy 453.258435 -120.609364) (xy 453.242367 -120.662771) (xy 453.218695 -120.713268) (xy 453.187922 -120.759781)
			(xy 453.150705 -120.801318) (xy 453.107837 -120.836993) (xy 453.060231 -120.866047) (xy 453.008902 -120.887859)
			(xy 452.954945 -120.901965) (xy 452.899508 -120.908065) (xy 452.843774 -120.906028) (xy 452.788931 -120.895898)
			(xy 452.736147 -120.877891) (xy 452.686547 -120.85239) (xy 452.641189 -120.819939) (xy 452.60104 -120.78123)
			(xy 452.566954 -120.737087) (xy 452.539658 -120.688452) (xy 452.519735 -120.636361) (xy 452.507609 -120.581924)
			(xy 452.503538 -120.526302) (xy 451.646777 -120.526302) (xy 451.67586 -120.558761) (xy 451.706633 -120.605274)
			(xy 451.730305 -120.655771) (xy 451.746373 -120.709178) (xy 451.754493 -120.764354) (xy 451.755002 -120.79224)
			(xy 451.754493 -120.820126) (xy 451.746373 -120.875302) (xy 451.730305 -120.928709) (xy 451.706633 -120.979206)
			(xy 451.67586 -121.025719) (xy 451.638643 -121.067256) (xy 451.595775 -121.102931) (xy 451.548169 -121.131985)
			(xy 451.49684 -121.153797) (xy 451.442883 -121.167903) (xy 451.387446 -121.174003) (xy 451.331712 -121.171966)
			(xy 451.276869 -121.161836) (xy 451.224085 -121.143829) (xy 451.174485 -121.118328) (xy 451.129127 -121.085877)
			(xy 451.088978 -121.047168) (xy 451.054892 -121.003025) (xy 451.027596 -120.95439) (xy 451.007673 -120.902299)
			(xy 450.995547 -120.847862) (xy 450.991476 -120.79224) (xy 448.522198 -120.79224) (xy 448.508405 -120.803719)
			(xy 448.460799 -120.832773) (xy 448.40947 -120.854585) (xy 448.355513 -120.868691) (xy 448.300076 -120.874791)
			(xy 448.244342 -120.872754) (xy 448.189499 -120.862624) (xy 448.136715 -120.844617) (xy 448.087115 -120.819116)
			(xy 448.041757 -120.786665) (xy 448.001608 -120.747956) (xy 447.967522 -120.703813) (xy 447.940226 -120.655178)
			(xy 447.920303 -120.603087) (xy 447.908177 -120.54865) (xy 447.904106 -120.493028) (xy 436.350184 -120.493028)
			(xy 436.370787 -120.532892) (xy 436.38724 -120.571514) (xy 436.663573 -121.238772) (xy 445.884298 -121.238772)
			(xy 445.888369 -121.18315) (xy 445.900495 -121.128713) (xy 445.920418 -121.076622) (xy 445.947714 -121.027987)
			(xy 445.9818 -120.983844) (xy 446.021949 -120.945135) (xy 446.067307 -120.912684) (xy 446.116907 -120.887183)
			(xy 446.169691 -120.869176) (xy 446.224534 -120.859046) (xy 446.280268 -120.857009) (xy 446.335705 -120.863109)
			(xy 446.389662 -120.877215) (xy 446.440991 -120.899027) (xy 446.488597 -120.928081) (xy 446.531465 -120.963756)
			(xy 446.568682 -121.005293) (xy 446.599455 -121.051806) (xy 446.623127 -121.102303) (xy 446.639195 -121.15571)
			(xy 446.647315 -121.210886) (xy 446.647824 -121.238772) (xy 446.647315 -121.266658) (xy 446.639195 -121.321834)
			(xy 446.623127 -121.375241) (xy 446.599455 -121.425738) (xy 446.568682 -121.472251) (xy 446.53573 -121.509028)
			(xy 447.929506 -121.509028) (xy 447.933577 -121.453406) (xy 447.945703 -121.398969) (xy 447.965626 -121.346878)
			(xy 447.992922 -121.298243) (xy 448.027008 -121.2541) (xy 448.067157 -121.215391) (xy 448.112515 -121.18294)
			(xy 448.162115 -121.157439) (xy 448.214899 -121.139432) (xy 448.269742 -121.129302) (xy 448.325476 -121.127265)
			(xy 448.380913 -121.133365) (xy 448.43487 -121.147471) (xy 448.486199 -121.169283) (xy 448.533805 -121.198337)
			(xy 448.576673 -121.234012) (xy 448.61389 -121.275549) (xy 448.644663 -121.322062) (xy 448.668335 -121.372559)
			(xy 448.684403 -121.425966) (xy 448.692523 -121.481142) (xy 448.693032 -121.509028) (xy 448.692523 -121.536914)
			(xy 448.684403 -121.59209) (xy 448.668335 -121.645497) (xy 448.644663 -121.695994) (xy 448.61389 -121.742507)
			(xy 448.576673 -121.784044) (xy 448.547598 -121.80824) (xy 448.836032 -121.80824) (xy 448.840103 -121.752618)
			(xy 448.852229 -121.698181) (xy 448.872152 -121.64609) (xy 448.899448 -121.597455) (xy 448.933534 -121.553312)
			(xy 448.973683 -121.514603) (xy 449.019041 -121.482152) (xy 449.068641 -121.456651) (xy 449.121425 -121.438644)
			(xy 449.176268 -121.428514) (xy 449.232002 -121.426477) (xy 449.287439 -121.432577) (xy 449.341396 -121.446683)
			(xy 449.392725 -121.468495) (xy 449.440331 -121.497549) (xy 449.483199 -121.533224) (xy 449.520416 -121.574761)
			(xy 449.551189 -121.621274) (xy 449.574861 -121.671771) (xy 449.590929 -121.725178) (xy 449.599049 -121.780354)
			(xy 449.599558 -121.80824) (xy 449.599049 -121.836126) (xy 449.590929 -121.891302) (xy 449.574861 -121.944709)
			(xy 449.551189 -121.995206) (xy 449.520416 -122.041719) (xy 449.483199 -122.083256) (xy 449.440331 -122.118931)
			(xy 449.392725 -122.147985) (xy 449.341396 -122.169797) (xy 449.287439 -122.183903) (xy 449.232002 -122.190003)
			(xy 449.176268 -122.187966) (xy 449.121425 -122.177836) (xy 449.068641 -122.159829) (xy 449.019041 -122.134328)
			(xy 448.973683 -122.101877) (xy 448.933534 -122.063168) (xy 448.899448 -122.019025) (xy 448.872152 -121.97039)
			(xy 448.852229 -121.918299) (xy 448.840103 -121.863862) (xy 448.836032 -121.80824) (xy 448.547598 -121.80824)
			(xy 448.533805 -121.819719) (xy 448.486199 -121.848773) (xy 448.43487 -121.870585) (xy 448.380913 -121.884691)
			(xy 448.325476 -121.890791) (xy 448.269742 -121.888754) (xy 448.214899 -121.878624) (xy 448.162115 -121.860617)
			(xy 448.112515 -121.835116) (xy 448.067157 -121.802665) (xy 448.027008 -121.763956) (xy 447.992922 -121.719813)
			(xy 447.965626 -121.671178) (xy 447.945703 -121.619087) (xy 447.933577 -121.56465) (xy 447.929506 -121.509028)
			(xy 446.53573 -121.509028) (xy 446.531465 -121.513788) (xy 446.488597 -121.549463) (xy 446.440991 -121.578517)
			(xy 446.389662 -121.600329) (xy 446.335705 -121.614435) (xy 446.280268 -121.620535) (xy 446.224534 -121.618498)
			(xy 446.169691 -121.608368) (xy 446.116907 -121.590361) (xy 446.067307 -121.56486) (xy 446.021949 -121.532409)
			(xy 445.9818 -121.4937) (xy 445.947714 -121.449557) (xy 445.920418 -121.400922) (xy 445.900495 -121.348831)
			(xy 445.888369 -121.294394) (xy 445.884298 -121.238772) (xy 436.663573 -121.238772) (xy 437.196253 -122.525028)
			(xy 447.90563 -122.525028) (xy 447.909701 -122.469406) (xy 447.921827 -122.414969) (xy 447.94175 -122.362878)
			(xy 447.969046 -122.314243) (xy 448.003132 -122.2701) (xy 448.043281 -122.231391) (xy 448.088639 -122.19894)
			(xy 448.138239 -122.173439) (xy 448.191023 -122.155432) (xy 448.245866 -122.145302) (xy 448.3016 -122.143265)
			(xy 448.357037 -122.149365) (xy 448.410994 -122.163471) (xy 448.462323 -122.185283) (xy 448.509929 -122.214337)
			(xy 448.552797 -122.250012) (xy 448.590014 -122.291549) (xy 448.620787 -122.338062) (xy 448.644459 -122.388559)
			(xy 448.660527 -122.441966) (xy 448.668647 -122.497142) (xy 448.669156 -122.525028) (xy 448.668647 -122.552914)
			(xy 448.660527 -122.60809) (xy 448.644459 -122.661497) (xy 448.620787 -122.711994) (xy 448.590014 -122.758507)
			(xy 448.552797 -122.800044) (xy 448.509929 -122.835719) (xy 448.462323 -122.864773) (xy 448.410994 -122.886585)
			(xy 448.357037 -122.900691) (xy 448.3016 -122.906791) (xy 448.245866 -122.904754) (xy 448.191023 -122.894624)
			(xy 448.138239 -122.876617) (xy 448.088639 -122.851116) (xy 448.043281 -122.818665) (xy 448.003132 -122.779956)
			(xy 447.969046 -122.735813) (xy 447.94175 -122.687178) (xy 447.921827 -122.635087) (xy 447.909701 -122.58065)
			(xy 447.90563 -122.525028) (xy 437.196253 -122.525028) (xy 437.543925 -123.364548) (xy 442.364398 -123.364548)
			(xy 442.364398 -123.310052) (xy 442.372153 -123.25611) (xy 442.387506 -123.20382) (xy 442.410144 -123.154248)
			(xy 442.439605 -123.108401) (xy 442.475292 -123.067214) (xy 442.516476 -123.031525) (xy 442.56232 -123.002059)
			(xy 442.61189 -122.979417) (xy 442.664178 -122.96406) (xy 442.71812 -122.9563) (xy 442.745368 -122.955812)
			(xy 442.772738 -122.956294) (xy 442.826916 -122.964107) (xy 442.879419 -122.979593) (xy 442.929166 -123.002431)
			(xy 442.975134 -123.032152) (xy 442.996066 -123.049792) (xy 443.003178 -123.055888) (xy 443.019942 -123.062238)
			(xy 443.078616 -123.062238) (xy 443.078616 -123.049792) (xy 443.120272 -123.049792) (xy 443.13602 -123.044204)
			(xy 443.142878 -123.03887) (xy 443.163884 -123.022696) (xy 443.209535 -122.995737) (xy 443.25848 -122.975361)
			(xy 443.309776 -122.961961) (xy 443.362433 -122.955796) (xy 443.415437 -122.956984) (xy 443.467765 -122.965502)
			(xy 443.518408 -122.981186) (xy 443.566391 -123.003735) (xy 443.610789 -123.032712) (xy 443.631066 -123.049792)
			(xy 443.638178 -123.055888) (xy 443.654942 -123.062238) (xy 443.713616 -123.062238) (xy 443.713616 -123.049792)
			(xy 443.755272 -123.049792) (xy 443.77102 -123.044204) (xy 443.777878 -123.03887) (xy 443.798207 -123.023221)
			(xy 443.842252 -122.996919) (xy 443.889428 -122.976763) (xy 443.938881 -122.963119) (xy 443.989718 -122.956232)
			(xy 444.015368 -122.955812) (xy 444.042624 -122.956233) (xy 444.096581 -122.963986) (xy 444.148886 -122.97934)
			(xy 444.198472 -123.001982) (xy 444.244332 -123.031451) (xy 444.285531 -123.067147) (xy 444.32123 -123.108342)
			(xy 444.350702 -123.154199) (xy 444.373348 -123.203784) (xy 444.388707 -123.256088) (xy 444.396465 -123.310044)
			(xy 444.396465 -123.364556) (xy 444.388707 -123.418512) (xy 444.373348 -123.470816) (xy 444.350702 -123.520401)
			(xy 444.32123 -123.566258) (xy 444.285531 -123.607453) (xy 444.244332 -123.643149) (xy 444.198472 -123.672618)
			(xy 444.148886 -123.69526) (xy 444.096581 -123.710614) (xy 444.042624 -123.718367) (xy 444.015368 -123.718828)
			(xy 443.987996 -123.718398) (xy 443.933815 -123.710574) (xy 443.881311 -123.695078) (xy 443.831564 -123.672227)
			(xy 443.7856 -123.642494) (xy 443.76467 -123.624848) (xy 443.757558 -123.618752) (xy 443.740794 -123.612402)
			(xy 443.654942 -123.612402) (xy 443.638178 -123.618752) (xy 443.631066 -123.624848) (xy 443.610133 -123.642489)
			(xy 443.564165 -123.672213) (xy 443.514419 -123.695059) (xy 443.461917 -123.710555) (xy 443.407739 -123.718384)
			(xy 443.352997 -123.718384) (xy 443.298819 -123.710555) (xy 443.246317 -123.695059) (xy 443.196571 -123.672213)
			(xy 443.150603 -123.642489) (xy 443.12967 -123.624848) (xy 443.122558 -123.618752) (xy 443.105794 -123.612402)
			(xy 443.04712 -123.612402) (xy 443.04712 -123.624848) (xy 443.005464 -123.624848) (xy 442.989716 -123.630436)
			(xy 442.982858 -123.63577) (xy 442.962522 -123.651408) (xy 442.918478 -123.677711) (xy 442.871304 -123.697868)
			(xy 442.821853 -123.711515) (xy 442.771018 -123.718406) (xy 442.745368 -123.718828) (xy 442.71812 -123.7183)
			(xy 442.664178 -123.71054) (xy 442.61189 -123.695183) (xy 442.56232 -123.672541) (xy 442.516476 -123.643075)
			(xy 442.475292 -123.607386) (xy 442.439605 -123.566199) (xy 442.410144 -123.520352) (xy 442.387506 -123.47078)
			(xy 442.372153 -123.41849) (xy 442.364398 -123.364548) (xy 437.543925 -123.364548) (xy 437.73598 -123.828302)
			(xy 437.741454 -123.839718) (xy 437.761036 -123.855715) (xy 437.773318 -123.858782) (xy 437.773826 -123.858782)
			(xy 437.782462 -123.860306) (xy 437.806592 -123.864624) (xy 437.815017 -123.865799) (xy 437.83181 -123.863145)
			(xy 437.846819 -123.855158) (xy 437.85282 -123.84913) (xy 437.870942 -123.830297) (xy 437.911445 -123.797264)
			(xy 437.956073 -123.770062) (xy 438.003994 -123.749201) (xy 438.054312 -123.735069) (xy 438.106088 -123.72793)
			(xy 438.13222 -123.727464) (xy 438.159471 -123.727951) (xy 438.213418 -123.73571) (xy 438.265712 -123.751066)
			(xy 438.315289 -123.773708) (xy 438.361138 -123.803175) (xy 438.402329 -123.838866) (xy 438.438021 -123.880055)
			(xy 438.467488 -123.925904) (xy 438.490131 -123.97548) (xy 438.505488 -124.027774) (xy 438.513248 -124.081721)
			(xy 438.513728 -124.108972) (xy 438.513261 -124.136307) (xy 438.50546 -124.190416) (xy 438.490013 -124.242858)
			(xy 438.467238 -124.292557) (xy 438.437601 -124.338495) (xy 438.420002 -124.359416) (xy 438.419748 -124.35967)
			(xy 438.419494 -124.359924) (xy 438.413913 -124.367012) (xy 438.40768 -124.383929) (xy 438.407302 -124.392944)
			(xy 438.407302 -124.459746) (xy 438.40739 -124.464157) (xy 438.408925 -124.472843) (xy 438.41035 -124.477018)
			(xy 438.413652 -124.486416) (xy 438.420002 -124.493528) (xy 438.436151 -124.51269) (xy 438.463794 -124.554486)
			(xy 438.47512 -124.57684) (xy 438.481724 -124.590048) (xy 438.506108 -124.605288) (xy 438.71007 -124.605288)
			(xy 438.72277 -124.603764) (xy 438.740296 -124.599192) (xy 438.74563 -124.596398) (xy 438.769028 -124.584718)
			(xy 438.818286 -124.567158) (xy 438.86948 -124.556489) (xy 438.921652 -124.55291) (xy 438.973824 -124.556489)
			(xy 439.025018 -124.567158) (xy 439.074276 -124.584718) (xy 439.097674 -124.596398) (xy 439.103008 -124.599192)
			(xy 439.120534 -124.603764) (xy 439.133234 -124.605288) (xy 439.34507 -124.605288) (xy 439.35777 -124.603764)
			(xy 439.375296 -124.599192) (xy 439.38063 -124.596398) (xy 439.404028 -124.584718) (xy 439.453286 -124.567158)
			(xy 439.50448 -124.556489) (xy 439.556652 -124.55291) (xy 439.608824 -124.556489) (xy 439.660018 -124.567158)
			(xy 439.709276 -124.584718) (xy 439.732674 -124.596398) (xy 439.738008 -124.599192) (xy 439.755534 -124.603764)
			(xy 439.768234 -124.605288) (xy 440.612022 -124.605288) (xy 440.622448 -124.604791) (xy 440.641599 -124.596538)
			(xy 440.649106 -124.589286) (xy 440.699652 -124.535692) (xy 440.706302 -124.527946) (xy 440.713381 -124.508816)
			(xy 440.713368 -124.498608) (xy 440.713368 -124.498354) (xy 440.71286 -124.47778) (xy 440.713331 -124.450447)
			(xy 440.721138 -124.39634) (xy 440.736589 -124.343902) (xy 440.759368 -124.294207) (xy 440.789008 -124.248273)
			(xy 440.806586 -124.227336) (xy 440.80684 -124.227082) (xy 440.807094 -124.226828) (xy 440.812684 -124.219743)
			(xy 440.818936 -124.202826) (xy 440.819286 -124.193808) (xy 440.819286 -124.127006) (xy 440.819203 -124.122594)
			(xy 440.817679 -124.113904) (xy 440.816238 -124.109734) (xy 440.812936 -124.100336) (xy 440.806586 -124.093224)
			(xy 440.788992 -124.072298) (xy 440.759351 -124.026361) (xy 440.736569 -123.976664) (xy 440.721113 -123.924224)
			(xy 440.7133 -123.870115) (xy 440.71286 -123.84278) (xy 440.713346 -123.815529) (xy 440.721102 -123.761581)
			(xy 440.736457 -123.709286) (xy 440.759099 -123.659709) (xy 440.788565 -123.613859) (xy 440.824256 -123.572668)
			(xy 440.865447 -123.536977) (xy 440.911297 -123.507511) (xy 440.960874 -123.484869) (xy 441.013169 -123.469514)
			(xy 441.067117 -123.461758) (xy 441.121619 -123.461758) (xy 441.175567 -123.469514) (xy 441.227862 -123.484869)
			(xy 441.277439 -123.507511) (xy 441.323289 -123.536977) (xy 441.36448 -123.572668) (xy 441.400171 -123.613859)
			(xy 441.429637 -123.659709) (xy 441.452279 -123.709286) (xy 441.467634 -123.761581) (xy 441.47539 -123.815529)
			(xy 441.47551 -123.82223) (xy 445.742305 -123.82223) (xy 445.742308 -123.767732) (xy 445.750066 -123.713789)
			(xy 445.765422 -123.6615) (xy 445.788064 -123.611928) (xy 445.81753 -123.566082) (xy 445.85322 -123.524897)
			(xy 445.894408 -123.48921) (xy 445.940256 -123.459748) (xy 445.98983 -123.437111) (xy 446.042121 -123.421759)
			(xy 446.096065 -123.414005) (xy 446.123314 -123.41352) (xy 446.123822 -123.41352) (xy 446.134194 -123.4136)
			(xy 446.154906 -123.414744) (xy 446.165224 -123.415806) (xy 446.179773 -123.416855) (xy 446.208463 -123.411663)
			(xy 446.23452 -123.398583) (xy 446.255824 -123.378678) (xy 446.270643 -123.353569) (xy 446.27777 -123.325298)
			(xy 446.276627 -123.296165) (xy 446.272412 -123.282202) (xy 446.263052 -123.252595) (xy 446.252974 -123.191327)
			(xy 446.252346 -123.160282) (xy 446.252346 -123.160028) (xy 446.252825 -123.132772) (xy 446.260579 -123.078814)
			(xy 446.275934 -123.026509) (xy 446.298576 -122.976922) (xy 446.328045 -122.931062) (xy 446.363741 -122.889863)
			(xy 446.404937 -122.854164) (xy 446.450795 -122.824691) (xy 446.50038 -122.802045) (xy 446.552684 -122.786686)
			(xy 446.606641 -122.778927) (xy 446.661153 -122.778927) (xy 446.71511 -122.786684) (xy 446.767414 -122.802042)
			(xy 446.816999 -122.824688) (xy 446.862857 -122.85416) (xy 446.904054 -122.889859) (xy 446.939751 -122.931057)
			(xy 446.969221 -122.976916) (xy 446.991864 -123.026503) (xy 447.007219 -123.078808) (xy 447.014975 -123.132765)
			(xy 447.014971 -123.187277) (xy 447.00721 -123.241234) (xy 446.991849 -123.293537) (xy 446.9692 -123.343121)
			(xy 446.939725 -123.388977) (xy 446.904024 -123.430172) (xy 446.862823 -123.465866) (xy 446.816962 -123.495332)
			(xy 446.767374 -123.517972) (xy 446.715068 -123.533325) (xy 446.66111 -123.541076) (xy 446.633854 -123.541536)
			(xy 446.633346 -123.541536) (xy 446.622974 -123.541459) (xy 446.602262 -123.540313) (xy 446.591944 -123.53925)
			(xy 446.577396 -123.53823) (xy 446.548715 -123.543427) (xy 446.522667 -123.556507) (xy 446.501368 -123.576405)
			(xy 446.48655 -123.601505) (xy 446.479417 -123.629767) (xy 446.480549 -123.658893) (xy 446.484756 -123.672854)
			(xy 446.494108 -123.702463) (xy 446.504191 -123.763729) (xy 446.504822 -123.794774) (xy 446.504822 -123.795028)
			(xy 447.949064 -123.795028) (xy 447.953135 -123.739406) (xy 447.965261 -123.684969) (xy 447.985184 -123.632878)
			(xy 448.01248 -123.584243) (xy 448.046566 -123.5401) (xy 448.086715 -123.501391) (xy 448.132073 -123.46894)
			(xy 448.181673 -123.443439) (xy 448.234457 -123.425432) (xy 448.2893 -123.415302) (xy 448.345034 -123.413265)
			(xy 448.400471 -123.419365) (xy 448.454428 -123.433471) (xy 448.505757 -123.455283) (xy 448.553363 -123.484337)
			(xy 448.596231 -123.520012) (xy 448.633448 -123.561549) (xy 448.664221 -123.608062) (xy 448.687893 -123.658559)
			(xy 448.703961 -123.711966) (xy 448.712081 -123.767142) (xy 448.71259 -123.795028) (xy 448.712081 -123.822914)
			(xy 448.703961 -123.87809) (xy 448.687893 -123.931497) (xy 448.664221 -123.981994) (xy 448.633448 -124.028507)
			(xy 448.596231 -124.070044) (xy 448.553363 -124.105719) (xy 448.505757 -124.134773) (xy 448.454428 -124.156585)
			(xy 448.400471 -124.170691) (xy 448.345034 -124.176791) (xy 448.2893 -124.174754) (xy 448.234457 -124.164624)
			(xy 448.181673 -124.146617) (xy 448.132073 -124.121116) (xy 448.086715 -124.088665) (xy 448.046566 -124.049956)
			(xy 448.01248 -124.005813) (xy 447.985184 -123.957178) (xy 447.965261 -123.905087) (xy 447.953135 -123.85065)
			(xy 447.949064 -123.795028) (xy 446.504822 -123.795028) (xy 446.504292 -123.822277) (xy 446.496532 -123.87622)
			(xy 446.481174 -123.928509) (xy 446.458532 -123.978081) (xy 446.429065 -124.023925) (xy 446.393373 -124.06511)
			(xy 446.352184 -124.100795) (xy 446.306335 -124.130256) (xy 446.256761 -124.152892) (xy 446.204469 -124.168243)
			(xy 446.150526 -124.175995) (xy 446.096028 -124.175992) (xy 446.042085 -124.168233) (xy 445.989795 -124.152876)
			(xy 445.940224 -124.130234) (xy 445.894379 -124.100767) (xy 445.853194 -124.065077) (xy 445.817507 -124.023888)
			(xy 445.788046 -123.97804) (xy 445.765409 -123.928465) (xy 445.750058 -123.876174) (xy 445.742305 -123.82223)
			(xy 441.47551 -123.82223) (xy 441.475876 -123.84278) (xy 441.475408 -123.870115) (xy 441.467607 -123.924224)
			(xy 441.452161 -123.976666) (xy 441.429388 -124.026366) (xy 441.399752 -124.072306) (xy 441.38215 -124.093224)
			(xy 441.381896 -124.093478) (xy 441.381642 -124.093732) (xy 441.376058 -124.100819) (xy 441.369821 -124.117736)
			(xy 441.36945 -124.126752) (xy 441.36945 -124.193554) (xy 441.369538 -124.197965) (xy 441.371073 -124.206651)
			(xy 441.372498 -124.210826) (xy 441.3758 -124.220224) (xy 441.38215 -124.227336) (xy 441.399739 -124.248264)
			(xy 441.42937 -124.294203) (xy 441.452142 -124.343901) (xy 441.467588 -124.39634) (xy 441.475392 -124.450447)
			(xy 441.475876 -124.47778) (xy 441.475368 -124.498354) (xy 441.475368 -124.498608) (xy 441.475361 -124.508817)
			(xy 441.482432 -124.527949) (xy 441.489084 -124.535692) (xy 441.53963 -124.589286) (xy 441.542332 -124.592107)
			(xy 441.548453 -124.596961) (xy 441.551822 -124.598938) (xy 441.552076 -124.598938) (xy 441.5578 -124.601898)
			(xy 441.570273 -124.605115) (xy 441.576714 -124.605288) (xy 442.90107 -124.605288) (xy 442.910456 -124.604855)
			(xy 442.927975 -124.598106) (xy 442.941914 -124.585529) (xy 442.946536 -124.577348) (xy 442.987176 -124.496068)
			(xy 442.991029 -124.487504) (xy 442.992886 -124.468834) (xy 442.987875 -124.450753) (xy 442.982604 -124.442982)
			(xy 442.964865 -124.418122) (xy 442.93669 -124.363943) (xy 442.917501 -124.305968) (xy 442.907787 -124.245678)
			(xy 442.907166 -124.215144) (xy 442.907626 -124.187888) (xy 442.915378 -124.133931) (xy 442.93073 -124.081627)
			(xy 442.953369 -124.032039) (xy 442.982836 -123.986179) (xy 443.018529 -123.944979) (xy 443.059723 -123.909278)
			(xy 443.105578 -123.879803) (xy 443.155161 -123.857154) (xy 443.207463 -123.841792) (xy 443.261418 -123.834031)
			(xy 443.288674 -123.833636) (xy 443.316411 -123.834139) (xy 443.371298 -123.84218) (xy 443.424443 -123.858083)
			(xy 443.474726 -123.881512) (xy 443.521088 -123.911974) (xy 443.562551 -123.948826) (xy 443.598242 -123.991293)
			(xy 443.62741 -124.03848) (xy 443.649439 -124.089392) (xy 443.663865 -124.142957) (xy 443.667642 -124.17044)
			(xy 443.669166 -124.184664) (xy 443.670436 -124.215144) (xy 443.669879 -124.244858) (xy 443.660676 -124.303569)
			(xy 443.642471 -124.36014) (xy 443.615703 -124.413199) (xy 443.598808 -124.437648) (xy 443.59449 -124.44349)
			(xy 443.589342 -124.451267) (xy 443.584488 -124.469259) (xy 443.586383 -124.487797) (xy 443.590172 -124.496322)
			(xy 443.599824 -124.515626) (xy 443.630812 -124.577348) (xy 443.635364 -124.585585) (xy 443.649306 -124.598204)
			(xy 443.666873 -124.604918) (xy 443.676278 -124.605288) (xy 449.190364 -124.605288) (xy 449.19912 -124.604973)
			(xy 449.215621 -124.599126) (xy 449.222622 -124.593858) (xy 449.222622 -124.593604) (xy 449.228964 -124.587978)
			(xy 449.237901 -124.573586) (xy 449.240148 -124.56541) (xy 449.240402 -124.564648) (xy 449.240402 -124.56414)
			(xy 449.246387 -124.537276) (xy 449.265045 -124.485497) (xy 449.290948 -124.436935) (xy 449.323558 -124.392598)
			(xy 449.362199 -124.353406) (xy 449.406068 -124.32017) (xy 449.454257 -124.293581) (xy 449.505766 -124.27419)
			(xy 449.559526 -124.2624) (xy 449.614423 -124.258454) (xy 449.669316 -124.262435) (xy 449.723069 -124.27426)
			(xy 449.774565 -124.293684) (xy 449.822737 -124.320304) (xy 449.866586 -124.353567) (xy 449.905201 -124.392785)
			(xy 449.937783 -124.437143) (xy 449.963654 -124.485721) (xy 449.982279 -124.537512) (xy 449.988178 -124.564394)
			(xy 449.989956 -124.57303) (xy 449.998592 -124.587508) (xy 450.005196 -124.59335) (xy 450.012302 -124.598872)
			(xy 450.02922 -124.604976) (xy 450.038216 -124.605288) (xy 452.606918 -124.605288) (xy 452.616986 -124.604861)
			(xy 452.635585 -124.597141) (xy 452.642986 -124.590302) (xy 455.109072 -122.124216) (xy 455.115908 -122.116814)
			(xy 455.123617 -122.098216) (xy 455.124058 -122.088148) (xy 455.124058 -120.862344) (xy 455.123628 -120.852266)
			(xy 455.115853 -120.833669) (xy 455.101494 -120.819524) (xy 455.092308 -120.815354) (xy 455.046588 -120.796812)
			(xy 454.990454 -120.774206) (xy 454.960228 -120.78081) (xy 454.949306 -120.791986) (xy 454.931274 -120.809962)
			(xy 454.89127 -120.841461) (xy 454.84743 -120.867356) (xy 454.800535 -120.887188) (xy 454.751418 -120.900604)
			(xy 454.700952 -120.907365) (xy 454.675494 -120.90781) (xy 454.648243 -120.907324) (xy 454.594296 -120.899567)
			(xy 454.542001 -120.884211) (xy 454.492424 -120.861569) (xy 454.446575 -120.832103) (xy 454.405385 -120.796411)
			(xy 454.369694 -120.755221) (xy 454.340228 -120.70937) (xy 454.317587 -120.659793) (xy 454.302232 -120.607499)
			(xy 454.294476 -120.553551) (xy 454.294476 -120.499049) (xy 454.302232 -120.445101) (xy 454.317587 -120.392807)
			(xy 454.340228 -120.34323) (xy 454.369694 -120.297379) (xy 454.405385 -120.256189) (xy 454.446575 -120.220497)
			(xy 454.492424 -120.191031) (xy 454.542001 -120.168389) (xy 454.594296 -120.153033) (xy 454.648243 -120.145276)
			(xy 454.675494 -120.144794) (xy 454.700953 -120.145216) (xy 454.751419 -120.151986) (xy 454.800536 -120.165408)
			(xy 454.847432 -120.185242) (xy 454.891274 -120.211137) (xy 454.931283 -120.242632) (xy 454.949306 -120.260618)
			(xy 454.94956 -120.260872) (xy 454.949814 -120.261126) (xy 454.960482 -120.272048) (xy 454.990708 -120.278398)
			(xy 455.092308 -120.23725) (xy 455.101481 -120.233063) (xy 455.115814 -120.218903) (xy 455.123629 -120.200332)
			(xy 455.124058 -120.19026) (xy 455.124058 -119.34952) (xy 455.123664 -119.340254) (xy 455.117059 -119.322942)
			(xy 455.104685 -119.309151) (xy 455.096626 -119.304562) (xy 455.093832 -119.303038) (xy 455.007218 -119.26951)
			(xy 455.00281 -119.267946) (xy 454.993607 -119.266277) (xy 454.98893 -119.266208) (xy 454.972674 -119.266208)
			(xy 454.953116 -119.274844) (xy 454.94575 -119.282718) (xy 454.927612 -119.302029) (xy 454.886916 -119.335952)
			(xy 454.841912 -119.363907) (xy 454.793467 -119.385354) (xy 454.742517 -119.39988) (xy 454.690046 -119.407203)
			(xy 454.663556 -119.407686) (xy 454.636308 -119.407197) (xy 454.582369 -119.399436) (xy 454.530082 -119.384078)
			(xy 454.480513 -119.361435) (xy 454.434671 -119.33197) (xy 454.393489 -119.29628) (xy 454.357804 -119.255093)
			(xy 454.328344 -119.209248) (xy 454.305707 -119.159676) (xy 454.290355 -119.107388) (xy 454.2826 -119.053448)
			(xy 454.2826 -118.998952) (xy 454.290355 -118.945012) (xy 454.305707 -118.892723) (xy 454.328344 -118.843152)
			(xy 454.357804 -118.797307) (xy 454.393489 -118.75612) (xy 454.434671 -118.72043) (xy 454.480513 -118.690965)
			(xy 454.530082 -118.668322) (xy 454.582369 -118.652964) (xy 454.636308 -118.645203) (xy 454.663556 -118.64467)
			(xy 454.690197 -118.645138) (xy 454.742961 -118.65256) (xy 454.794178 -118.667251) (xy 454.842853 -118.688927)
			(xy 454.888039 -118.717164) (xy 454.928855 -118.751414) (xy 454.94702 -118.770908) (xy 454.957688 -118.782846)
			(xy 454.988168 -118.789958) (xy 455.091292 -118.750334) (xy 455.096372 -118.748048) (xy 455.096626 -118.747794)
			(xy 455.104636 -118.743155) (xy 455.116938 -118.729344) (xy 455.123577 -118.712081) (xy 455.124058 -118.702836)
			(xy 455.124058 -115.39093) (xy 455.123848 -115.384494) (xy 455.12063 -115.37203) (xy 455.117708 -115.366292)
			(xy 455.103484 -115.340892) (xy 455.095102 -115.331748) (xy 455.090022 -115.328446) (xy 455.067982 -115.313196)
			(xy 455.027999 -115.277505) (xy 454.9934 -115.236573) (xy 454.964868 -115.191203) (xy 454.942961 -115.142289)
			(xy 454.928112 -115.090792) (xy 454.920612 -115.037723) (xy 454.920608 -114.984128) (xy 454.928101 -114.931058)
			(xy 454.942944 -114.879559) (xy 454.964843 -114.830642) (xy 454.99337 -114.785269) (xy 455.027963 -114.744332)
			(xy 455.067942 -114.708636) (xy 455.090022 -114.693446) (xy 455.095102 -114.690144) (xy 455.103484 -114.681)
			(xy 455.117708 -114.6556) (xy 455.120666 -114.649876) (xy 455.12388 -114.637403) (xy 455.124058 -114.630962)
			(xy 455.124058 -102.376478) (xy 455.123611 -102.366635) (xy 455.116191 -102.348403) (xy 455.102426 -102.334332)
			(xy 455.093578 -102.329996) (xy 455.008234 -102.292912) (xy 454.999075 -102.289391) (xy 454.979479 -102.288853)
			(xy 454.96112 -102.295727) (xy 454.953624 -102.302056) (xy 454.932343 -102.321005) (xy 454.885213 -102.353028)
			(xy 454.833845 -102.377688) (xy 454.779382 -102.394436) (xy 454.723034 -102.4029) (xy 454.694544 -102.403402)
			(xy 454.667289 -102.402942) (xy 454.613334 -102.39519) (xy 454.561031 -102.379837) (xy 454.511446 -102.357197)
			(xy 454.465588 -102.32773) (xy 454.42439 -102.292037) (xy 454.388692 -102.250843) (xy 454.359221 -102.204988)
			(xy 454.336576 -102.155405) (xy 454.321218 -102.103103) (xy 454.313461 -102.049149) (xy 454.313036 -102.021894)
			(xy 454.313506 -101.99456) (xy 454.321311 -101.940452) (xy 454.336759 -101.888013) (xy 454.359536 -101.838316)
			(xy 454.389174 -101.792379) (xy 454.406762 -101.77145) (xy 454.407016 -101.771196) (xy 454.40727 -101.770942)
			(xy 454.412864 -101.763858) (xy 454.419124 -101.746941) (xy 454.419462 -101.737922) (xy 454.419462 -101.67112)
			(xy 454.419371 -101.66671) (xy 454.417833 -101.658025) (xy 454.416414 -101.653848) (xy 454.413112 -101.64445)
			(xy 454.406762 -101.637338) (xy 454.389162 -101.616416) (xy 454.359511 -101.570483) (xy 454.336723 -101.520786)
			(xy 454.321267 -101.468344) (xy 454.31346 -101.414232) (xy 454.31346 -101.359559) (xy 454.321269 -101.305448)
			(xy 454.336726 -101.253006) (xy 454.359515 -101.203309) (xy 454.389168 -101.157377) (xy 454.406762 -101.13645)
			(xy 454.407016 -101.136196) (xy 454.40727 -101.135942) (xy 454.412864 -101.128858) (xy 454.419124 -101.111941)
			(xy 454.419462 -101.102922) (xy 454.419462 -101.03612) (xy 454.419371 -101.03171) (xy 454.417833 -101.023025)
			(xy 454.416414 -101.018848) (xy 454.413112 -101.00945) (xy 454.406762 -101.002338) (xy 454.389174 -100.98141)
			(xy 454.359545 -100.93547) (xy 454.336776 -100.885772) (xy 454.321333 -100.833333) (xy 454.313532 -100.779227)
			(xy 454.313036 -100.751894) (xy 454.3135 -100.724643) (xy 454.321258 -100.670695) (xy 454.336615 -100.6184)
			(xy 454.359258 -100.568823) (xy 454.388727 -100.522974) (xy 454.424421 -100.481786) (xy 454.465614 -100.446097)
			(xy 454.511467 -100.416634) (xy 454.561047 -100.393997) (xy 454.613344 -100.378647) (xy 454.667293 -100.370896)
			(xy 454.694544 -100.370386) (xy 454.723032 -100.370916) (xy 454.779374 -100.379387) (xy 454.833833 -100.396134)
			(xy 454.8852 -100.420786) (xy 454.932334 -100.452796) (xy 454.953624 -100.471732) (xy 454.962129 -100.478851)
			(xy 454.983199 -100.485704) (xy 454.994264 -100.48494) (xy 455.00163 -100.483924) (xy 455.093578 -100.443792)
			(xy 455.102405 -100.43943) (xy 455.116142 -100.425349) (xy 455.123595 -100.407144) (xy 455.124058 -100.39731)
			(xy 455.124058 -77.578712) (xy 455.123711 -77.569979) (xy 455.117838 -77.553532) (xy 455.106746 -77.540042)
			(xy 455.09942 -77.535278) (xy 455.024744 -77.490574) (xy 455.017089 -77.48643) (xy 455.000026 -77.483044)
			(xy 454.982811 -77.485545) (xy 454.97496 -77.489304) (xy 454.974706 -77.489304) (xy 454.946978 -77.50338)
			(xy 454.888081 -77.523315) (xy 454.826726 -77.533412) (xy 454.795636 -77.534008) (xy 454.789794 -77.534008)
			(xy 454.760241 -77.533019) (xy 454.70196 -77.523042) (xy 454.645915 -77.504197) (xy 454.593447 -77.476933)
			(xy 454.545812 -77.441904) (xy 454.504149 -77.399947) (xy 454.469455 -77.352067) (xy 454.45553 -77.325982)
			(xy 454.449359 -77.316793) (xy 454.431052 -77.304397) (xy 454.420224 -77.302106) (xy 454.34631 -77.28585)
			(xy 454.340957 -77.284861) (xy 454.330073 -77.284861) (xy 454.32472 -77.28585) (xy 454.312782 -77.28839)
			(xy 454.292175 -77.304969) (xy 454.247245 -77.332871) (xy 454.198883 -77.354279) (xy 454.148021 -77.368779)
			(xy 454.09564 -77.376092) (xy 454.069196 -77.376528) (xy 454.041944 -77.376042) (xy 453.987993 -77.368285)
			(xy 453.935696 -77.352928) (xy 453.886117 -77.330286) (xy 453.840265 -77.300818) (xy 453.799073 -77.265124)
			(xy 453.76338 -77.223932) (xy 453.733912 -77.178079) (xy 453.71127 -77.1285) (xy 453.695915 -77.076203)
			(xy 453.688158 -77.022252) (xy 453.688158 -76.967748) (xy 453.695915 -76.913797) (xy 453.71127 -76.8615)
			(xy 453.733912 -76.811921) (xy 453.76338 -76.766068) (xy 453.799073 -76.724876) (xy 453.840265 -76.689182)
			(xy 453.886117 -76.659714) (xy 453.935696 -76.637072) (xy 453.987993 -76.621715) (xy 454.041944 -76.613958)
			(xy 454.069196 -76.613512) (xy 454.095407 -76.613953) (xy 454.147333 -76.62114) (xy 454.197788 -76.635365)
			(xy 454.245821 -76.656362) (xy 454.290529 -76.683734) (xy 454.33107 -76.716967) (xy 454.366682 -76.755436)
			(xy 454.396694 -76.798416) (xy 454.409048 -76.821538) (xy 454.415227 -76.830714) (xy 454.43354 -76.843078)
			(xy 454.444354 -76.845414) (xy 454.518268 -76.86167) (xy 454.523616 -76.862714) (xy 454.53451 -76.862714)
			(xy 454.539858 -76.86167) (xy 454.551796 -76.85913) (xy 454.572404 -76.842552) (xy 454.617335 -76.814654)
			(xy 454.665697 -76.793248) (xy 454.716558 -76.778748) (xy 454.768938 -76.771433) (xy 454.795382 -76.770992)
			(xy 454.795636 -76.770992) (xy 454.826723 -76.771627) (xy 454.88807 -76.781736) (xy 454.946974 -76.801635)
			(xy 454.974706 -76.815696) (xy 454.986644 -76.822046) (xy 455.01306 -76.821284) (xy 455.09942 -76.769722)
			(xy 455.106704 -76.764911) (xy 455.117765 -76.75142) (xy 455.123684 -76.735009) (xy 455.124058 -76.726288)
			(xy 455.124058 -76.177648) (xy 455.123624 -76.167583) (xy 455.115892 -76.148996) (xy 455.109072 -76.14158)
			(xy 454.344786 -75.377294) (xy 454.337386 -75.37045) (xy 454.318789 -75.362722) (xy 454.308718 -75.362308)
			(xy 404.537164 -75.362308) (xy 404.534116 -75.362816) (xy 404.505414 -75.365102) (xy 404.504906 -75.365102)
			(xy 404.494238 -75.365356) (xy 404.410164 -75.365356) (xy 404.405846 -75.367134) (xy 403.631908 -76.141072)
			(xy 403.629368 -76.143866) (xy 403.616414 -76.15682) (xy 403.615144 -76.159868) (xy 403.615144 -77.175106)
			(xy 430.18405 -77.175106) (xy 430.188121 -77.119484) (xy 430.200247 -77.065047) (xy 430.22017 -77.012956)
			(xy 430.247466 -76.964321) (xy 430.281552 -76.920178) (xy 430.321701 -76.881469) (xy 430.367059 -76.849018)
			(xy 430.416659 -76.823517) (xy 430.469443 -76.80551) (xy 430.524286 -76.79538) (xy 430.58002 -76.793343)
			(xy 430.635457 -76.799443) (xy 430.689414 -76.813549) (xy 430.740743 -76.835361) (xy 430.788349 -76.864415)
			(xy 430.831217 -76.90009) (xy 430.868434 -76.941627) (xy 430.899207 -76.98814) (xy 430.922879 -77.038637)
			(xy 430.938947 -77.092044) (xy 430.947067 -77.14722) (xy 430.947576 -77.175106) (xy 430.947067 -77.202992)
			(xy 430.938947 -77.258168) (xy 430.922879 -77.311575) (xy 430.899207 -77.362072) (xy 430.868434 -77.408585)
			(xy 430.831217 -77.450122) (xy 430.788349 -77.485797) (xy 430.740743 -77.514851) (xy 430.689414 -77.536663)
			(xy 430.635457 -77.550769) (xy 430.58002 -77.556869) (xy 430.524286 -77.554832) (xy 430.469443 -77.544702)
			(xy 430.416659 -77.526695) (xy 430.367059 -77.501194) (xy 430.321701 -77.468743) (xy 430.281552 -77.430034)
			(xy 430.247466 -77.385891) (xy 430.22017 -77.337256) (xy 430.200247 -77.285165) (xy 430.188121 -77.230728)
			(xy 430.18405 -77.175106) (xy 403.615144 -77.175106) (xy 403.615144 -80.019906) (xy 420.800782 -80.019906)
			(xy 420.804853 -79.964284) (xy 420.816979 -79.909847) (xy 420.836902 -79.857756) (xy 420.864198 -79.809121)
			(xy 420.898284 -79.764978) (xy 420.938433 -79.726269) (xy 420.983791 -79.693818) (xy 421.033391 -79.668317)
			(xy 421.086175 -79.65031) (xy 421.141018 -79.64018) (xy 421.196752 -79.638143) (xy 421.252189 -79.644243)
			(xy 421.306146 -79.658349) (xy 421.357475 -79.680161) (xy 421.405081 -79.709215) (xy 421.447949 -79.74489)
			(xy 421.485166 -79.786427) (xy 421.515939 -79.83294) (xy 421.539611 -79.883437) (xy 421.555679 -79.936844)
			(xy 421.562333 -79.98206) (xy 427.948088 -79.98206) (xy 427.952159 -79.926438) (xy 427.964285 -79.872001)
			(xy 427.984208 -79.81991) (xy 428.011504 -79.771275) (xy 428.04559 -79.727132) (xy 428.085739 -79.688423)
			(xy 428.131097 -79.655972) (xy 428.180697 -79.630471) (xy 428.233481 -79.612464) (xy 428.288324 -79.602334)
			(xy 428.344058 -79.600297) (xy 428.399495 -79.606397) (xy 428.453452 -79.620503) (xy 428.504781 -79.642315)
			(xy 428.552387 -79.671369) (xy 428.595255 -79.707044) (xy 428.632472 -79.748581) (xy 428.663245 -79.795094)
			(xy 428.686917 -79.845591) (xy 428.702985 -79.898998) (xy 428.711105 -79.954174) (xy 428.711614 -79.98206)
			(xy 428.711105 -80.009946) (xy 428.702985 -80.065122) (xy 428.686917 -80.118529) (xy 428.663245 -80.169026)
			(xy 428.632472 -80.215539) (xy 428.595255 -80.257076) (xy 428.552387 -80.292751) (xy 428.504781 -80.321805)
			(xy 428.453452 -80.343617) (xy 428.399495 -80.357723) (xy 428.344058 -80.363823) (xy 428.288324 -80.361786)
			(xy 428.233481 -80.351656) (xy 428.180697 -80.333649) (xy 428.131097 -80.308148) (xy 428.085739 -80.275697)
			(xy 428.04559 -80.236988) (xy 428.011504 -80.192845) (xy 427.984208 -80.14421) (xy 427.964285 -80.092119)
			(xy 427.952159 -80.037682) (xy 427.948088 -79.98206) (xy 421.562333 -79.98206) (xy 421.563799 -79.99202)
			(xy 421.564308 -80.019906) (xy 421.563799 -80.047792) (xy 421.555679 -80.102968) (xy 421.539611 -80.156375)
			(xy 421.515939 -80.206872) (xy 421.485166 -80.253385) (xy 421.447949 -80.294922) (xy 421.405081 -80.330597)
			(xy 421.357475 -80.359651) (xy 421.306146 -80.381463) (xy 421.252189 -80.395569) (xy 421.196752 -80.401669)
			(xy 421.141018 -80.399632) (xy 421.086175 -80.389502) (xy 421.033391 -80.371495) (xy 420.983791 -80.345994)
			(xy 420.938433 -80.313543) (xy 420.898284 -80.274834) (xy 420.864198 -80.230691) (xy 420.836902 -80.182056)
			(xy 420.816979 -80.129965) (xy 420.804853 -80.075528) (xy 420.800782 -80.019906) (xy 403.615144 -80.019906)
			(xy 403.615144 -80.449674) (xy 426.661324 -80.449674) (xy 426.665395 -80.394052) (xy 426.677521 -80.339615)
			(xy 426.697444 -80.287524) (xy 426.72474 -80.238889) (xy 426.758826 -80.194746) (xy 426.798975 -80.156037)
			(xy 426.844333 -80.123586) (xy 426.893933 -80.098085) (xy 426.946717 -80.080078) (xy 427.00156 -80.069948)
			(xy 427.057294 -80.067911) (xy 427.112731 -80.074011) (xy 427.166688 -80.088117) (xy 427.218017 -80.109929)
			(xy 427.265623 -80.138983) (xy 427.308491 -80.174658) (xy 427.345708 -80.216195) (xy 427.376481 -80.262708)
			(xy 427.400153 -80.313205) (xy 427.416221 -80.366612) (xy 427.424341 -80.421788) (xy 427.42485 -80.449674)
			(xy 427.424341 -80.47756) (xy 427.416221 -80.532736) (xy 427.400153 -80.586143) (xy 427.376481 -80.63664)
			(xy 427.345708 -80.683153) (xy 427.308491 -80.72469) (xy 427.265623 -80.760365) (xy 427.218017 -80.789419)
			(xy 427.166688 -80.811231) (xy 427.112731 -80.825337) (xy 427.057294 -80.831437) (xy 427.00156 -80.8294)
			(xy 426.946717 -80.81927) (xy 426.893933 -80.801263) (xy 426.844333 -80.775762) (xy 426.798975 -80.743311)
			(xy 426.758826 -80.704602) (xy 426.72474 -80.660459) (xy 426.697444 -80.611824) (xy 426.677521 -80.559733)
			(xy 426.665395 -80.505296) (xy 426.661324 -80.449674) (xy 403.615144 -80.449674) (xy 403.615144 -81.698846)
			(xy 429.1617 -81.698846) (xy 429.165771 -81.643224) (xy 429.177897 -81.588787) (xy 429.19782 -81.536696)
			(xy 429.225116 -81.488061) (xy 429.259202 -81.443918) (xy 429.299351 -81.405209) (xy 429.344709 -81.372758)
			(xy 429.394309 -81.347257) (xy 429.447093 -81.32925) (xy 429.501936 -81.31912) (xy 429.55767 -81.317083)
			(xy 429.613107 -81.323183) (xy 429.667064 -81.337289) (xy 429.718393 -81.359101) (xy 429.765999 -81.388155)
			(xy 429.808867 -81.42383) (xy 429.846084 -81.465367) (xy 429.876857 -81.51188) (xy 429.900529 -81.562377)
			(xy 429.916597 -81.615784) (xy 429.924717 -81.67096) (xy 429.925226 -81.698846) (xy 429.924717 -81.726732)
			(xy 429.916597 -81.781908) (xy 429.900529 -81.835315) (xy 429.876857 -81.885812) (xy 429.846084 -81.932325)
			(xy 429.808867 -81.973862) (xy 429.765999 -82.009537) (xy 429.718393 -82.038591) (xy 429.667064 -82.060403)
			(xy 429.613107 -82.074509) (xy 429.55767 -82.080609) (xy 429.501936 -82.078572) (xy 429.447093 -82.068442)
			(xy 429.394309 -82.050435) (xy 429.344709 -82.024934) (xy 429.299351 -81.992483) (xy 429.259202 -81.953774)
			(xy 429.225116 -81.909631) (xy 429.19782 -81.860996) (xy 429.177897 -81.808905) (xy 429.165771 -81.754468)
			(xy 429.1617 -81.698846) (xy 403.615144 -81.698846) (xy 403.615144 -82.331306) (xy 424.871386 -82.331306)
			(xy 424.875457 -82.275684) (xy 424.887583 -82.221247) (xy 424.907506 -82.169156) (xy 424.934802 -82.120521)
			(xy 424.968888 -82.076378) (xy 425.009037 -82.037669) (xy 425.054395 -82.005218) (xy 425.103995 -81.979717)
			(xy 425.156779 -81.96171) (xy 425.211622 -81.95158) (xy 425.267356 -81.949543) (xy 425.322793 -81.955643)
			(xy 425.37675 -81.969749) (xy 425.428079 -81.991561) (xy 425.475685 -82.020615) (xy 425.518553 -82.05629)
			(xy 425.55577 -82.097827) (xy 425.586543 -82.14434) (xy 425.610215 -82.194837) (xy 425.626283 -82.248244)
			(xy 425.634403 -82.30342) (xy 425.634912 -82.331306) (xy 425.634403 -82.359192) (xy 425.626284 -82.414364)
			(xy 425.781722 -82.414364) (xy 425.785793 -82.358742) (xy 425.797919 -82.304305) (xy 425.817842 -82.252214)
			(xy 425.845138 -82.203579) (xy 425.879224 -82.159436) (xy 425.919373 -82.120727) (xy 425.964731 -82.088276)
			(xy 426.014331 -82.062775) (xy 426.067115 -82.044768) (xy 426.121958 -82.034638) (xy 426.177692 -82.032601)
			(xy 426.233129 -82.038701) (xy 426.287086 -82.052807) (xy 426.338415 -82.074619) (xy 426.386021 -82.103673)
			(xy 426.428889 -82.139348) (xy 426.466106 -82.180885) (xy 426.496879 -82.227398) (xy 426.520551 -82.277895)
			(xy 426.536619 -82.331302) (xy 426.544739 -82.386478) (xy 426.545248 -82.414364) (xy 426.545007 -82.427572)
			(xy 427.232824 -82.427572) (xy 427.236895 -82.37195) (xy 427.249021 -82.317513) (xy 427.268944 -82.265422)
			(xy 427.29624 -82.216787) (xy 427.330326 -82.172644) (xy 427.370475 -82.133935) (xy 427.415833 -82.101484)
			(xy 427.465433 -82.075983) (xy 427.518217 -82.057976) (xy 427.57306 -82.047846) (xy 427.628794 -82.045809)
			(xy 427.684231 -82.051909) (xy 427.738188 -82.066015) (xy 427.789517 -82.087827) (xy 427.837123 -82.116881)
			(xy 427.879991 -82.152556) (xy 427.917208 -82.194093) (xy 427.947981 -82.240606) (xy 427.971653 -82.291103)
			(xy 427.987721 -82.34451) (xy 427.995841 -82.399686) (xy 427.99635 -82.427572) (xy 427.995841 -82.455458)
			(xy 427.987721 -82.510634) (xy 427.971653 -82.564041) (xy 427.947981 -82.614538) (xy 427.917208 -82.661051)
			(xy 427.879991 -82.702588) (xy 427.837123 -82.738263) (xy 427.789517 -82.767317) (xy 427.738188 -82.789129)
			(xy 427.684231 -82.803235) (xy 427.628794 -82.809335) (xy 427.57306 -82.807298) (xy 427.518217 -82.797168)
			(xy 427.465433 -82.779161) (xy 427.415833 -82.75366) (xy 427.370475 -82.721209) (xy 427.330326 -82.6825)
			(xy 427.29624 -82.638357) (xy 427.268944 -82.589722) (xy 427.249021 -82.537631) (xy 427.236895 -82.483194)
			(xy 427.232824 -82.427572) (xy 426.545007 -82.427572) (xy 426.544739 -82.44225) (xy 426.536619 -82.497426)
			(xy 426.520551 -82.550833) (xy 426.496879 -82.60133) (xy 426.466106 -82.647843) (xy 426.428889 -82.68938)
			(xy 426.386021 -82.725055) (xy 426.338415 -82.754109) (xy 426.287086 -82.775921) (xy 426.233129 -82.790027)
			(xy 426.177692 -82.796127) (xy 426.121958 -82.79409) (xy 426.067115 -82.78396) (xy 426.014331 -82.765953)
			(xy 425.964731 -82.740452) (xy 425.919373 -82.708001) (xy 425.879224 -82.669292) (xy 425.845138 -82.625149)
			(xy 425.817842 -82.576514) (xy 425.797919 -82.524423) (xy 425.785793 -82.469986) (xy 425.781722 -82.414364)
			(xy 425.626284 -82.414364) (xy 425.626283 -82.414368) (xy 425.610215 -82.467775) (xy 425.586543 -82.518272)
			(xy 425.55577 -82.564785) (xy 425.518553 -82.606322) (xy 425.475685 -82.641997) (xy 425.428079 -82.671051)
			(xy 425.37675 -82.692863) (xy 425.322793 -82.706969) (xy 425.267356 -82.713069) (xy 425.211622 -82.711032)
			(xy 425.156779 -82.700902) (xy 425.103995 -82.682895) (xy 425.054395 -82.657394) (xy 425.009037 -82.624943)
			(xy 424.968888 -82.586234) (xy 424.934802 -82.542091) (xy 424.907506 -82.493456) (xy 424.887583 -82.441365)
			(xy 424.875457 -82.386928) (xy 424.871386 -82.331306) (xy 403.615144 -82.331306) (xy 403.615144 -84.410804)
			(xy 408.03703 -84.410804) (xy 408.037528 -84.383158) (xy 408.045502 -84.328444) (xy 408.061298 -84.275456)
			(xy 408.084585 -84.225307) (xy 408.114873 -84.179049) (xy 408.151527 -84.137652) (xy 408.193778 -84.101986)
			(xy 408.240738 -84.072799) (xy 408.265884 -84.0613) (xy 408.278222 -84.055474) (xy 408.299421 -84.038308)
			(xy 408.315322 -84.016145) (xy 408.324793 -83.990564) (xy 408.327157 -83.963389) (xy 408.322247 -83.936557)
			(xy 408.310412 -83.911981) (xy 408.292496 -83.891411) (xy 408.281378 -83.8835) (xy 408.259316 -83.868279)
			(xy 408.21932 -83.832594) (xy 408.184711 -83.791663) (xy 408.15617 -83.746293) (xy 408.134258 -83.697376)
			(xy 408.119405 -83.645874) (xy 408.111905 -83.5928) (xy 408.111452 -83.566) (xy 408.111938 -83.538749)
			(xy 408.119694 -83.484801) (xy 408.135049 -83.432506) (xy 408.157691 -83.382929) (xy 408.187157 -83.337079)
			(xy 408.222848 -83.295888) (xy 408.264039 -83.260197) (xy 408.309889 -83.230731) (xy 408.359466 -83.208089)
			(xy 408.411761 -83.192734) (xy 408.465709 -83.184978) (xy 408.520211 -83.184978) (xy 408.574159 -83.192734)
			(xy 408.626454 -83.208089) (xy 408.676031 -83.230731) (xy 408.721881 -83.260197) (xy 408.763072 -83.295888)
			(xy 408.798763 -83.337079) (xy 408.828229 -83.382929) (xy 408.850871 -83.432506) (xy 408.866226 -83.484801)
			(xy 408.873982 -83.538749) (xy 408.874468 -83.566) (xy 408.873974 -83.593646) (xy 408.866 -83.64836)
			(xy 408.850203 -83.701348) (xy 408.826916 -83.751497) (xy 408.796627 -83.797756) (xy 408.759973 -83.839152)
			(xy 408.717721 -83.874818) (xy 408.67076 -83.904005) (xy 408.645614 -83.915504) (xy 408.633273 -83.921324)
			(xy 408.612074 -83.938491) (xy 408.596173 -83.960655) (xy 408.586703 -83.986237) (xy 408.584339 -84.013413)
			(xy 408.58925 -84.040246) (xy 408.601085 -84.064823) (xy 408.619001 -84.085392) (xy 408.63012 -84.093304)
			(xy 408.652184 -84.108523) (xy 408.692179 -84.144209) (xy 408.726788 -84.185139) (xy 408.755329 -84.23051)
			(xy 408.777241 -84.279427) (xy 408.792093 -84.33093) (xy 408.799593 -84.384003) (xy 408.800046 -84.410804)
			(xy 408.79956 -84.438055) (xy 408.791804 -84.492003) (xy 408.776449 -84.544298) (xy 408.753807 -84.593875)
			(xy 408.724341 -84.639725) (xy 408.68865 -84.680916) (xy 408.647459 -84.716607) (xy 408.601609 -84.746073)
			(xy 408.552032 -84.768715) (xy 408.499737 -84.78407) (xy 408.445789 -84.791826) (xy 408.391287 -84.791826)
			(xy 408.337339 -84.78407) (xy 408.285044 -84.768715) (xy 408.235467 -84.746073) (xy 408.189617 -84.716607)
			(xy 408.148426 -84.680916) (xy 408.112735 -84.639725) (xy 408.083269 -84.593875) (xy 408.060627 -84.544298)
			(xy 408.045272 -84.492003) (xy 408.037516 -84.438055) (xy 408.03703 -84.410804) (xy 403.615144 -84.410804)
			(xy 403.615144 -84.938108) (xy 413.4612 -84.938108) (xy 413.461671 -84.910698) (xy 413.469516 -84.856442)
			(xy 413.485047 -84.803868) (xy 413.507942 -84.754058) (xy 413.537732 -84.708038) (xy 413.573801 -84.666755)
			(xy 413.594296 -84.648548) (xy 413.601916 -84.641944) (xy 413.61106 -84.624418) (xy 413.617664 -84.542376)
			(xy 413.617927 -84.532498) (xy 413.611929 -84.513689) (xy 413.60598 -84.5058) (xy 413.605726 -84.505546)
			(xy 413.588681 -84.484776) (xy 413.559995 -84.439344) (xy 413.537969 -84.390336) (xy 413.52304 -84.338722)
			(xy 413.515504 -84.285523) (xy 413.515048 -84.258658) (xy 413.515656 -84.228536) (xy 413.525128 -84.169042)
			(xy 413.54383 -84.111774) (xy 413.571298 -84.058156) (xy 413.606849 -84.00952) (xy 413.627824 -83.987894)
			(xy 413.634488 -83.980605) (xy 413.642201 -83.962445) (xy 413.64281 -83.952588) (xy 413.643826 -83.881468)
			(xy 413.643526 -83.871721) (xy 413.636463 -83.853561) (xy 413.63011 -83.846162) (xy 413.629856 -83.845908)
			(xy 413.629602 -83.845654) (xy 413.610051 -83.824261) (xy 413.577007 -83.776651) (xy 413.55154 -83.724593)
			(xy 413.534233 -83.669284) (xy 413.525486 -83.611995) (xy 413.524954 -83.583018) (xy 413.525495 -83.555769)
			(xy 413.533248 -83.501825) (xy 413.548599 -83.449534) (xy 413.571235 -83.399959) (xy 413.600696 -83.354111)
			(xy 413.636382 -83.312921) (xy 413.677566 -83.27723) (xy 413.72341 -83.247762) (xy 413.772981 -83.225118)
			(xy 413.82527 -83.20976) (xy 413.879213 -83.201999) (xy 413.906462 -83.20151) (xy 413.935443 -83.202008)
			(xy 413.992739 -83.210756) (xy 414.048053 -83.228073) (xy 414.100109 -83.25356) (xy 414.147711 -83.286629)
			(xy 414.18976 -83.326519) (xy 414.225291 -83.372313) (xy 414.253484 -83.422955) (xy 414.27369 -83.477279)
			(xy 414.280096 -83.505548) (xy 414.282382 -83.516978) (xy 414.296606 -83.535774) (xy 414.389824 -83.581748)
			(xy 414.412684 -83.582002) (xy 414.423352 -83.576922) (xy 414.448964 -83.565343) (xy 414.50273 -83.548958)
			(xy 414.558317 -83.540633) (xy 414.58642 -83.540092) (xy 414.61367 -83.540579) (xy 414.667616 -83.548338)
			(xy 414.719908 -83.563695) (xy 414.769483 -83.586337) (xy 414.815331 -83.615804) (xy 414.856519 -83.651495)
			(xy 414.892208 -83.692685) (xy 414.921672 -83.738535) (xy 414.944312 -83.788111) (xy 414.959666 -83.840404)
			(xy 414.967422 -83.89435) (xy 414.967422 -83.94885) (xy 414.959666 -84.002796) (xy 414.944312 -84.055089)
			(xy 414.921672 -84.104665) (xy 414.892208 -84.150515) (xy 414.856519 -84.191705) (xy 414.815331 -84.227396)
			(xy 414.769483 -84.256863) (xy 414.719908 -84.279505) (xy 414.667616 -84.294862) (xy 414.61367 -84.302621)
			(xy 414.58642 -84.303108) (xy 414.558746 -84.30261) (xy 414.503979 -84.294596) (xy 414.450943 -84.278763)
			(xy 414.425638 -84.267548) (xy 414.415478 -84.262722) (xy 414.38195 -84.262722) (xy 414.376163 -84.26287)
			(xy 414.364877 -84.265429) (xy 414.359598 -84.267802) (xy 414.287462 -84.303108) (xy 414.272984 -84.321904)
			(xy 414.270946 -84.332318) (xy 424.612054 -84.332318) (xy 424.612493 -84.305713) (xy 424.619873 -84.253019)
			(xy 424.634508 -84.201862) (xy 424.656111 -84.153236) (xy 424.684265 -84.108086) (xy 424.718422 -84.067287)
			(xy 424.757918 -84.031634) (xy 424.779694 -84.016342) (xy 424.791206 -84.008047) (xy 424.809411 -83.986295)
			(xy 424.820927 -83.960373) (xy 424.824864 -83.932282) (xy 424.820917 -83.904192) (xy 424.809392 -83.878274)
			(xy 424.791179 -83.856528) (xy 424.779694 -83.848194) (xy 424.757924 -83.832898) (xy 424.718443 -83.797234)
			(xy 424.684297 -83.756431) (xy 424.656151 -83.711281) (xy 424.634548 -83.66266) (xy 424.619909 -83.611509)
			(xy 424.612516 -83.55882) (xy 424.612054 -83.532218) (xy 424.61254 -83.504967) (xy 424.620296 -83.451019)
			(xy 424.635651 -83.398724) (xy 424.658293 -83.349147) (xy 424.687759 -83.303297) (xy 424.72345 -83.262106)
			(xy 424.764641 -83.226415) (xy 424.810491 -83.196949) (xy 424.860068 -83.174307) (xy 424.912363 -83.158952)
			(xy 424.966311 -83.151196) (xy 425.020813 -83.151196) (xy 425.074761 -83.158952) (xy 425.127056 -83.174307)
			(xy 425.176633 -83.196949) (xy 425.222483 -83.226415) (xy 425.263674 -83.262106) (xy 425.299365 -83.303297)
			(xy 425.328831 -83.349147) (xy 425.351473 -83.398724) (xy 425.366828 -83.451019) (xy 425.374584 -83.504967)
			(xy 425.37507 -83.532218) (xy 425.374648 -83.558823) (xy 425.367263 -83.611518) (xy 425.352625 -83.662675)
			(xy 425.331018 -83.7113) (xy 425.302863 -83.75645) (xy 425.268704 -83.797248) (xy 425.229206 -83.832902)
			(xy 425.20743 -83.848194) (xy 425.195979 -83.856567) (xy 425.177771 -83.8783) (xy 425.166249 -83.904205)
			(xy 425.162303 -83.932282) (xy 425.166239 -83.96036) (xy 425.177752 -83.98627) (xy 425.195952 -84.008009)
			(xy 425.20743 -84.016342) (xy 425.229175 -84.031671) (xy 425.268656 -84.067331) (xy 425.302802 -84.108128)
			(xy 425.330952 -84.153272) (xy 425.352558 -84.201888) (xy 425.367203 -84.253034) (xy 425.374603 -84.305718)
			(xy 425.37507 -84.332318) (xy 425.374584 -84.359569) (xy 425.366828 -84.413517) (xy 425.351473 -84.465812)
			(xy 425.346667 -84.476336) (xy 427.965614 -84.476336) (xy 427.969685 -84.420714) (xy 427.981811 -84.366277)
			(xy 428.001734 -84.314186) (xy 428.02903 -84.265551) (xy 428.063116 -84.221408) (xy 428.103265 -84.182699)
			(xy 428.148623 -84.150248) (xy 428.198223 -84.124747) (xy 428.251007 -84.10674) (xy 428.30585 -84.09661)
			(xy 428.361584 -84.094573) (xy 428.417021 -84.100673) (xy 428.470978 -84.114779) (xy 428.522307 -84.136591)
			(xy 428.569913 -84.165645) (xy 428.612781 -84.20132) (xy 428.649998 -84.242857) (xy 428.659108 -84.256626)
			(xy 435.378352 -84.256626) (xy 435.378824 -84.230469) (xy 435.385969 -84.178644) (xy 435.400128 -84.128282)
			(xy 435.421035 -84.080327) (xy 435.448299 -84.035679) (xy 435.481408 -83.995174) (xy 435.51974 -83.959573)
			(xy 435.540912 -83.944206) (xy 435.545517 -83.940735) (xy 435.553209 -83.932147) (xy 435.556152 -83.927188)
			(xy 435.5589 -83.921928) (xy 435.562107 -83.910504) (xy 435.562502 -83.904582) (xy 435.565804 -83.811618)
			(xy 435.556152 -83.790028) (xy 435.546754 -83.782662) (xy 435.525355 -83.764453) (xy 435.487656 -83.722789)
			(xy 435.456479 -83.676045) (xy 435.432499 -83.625231) (xy 435.416234 -83.571449) (xy 435.408038 -83.515862)
			(xy 435.407562 -83.487768) (xy 435.408065 -83.459285) (xy 435.416547 -83.402953) (xy 435.433303 -83.348507)
			(xy 435.457962 -83.297154) (xy 435.489976 -83.250033) (xy 435.528634 -83.208192) (xy 435.57308 -83.172558)
			(xy 435.622325 -83.143921) (xy 435.648608 -83.13293) (xy 435.65826 -83.12912) (xy 435.672738 -83.114896)
			(xy 435.708806 -83.028536) (xy 435.708806 -83.00847) (xy 435.704742 -82.998818) (xy 435.695092 -82.975116)
			(xy 435.681519 -82.925771) (xy 435.674674 -82.875054) (xy 435.674262 -82.849466) (xy 435.674748 -82.822215)
			(xy 435.682504 -82.768267) (xy 435.697859 -82.715972) (xy 435.720501 -82.666395) (xy 435.749967 -82.620545)
			(xy 435.785658 -82.579354) (xy 435.826849 -82.543663) (xy 435.872699 -82.514197) (xy 435.922276 -82.491555)
			(xy 435.974571 -82.4762) (xy 436.028519 -82.468444) (xy 436.083021 -82.468444) (xy 436.136969 -82.4762)
			(xy 436.189264 -82.491555) (xy 436.238841 -82.514197) (xy 436.284691 -82.543663) (xy 436.325882 -82.579354)
			(xy 436.361573 -82.620545) (xy 436.391039 -82.666395) (xy 436.413681 -82.715972) (xy 436.429036 -82.768267)
			(xy 436.436792 -82.822215) (xy 436.437278 -82.849466) (xy 436.436694 -82.877946) (xy 436.428222 -82.934273)
			(xy 436.411477 -82.988716) (xy 436.38683 -83.040068) (xy 436.354827 -83.087188) (xy 436.31618 -83.129031)
			(xy 436.271745 -83.164669) (xy 436.22251 -83.19331) (xy 436.196232 -83.204304) (xy 436.18658 -83.208114)
			(xy 436.172102 -83.222338) (xy 436.136034 -83.308698) (xy 436.136034 -83.328764) (xy 436.140098 -83.338416)
			(xy 436.149761 -83.362114) (xy 436.163328 -83.41146) (xy 436.170168 -83.462179) (xy 436.170578 -83.487768)
			(xy 436.17013 -83.513926) (xy 436.162985 -83.565753) (xy 436.148824 -83.616117) (xy 436.127913 -83.664073)
			(xy 436.100645 -83.708722) (xy 436.067531 -83.749225) (xy 436.029192 -83.784823) (xy 436.008018 -83.800188)
			(xy 436.003418 -83.803666) (xy 435.995723 -83.812249) (xy 435.992778 -83.817206) (xy 435.990034 -83.822468)
			(xy 435.986824 -83.833891) (xy 435.986428 -83.839812) (xy 435.983126 -83.932776) (xy 435.992778 -83.954366)
			(xy 436.002176 -83.961732) (xy 436.023578 -83.979938) (xy 436.061275 -84.021603) (xy 436.092451 -84.068348)
			(xy 436.116431 -84.119162) (xy 436.132695 -84.172945) (xy 436.140892 -84.228532) (xy 436.141368 -84.256626)
			(xy 436.140882 -84.283877) (xy 436.133126 -84.337825) (xy 436.117771 -84.39012) (xy 436.095129 -84.439697)
			(xy 436.065663 -84.485547) (xy 436.029972 -84.526738) (xy 435.988781 -84.562429) (xy 435.942931 -84.591895)
			(xy 435.893354 -84.614537) (xy 435.841059 -84.629892) (xy 435.787111 -84.637648) (xy 435.732609 -84.637648)
			(xy 435.678661 -84.629892) (xy 435.626366 -84.614537) (xy 435.576789 -84.591895) (xy 435.530939 -84.562429)
			(xy 435.489748 -84.526738) (xy 435.454057 -84.485547) (xy 435.424591 -84.439697) (xy 435.401949 -84.39012)
			(xy 435.386594 -84.337825) (xy 435.378838 -84.283877) (xy 435.378352 -84.256626) (xy 428.659108 -84.256626)
			(xy 428.680771 -84.28937) (xy 428.704443 -84.339867) (xy 428.720511 -84.393274) (xy 428.728631 -84.44845)
			(xy 428.72914 -84.476336) (xy 428.728631 -84.504222) (xy 428.720511 -84.559398) (xy 428.704443 -84.612805)
			(xy 428.680771 -84.663302) (xy 428.656587 -84.699856) (xy 443.540904 -84.699856) (xy 443.544908 -84.494668)
			(xy 443.556915 -84.289792) (xy 443.576906 -84.085541) (xy 443.604851 -83.882226) (xy 443.640707 -83.680155)
			(xy 443.684421 -83.479637) (xy 443.735924 -83.280978) (xy 443.795139 -83.084479) (xy 443.861975 -82.89044)
			(xy 443.936331 -82.699157) (xy 444.018094 -82.51092) (xy 444.107139 -82.326017) (xy 444.20333 -82.144729)
			(xy 444.306521 -81.967332) (xy 444.416555 -81.794095) (xy 444.533264 -81.625284) (xy 444.65647 -81.461155)
			(xy 444.785987 -81.301958) (xy 444.921616 -81.147936) (xy 445.063151 -80.999322) (xy 445.210376 -80.856344)
			(xy 445.363068 -80.719219) (xy 445.520994 -80.588155) (xy 445.683913 -80.463353) (xy 445.851578 -80.345003)
			(xy 446.023732 -80.233284) (xy 446.200114 -80.128367) (xy 446.380455 -80.030412) (xy 446.564481 -79.939568)
			(xy 446.751911 -79.855972) (xy 446.94246 -79.779753) (xy 447.135837 -79.711027) (xy 447.331749 -79.649898)
			(xy 447.529896 -79.596459) (xy 447.729978 -79.550792) (xy 447.931689 -79.512965) (xy 448.134722 -79.483038)
			(xy 448.338769 -79.461055) (xy 448.543518 -79.44705) (xy 448.748657 -79.441044) (xy 448.953874 -79.443046)
			(xy 449.158857 -79.453054) (xy 449.363294 -79.471051) (xy 449.566872 -79.497011) (xy 449.769283 -79.530894)
			(xy 449.970217 -79.572649) (xy 450.16937 -79.622212) (xy 450.366437 -79.679507) (xy 450.561119 -79.744447)
			(xy 450.753119 -79.816933) (xy 450.942144 -79.896856) (xy 451.127907 -79.984092) (xy 451.310125 -80.07851)
			(xy 451.488521 -80.179965) (xy 451.662822 -80.288304) (xy 451.832764 -80.40336) (xy 451.998087 -80.52496)
			(xy 452.15854 -80.652917) (xy 452.313879 -80.787036) (xy 452.463866 -80.927115) (xy 452.608274 -81.072939)
			(xy 452.746882 -81.224285) (xy 452.87948 -81.380925) (xy 453.005866 -81.542619) (xy 453.125846 -81.709121)
			(xy 453.239239 -81.880177) (xy 453.345872 -82.055527) (xy 453.445582 -82.234904) (xy 453.538218 -82.418034)
			(xy 453.623638 -82.60464) (xy 453.701712 -82.794436) (xy 453.772322 -82.987134) (xy 453.835359 -83.18244)
			(xy 453.890729 -83.380056) (xy 453.938346 -83.579683) (xy 453.978138 -83.781015) (xy 454.010045 -83.983747)
			(xy 454.034018 -84.187569) (xy 454.05002 -84.392172) (xy 454.058027 -84.597242) (xy 454.058528 -84.699856)
			(xy 454.058027 -84.80247) (xy 454.05002 -85.00754) (xy 454.034018 -85.212143) (xy 454.010045 -85.415965)
			(xy 453.978138 -85.618697) (xy 453.938346 -85.820029) (xy 453.890729 -86.019656) (xy 453.835359 -86.217272)
			(xy 453.772322 -86.412578) (xy 453.701712 -86.605276) (xy 453.623638 -86.795072) (xy 453.538218 -86.981678)
			(xy 453.445582 -87.164808) (xy 453.345872 -87.344185) (xy 453.239239 -87.519535) (xy 453.125846 -87.690591)
			(xy 453.005866 -87.857093) (xy 452.87948 -88.018787) (xy 452.746882 -88.175427) (xy 452.608274 -88.326773)
			(xy 452.463866 -88.472597) (xy 452.313879 -88.612676) (xy 452.15854 -88.746795) (xy 451.998087 -88.874752)
			(xy 451.832764 -88.996352) (xy 451.662822 -89.111408) (xy 451.488521 -89.219747) (xy 451.310125 -89.321202)
			(xy 451.127907 -89.41562) (xy 450.942144 -89.502856) (xy 450.753119 -89.582779) (xy 450.561119 -89.655265)
			(xy 450.366437 -89.720205) (xy 450.16937 -89.7775) (xy 449.970217 -89.827063) (xy 449.769283 -89.868818)
			(xy 449.566872 -89.902701) (xy 449.363294 -89.928661) (xy 449.158857 -89.946658) (xy 448.953874 -89.956666)
			(xy 448.748657 -89.958668) (xy 448.543518 -89.952662) (xy 448.338769 -89.938657) (xy 448.134722 -89.916674)
			(xy 447.931689 -89.886747) (xy 447.729978 -89.84892) (xy 447.529896 -89.803253) (xy 447.331749 -89.749814)
			(xy 447.135837 -89.688685) (xy 446.94246 -89.619959) (xy 446.751911 -89.54374) (xy 446.564481 -89.460144)
			(xy 446.380455 -89.3693) (xy 446.200114 -89.271345) (xy 446.023732 -89.166428) (xy 445.851578 -89.054709)
			(xy 445.683913 -88.936359) (xy 445.520994 -88.811557) (xy 445.363068 -88.680493) (xy 445.210376 -88.543368)
			(xy 445.063151 -88.40039) (xy 444.921616 -88.251776) (xy 444.785987 -88.097754) (xy 444.65647 -87.938557)
			(xy 444.533264 -87.774428) (xy 444.416555 -87.605617) (xy 444.306521 -87.43238) (xy 444.20333 -87.254983)
			(xy 444.107139 -87.073695) (xy 444.018094 -86.888792) (xy 443.936331 -86.700555) (xy 443.861975 -86.509272)
			(xy 443.795139 -86.315233) (xy 443.735924 -86.118734) (xy 443.684421 -85.920075) (xy 443.640707 -85.719557)
			(xy 443.604851 -85.517486) (xy 443.576906 -85.314171) (xy 443.556915 -85.10992) (xy 443.544908 -84.905044)
			(xy 443.540904 -84.699856) (xy 428.656587 -84.699856) (xy 428.649998 -84.709815) (xy 428.612781 -84.751352)
			(xy 428.569913 -84.787027) (xy 428.522307 -84.816081) (xy 428.470978 -84.837893) (xy 428.417021 -84.851999)
			(xy 428.361584 -84.858099) (xy 428.30585 -84.856062) (xy 428.251007 -84.845932) (xy 428.198223 -84.827925)
			(xy 428.148623 -84.802424) (xy 428.103265 -84.769973) (xy 428.063116 -84.731264) (xy 428.02903 -84.687121)
			(xy 428.001734 -84.638486) (xy 427.981811 -84.586395) (xy 427.969685 -84.531958) (xy 427.965614 -84.476336)
			(xy 425.346667 -84.476336) (xy 425.328831 -84.515389) (xy 425.299365 -84.561239) (xy 425.263674 -84.60243)
			(xy 425.222483 -84.638121) (xy 425.176633 -84.667587) (xy 425.127056 -84.690229) (xy 425.074761 -84.705584)
			(xy 425.020813 -84.71334) (xy 424.966311 -84.71334) (xy 424.912363 -84.705584) (xy 424.860068 -84.690229)
			(xy 424.810491 -84.667587) (xy 424.764641 -84.638121) (xy 424.72345 -84.60243) (xy 424.687759 -84.561239)
			(xy 424.658293 -84.515389) (xy 424.635651 -84.465812) (xy 424.620296 -84.413517) (xy 424.61254 -84.359569)
			(xy 424.612054 -84.332318) (xy 414.270946 -84.332318) (xy 414.270698 -84.333588) (xy 414.265324 -84.358362)
			(xy 414.248847 -84.406303) (xy 414.226174 -84.451644) (xy 414.197703 -84.493588) (xy 414.163935 -84.531398)
			(xy 414.144968 -84.548218) (xy 414.137348 -84.554822) (xy 414.128204 -84.572348) (xy 414.1216 -84.65439)
			(xy 414.121311 -84.664269) (xy 414.127328 -84.683078) (xy 414.133284 -84.690966) (xy 414.133538 -84.69122)
			(xy 414.150577 -84.711995) (xy 414.179262 -84.757426) (xy 414.201288 -84.806433) (xy 414.216218 -84.858046)
			(xy 414.223758 -84.911243) (xy 414.224216 -84.938108) (xy 414.22373 -84.965359) (xy 414.215974 -85.019307)
			(xy 414.200619 -85.071602) (xy 414.177977 -85.121179) (xy 414.148511 -85.167029) (xy 414.11282 -85.20822)
			(xy 414.071629 -85.243911) (xy 414.067656 -85.246464) (xy 415.15868 -85.246464) (xy 415.162751 -85.190842)
			(xy 415.174877 -85.136405) (xy 415.1948 -85.084314) (xy 415.222096 -85.035679) (xy 415.256182 -84.991536)
			(xy 415.296331 -84.952827) (xy 415.341689 -84.920376) (xy 415.391289 -84.894875) (xy 415.444073 -84.876868)
			(xy 415.498916 -84.866738) (xy 415.55465 -84.864701) (xy 415.610087 -84.870801) (xy 415.664044 -84.884907)
			(xy 415.715373 -84.906719) (xy 415.762979 -84.935773) (xy 415.805847 -84.971448) (xy 415.843064 -85.012985)
			(xy 415.873837 -85.059498) (xy 415.897509 -85.109995) (xy 415.913577 -85.163402) (xy 415.921697 -85.218578)
			(xy 415.9219 -85.2297) (xy 416.185602 -85.2297) (xy 416.189673 -85.174078) (xy 416.201799 -85.119641)
			(xy 416.221722 -85.06755) (xy 416.249018 -85.018915) (xy 416.283104 -84.974772) (xy 416.323253 -84.936063)
			(xy 416.368611 -84.903612) (xy 416.418211 -84.878111) (xy 416.470995 -84.860104) (xy 416.525838 -84.849974)
			(xy 416.581572 -84.847937) (xy 416.637009 -84.854037) (xy 416.690966 -84.868143) (xy 416.742295 -84.889955)
			(xy 416.789901 -84.919009) (xy 416.832769 -84.954684) (xy 416.869986 -84.996221) (xy 416.900759 -85.042734)
			(xy 416.924431 -85.093231) (xy 416.940499 -85.146638) (xy 416.948619 -85.201814) (xy 416.949128 -85.2297)
			(xy 416.948619 -85.257586) (xy 416.940499 -85.312762) (xy 416.924431 -85.366169) (xy 416.900759 -85.416666)
			(xy 416.894388 -85.426296) (xy 428.157638 -85.426296) (xy 428.161709 -85.370674) (xy 428.173835 -85.316237)
			(xy 428.193758 -85.264146) (xy 428.221054 -85.215511) (xy 428.25514 -85.171368) (xy 428.295289 -85.132659)
			(xy 428.340647 -85.100208) (xy 428.390247 -85.074707) (xy 428.443031 -85.0567) (xy 428.497874 -85.04657)
			(xy 428.553608 -85.044533) (xy 428.609045 -85.050633) (xy 428.663002 -85.064739) (xy 428.714331 -85.086551)
			(xy 428.761937 -85.115605) (xy 428.804805 -85.15128) (xy 428.842022 -85.192817) (xy 428.872795 -85.23933)
			(xy 428.896467 -85.289827) (xy 428.912535 -85.343234) (xy 428.920655 -85.39841) (xy 428.921164 -85.426296)
			(xy 428.920655 -85.454182) (xy 428.912535 -85.509358) (xy 428.896467 -85.562765) (xy 428.872795 -85.613262)
			(xy 428.842022 -85.659775) (xy 428.804805 -85.701312) (xy 428.761937 -85.736987) (xy 428.714331 -85.766041)
			(xy 428.663002 -85.787853) (xy 428.609045 -85.801959) (xy 428.553608 -85.808059) (xy 428.497874 -85.806022)
			(xy 428.443031 -85.795892) (xy 428.390247 -85.777885) (xy 428.340647 -85.752384) (xy 428.295289 -85.719933)
			(xy 428.25514 -85.681224) (xy 428.221054 -85.637081) (xy 428.193758 -85.588446) (xy 428.173835 -85.536355)
			(xy 428.161709 -85.481918) (xy 428.157638 -85.426296) (xy 416.894388 -85.426296) (xy 416.869986 -85.463179)
			(xy 416.832769 -85.504716) (xy 416.789901 -85.540391) (xy 416.742295 -85.569445) (xy 416.690966 -85.591257)
			(xy 416.637009 -85.605363) (xy 416.581572 -85.611463) (xy 416.525838 -85.609426) (xy 416.470995 -85.599296)
			(xy 416.418211 -85.581289) (xy 416.368611 -85.555788) (xy 416.323253 -85.523337) (xy 416.283104 -85.484628)
			(xy 416.249018 -85.440485) (xy 416.221722 -85.39185) (xy 416.201799 -85.339759) (xy 416.189673 -85.285322)
			(xy 416.185602 -85.2297) (xy 415.9219 -85.2297) (xy 415.922206 -85.246464) (xy 415.921697 -85.27435)
			(xy 415.913577 -85.329526) (xy 415.897509 -85.382933) (xy 415.873837 -85.43343) (xy 415.843064 -85.479943)
			(xy 415.805847 -85.52148) (xy 415.762979 -85.557155) (xy 415.715373 -85.586209) (xy 415.664044 -85.608021)
			(xy 415.610087 -85.622127) (xy 415.55465 -85.628227) (xy 415.498916 -85.62619) (xy 415.444073 -85.61606)
			(xy 415.391289 -85.598053) (xy 415.341689 -85.572552) (xy 415.296331 -85.540101) (xy 415.256182 -85.501392)
			(xy 415.222096 -85.457249) (xy 415.1948 -85.408614) (xy 415.174877 -85.356523) (xy 415.162751 -85.302086)
			(xy 415.15868 -85.246464) (xy 414.067656 -85.246464) (xy 414.025779 -85.273377) (xy 413.976202 -85.296019)
			(xy 413.923907 -85.311374) (xy 413.869959 -85.31913) (xy 413.815457 -85.31913) (xy 413.761509 -85.311374)
			(xy 413.709214 -85.296019) (xy 413.659637 -85.273377) (xy 413.613787 -85.243911) (xy 413.572596 -85.20822)
			(xy 413.536905 -85.167029) (xy 413.507439 -85.121179) (xy 413.484797 -85.071602) (xy 413.469442 -85.019307)
			(xy 413.461686 -84.965359) (xy 413.4612 -84.938108) (xy 403.615144 -84.938108) (xy 403.615144 -86.328504)
			(xy 404.314152 -86.328504) (xy 404.314544 -86.301444) (xy 404.322191 -86.247868) (xy 404.337332 -86.195911)
			(xy 404.359664 -86.146614) (xy 404.388738 -86.100967) (xy 404.42397 -86.059887) (xy 404.464654 -86.024198)
			(xy 404.509972 -85.994617) (xy 404.559017 -85.971736) (xy 404.610802 -85.956015) (xy 404.664289 -85.94777)
			(xy 404.691342 -85.946996) (xy 404.703788 -85.946742) (xy 404.725124 -85.93582) (xy 404.786846 -85.84819)
			(xy 404.790402 -85.824568) (xy 404.786338 -85.81263) (xy 404.776879 -85.782844) (xy 404.766667 -85.721193)
			(xy 404.766018 -85.689948) (xy 404.766018 -85.689694) (xy 404.766504 -85.662443) (xy 404.77426 -85.608495)
			(xy 404.789615 -85.5562) (xy 404.812257 -85.506623) (xy 404.841723 -85.460773) (xy 404.877414 -85.419582)
			(xy 404.918605 -85.383891) (xy 404.964455 -85.354425) (xy 405.014032 -85.331783) (xy 405.066327 -85.316428)
			(xy 405.120275 -85.308672) (xy 405.174777 -85.308672) (xy 405.228725 -85.316428) (xy 405.28102 -85.331783)
			(xy 405.330597 -85.354425) (xy 405.376447 -85.383891) (xy 405.417638 -85.419582) (xy 405.453329 -85.460773)
			(xy 405.482795 -85.506623) (xy 405.505437 -85.5562) (xy 405.520792 -85.608495) (xy 405.528548 -85.662443)
			(xy 405.529034 -85.689694) (xy 405.528555 -85.71675) (xy 405.520911 -85.770318) (xy 405.505774 -85.822269)
			(xy 405.483449 -85.87156) (xy 405.454383 -85.917203) (xy 405.41916 -85.958281) (xy 405.378487 -85.993969)
			(xy 405.333179 -86.023554) (xy 405.284146 -86.046439) (xy 405.23237 -86.062167) (xy 405.178893 -86.070422)
			(xy 405.151844 -86.071202) (xy 405.139398 -86.071456) (xy 405.118062 -86.082378) (xy 405.05634 -86.170008)
			(xy 405.052784 -86.19363) (xy 405.056848 -86.205568) (xy 405.066306 -86.235354) (xy 405.068399 -86.247986)
			(xy 423.538648 -86.247986) (xy 423.542719 -86.192364) (xy 423.554845 -86.137927) (xy 423.574768 -86.085836)
			(xy 423.602064 -86.037201) (xy 423.63615 -85.993058) (xy 423.676299 -85.954349) (xy 423.721657 -85.921898)
			(xy 423.771257 -85.896397) (xy 423.824041 -85.87839) (xy 423.878884 -85.86826) (xy 423.934618 -85.866223)
			(xy 423.990055 -85.872323) (xy 424.044012 -85.886429) (xy 424.095341 -85.908241) (xy 424.142947 -85.937295)
			(xy 424.185815 -85.97297) (xy 424.223032 -86.014507) (xy 424.253805 -86.06102) (xy 424.277477 -86.111517)
			(xy 424.293545 -86.164924) (xy 424.301665 -86.2201) (xy 424.302174 -86.247986) (xy 424.301665 -86.275872)
			(xy 424.293545 -86.331048) (xy 424.277477 -86.384455) (xy 424.253805 -86.434952) (xy 424.223032 -86.481465)
			(xy 424.185949 -86.522852) (xy 434.653391 -86.522852) (xy 434.653391 -86.468348) (xy 434.661149 -86.414399)
			(xy 434.676505 -86.362103) (xy 434.699148 -86.312525) (xy 434.728616 -86.266675) (xy 434.764311 -86.225485)
			(xy 434.805504 -86.189795) (xy 434.851357 -86.160331) (xy 434.900937 -86.137692) (xy 434.953234 -86.122341)
			(xy 435.007184 -86.114589) (xy 435.034436 -86.114128) (xy 435.061805 -86.114638) (xy 435.115983 -86.122446)
			(xy 435.168486 -86.137924) (xy 435.218235 -86.160754) (xy 435.264207 -86.190466) (xy 435.305455 -86.226449)
			(xy 435.341131 -86.267963) (xy 435.370501 -86.314153) (xy 435.382162 -86.338918) (xy 435.388643 -86.352149)
			(xy 435.40789 -86.37444) (xy 435.4327 -86.390307) (xy 435.461009 -86.398428) (xy 435.490458 -86.398126)
			(xy 435.518595 -86.389428) (xy 435.543076 -86.373057) (xy 435.55285 -86.362032) (xy 435.571051 -86.340912)
			(xy 435.612568 -86.303701) (xy 435.659062 -86.272935) (xy 435.709542 -86.249269) (xy 435.762931 -86.23321)
			(xy 435.81809 -86.225098) (xy 435.845966 -86.224618) (xy 435.84622 -86.224618) (xy 435.873472 -86.225053)
			(xy 435.927421 -86.232813) (xy 435.979717 -86.24817) (xy 436.029295 -86.270814) (xy 436.075146 -86.300283)
			(xy 436.116337 -86.335977) (xy 436.152029 -86.37717) (xy 436.181495 -86.423022) (xy 436.204137 -86.472601)
			(xy 436.219492 -86.524898) (xy 436.227248 -86.578848) (xy 436.227248 -86.633352) (xy 436.219492 -86.687302)
			(xy 436.204137 -86.739599) (xy 436.181495 -86.789178) (xy 436.152029 -86.83503) (xy 436.116337 -86.876223)
			(xy 436.075146 -86.911917) (xy 436.029295 -86.941386) (xy 435.979717 -86.96403) (xy 435.927421 -86.979387)
			(xy 435.873472 -86.987147) (xy 435.84622 -86.987634) (xy 435.818849 -86.987183) (xy 435.764667 -86.979369)
			(xy 435.712161 -86.963883) (xy 435.662411 -86.941045) (xy 435.616439 -86.911325) (xy 435.575192 -86.875333)
			(xy 435.539519 -86.833811) (xy 435.510153 -86.787612) (xy 435.498494 -86.762844) (xy 435.491938 -86.749656)
			(xy 435.472702 -86.727377) (xy 435.447906 -86.711517) (xy 435.419615 -86.703394) (xy 435.390182 -86.703686)
			(xy 435.362057 -86.712368) (xy 435.337581 -86.728717) (xy 435.327806 -86.73973) (xy 435.30962 -86.760863)
			(xy 435.268101 -86.798075) (xy 435.221604 -86.82884) (xy 435.171121 -86.852504) (xy 435.117729 -86.86856)
			(xy 435.062567 -86.876667) (xy 435.03469 -86.877144) (xy 435.034436 -86.877144) (xy 435.007184 -86.876611)
			(xy 434.953234 -86.868859) (xy 434.900937 -86.853508) (xy 434.851357 -86.830869) (xy 434.805504 -86.801405)
			(xy 434.764311 -86.765715) (xy 434.728616 -86.724525) (xy 434.699148 -86.678675) (xy 434.676505 -86.629097)
			(xy 434.661149 -86.576801) (xy 434.653391 -86.522852) (xy 424.185949 -86.522852) (xy 424.185815 -86.523002)
			(xy 424.142947 -86.558677) (xy 424.095341 -86.587731) (xy 424.044012 -86.609543) (xy 423.990055 -86.623649)
			(xy 423.934618 -86.629749) (xy 423.878884 -86.627712) (xy 423.824041 -86.617582) (xy 423.771257 -86.599575)
			(xy 423.721657 -86.574074) (xy 423.676299 -86.541623) (xy 423.63615 -86.502914) (xy 423.602064 -86.458771)
			(xy 423.574768 -86.410136) (xy 423.554845 -86.358045) (xy 423.542719 -86.303608) (xy 423.538648 -86.247986)
			(xy 405.068399 -86.247986) (xy 405.076519 -86.297005) (xy 405.077168 -86.32825) (xy 405.077168 -86.328504)
			(xy 405.076574 -86.359499) (xy 405.066532 -86.420669) (xy 405.046715 -86.479405) (xy 405.032718 -86.507066)
			(xy 405.026114 -86.519512) (xy 405.027384 -86.546944) (xy 405.083772 -86.63305) (xy 405.089039 -86.640416)
			(xy 405.103571 -86.651195) (xy 405.120951 -86.65622) (xy 405.13 -86.65591) (xy 405.157686 -86.654894)
			(xy 405.18494 -86.65534) (xy 405.238894 -86.663095) (xy 405.291194 -86.67845) (xy 405.340778 -86.701092)
			(xy 405.386634 -86.73056) (xy 405.427829 -86.766254) (xy 405.463526 -86.807447) (xy 405.492996 -86.853301)
			(xy 405.515641 -86.902883) (xy 405.531 -86.955183) (xy 405.538758 -87.009136) (xy 405.538759 -87.04665)
			(xy 406.949662 -87.04665) (xy 406.949662 -86.99215) (xy 406.957417 -86.938203) (xy 406.972771 -86.88591)
			(xy 406.99541 -86.836334) (xy 407.024873 -86.790483) (xy 407.060562 -86.749293) (xy 407.101748 -86.7136)
			(xy 407.147595 -86.684131) (xy 407.197169 -86.661486) (xy 407.24946 -86.646127) (xy 407.303406 -86.638365)
			(xy 407.330656 -86.637876) (xy 407.360001 -86.638465) (xy 407.417997 -86.647469) (xy 407.473932 -86.665239)
			(xy 407.52649 -86.691358) (xy 407.574433 -86.725211) (xy 407.616633 -86.766) (xy 407.652095 -86.812766)
			(xy 407.679984 -86.864406) (xy 407.69032 -86.891876) (xy 407.69032 -86.892384) (xy 407.693908 -86.901167)
			(xy 407.706452 -86.915385) (xy 407.714704 -86.92007) (xy 407.776172 -86.952328) (xy 407.78481 -86.956322)
			(xy 407.803729 -86.958278) (xy 407.813002 -86.956138) (xy 407.81351 -86.956138) (xy 407.83847 -86.949632)
			(xy 407.889574 -86.942627) (xy 407.915364 -86.942168) (xy 407.942617 -86.942677) (xy 407.996568 -86.950429)
			(xy 408.048867 -86.965781) (xy 408.098449 -86.98842) (xy 408.144303 -87.017885) (xy 408.185498 -87.053577)
			(xy 408.221193 -87.094768) (xy 408.250663 -87.14062) (xy 408.273306 -87.190199) (xy 408.288663 -87.242497)
			(xy 408.296421 -87.296447) (xy 408.296421 -87.350953) (xy 408.288663 -87.404903) (xy 408.273306 -87.457201)
			(xy 408.250663 -87.50678) (xy 408.221193 -87.552632) (xy 408.185498 -87.593823) (xy 408.144303 -87.629515)
			(xy 408.098449 -87.65898) (xy 408.048867 -87.681619) (xy 407.996568 -87.696971) (xy 407.942617 -87.704723)
			(xy 407.915364 -87.705184) (xy 407.886018 -87.704604) (xy 407.828021 -87.695602) (xy 407.772084 -87.677833)
			(xy 407.719524 -87.651713) (xy 407.67158 -87.617859) (xy 407.629381 -87.577067) (xy 407.593921 -87.530299)
			(xy 407.566034 -87.478655) (xy 407.5557 -87.451184) (xy 407.5557 -87.450676) (xy 407.552083 -87.441907)
			(xy 407.53956 -87.427681) (xy 407.531316 -87.42299) (xy 407.469848 -87.390732) (xy 407.46119 -87.386804)
			(xy 407.442296 -87.384845) (xy 407.433018 -87.386922) (xy 407.43251 -87.386922) (xy 407.407549 -87.393426)
			(xy 407.356446 -87.400432) (xy 407.330656 -87.400892) (xy 407.303406 -87.400435) (xy 407.24946 -87.392673)
			(xy 407.197169 -87.377314) (xy 407.147595 -87.354669) (xy 407.101748 -87.3252) (xy 407.060561 -87.289507)
			(xy 407.024873 -87.248317) (xy 406.99541 -87.202466) (xy 406.972771 -87.15289) (xy 406.957417 -87.100597)
			(xy 406.949662 -87.04665) (xy 405.538759 -87.04665) (xy 405.53876 -87.063644) (xy 405.531004 -87.117598)
			(xy 405.515648 -87.169898) (xy 405.493006 -87.219481) (xy 405.463538 -87.265337) (xy 405.427843 -87.306532)
			(xy 405.38665 -87.342228) (xy 405.340795 -87.371698) (xy 405.291213 -87.394343) (xy 405.238913 -87.4097)
			(xy 405.18496 -87.417459) (xy 405.130452 -87.41746) (xy 405.076498 -87.409703) (xy 405.024198 -87.394347)
			(xy 404.974615 -87.371704) (xy 404.92876 -87.342235) (xy 404.887565 -87.306541) (xy 404.851869 -87.265346)
			(xy 404.8224 -87.219492) (xy 404.799756 -87.169909) (xy 404.784399 -87.117609) (xy 404.776641 -87.063656)
			(xy 404.776178 -87.036402) (xy 404.776781 -87.005408) (xy 404.78682 -86.944238) (xy 404.806633 -86.885501)
			(xy 404.820628 -86.85784) (xy 404.827232 -86.845394) (xy 404.825962 -86.817962) (xy 404.769574 -86.731856)
			(xy 404.764339 -86.724464) (xy 404.749793 -86.713689) (xy 404.732399 -86.708677) (xy 404.723346 -86.708996)
			(xy 404.69566 -86.710012) (xy 404.668408 -86.709559) (xy 404.614459 -86.701798) (xy 404.562164 -86.686438)
			(xy 404.512587 -86.663792) (xy 404.466737 -86.634322) (xy 404.425547 -86.598627) (xy 404.389856 -86.557434)
			(xy 404.360391 -86.511581) (xy 404.33775 -86.462002) (xy 404.322395 -86.409706) (xy 404.314638 -86.355756)
			(xy 404.314152 -86.328504) (xy 403.615144 -86.328504) (xy 403.615144 -87.78113) (xy 415.281364 -87.78113)
			(xy 415.281924 -87.752012) (xy 415.290765 -87.694452) (xy 415.308246 -87.638903) (xy 415.333962 -87.586653)
			(xy 415.367316 -87.538916) (xy 415.387028 -87.517478) (xy 415.393068 -87.510542) (xy 415.400237 -87.493623)
			(xy 415.400998 -87.484458) (xy 415.403538 -87.417148) (xy 415.40353 -87.40787) (xy 415.397671 -87.390283)
			(xy 415.392108 -87.382858) (xy 415.375713 -87.362285) (xy 415.348139 -87.317483) (xy 415.326987 -87.269316)
			(xy 415.312659 -87.218699) (xy 415.305427 -87.166591) (xy 415.304986 -87.140288) (xy 415.305472 -87.113037)
			(xy 415.313228 -87.059089) (xy 415.328583 -87.006794) (xy 415.351225 -86.957217) (xy 415.380691 -86.911367)
			(xy 415.416382 -86.870176) (xy 415.457573 -86.834485) (xy 415.503423 -86.805019) (xy 415.553 -86.782377)
			(xy 415.605295 -86.767022) (xy 415.659243 -86.759266) (xy 415.713745 -86.759266) (xy 415.767693 -86.767022)
			(xy 415.819988 -86.782377) (xy 415.869565 -86.805019) (xy 415.915415 -86.834485) (xy 415.956606 -86.870176)
			(xy 415.992297 -86.911367) (xy 416.016499 -86.949026) (xy 425.84827 -86.949026) (xy 425.852341 -86.893404)
			(xy 425.864467 -86.838967) (xy 425.88439 -86.786876) (xy 425.911686 -86.738241) (xy 425.945772 -86.694098)
			(xy 425.985921 -86.655389) (xy 426.031279 -86.622938) (xy 426.080879 -86.597437) (xy 426.133663 -86.57943)
			(xy 426.188506 -86.5693) (xy 426.24424 -86.567263) (xy 426.299677 -86.573363) (xy 426.353634 -86.587469)
			(xy 426.404963 -86.609281) (xy 426.452569 -86.638335) (xy 426.495437 -86.67401) (xy 426.532654 -86.715547)
			(xy 426.563427 -86.76206) (xy 426.587099 -86.812557) (xy 426.603167 -86.865964) (xy 426.611287 -86.92114)
			(xy 426.611796 -86.949026) (xy 426.611287 -86.976912) (xy 426.603167 -87.032088) (xy 426.587099 -87.085495)
			(xy 426.563427 -87.135992) (xy 426.532654 -87.182505) (xy 426.495437 -87.224042) (xy 426.452569 -87.259717)
			(xy 426.404963 -87.288771) (xy 426.353634 -87.310583) (xy 426.299677 -87.324689) (xy 426.24424 -87.330789)
			(xy 426.188506 -87.328752) (xy 426.133663 -87.318622) (xy 426.080879 -87.300615) (xy 426.031279 -87.275114)
			(xy 425.985921 -87.242663) (xy 425.945772 -87.203954) (xy 425.911686 -87.159811) (xy 425.88439 -87.111176)
			(xy 425.864467 -87.059085) (xy 425.852341 -87.004648) (xy 425.84827 -86.949026) (xy 416.016499 -86.949026)
			(xy 416.021763 -86.957217) (xy 416.044405 -87.006794) (xy 416.05976 -87.059089) (xy 416.067516 -87.113037)
			(xy 416.068002 -87.140288) (xy 416.067436 -87.169405) (xy 416.058594 -87.226964) (xy 416.041113 -87.282513)
			(xy 416.015399 -87.334763) (xy 415.982048 -87.382501) (xy 415.981486 -87.383112) (xy 434.523386 -87.383112)
			(xy 434.527457 -87.32749) (xy 434.539583 -87.273053) (xy 434.559506 -87.220962) (xy 434.586802 -87.172327)
			(xy 434.620888 -87.128184) (xy 434.661037 -87.089475) (xy 434.706395 -87.057024) (xy 434.755995 -87.031523)
			(xy 434.808779 -87.013516) (xy 434.863622 -87.003386) (xy 434.919356 -87.001349) (xy 434.974793 -87.007449)
			(xy 435.02875 -87.021555) (xy 435.080079 -87.043367) (xy 435.127685 -87.072421) (xy 435.170553 -87.108096)
			(xy 435.20777 -87.149633) (xy 435.238543 -87.196146) (xy 435.262215 -87.246643) (xy 435.278283 -87.30005)
			(xy 435.286403 -87.355226) (xy 435.286912 -87.383112) (xy 435.286403 -87.410998) (xy 435.278283 -87.466174)
			(xy 435.262215 -87.519581) (xy 435.238543 -87.570078) (xy 435.20777 -87.616591) (xy 435.170553 -87.658128)
			(xy 435.127685 -87.693803) (xy 435.080079 -87.722857) (xy 435.02875 -87.744669) (xy 434.974793 -87.758775)
			(xy 434.919356 -87.764875) (xy 434.863622 -87.762838) (xy 434.808779 -87.752708) (xy 434.755995 -87.734701)
			(xy 434.706395 -87.7092) (xy 434.661037 -87.676749) (xy 434.620888 -87.63804) (xy 434.586802 -87.593897)
			(xy 434.559506 -87.545262) (xy 434.539583 -87.493171) (xy 434.527457 -87.438734) (xy 434.523386 -87.383112)
			(xy 415.981486 -87.383112) (xy 415.962338 -87.40394) (xy 415.956286 -87.410867) (xy 415.949125 -87.427793)
			(xy 415.948368 -87.43696) (xy 415.945828 -87.50427) (xy 415.945813 -87.51355) (xy 415.951685 -87.531138)
			(xy 415.957258 -87.53856) (xy 415.973671 -87.55912) (xy 416.00124 -87.603925) (xy 416.022388 -87.652096)
			(xy 416.036712 -87.702717) (xy 416.04394 -87.754826) (xy 416.04438 -87.78113) (xy 416.043894 -87.808381)
			(xy 416.036138 -87.862329) (xy 416.020783 -87.914624) (xy 415.998141 -87.964201) (xy 415.968675 -88.010051)
			(xy 415.932984 -88.051242) (xy 415.891793 -88.086933) (xy 415.845943 -88.116399) (xy 415.796366 -88.139041)
			(xy 415.744071 -88.154396) (xy 415.690123 -88.162152) (xy 415.635621 -88.162152) (xy 415.581673 -88.154396)
			(xy 415.529378 -88.139041) (xy 415.479801 -88.116399) (xy 415.433951 -88.086933) (xy 415.39276 -88.051242)
			(xy 415.357069 -88.010051) (xy 415.327603 -87.964201) (xy 415.304961 -87.914624) (xy 415.289606 -87.862329)
			(xy 415.28185 -87.808381) (xy 415.281364 -87.78113) (xy 403.615144 -87.78113) (xy 403.615144 -88.247728)
			(xy 413.814006 -88.247728) (xy 413.814492 -88.220477) (xy 413.822248 -88.166529) (xy 413.837603 -88.114234)
			(xy 413.860245 -88.064657) (xy 413.889711 -88.018807) (xy 413.925402 -87.977616) (xy 413.966593 -87.941925)
			(xy 414.012443 -87.912459) (xy 414.06202 -87.889817) (xy 414.114315 -87.874462) (xy 414.168263 -87.866706)
			(xy 414.222765 -87.866706) (xy 414.276713 -87.874462) (xy 414.329008 -87.889817) (xy 414.378585 -87.912459)
			(xy 414.424435 -87.941925) (xy 414.465626 -87.977616) (xy 414.501317 -88.018807) (xy 414.530783 -88.064657)
			(xy 414.553425 -88.114234) (xy 414.56878 -88.166529) (xy 414.576536 -88.220477) (xy 414.577022 -88.247728)
			(xy 414.576534 -88.275186) (xy 414.568675 -88.329535) (xy 414.55494 -88.375998) (xy 428.223678 -88.375998)
			(xy 428.227749 -88.320376) (xy 428.239875 -88.265939) (xy 428.259798 -88.213848) (xy 428.287094 -88.165213)
			(xy 428.32118 -88.12107) (xy 428.361329 -88.082361) (xy 428.406687 -88.04991) (xy 428.456287 -88.024409)
			(xy 428.509071 -88.006402) (xy 428.563914 -87.996272) (xy 428.619648 -87.994235) (xy 428.675085 -88.000335)
			(xy 428.729042 -88.014441) (xy 428.780371 -88.036253) (xy 428.827977 -88.065307) (xy 428.870845 -88.100982)
			(xy 428.908062 -88.142519) (xy 428.938835 -88.189032) (xy 428.962507 -88.239529) (xy 428.978575 -88.292936)
			(xy 428.986695 -88.348112) (xy 428.987204 -88.375998) (xy 428.986842 -88.39581) (xy 429.557686 -88.39581)
			(xy 429.561757 -88.340188) (xy 429.573883 -88.285751) (xy 429.593806 -88.23366) (xy 429.621102 -88.185025)
			(xy 429.655188 -88.140882) (xy 429.695337 -88.102173) (xy 429.740695 -88.069722) (xy 429.790295 -88.044221)
			(xy 429.843079 -88.026214) (xy 429.897922 -88.016084) (xy 429.953656 -88.014047) (xy 430.009093 -88.020147)
			(xy 430.06305 -88.034253) (xy 430.114379 -88.056065) (xy 430.161985 -88.085119) (xy 430.204853 -88.120794)
			(xy 430.24207 -88.162331) (xy 430.272843 -88.208844) (xy 430.296515 -88.259341) (xy 430.312583 -88.312748)
			(xy 430.320703 -88.367924) (xy 430.321212 -88.39581) (xy 430.320703 -88.423696) (xy 430.312583 -88.478872)
			(xy 430.296515 -88.532279) (xy 430.272843 -88.582776) (xy 430.24207 -88.629289) (xy 430.204853 -88.670826)
			(xy 430.161985 -88.706501) (xy 430.114379 -88.735555) (xy 430.06305 -88.757367) (xy 430.009093 -88.771473)
			(xy 429.953656 -88.777573) (xy 429.897922 -88.775536) (xy 429.843079 -88.765406) (xy 429.790295 -88.747399)
			(xy 429.740695 -88.721898) (xy 429.695337 -88.689447) (xy 429.655188 -88.650738) (xy 429.621102 -88.606595)
			(xy 429.593806 -88.55796) (xy 429.573883 -88.505869) (xy 429.561757 -88.451432) (xy 429.557686 -88.39581)
			(xy 428.986842 -88.39581) (xy 428.986695 -88.403884) (xy 428.978575 -88.45906) (xy 428.962507 -88.512467)
			(xy 428.938835 -88.562964) (xy 428.908062 -88.609477) (xy 428.870845 -88.651014) (xy 428.827977 -88.686689)
			(xy 428.780371 -88.715743) (xy 428.729042 -88.737555) (xy 428.675085 -88.751661) (xy 428.619648 -88.757761)
			(xy 428.563914 -88.755724) (xy 428.509071 -88.745594) (xy 428.456287 -88.727587) (xy 428.406687 -88.702086)
			(xy 428.361329 -88.669635) (xy 428.32118 -88.630926) (xy 428.287094 -88.586783) (xy 428.259798 -88.538148)
			(xy 428.239875 -88.486057) (xy 428.227749 -88.43162) (xy 428.223678 -88.375998) (xy 414.55494 -88.375998)
			(xy 414.553108 -88.382197) (xy 414.530155 -88.432085) (xy 414.500291 -88.478169) (xy 414.46413 -88.519498)
			(xy 414.42242 -88.555218) (xy 414.399476 -88.570308) (xy 414.387288 -88.57852) (xy 414.367935 -88.600626)
			(xy 414.355681 -88.627329) (xy 414.351542 -88.656416) (xy 414.355861 -88.685477) (xy 414.36828 -88.712104)
			(xy 414.38777 -88.734089) (xy 414.399984 -88.742266) (xy 414.423244 -88.757258) (xy 414.465518 -88.792969)
			(xy 414.502191 -88.83441) (xy 414.532495 -88.880714) (xy 414.555795 -88.930908) (xy 414.571601 -88.983941)
			(xy 414.579583 -89.038701) (xy 414.58007 -89.06637) (xy 414.579584 -89.093621) (xy 414.571828 -89.147569)
			(xy 414.556473 -89.199864) (xy 414.533831 -89.249441) (xy 414.504365 -89.295291) (xy 414.468674 -89.336482)
			(xy 414.427483 -89.372173) (xy 414.381633 -89.401639) (xy 414.332056 -89.424281) (xy 414.31138 -89.430352)
			(xy 419.929816 -89.430352) (xy 419.933887 -89.37473) (xy 419.946013 -89.320293) (xy 419.965936 -89.268202)
			(xy 419.993232 -89.219567) (xy 420.027318 -89.175424) (xy 420.067467 -89.136715) (xy 420.112825 -89.104264)
			(xy 420.162425 -89.078763) (xy 420.215209 -89.060756) (xy 420.270052 -89.050626) (xy 420.325786 -89.048589)
			(xy 420.381223 -89.054689) (xy 420.43518 -89.068795) (xy 420.486509 -89.090607) (xy 420.534115 -89.119661)
			(xy 420.576983 -89.155336) (xy 420.6142 -89.196873) (xy 420.644973 -89.243386) (xy 420.668645 -89.293883)
			(xy 420.684713 -89.34729) (xy 420.692833 -89.402466) (xy 420.693342 -89.430352) (xy 420.692833 -89.458238)
			(xy 420.684713 -89.513414) (xy 420.668645 -89.566821) (xy 420.644973 -89.617318) (xy 420.6142 -89.663831)
			(xy 420.576983 -89.705368) (xy 420.534115 -89.741043) (xy 420.501164 -89.761153) (xy 422.18606 -89.761153)
			(xy 422.18606 -89.706647) (xy 422.193817 -89.652697) (xy 422.209173 -89.6004) (xy 422.231815 -89.55082)
			(xy 422.261282 -89.504968) (xy 422.296976 -89.463776) (xy 422.338168 -89.428082) (xy 422.38402 -89.398615)
			(xy 422.4336 -89.375973) (xy 422.485897 -89.360617) (xy 422.539847 -89.35286) (xy 422.5671 -89.352374)
			(xy 422.594118 -89.352881) (xy 422.64761 -89.360518) (xy 422.699491 -89.375624) (xy 422.748722 -89.397899)
			(xy 422.794318 -89.426895) (xy 422.835368 -89.462034) (xy 422.87105 -89.502612) (xy 422.900651 -89.547818)
			(xy 422.91254 -89.572084) (xy 422.919278 -89.585231) (xy 422.938949 -89.607253) (xy 422.964097 -89.622728)
			(xy 422.992621 -89.630364) (xy 423.022138 -89.629523) (xy 423.050181 -89.620275) (xy 423.074407 -89.603392)
			(xy 423.08399 -89.59215) (xy 423.102187 -89.570117) (xy 423.144068 -89.531242) (xy 423.191278 -89.499046)
			(xy 423.24276 -89.474249) (xy 423.297364 -89.457405) (xy 423.353869 -89.448891) (xy 423.38244 -89.448386)
			(xy 423.409689 -89.448886) (xy 423.463632 -89.456648) (xy 423.515921 -89.472006) (xy 423.565492 -89.494649)
			(xy 423.611337 -89.524116) (xy 423.652522 -89.559807) (xy 423.688208 -89.600995) (xy 423.71767 -89.646843)
			(xy 423.740308 -89.696417) (xy 423.755661 -89.748708) (xy 423.762695 -89.797636) (xy 423.880024 -89.797636)
			(xy 423.884095 -89.742014) (xy 423.896221 -89.687577) (xy 423.916144 -89.635486) (xy 423.94344 -89.586851)
			(xy 423.977526 -89.542708) (xy 424.017675 -89.503999) (xy 424.063033 -89.471548) (xy 424.112633 -89.446047)
			(xy 424.165417 -89.42804) (xy 424.22026 -89.41791) (xy 424.275994 -89.415873) (xy 424.331431 -89.421973)
			(xy 424.385388 -89.436079) (xy 424.436717 -89.457891) (xy 424.484323 -89.486945) (xy 424.527191 -89.52262)
			(xy 424.564408 -89.564157) (xy 424.595181 -89.61067) (xy 424.618853 -89.661167) (xy 424.634921 -89.714574)
			(xy 424.643041 -89.76975) (xy 424.64355 -89.797636) (xy 424.643041 -89.825522) (xy 424.634921 -89.880698)
			(xy 424.633394 -89.885774) (xy 424.743624 -89.885774) (xy 424.747695 -89.830152) (xy 424.759821 -89.775715)
			(xy 424.779744 -89.723624) (xy 424.80704 -89.674989) (xy 424.841126 -89.630846) (xy 424.881275 -89.592137)
			(xy 424.926633 -89.559686) (xy 424.976233 -89.534185) (xy 425.029017 -89.516178) (xy 425.08386 -89.506048)
			(xy 425.139594 -89.504011) (xy 425.195031 -89.510111) (xy 425.248988 -89.524217) (xy 425.300317 -89.546029)
			(xy 425.347923 -89.575083) (xy 425.390791 -89.610758) (xy 425.428008 -89.652295) (xy 425.458781 -89.698808)
			(xy 425.482453 -89.749305) (xy 425.498521 -89.802712) (xy 425.499396 -89.808655) (xy 428.521535 -89.808655)
			(xy 428.521535 -89.754145) (xy 428.529293 -89.700189) (xy 428.544651 -89.647887) (xy 428.567296 -89.598302)
			(xy 428.596768 -89.552446) (xy 428.632466 -89.51125) (xy 428.673663 -89.475555) (xy 428.719522 -89.446086)
			(xy 428.769107 -89.423443) (xy 428.82141 -89.408088) (xy 428.875367 -89.400333) (xy 428.902622 -89.399872)
			(xy 428.929525 -89.400328) (xy 428.982794 -89.407902) (xy 429.034472 -89.422884) (xy 429.083534 -89.444975)
			(xy 429.129006 -89.473738) (xy 429.169988 -89.508603) (xy 429.205666 -89.548878) (xy 429.220884 -89.571068)
			(xy 429.229118 -89.582656) (xy 429.250656 -89.601185) (xy 429.276467 -89.613058) (xy 429.304552 -89.617356)
			(xy 429.332733 -89.613746) (xy 429.358827 -89.602508) (xy 429.380812 -89.584511) (xy 429.389286 -89.5731)
			(xy 429.404651 -89.551764) (xy 429.440252 -89.513075) (xy 429.480831 -89.479645) (xy 429.525618 -89.452107)
			(xy 429.573764 -89.430984) (xy 429.624356 -89.416676) (xy 429.676434 -89.409455) (xy 429.702722 -89.409016)
			(xy 429.729974 -89.409455) (xy 429.783923 -89.417215) (xy 429.836218 -89.432573) (xy 429.885796 -89.455217)
			(xy 429.931646 -89.484685) (xy 429.972836 -89.520379) (xy 430.008528 -89.561571) (xy 430.037994 -89.607424)
			(xy 430.060635 -89.657003) (xy 430.07599 -89.709299) (xy 430.083746 -89.763248) (xy 430.083746 -89.817752)
			(xy 430.07599 -89.871701) (xy 430.060635 -89.923997) (xy 430.037994 -89.973576) (xy 430.008528 -90.019429)
			(xy 429.972836 -90.060621) (xy 429.931646 -90.096315) (xy 429.885796 -90.125783) (xy 429.836218 -90.148427)
			(xy 429.783923 -90.163785) (xy 429.729974 -90.171545) (xy 429.702722 -90.172032) (xy 429.675821 -90.17154)
			(xy 429.622552 -90.163972) (xy 429.570875 -90.148997) (xy 429.521814 -90.126912) (xy 429.476341 -90.098154)
			(xy 429.435359 -90.063294) (xy 429.399679 -90.023023) (xy 429.38446 -90.000836) (xy 429.376297 -89.989194)
			(xy 429.354743 -89.970662) (xy 429.328916 -89.958791) (xy 429.300817 -89.954499) (xy 429.272624 -89.95812)
			(xy 429.246521 -89.969372) (xy 429.224532 -89.987384) (xy 429.216058 -89.998804) (xy 429.200729 -90.020167)
			(xy 429.165122 -90.058855) (xy 429.124537 -90.092283) (xy 429.079744 -90.119818) (xy 429.031591 -90.140937)
			(xy 428.980994 -90.155239) (xy 428.928912 -90.162453) (xy 428.902622 -90.162888) (xy 428.875367 -90.162467)
			(xy 428.82141 -90.154712) (xy 428.769107 -90.139357) (xy 428.719522 -90.116714) (xy 428.673663 -90.087245)
			(xy 428.632466 -90.05155) (xy 428.596768 -90.010354) (xy 428.567296 -89.964498) (xy 428.544651 -89.914913)
			(xy 428.529293 -89.862611) (xy 428.521535 -89.808655) (xy 425.499396 -89.808655) (xy 425.506641 -89.857888)
			(xy 425.50715 -89.885774) (xy 425.506641 -89.91366) (xy 425.498521 -89.968836) (xy 425.482453 -90.022243)
			(xy 425.458781 -90.07274) (xy 425.428008 -90.119253) (xy 425.390791 -90.16079) (xy 425.347923 -90.196465)
			(xy 425.300317 -90.225519) (xy 425.248988 -90.247331) (xy 425.195031 -90.261437) (xy 425.139594 -90.267537)
			(xy 425.08386 -90.2655) (xy 425.029017 -90.25537) (xy 424.976233 -90.237363) (xy 424.926633 -90.211862)
			(xy 424.881275 -90.179411) (xy 424.841126 -90.140702) (xy 424.80704 -90.096559) (xy 424.779744 -90.047924)
			(xy 424.759821 -89.995833) (xy 424.747695 -89.941396) (xy 424.743624 -89.885774) (xy 424.633394 -89.885774)
			(xy 424.618853 -89.934105) (xy 424.595181 -89.984602) (xy 424.564408 -90.031115) (xy 424.527191 -90.072652)
			(xy 424.484323 -90.108327) (xy 424.436717 -90.137381) (xy 424.385388 -90.159193) (xy 424.331431 -90.173299)
			(xy 424.275994 -90.179399) (xy 424.22026 -90.177362) (xy 424.165417 -90.167232) (xy 424.112633 -90.149225)
			(xy 424.063033 -90.123724) (xy 424.017675 -90.091273) (xy 423.977526 -90.052564) (xy 423.94344 -90.008421)
			(xy 423.916144 -89.959786) (xy 423.896221 -89.907695) (xy 423.884095 -89.853258) (xy 423.880024 -89.797636)
			(xy 423.762695 -89.797636) (xy 423.763416 -89.802651) (xy 423.763416 -89.857149) (xy 423.755661 -89.911092)
			(xy 423.740308 -89.963383) (xy 423.71767 -90.012957) (xy 423.688208 -90.058805) (xy 423.652522 -90.099993)
			(xy 423.611337 -90.135684) (xy 423.565492 -90.165151) (xy 423.515921 -90.187794) (xy 423.463632 -90.203152)
			(xy 423.409689 -90.210914) (xy 423.38244 -90.211402) (xy 423.35542 -90.210959) (xy 423.301924 -90.203313)
			(xy 423.250041 -90.188198) (xy 423.200809 -90.165914) (xy 423.155213 -90.136909) (xy 423.114165 -90.101762)
			(xy 423.078485 -90.061175) (xy 423.048887 -90.015961) (xy 423.037 -89.991692) (xy 423.030208 -89.978577)
			(xy 423.010545 -89.956563) (xy 422.985408 -89.941092) (xy 422.956896 -89.933454) (xy 422.927391 -89.934289)
			(xy 422.899357 -89.943525) (xy 422.875134 -89.960392) (xy 422.86555 -89.971626) (xy 422.847325 -89.993634)
			(xy 422.80545 -90.032512) (xy 422.758247 -90.064712) (xy 422.70677 -90.089513) (xy 422.652171 -90.106362)
			(xy 422.59567 -90.114882) (xy 422.5671 -90.11539) (xy 422.539847 -90.11494) (xy 422.485897 -90.107183)
			(xy 422.4336 -90.091827) (xy 422.38402 -90.069185) (xy 422.338168 -90.039718) (xy 422.296976 -90.004024)
			(xy 422.261282 -89.962832) (xy 422.231815 -89.91698) (xy 422.209173 -89.8674) (xy 422.193817 -89.815103)
			(xy 422.18606 -89.761153) (xy 420.501164 -89.761153) (xy 420.486509 -89.770097) (xy 420.43518 -89.791909)
			(xy 420.381223 -89.806015) (xy 420.325786 -89.812115) (xy 420.270052 -89.810078) (xy 420.215209 -89.799948)
			(xy 420.162425 -89.781941) (xy 420.112825 -89.75644) (xy 420.067467 -89.723989) (xy 420.027318 -89.68528)
			(xy 419.993232 -89.641137) (xy 419.965936 -89.592502) (xy 419.946013 -89.540411) (xy 419.933887 -89.485974)
			(xy 419.929816 -89.430352) (xy 414.31138 -89.430352) (xy 414.279761 -89.439636) (xy 414.225813 -89.447392)
			(xy 414.171311 -89.447392) (xy 414.117363 -89.439636) (xy 414.065068 -89.424281) (xy 414.015491 -89.401639)
			(xy 413.969641 -89.372173) (xy 413.92845 -89.336482) (xy 413.892759 -89.295291) (xy 413.863293 -89.249441)
			(xy 413.840651 -89.199864) (xy 413.825296 -89.147569) (xy 413.81754 -89.093621) (xy 413.817054 -89.06637)
			(xy 413.817505 -89.038911) (xy 413.825367 -88.984558) (xy 413.840937 -88.931893) (xy 413.863895 -88.882004)
			(xy 413.893766 -88.83592) (xy 413.929934 -88.794593) (xy 413.971652 -88.758877) (xy 413.9946 -88.74379)
			(xy 414.006783 -88.735575) (xy 414.026121 -88.713465) (xy 414.038365 -88.686764) (xy 414.0425 -88.657683)
			(xy 414.038184 -88.628627) (xy 414.025775 -88.602003) (xy 414.006299 -88.580014) (xy 413.994092 -88.571832)
			(xy 413.970848 -88.556815) (xy 413.928571 -88.521112) (xy 413.891894 -88.479676) (xy 413.861586 -88.433376)
			(xy 413.838284 -88.383185) (xy 413.822476 -88.330154) (xy 413.814493 -88.275396) (xy 413.814006 -88.247728)
			(xy 403.615144 -88.247728) (xy 403.615144 -89.149936) (xy 404.612346 -89.149936) (xy 404.616417 -89.094314)
			(xy 404.628543 -89.039877) (xy 404.648466 -88.987786) (xy 404.675762 -88.939151) (xy 404.709848 -88.895008)
			(xy 404.749997 -88.856299) (xy 404.795355 -88.823848) (xy 404.844955 -88.798347) (xy 404.897739 -88.78034)
			(xy 404.952582 -88.77021) (xy 405.008316 -88.768173) (xy 405.063753 -88.774273) (xy 405.11771 -88.788379)
			(xy 405.169039 -88.810191) (xy 405.216645 -88.839245) (xy 405.259513 -88.87492) (xy 405.29673 -88.916457)
			(xy 405.327503 -88.96297) (xy 405.351175 -89.013467) (xy 405.367243 -89.066874) (xy 405.375363 -89.12205)
			(xy 405.375872 -89.149936) (xy 405.375784 -89.154762) (xy 405.566624 -89.154762) (xy 405.570695 -89.09914)
			(xy 405.582821 -89.044703) (xy 405.602744 -88.992612) (xy 405.63004 -88.943977) (xy 405.664126 -88.899834)
			(xy 405.704275 -88.861125) (xy 405.749633 -88.828674) (xy 405.799233 -88.803173) (xy 405.852017 -88.785166)
			(xy 405.90686 -88.775036) (xy 405.962594 -88.772999) (xy 406.018031 -88.779099) (xy 406.071988 -88.793205)
			(xy 406.123317 -88.815017) (xy 406.170923 -88.844071) (xy 406.213791 -88.879746) (xy 406.251008 -88.921283)
			(xy 406.281781 -88.967796) (xy 406.305453 -89.018293) (xy 406.321521 -89.0717) (xy 406.329641 -89.126876)
			(xy 406.33015 -89.154762) (xy 406.329946 -89.165938) (xy 406.561034 -89.165938) (xy 406.565105 -89.110316)
			(xy 406.577231 -89.055879) (xy 406.597154 -89.003788) (xy 406.62445 -88.955153) (xy 406.658536 -88.91101)
			(xy 406.698685 -88.872301) (xy 406.744043 -88.83985) (xy 406.793643 -88.814349) (xy 406.846427 -88.796342)
			(xy 406.90127 -88.786212) (xy 406.957004 -88.784175) (xy 407.012441 -88.790275) (xy 407.066398 -88.804381)
			(xy 407.117727 -88.826193) (xy 407.165333 -88.855247) (xy 407.208201 -88.890922) (xy 407.245418 -88.932459)
			(xy 407.276191 -88.978972) (xy 407.299863 -89.029469) (xy 407.315931 -89.082876) (xy 407.324051 -89.138052)
			(xy 407.324495 -89.162382) (xy 412.65932 -89.162382) (xy 412.663391 -89.10676) (xy 412.675517 -89.052323)
			(xy 412.69544 -89.000232) (xy 412.722736 -88.951597) (xy 412.756822 -88.907454) (xy 412.796971 -88.868745)
			(xy 412.842329 -88.836294) (xy 412.891929 -88.810793) (xy 412.944713 -88.792786) (xy 412.999556 -88.782656)
			(xy 413.05529 -88.780619) (xy 413.110727 -88.786719) (xy 413.164684 -88.800825) (xy 413.216013 -88.822637)
			(xy 413.263619 -88.851691) (xy 413.306487 -88.887366) (xy 413.343704 -88.928903) (xy 413.374477 -88.975416)
			(xy 413.398149 -89.025913) (xy 413.414217 -89.07932) (xy 413.422337 -89.134496) (xy 413.422846 -89.162382)
			(xy 413.422337 -89.190268) (xy 413.414217 -89.245444) (xy 413.398149 -89.298851) (xy 413.374477 -89.349348)
			(xy 413.343704 -89.395861) (xy 413.306487 -89.437398) (xy 413.263619 -89.473073) (xy 413.216013 -89.502127)
			(xy 413.164684 -89.523939) (xy 413.110727 -89.538045) (xy 413.05529 -89.544145) (xy 412.999556 -89.542108)
			(xy 412.944713 -89.531978) (xy 412.891929 -89.513971) (xy 412.842329 -89.48847) (xy 412.796971 -89.456019)
			(xy 412.756822 -89.41731) (xy 412.722736 -89.373167) (xy 412.69544 -89.324532) (xy 412.675517 -89.272441)
			(xy 412.663391 -89.218004) (xy 412.65932 -89.162382) (xy 407.324495 -89.162382) (xy 407.32456 -89.165938)
			(xy 407.324051 -89.193824) (xy 407.315931 -89.249) (xy 407.299863 -89.302407) (xy 407.276191 -89.352904)
			(xy 407.245418 -89.399417) (xy 407.208201 -89.440954) (xy 407.165333 -89.476629) (xy 407.117727 -89.505683)
			(xy 407.066398 -89.527495) (xy 407.012441 -89.541601) (xy 406.957004 -89.547701) (xy 406.90127 -89.545664)
			(xy 406.846427 -89.535534) (xy 406.793643 -89.517527) (xy 406.744043 -89.492026) (xy 406.698685 -89.459575)
			(xy 406.658536 -89.420866) (xy 406.62445 -89.376723) (xy 406.597154 -89.328088) (xy 406.577231 -89.275997)
			(xy 406.565105 -89.22156) (xy 406.561034 -89.165938) (xy 406.329946 -89.165938) (xy 406.329641 -89.182648)
			(xy 406.321521 -89.237824) (xy 406.305453 -89.291231) (xy 406.281781 -89.341728) (xy 406.251008 -89.388241)
			(xy 406.213791 -89.429778) (xy 406.170923 -89.465453) (xy 406.123317 -89.494507) (xy 406.071988 -89.516319)
			(xy 406.018031 -89.530425) (xy 405.962594 -89.536525) (xy 405.90686 -89.534488) (xy 405.852017 -89.524358)
			(xy 405.799233 -89.506351) (xy 405.749633 -89.48085) (xy 405.704275 -89.448399) (xy 405.664126 -89.40969)
			(xy 405.63004 -89.365547) (xy 405.602744 -89.316912) (xy 405.582821 -89.264821) (xy 405.570695 -89.210384)
			(xy 405.566624 -89.154762) (xy 405.375784 -89.154762) (xy 405.375363 -89.177822) (xy 405.367243 -89.232998)
			(xy 405.351175 -89.286405) (xy 405.327503 -89.336902) (xy 405.29673 -89.383415) (xy 405.259513 -89.424952)
			(xy 405.216645 -89.460627) (xy 405.169039 -89.489681) (xy 405.11771 -89.511493) (xy 405.063753 -89.525599)
			(xy 405.008316 -89.531699) (xy 404.952582 -89.529662) (xy 404.897739 -89.519532) (xy 404.844955 -89.501525)
			(xy 404.795355 -89.476024) (xy 404.749997 -89.443573) (xy 404.709848 -89.404864) (xy 404.675762 -89.360721)
			(xy 404.648466 -89.312086) (xy 404.628543 -89.259995) (xy 404.616417 -89.205558) (xy 404.612346 -89.149936)
			(xy 403.615144 -89.149936) (xy 403.615144 -90.682064) (xy 429.17821 -90.682064) (xy 429.182281 -90.626442)
			(xy 429.194407 -90.572005) (xy 429.21433 -90.519914) (xy 429.241626 -90.471279) (xy 429.275712 -90.427136)
			(xy 429.315861 -90.388427) (xy 429.361219 -90.355976) (xy 429.410819 -90.330475) (xy 429.463603 -90.312468)
			(xy 429.518446 -90.302338) (xy 429.57418 -90.300301) (xy 429.629617 -90.306401) (xy 429.683574 -90.320507)
			(xy 429.734903 -90.342319) (xy 429.782509 -90.371373) (xy 429.825377 -90.407048) (xy 429.862594 -90.448585)
			(xy 429.893367 -90.495098) (xy 429.917039 -90.545595) (xy 429.933107 -90.599002) (xy 429.941227 -90.654178)
			(xy 429.941736 -90.682064) (xy 429.941227 -90.70995) (xy 429.933107 -90.765126) (xy 429.917039 -90.818533)
			(xy 429.893367 -90.86903) (xy 429.862594 -90.915543) (xy 429.825377 -90.95708) (xy 429.782509 -90.992755)
			(xy 429.734903 -91.021809) (xy 429.683574 -91.043621) (xy 429.629617 -91.057727) (xy 429.57418 -91.063827)
			(xy 429.518446 -91.06179) (xy 429.463603 -91.05166) (xy 429.410819 -91.033653) (xy 429.361219 -91.008152)
			(xy 429.315861 -90.975701) (xy 429.275712 -90.936992) (xy 429.241626 -90.892849) (xy 429.21433 -90.844214)
			(xy 429.194407 -90.792123) (xy 429.182281 -90.737686) (xy 429.17821 -90.682064) (xy 403.615144 -90.682064)
			(xy 403.615144 -93.708447) (xy 417.390634 -93.708447) (xy 417.390634 -93.621553) (xy 417.398651 -93.535028)
			(xy 417.414618 -93.449613) (xy 417.438398 -93.366035) (xy 417.469787 -93.285008) (xy 417.508519 -93.207223)
			(xy 417.554263 -93.133343) (xy 417.606628 -93.063999) (xy 417.665168 -92.999782) (xy 417.729383 -92.941241)
			(xy 417.798726 -92.888874) (xy 417.872605 -92.843129) (xy 417.95039 -92.804395) (xy 418.031416 -92.773004)
			(xy 418.114994 -92.749223) (xy 418.200409 -92.733254) (xy 418.286933 -92.725235) (xy 418.33038 -92.724732)
			(xy 420.18458 -92.724732) (xy 420.228031 -92.725198) (xy 420.314564 -92.733214) (xy 420.399987 -92.749182)
			(xy 420.483573 -92.772963) (xy 420.564607 -92.804355) (xy 420.6424 -92.843091) (xy 420.716286 -92.88884)
			(xy 420.785636 -92.941211) (xy 420.849857 -92.999757) (xy 420.908402 -93.06398) (xy 420.960772 -93.133331)
			(xy 421.006519 -93.207218) (xy 421.045253 -93.285011) (xy 421.076644 -93.366046) (xy 421.100423 -93.449632)
			(xy 421.116388 -93.535056) (xy 421.124403 -93.621589) (xy 421.124888 -93.66504) (xy 421.124333 -93.710088)
			(xy 421.115672 -93.799766) (xy 421.098483 -93.888207) (xy 421.072922 -93.974601) (xy 421.056562 -94.016576)
			(xy 421.056562 -94.01683) (xy 421.052244 -94.027752) (xy 421.053006 -94.039182) (xy 421.053535 -94.045129)
			(xy 421.056997 -94.056551) (xy 421.059864 -94.061788) (xy 421.100758 -94.13113) (xy 421.103871 -94.136088)
			(xy 421.111953 -94.144552) (xy 421.11676 -94.147894) (xy 421.117014 -94.147894) (xy 421.121964 -94.150926)
			(xy 421.132864 -94.154908) (xy 421.138604 -94.155768) (xy 421.184559 -94.161986) (xy 421.275264 -94.181321)
			(xy 421.363948 -94.208454) (xy 421.386324 -94.21749) (xy 437.504838 -94.21749) (xy 437.508909 -94.161868)
			(xy 437.521035 -94.107431) (xy 437.540958 -94.05534) (xy 437.568254 -94.006705) (xy 437.60234 -93.962562)
			(xy 437.642489 -93.923853) (xy 437.687847 -93.891402) (xy 437.737447 -93.865901) (xy 437.790231 -93.847894)
			(xy 437.845074 -93.837764) (xy 437.900808 -93.835727) (xy 437.956245 -93.841827) (xy 438.010202 -93.855933)
			(xy 438.061531 -93.877745) (xy 438.109137 -93.906799) (xy 438.152005 -93.942474) (xy 438.187904 -93.98254)
			(xy 442.727078 -93.98254) (xy 442.731149 -93.926918) (xy 442.743275 -93.872481) (xy 442.763198 -93.82039)
			(xy 442.790494 -93.771755) (xy 442.82458 -93.727612) (xy 442.864729 -93.688903) (xy 442.910087 -93.656452)
			(xy 442.959687 -93.630951) (xy 443.012471 -93.612944) (xy 443.067314 -93.602814) (xy 443.123048 -93.600777)
			(xy 443.178485 -93.606877) (xy 443.232442 -93.620983) (xy 443.283771 -93.642795) (xy 443.331377 -93.671849)
			(xy 443.374245 -93.707524) (xy 443.411462 -93.749061) (xy 443.442235 -93.795574) (xy 443.465907 -93.846071)
			(xy 443.481975 -93.899478) (xy 443.490095 -93.954654) (xy 443.490604 -93.98254) (xy 443.490095 -94.010426)
			(xy 443.481975 -94.065602) (xy 443.465907 -94.119009) (xy 443.442235 -94.169506) (xy 443.411462 -94.216019)
			(xy 443.381696 -94.24924) (xy 443.73622 -94.24924) (xy 443.740291 -94.193618) (xy 443.752417 -94.139181)
			(xy 443.77234 -94.08709) (xy 443.799636 -94.038455) (xy 443.833722 -93.994312) (xy 443.873871 -93.955603)
			(xy 443.919229 -93.923152) (xy 443.968829 -93.897651) (xy 444.021613 -93.879644) (xy 444.076456 -93.869514)
			(xy 444.13219 -93.867477) (xy 444.187627 -93.873577) (xy 444.241584 -93.887683) (xy 444.292913 -93.909495)
			(xy 444.340519 -93.938549) (xy 444.383387 -93.974224) (xy 444.420604 -94.015761) (xy 444.451377 -94.062274)
			(xy 444.475049 -94.112771) (xy 444.491117 -94.166178) (xy 444.499237 -94.221354) (xy 444.499746 -94.24924)
			(xy 444.499672 -94.253304) (xy 444.75222 -94.253304) (xy 444.756291 -94.197682) (xy 444.768417 -94.143245)
			(xy 444.78834 -94.091154) (xy 444.815636 -94.042519) (xy 444.849722 -93.998376) (xy 444.889871 -93.959667)
			(xy 444.935229 -93.927216) (xy 444.984829 -93.901715) (xy 445.037613 -93.883708) (xy 445.092456 -93.873578)
			(xy 445.14819 -93.871541) (xy 445.203627 -93.877641) (xy 445.257584 -93.891747) (xy 445.308913 -93.913559)
			(xy 445.356519 -93.942613) (xy 445.399387 -93.978288) (xy 445.436604 -94.019825) (xy 445.467377 -94.066338)
			(xy 445.491049 -94.116835) (xy 445.507117 -94.170242) (xy 445.515237 -94.225418) (xy 445.515282 -94.227904)
			(xy 445.76822 -94.227904) (xy 445.772291 -94.172282) (xy 445.784417 -94.117845) (xy 445.80434 -94.065754)
			(xy 445.831636 -94.017119) (xy 445.865722 -93.972976) (xy 445.905871 -93.934267) (xy 445.951229 -93.901816)
			(xy 446.000829 -93.876315) (xy 446.053613 -93.858308) (xy 446.108456 -93.848178) (xy 446.16419 -93.846141)
			(xy 446.219627 -93.852241) (xy 446.273584 -93.866347) (xy 446.324913 -93.888159) (xy 446.372519 -93.917213)
			(xy 446.415387 -93.952888) (xy 446.452604 -93.994425) (xy 446.483377 -94.040938) (xy 446.507049 -94.091435)
			(xy 446.523117 -94.144842) (xy 446.531237 -94.200018) (xy 446.531746 -94.227904) (xy 446.53131 -94.25178)
			(xy 446.78422 -94.25178) (xy 446.788291 -94.196158) (xy 446.800417 -94.141721) (xy 446.82034 -94.08963)
			(xy 446.847636 -94.040995) (xy 446.881722 -93.996852) (xy 446.921871 -93.958143) (xy 446.967229 -93.925692)
			(xy 447.016829 -93.900191) (xy 447.069613 -93.882184) (xy 447.124456 -93.872054) (xy 447.18019 -93.870017)
			(xy 447.235627 -93.876117) (xy 447.289584 -93.890223) (xy 447.340913 -93.912035) (xy 447.388519 -93.941089)
			(xy 447.431387 -93.976764) (xy 447.468604 -94.018301) (xy 447.499377 -94.064814) (xy 447.523049 -94.115311)
			(xy 447.539117 -94.168718) (xy 447.544949 -94.208346) (xy 448.05422 -94.208346) (xy 448.058291 -94.152724)
			(xy 448.070417 -94.098287) (xy 448.09034 -94.046196) (xy 448.117636 -93.997561) (xy 448.151722 -93.953418)
			(xy 448.191871 -93.914709) (xy 448.237229 -93.882258) (xy 448.286829 -93.856757) (xy 448.339613 -93.83875)
			(xy 448.394456 -93.82862) (xy 448.45019 -93.826583) (xy 448.505627 -93.832683) (xy 448.559584 -93.846789)
			(xy 448.610913 -93.868601) (xy 448.658519 -93.897655) (xy 448.701387 -93.93333) (xy 448.738604 -93.974867)
			(xy 448.769377 -94.02138) (xy 448.793049 -94.071877) (xy 448.809117 -94.125284) (xy 448.817237 -94.18046)
			(xy 448.817746 -94.208346) (xy 448.817237 -94.236232) (xy 448.809117 -94.291408) (xy 448.793049 -94.344815)
			(xy 448.769377 -94.395312) (xy 448.738604 -94.441825) (xy 448.701387 -94.483362) (xy 448.658519 -94.519037)
			(xy 448.610913 -94.548091) (xy 448.559584 -94.569903) (xy 448.505627 -94.584009) (xy 448.45019 -94.590109)
			(xy 448.394456 -94.588072) (xy 448.339613 -94.577942) (xy 448.286829 -94.559935) (xy 448.237229 -94.534434)
			(xy 448.191871 -94.501983) (xy 448.151722 -94.463274) (xy 448.117636 -94.419131) (xy 448.09034 -94.370496)
			(xy 448.070417 -94.318405) (xy 448.058291 -94.263968) (xy 448.05422 -94.208346) (xy 447.544949 -94.208346)
			(xy 447.547237 -94.223894) (xy 447.547746 -94.25178) (xy 447.547237 -94.279666) (xy 447.539117 -94.334842)
			(xy 447.523049 -94.388249) (xy 447.499377 -94.438746) (xy 447.468604 -94.485259) (xy 447.431387 -94.526796)
			(xy 447.388519 -94.562471) (xy 447.340913 -94.591525) (xy 447.289584 -94.613337) (xy 447.235627 -94.627443)
			(xy 447.18019 -94.633543) (xy 447.124456 -94.631506) (xy 447.069613 -94.621376) (xy 447.016829 -94.603369)
			(xy 446.967229 -94.577868) (xy 446.921871 -94.545417) (xy 446.881722 -94.506708) (xy 446.847636 -94.462565)
			(xy 446.82034 -94.41393) (xy 446.800417 -94.361839) (xy 446.788291 -94.307402) (xy 446.78422 -94.25178)
			(xy 446.53131 -94.25178) (xy 446.531237 -94.25579) (xy 446.523117 -94.310966) (xy 446.507049 -94.364373)
			(xy 446.483377 -94.41487) (xy 446.452604 -94.461383) (xy 446.415387 -94.50292) (xy 446.372519 -94.538595)
			(xy 446.324913 -94.567649) (xy 446.273584 -94.589461) (xy 446.219627 -94.603567) (xy 446.16419 -94.609667)
			(xy 446.108456 -94.60763) (xy 446.053613 -94.5975) (xy 446.000829 -94.579493) (xy 445.951229 -94.553992)
			(xy 445.905871 -94.521541) (xy 445.865722 -94.482832) (xy 445.831636 -94.438689) (xy 445.80434 -94.390054)
			(xy 445.784417 -94.337963) (xy 445.772291 -94.283526) (xy 445.76822 -94.227904) (xy 445.515282 -94.227904)
			(xy 445.515746 -94.253304) (xy 445.515237 -94.28119) (xy 445.507117 -94.336366) (xy 445.491049 -94.389773)
			(xy 445.467377 -94.44027) (xy 445.436604 -94.486783) (xy 445.399387 -94.52832) (xy 445.356519 -94.563995)
			(xy 445.308913 -94.593049) (xy 445.257584 -94.614861) (xy 445.203627 -94.628967) (xy 445.14819 -94.635067)
			(xy 445.092456 -94.63303) (xy 445.037613 -94.6229) (xy 444.984829 -94.604893) (xy 444.935229 -94.579392)
			(xy 444.889871 -94.546941) (xy 444.849722 -94.508232) (xy 444.815636 -94.464089) (xy 444.78834 -94.415454)
			(xy 444.768417 -94.363363) (xy 444.756291 -94.308926) (xy 444.75222 -94.253304) (xy 444.499672 -94.253304)
			(xy 444.499237 -94.277126) (xy 444.491117 -94.332302) (xy 444.475049 -94.385709) (xy 444.451377 -94.436206)
			(xy 444.420604 -94.482719) (xy 444.383387 -94.524256) (xy 444.340519 -94.559931) (xy 444.292913 -94.588985)
			(xy 444.241584 -94.610797) (xy 444.187627 -94.624903) (xy 444.13219 -94.631003) (xy 444.076456 -94.628966)
			(xy 444.021613 -94.618836) (xy 443.968829 -94.600829) (xy 443.919229 -94.575328) (xy 443.873871 -94.542877)
			(xy 443.833722 -94.504168) (xy 443.799636 -94.460025) (xy 443.77234 -94.41139) (xy 443.752417 -94.359299)
			(xy 443.740291 -94.304862) (xy 443.73622 -94.24924) (xy 443.381696 -94.24924) (xy 443.374245 -94.257556)
			(xy 443.331377 -94.293231) (xy 443.283771 -94.322285) (xy 443.232442 -94.344097) (xy 443.178485 -94.358203)
			(xy 443.123048 -94.364303) (xy 443.067314 -94.362266) (xy 443.012471 -94.352136) (xy 442.959687 -94.334129)
			(xy 442.910087 -94.308628) (xy 442.864729 -94.276177) (xy 442.82458 -94.237468) (xy 442.790494 -94.193325)
			(xy 442.763198 -94.14469) (xy 442.743275 -94.092599) (xy 442.731149 -94.038162) (xy 442.727078 -93.98254)
			(xy 438.187904 -93.98254) (xy 438.189222 -93.984011) (xy 438.219995 -94.030524) (xy 438.243667 -94.081021)
			(xy 438.259735 -94.134428) (xy 438.267855 -94.189604) (xy 438.268364 -94.21749) (xy 438.267855 -94.245376)
			(xy 438.259735 -94.300552) (xy 438.243667 -94.353959) (xy 438.219995 -94.404456) (xy 438.189222 -94.450969)
			(xy 438.152005 -94.492506) (xy 438.109137 -94.528181) (xy 438.061531 -94.557235) (xy 438.010202 -94.579047)
			(xy 437.956245 -94.593153) (xy 437.900808 -94.599253) (xy 437.845074 -94.597216) (xy 437.790231 -94.587086)
			(xy 437.737447 -94.569079) (xy 437.687847 -94.543578) (xy 437.642489 -94.511127) (xy 437.60234 -94.472418)
			(xy 437.568254 -94.428275) (xy 437.540958 -94.37964) (xy 437.521035 -94.327549) (xy 437.508909 -94.273112)
			(xy 437.504838 -94.21749) (xy 421.386324 -94.21749) (xy 421.449944 -94.243181) (xy 421.532602 -94.285238)
			(xy 421.611298 -94.334309) (xy 421.68544 -94.390024) (xy 421.754468 -94.451961) (xy 421.817861 -94.519655)
			(xy 421.875141 -94.592595) (xy 421.925876 -94.670229) (xy 421.969683 -94.751973) (xy 422.006231 -94.83721)
			(xy 422.035246 -94.925297) (xy 422.056508 -95.01557) (xy 422.069856 -95.107346) (xy 422.07519 -95.199935)
			(xy 422.07247 -95.292638) (xy 422.061717 -95.384754) (xy 422.04301 -95.475591) (xy 422.016493 -95.564461)
			(xy 421.982364 -95.650695) (xy 421.94088 -95.733643) (xy 421.892356 -95.812678) (xy 421.837157 -95.887204)
			(xy 421.775699 -95.95666) (xy 421.740959 -95.989648) (xy 423.864022 -95.989648) (xy 423.868093 -95.934026)
			(xy 423.880219 -95.879589) (xy 423.900142 -95.827498) (xy 423.927438 -95.778863) (xy 423.961524 -95.73472)
			(xy 424.001673 -95.696011) (xy 424.047031 -95.66356) (xy 424.096631 -95.638059) (xy 424.149415 -95.620052)
			(xy 424.204258 -95.609922) (xy 424.259992 -95.607885) (xy 424.315429 -95.613985) (xy 424.369386 -95.628091)
			(xy 424.420715 -95.649903) (xy 424.468321 -95.678957) (xy 424.511189 -95.714632) (xy 424.548406 -95.756169)
			(xy 424.578689 -95.801942) (xy 436.941466 -95.801942) (xy 436.945537 -95.74632) (xy 436.957663 -95.691883)
			(xy 436.977586 -95.639792) (xy 437.004882 -95.591157) (xy 437.038968 -95.547014) (xy 437.079117 -95.508305)
			(xy 437.124475 -95.475854) (xy 437.174075 -95.450353) (xy 437.226859 -95.432346) (xy 437.281702 -95.422216)
			(xy 437.337436 -95.420179) (xy 437.392873 -95.426279) (xy 437.44683 -95.440385) (xy 437.498159 -95.462197)
			(xy 437.545765 -95.491251) (xy 437.588633 -95.526926) (xy 437.62585 -95.568463) (xy 437.656623 -95.614976)
			(xy 437.680295 -95.665473) (xy 437.696363 -95.71888) (xy 437.704483 -95.774056) (xy 437.704992 -95.801942)
			(xy 437.957466 -95.801942) (xy 437.961537 -95.74632) (xy 437.973663 -95.691883) (xy 437.993586 -95.639792)
			(xy 438.020882 -95.591157) (xy 438.054968 -95.547014) (xy 438.095117 -95.508305) (xy 438.140475 -95.475854)
			(xy 438.190075 -95.450353) (xy 438.242859 -95.432346) (xy 438.297702 -95.422216) (xy 438.353436 -95.420179)
			(xy 438.408873 -95.426279) (xy 438.46283 -95.440385) (xy 438.514159 -95.462197) (xy 438.561765 -95.491251)
			(xy 438.604633 -95.526926) (xy 438.64185 -95.568463) (xy 438.672623 -95.614976) (xy 438.696295 -95.665473)
			(xy 438.712363 -95.71888) (xy 438.720483 -95.774056) (xy 438.720992 -95.801942) (xy 438.974736 -95.801942)
			(xy 438.978807 -95.74632) (xy 438.990933 -95.691883) (xy 439.010856 -95.639792) (xy 439.038152 -95.591157)
			(xy 439.072238 -95.547014) (xy 439.112387 -95.508305) (xy 439.157745 -95.475854) (xy 439.207345 -95.450353)
			(xy 439.260129 -95.432346) (xy 439.314972 -95.422216) (xy 439.370706 -95.420179) (xy 439.426143 -95.426279)
			(xy 439.4801 -95.440385) (xy 439.531429 -95.462197) (xy 439.579035 -95.491251) (xy 439.621903 -95.526926)
			(xy 439.65912 -95.568463) (xy 439.689893 -95.614976) (xy 439.710038 -95.65795) (xy 440.264801 -95.65795)
			(xy 440.264801 -95.60345) (xy 440.272557 -95.549505) (xy 440.287912 -95.497214) (xy 440.310552 -95.447639)
			(xy 440.340017 -95.401791) (xy 440.375706 -95.360604) (xy 440.416895 -95.324914) (xy 440.462743 -95.29545)
			(xy 440.512317 -95.27281) (xy 440.564609 -95.257457) (xy 440.618554 -95.249701) (xy 440.645804 -95.249238)
			(xy 440.673197 -95.249735) (xy 440.727421 -95.25756) (xy 440.779968 -95.273062) (xy 440.829756 -95.295922)
			(xy 440.875761 -95.32567) (xy 440.917037 -95.361695) (xy 440.952735 -95.403254) (xy 440.982119 -95.449493)
			(xy 440.993784 -95.474282) (xy 440.999692 -95.486342) (xy 441.016727 -95.50709) (xy 441.038587 -95.522671)
			(xy 441.063758 -95.532004) (xy 441.090492 -95.534441) (xy 441.116935 -95.529815) (xy 441.141254 -95.518445)
			(xy 441.151772 -95.510096) (xy 441.172472 -95.493223) (xy 441.217717 -95.464852) (xy 441.266479 -95.443075)
			(xy 441.317805 -95.428321) (xy 441.370688 -95.420877) (xy 441.39739 -95.420434) (xy 441.397644 -95.420434)
			(xy 441.424896 -95.420839) (xy 441.478845 -95.428601) (xy 441.53114 -95.443962) (xy 441.580717 -95.466608)
			(xy 441.626567 -95.496079) (xy 441.667757 -95.531774) (xy 441.703448 -95.572968) (xy 441.732913 -95.618821)
			(xy 441.755553 -95.668401) (xy 441.770908 -95.720698) (xy 441.778664 -95.774648) (xy 441.778664 -95.801942)
			(xy 442.021466 -95.801942) (xy 442.025537 -95.74632) (xy 442.037663 -95.691883) (xy 442.057586 -95.639792)
			(xy 442.084882 -95.591157) (xy 442.118968 -95.547014) (xy 442.159117 -95.508305) (xy 442.204475 -95.475854)
			(xy 442.254075 -95.450353) (xy 442.306859 -95.432346) (xy 442.361702 -95.422216) (xy 442.417436 -95.420179)
			(xy 442.472873 -95.426279) (xy 442.52683 -95.440385) (xy 442.578159 -95.462197) (xy 442.625765 -95.491251)
			(xy 442.668633 -95.526926) (xy 442.70585 -95.568463) (xy 442.736623 -95.614976) (xy 442.760295 -95.665473)
			(xy 442.776363 -95.71888) (xy 442.784483 -95.774056) (xy 442.784992 -95.801942) (xy 442.784483 -95.829828)
			(xy 442.777338 -95.878378) (xy 447.420115 -95.878378) (xy 447.427868 -95.824421) (xy 447.443221 -95.772116)
			(xy 447.465861 -95.722529) (xy 447.495329 -95.676668) (xy 447.531023 -95.635468) (xy 447.572217 -95.599767)
			(xy 447.618072 -95.570292) (xy 447.667656 -95.547643) (xy 447.719958 -95.532281) (xy 447.773914 -95.524519)
			(xy 447.828426 -95.524515) (xy 447.882383 -95.532268) (xy 447.934688 -95.547622) (xy 447.984275 -95.570263)
			(xy 448.030135 -95.599731) (xy 448.071335 -95.635425) (xy 448.107035 -95.67662) (xy 448.13651 -95.722476)
			(xy 448.159158 -95.77206) (xy 448.17452 -95.824362) (xy 448.182281 -95.878318) (xy 448.182746 -95.905574)
			(xy 448.182746 -95.906082) (xy 448.182663 -95.916454) (xy 448.181521 -95.937166) (xy 448.18046 -95.947484)
			(xy 448.179401 -95.96203) (xy 448.184605 -95.990714) (xy 448.197692 -96.016765) (xy 448.217597 -96.038064)
			(xy 448.242703 -96.052882) (xy 448.27097 -96.060014) (xy 448.3001 -96.05888) (xy 448.314064 -96.054672)
			(xy 448.343673 -96.045318) (xy 448.404939 -96.035236) (xy 448.435984 -96.034606) (xy 448.436238 -96.034606)
			(xy 448.463486 -96.035119) (xy 448.517426 -96.04288) (xy 448.569712 -96.058237) (xy 448.619281 -96.08088)
			(xy 448.665123 -96.110346) (xy 448.706305 -96.146036) (xy 448.741989 -96.187224) (xy 448.771448 -96.233071)
			(xy 448.794083 -96.282643) (xy 448.809433 -96.334932) (xy 448.817185 -96.388873) (xy 448.817182 -96.443368)
			(xy 448.809424 -96.497309) (xy 448.794069 -96.549596) (xy 448.771428 -96.599166) (xy 448.741964 -96.645009)
			(xy 448.706276 -96.686193) (xy 448.66509 -96.721879) (xy 448.619245 -96.75134) (xy 448.569673 -96.773977)
			(xy 448.517385 -96.789329) (xy 448.463444 -96.797084) (xy 448.408949 -96.797084) (xy 448.355008 -96.789328)
			(xy 448.30272 -96.773975) (xy 448.253149 -96.751337) (xy 448.207305 -96.721875) (xy 448.166119 -96.686188)
			(xy 448.130432 -96.645004) (xy 448.100968 -96.59916) (xy 448.078329 -96.54959) (xy 448.062974 -96.497302)
			(xy 448.055217 -96.443362) (xy 448.05473 -96.416114) (xy 448.05473 -96.415606) (xy 448.054812 -96.405234)
			(xy 448.055955 -96.384522) (xy 448.057016 -96.374204) (xy 448.058118 -96.359659) (xy 448.052909 -96.330969)
			(xy 448.039816 -96.304914) (xy 448.019904 -96.283612) (xy 447.99479 -96.268795) (xy 447.966515 -96.261666)
			(xy 447.937378 -96.262804) (xy 447.923412 -96.267016) (xy 447.893805 -96.276375) (xy 447.832537 -96.286454)
			(xy 447.801492 -96.287082) (xy 447.801238 -96.287082) (xy 447.773982 -96.286686) (xy 447.720025 -96.278933)
			(xy 447.66772 -96.263581) (xy 447.618132 -96.240941) (xy 447.572271 -96.211474) (xy 447.531071 -96.17578)
			(xy 447.495369 -96.134586) (xy 447.465894 -96.088731) (xy 447.443244 -96.039148) (xy 447.427882 -95.986846)
			(xy 447.420119 -95.93289) (xy 447.420115 -95.878378) (xy 442.777338 -95.878378) (xy 442.776363 -95.885004)
			(xy 442.760295 -95.938411) (xy 442.736623 -95.988908) (xy 442.70585 -96.035421) (xy 442.668633 -96.076958)
			(xy 442.625765 -96.112633) (xy 442.578159 -96.141687) (xy 442.52683 -96.163499) (xy 442.472873 -96.177605)
			(xy 442.417436 -96.183705) (xy 442.361702 -96.181668) (xy 442.306859 -96.171538) (xy 442.254075 -96.153531)
			(xy 442.204475 -96.12803) (xy 442.159117 -96.095579) (xy 442.118968 -96.05687) (xy 442.084882 -96.012727)
			(xy 442.057586 -95.964092) (xy 442.037663 -95.912001) (xy 442.025537 -95.857564) (xy 442.021466 -95.801942)
			(xy 441.778664 -95.801942) (xy 441.778664 -95.829152) (xy 441.770908 -95.883102) (xy 441.755553 -95.935399)
			(xy 441.732913 -95.984979) (xy 441.703448 -96.030832) (xy 441.667757 -96.072026) (xy 441.626567 -96.107721)
			(xy 441.580717 -96.137192) (xy 441.53114 -96.159838) (xy 441.478845 -96.175199) (xy 441.424896 -96.182961)
			(xy 441.397644 -96.18345) (xy 441.370249 -96.183003) (xy 441.316023 -96.175171) (xy 441.263475 -96.159662)
			(xy 441.213686 -96.136794) (xy 441.167681 -96.107039) (xy 441.126406 -96.071008) (xy 441.09071 -96.029443)
			(xy 441.061328 -95.983198) (xy 441.049664 -95.958406) (xy 441.043827 -95.946308) (xy 441.026779 -95.925557)
			(xy 441.004904 -95.909976) (xy 440.97972 -95.900648) (xy 440.952974 -95.898217) (xy 440.926521 -95.902854)
			(xy 440.902196 -95.914237) (xy 440.891676 -95.922592) (xy 440.870957 -95.939441) (xy 440.825718 -95.967816)
			(xy 440.77696 -95.989598) (xy 440.725639 -96.004358) (xy 440.672759 -96.011808) (xy 440.646058 -96.012254)
			(xy 440.645804 -96.012254) (xy 440.618554 -96.011699) (xy 440.564609 -96.003943) (xy 440.512317 -95.98859)
			(xy 440.462743 -95.96595) (xy 440.416895 -95.936486) (xy 440.375706 -95.900796) (xy 440.340017 -95.859609)
			(xy 440.310552 -95.813761) (xy 440.287912 -95.764186) (xy 440.272557 -95.711895) (xy 440.264801 -95.65795)
			(xy 439.710038 -95.65795) (xy 439.713565 -95.665473) (xy 439.729633 -95.71888) (xy 439.737753 -95.774056)
			(xy 439.738262 -95.801942) (xy 439.737753 -95.829828) (xy 439.729633 -95.885004) (xy 439.713565 -95.938411)
			(xy 439.689893 -95.988908) (xy 439.65912 -96.035421) (xy 439.621903 -96.076958) (xy 439.579035 -96.112633)
			(xy 439.531429 -96.141687) (xy 439.4801 -96.163499) (xy 439.426143 -96.177605) (xy 439.370706 -96.183705)
			(xy 439.314972 -96.181668) (xy 439.260129 -96.171538) (xy 439.207345 -96.153531) (xy 439.157745 -96.12803)
			(xy 439.112387 -96.095579) (xy 439.072238 -96.05687) (xy 439.038152 -96.012727) (xy 439.010856 -95.964092)
			(xy 438.990933 -95.912001) (xy 438.978807 -95.857564) (xy 438.974736 -95.801942) (xy 438.720992 -95.801942)
			(xy 438.720483 -95.829828) (xy 438.712363 -95.885004) (xy 438.696295 -95.938411) (xy 438.672623 -95.988908)
			(xy 438.64185 -96.035421) (xy 438.604633 -96.076958) (xy 438.561765 -96.112633) (xy 438.514159 -96.141687)
			(xy 438.46283 -96.163499) (xy 438.408873 -96.177605) (xy 438.353436 -96.183705) (xy 438.297702 -96.181668)
			(xy 438.242859 -96.171538) (xy 438.190075 -96.153531) (xy 438.140475 -96.12803) (xy 438.095117 -96.095579)
			(xy 438.054968 -96.05687) (xy 438.020882 -96.012727) (xy 437.993586 -95.964092) (xy 437.973663 -95.912001)
			(xy 437.961537 -95.857564) (xy 437.957466 -95.801942) (xy 437.704992 -95.801942) (xy 437.704483 -95.829828)
			(xy 437.696363 -95.885004) (xy 437.680295 -95.938411) (xy 437.656623 -95.988908) (xy 437.62585 -96.035421)
			(xy 437.588633 -96.076958) (xy 437.545765 -96.112633) (xy 437.498159 -96.141687) (xy 437.44683 -96.163499)
			(xy 437.392873 -96.177605) (xy 437.337436 -96.183705) (xy 437.281702 -96.181668) (xy 437.226859 -96.171538)
			(xy 437.174075 -96.153531) (xy 437.124475 -96.12803) (xy 437.079117 -96.095579) (xy 437.038968 -96.05687)
			(xy 437.004882 -96.012727) (xy 436.977586 -95.964092) (xy 436.957663 -95.912001) (xy 436.945537 -95.857564)
			(xy 436.941466 -95.801942) (xy 424.578689 -95.801942) (xy 424.579179 -95.802682) (xy 424.602851 -95.853179)
			(xy 424.618919 -95.906586) (xy 424.627039 -95.961762) (xy 424.627548 -95.989648) (xy 424.627039 -96.017534)
			(xy 424.618919 -96.07271) (xy 424.602851 -96.126117) (xy 424.579179 -96.176614) (xy 424.548406 -96.223127)
			(xy 424.511189 -96.264664) (xy 424.468321 -96.300339) (xy 424.420715 -96.329393) (xy 424.369386 -96.351205)
			(xy 424.315429 -96.365311) (xy 424.259992 -96.371411) (xy 424.204258 -96.369374) (xy 424.149415 -96.359244)
			(xy 424.096631 -96.341237) (xy 424.047031 -96.315736) (xy 424.001673 -96.283285) (xy 423.961524 -96.244576)
			(xy 423.927438 -96.200433) (xy 423.900142 -96.151798) (xy 423.880219 -96.099707) (xy 423.868093 -96.04527)
			(xy 423.864022 -95.989648) (xy 421.740959 -95.989648) (xy 421.708446 -96.020521) (xy 421.635906 -96.078305)
			(xy 421.558625 -96.129577) (xy 421.477187 -96.173949) (xy 421.392205 -96.211088) (xy 421.304321 -96.240713)
			(xy 421.214199 -96.2626) (xy 421.122517 -96.276584) (xy 421.029967 -96.28256) (xy 420.937248 -96.280483)
			(xy 420.845059 -96.270368) (xy 420.754095 -96.252292) (xy 420.665043 -96.226391) (xy 420.578574 -96.192861)
			(xy 420.495341 -96.151954) (xy 420.415971 -96.103979) (xy 420.341064 -96.049298) (xy 420.271184 -95.988323)
			(xy 420.206859 -95.921514) (xy 420.148573 -95.849376) (xy 420.096766 -95.772453) (xy 420.05183 -95.691324)
			(xy 420.014103 -95.606602) (xy 419.98387 -95.518926) (xy 419.961359 -95.428957) (xy 419.946739 -95.337374)
			(xy 419.940121 -95.244868) (xy 419.941556 -95.152137) (xy 419.951031 -95.05988) (xy 419.968476 -94.968793)
			(xy 419.993759 -94.879563) (xy 420.026689 -94.792864) (xy 420.046404 -94.75089) (xy 420.04869 -94.746318)
			(xy 420.04996 -94.741238) (xy 420.051961 -94.731134) (xy 420.048705 -94.710818) (xy 420.04361 -94.701868)
			(xy 419.99789 -94.62897) (xy 419.993044 -94.621868) (xy 419.979555 -94.611221) (xy 419.963304 -94.605633)
			(xy 419.95471 -94.605348) (xy 418.33038 -94.605348) (xy 418.286933 -94.604765) (xy 418.200409 -94.596746)
			(xy 418.114994 -94.580777) (xy 418.031416 -94.556996) (xy 417.95039 -94.525605) (xy 417.872605 -94.486871)
			(xy 417.798726 -94.441126) (xy 417.729383 -94.388759) (xy 417.665168 -94.330218) (xy 417.606628 -94.266001)
			(xy 417.554263 -94.196657) (xy 417.508519 -94.122777) (xy 417.469787 -94.044992) (xy 417.438398 -93.963965)
			(xy 417.414618 -93.880387) (xy 417.398651 -93.794972) (xy 417.390634 -93.708447) (xy 403.615144 -93.708447)
			(xy 403.615144 -95.438051) (xy 405.06726 -95.438051) (xy 405.06726 -95.383549) (xy 405.075016 -95.329602)
			(xy 405.09037 -95.277308) (xy 405.113009 -95.227731) (xy 405.142473 -95.18188) (xy 405.178162 -95.140689)
			(xy 405.21935 -95.104996) (xy 405.265198 -95.075527) (xy 405.314772 -95.052883) (xy 405.367065 -95.037524)
			(xy 405.421011 -95.029762) (xy 405.448262 -95.029274) (xy 405.474997 -95.029709) (xy 405.527944 -95.037171)
			(xy 405.57933 -95.051955) (xy 405.628148 -95.07377) (xy 405.67344 -95.102189) (xy 405.71432 -95.136655)
			(xy 405.732488 -95.156274) (xy 405.739854 -95.164402) (xy 405.759666 -95.173292) (xy 405.85898 -95.171768)
			(xy 405.878538 -95.16237) (xy 405.885904 -95.153734) (xy 405.904148 -95.132833) (xy 405.945595 -95.095957)
			(xy 405.991948 -95.065477) (xy 406.042228 -95.042035) (xy 406.095375 -95.026127) (xy 406.150266 -95.018089)
			(xy 406.178004 -95.01759) (xy 406.178258 -95.01759) (xy 406.205513 -95.018054) (xy 406.259468 -95.025807)
			(xy 406.31177 -95.041159) (xy 406.361356 -95.063799) (xy 406.407214 -95.093266) (xy 406.448411 -95.128959)
			(xy 406.484109 -95.170153) (xy 406.484821 -95.17126) (xy 416.22802 -95.17126) (xy 416.232091 -95.115638)
			(xy 416.244217 -95.061201) (xy 416.26414 -95.00911) (xy 416.291436 -94.960475) (xy 416.325522 -94.916332)
			(xy 416.365671 -94.877623) (xy 416.411029 -94.845172) (xy 416.460629 -94.819671) (xy 416.513413 -94.801664)
			(xy 416.568256 -94.791534) (xy 416.62399 -94.789497) (xy 416.679427 -94.795597) (xy 416.733384 -94.809703)
			(xy 416.784713 -94.831515) (xy 416.832319 -94.860569) (xy 416.875187 -94.896244) (xy 416.912404 -94.937781)
			(xy 416.943177 -94.984294) (xy 416.966849 -95.034791) (xy 416.982917 -95.088198) (xy 416.991037 -95.143374)
			(xy 416.991546 -95.17126) (xy 416.991037 -95.199146) (xy 416.982917 -95.254322) (xy 416.966849 -95.307729)
			(xy 416.943177 -95.358226) (xy 416.912404 -95.404739) (xy 416.875187 -95.446276) (xy 416.832319 -95.481951)
			(xy 416.784713 -95.511005) (xy 416.733384 -95.532817) (xy 416.679427 -95.546923) (xy 416.62399 -95.553023)
			(xy 416.568256 -95.550986) (xy 416.513413 -95.540856) (xy 416.460629 -95.522849) (xy 416.411029 -95.497348)
			(xy 416.365671 -95.464897) (xy 416.325522 -95.426188) (xy 416.291436 -95.382045) (xy 416.26414 -95.33341)
			(xy 416.244217 -95.281319) (xy 416.232091 -95.226882) (xy 416.22802 -95.17126) (xy 406.484821 -95.17126)
			(xy 406.513581 -95.216007) (xy 406.536226 -95.26559) (xy 406.551585 -95.317891) (xy 406.559343 -95.371845)
			(xy 406.559343 -95.426355) (xy 406.551585 -95.480309) (xy 406.536226 -95.53261) (xy 406.513581 -95.582193)
			(xy 406.484109 -95.628047) (xy 406.448411 -95.669241) (xy 406.407214 -95.704934) (xy 406.361356 -95.734401)
			(xy 406.31177 -95.757041) (xy 406.259468 -95.772393) (xy 406.205513 -95.780146) (xy 406.178258 -95.780606)
			(xy 406.151523 -95.780164) (xy 406.098576 -95.772705) (xy 406.04719 -95.757923) (xy 405.998372 -95.736109)
			(xy 405.953079 -95.70769) (xy 405.9122 -95.673225) (xy 405.894032 -95.653606) (xy 405.886666 -95.645478)
			(xy 405.866854 -95.636588) (xy 405.76754 -95.638112) (xy 405.747982 -95.64751) (xy 405.740616 -95.656146)
			(xy 405.722379 -95.677053) (xy 405.680929 -95.713925) (xy 405.634574 -95.744403) (xy 405.584292 -95.767843)
			(xy 405.531145 -95.78375) (xy 405.476254 -95.79179) (xy 405.448516 -95.79229) (xy 405.448262 -95.79229)
			(xy 405.421011 -95.791838) (xy 405.367065 -95.784076) (xy 405.314772 -95.768717) (xy 405.265198 -95.746073)
			(xy 405.21935 -95.716604) (xy 405.178162 -95.680911) (xy 405.142473 -95.63972) (xy 405.113009 -95.593869)
			(xy 405.09037 -95.544292) (xy 405.075016 -95.491998) (xy 405.06726 -95.438051) (xy 403.615144 -95.438051)
			(xy 403.615144 -96.45904) (xy 405.138128 -96.45904) (xy 405.138614 -96.431789) (xy 405.14637 -96.377841)
			(xy 405.161725 -96.325546) (xy 405.184367 -96.275969) (xy 405.213833 -96.230119) (xy 405.249524 -96.188928)
			(xy 405.290715 -96.153237) (xy 405.336565 -96.123771) (xy 405.386142 -96.101129) (xy 405.438437 -96.085774)
			(xy 405.492385 -96.078018) (xy 405.546887 -96.078018) (xy 405.600835 -96.085774) (xy 405.65313 -96.101129)
			(xy 405.702707 -96.123771) (xy 405.748557 -96.153237) (xy 405.789748 -96.188928) (xy 405.825439 -96.230119)
			(xy 405.854905 -96.275969) (xy 405.877547 -96.325546) (xy 405.892902 -96.377841) (xy 405.900307 -96.429346)
			(xy 415.757422 -96.429346) (xy 415.757422 -96.374854) (xy 415.765177 -96.320916) (xy 415.780528 -96.26863)
			(xy 415.803164 -96.219062) (xy 415.832623 -96.173218) (xy 415.868306 -96.132034) (xy 415.909486 -96.096347)
			(xy 415.955326 -96.066883) (xy 416.004893 -96.044242) (xy 416.057177 -96.028885) (xy 416.111114 -96.021125)
			(xy 416.13836 -96.020636) (xy 416.167179 -96.021157) (xy 416.224159 -96.029847) (xy 416.279184 -96.047006)
			(xy 416.331003 -96.072244) (xy 416.378439 -96.104986) (xy 416.420412 -96.144489) (xy 416.455968 -96.189853)
			(xy 416.470592 -96.214692) (xy 416.47853 -96.227544) (xy 416.500395 -96.248359) (xy 416.527391 -96.261871)
			(xy 416.557157 -96.266901) (xy 416.587093 -96.263007) (xy 416.614583 -96.250532) (xy 416.637224 -96.230564)
			(xy 416.645598 -96.217994) (xy 416.660612 -96.194657) (xy 416.696287 -96.152155) (xy 416.737744 -96.115272)
			(xy 416.784109 -96.084786) (xy 416.834402 -96.06134) (xy 416.887561 -96.04543) (xy 416.942465 -96.03739)
			(xy 416.97021 -96.036892) (xy 416.997461 -96.037378) (xy 417.051407 -96.045136) (xy 417.103701 -96.060492)
			(xy 417.153277 -96.083134) (xy 417.199126 -96.1126) (xy 417.240315 -96.148292) (xy 417.276006 -96.189482)
			(xy 417.305471 -96.235332) (xy 417.328111 -96.284908) (xy 417.343466 -96.337202) (xy 417.348895 -96.374966)
			(xy 442.727078 -96.374966) (xy 442.731149 -96.319344) (xy 442.743275 -96.264907) (xy 442.763198 -96.212816)
			(xy 442.790494 -96.164181) (xy 442.82458 -96.120038) (xy 442.864729 -96.081329) (xy 442.910087 -96.048878)
			(xy 442.959687 -96.023377) (xy 443.012471 -96.00537) (xy 443.067314 -95.99524) (xy 443.123048 -95.993203)
			(xy 443.178485 -95.999303) (xy 443.232442 -96.013409) (xy 443.283771 -96.035221) (xy 443.331377 -96.064275)
			(xy 443.374245 -96.09995) (xy 443.411462 -96.141487) (xy 443.442235 -96.188) (xy 443.465907 -96.238497)
			(xy 443.480906 -96.288352) (xy 444.152272 -96.288352) (xy 444.156343 -96.23273) (xy 444.168469 -96.178293)
			(xy 444.188392 -96.126202) (xy 444.215688 -96.077567) (xy 444.249774 -96.033424) (xy 444.289923 -95.994715)
			(xy 444.335281 -95.962264) (xy 444.384881 -95.936763) (xy 444.437665 -95.918756) (xy 444.492508 -95.908626)
			(xy 444.548242 -95.906589) (xy 444.603679 -95.912689) (xy 444.657636 -95.926795) (xy 444.708965 -95.948607)
			(xy 444.756571 -95.977661) (xy 444.799439 -96.013336) (xy 444.836656 -96.054873) (xy 444.867429 -96.101386)
			(xy 444.891101 -96.151883) (xy 444.907169 -96.20529) (xy 444.915289 -96.260466) (xy 444.91552 -96.273112)
			(xy 445.497964 -96.273112) (xy 445.502035 -96.21749) (xy 445.514161 -96.163053) (xy 445.534084 -96.110962)
			(xy 445.56138 -96.062327) (xy 445.595466 -96.018184) (xy 445.635615 -95.979475) (xy 445.680973 -95.947024)
			(xy 445.730573 -95.921523) (xy 445.783357 -95.903516) (xy 445.8382 -95.893386) (xy 445.893934 -95.891349)
			(xy 445.949371 -95.897449) (xy 446.003328 -95.911555) (xy 446.054657 -95.933367) (xy 446.102263 -95.962421)
			(xy 446.145131 -95.998096) (xy 446.182348 -96.039633) (xy 446.213121 -96.086146) (xy 446.236793 -96.136643)
			(xy 446.252861 -96.19005) (xy 446.260981 -96.245226) (xy 446.26149 -96.273112) (xy 446.260981 -96.300998)
			(xy 446.252861 -96.356174) (xy 446.236793 -96.409581) (xy 446.213121 -96.460078) (xy 446.182348 -96.506591)
			(xy 446.145131 -96.548128) (xy 446.102263 -96.583803) (xy 446.054657 -96.612857) (xy 446.003328 -96.634669)
			(xy 445.949371 -96.648775) (xy 445.893934 -96.654875) (xy 445.8382 -96.652838) (xy 445.783357 -96.642708)
			(xy 445.730573 -96.624701) (xy 445.680973 -96.5992) (xy 445.635615 -96.566749) (xy 445.595466 -96.52804)
			(xy 445.56138 -96.483897) (xy 445.534084 -96.435262) (xy 445.514161 -96.383171) (xy 445.502035 -96.328734)
			(xy 445.497964 -96.273112) (xy 444.91552 -96.273112) (xy 444.915798 -96.288352) (xy 444.915289 -96.316238)
			(xy 444.907169 -96.371414) (xy 444.891101 -96.424821) (xy 444.867429 -96.475318) (xy 444.836656 -96.521831)
			(xy 444.799439 -96.563368) (xy 444.756571 -96.599043) (xy 444.708965 -96.628097) (xy 444.657636 -96.649909)
			(xy 444.603679 -96.664015) (xy 444.548242 -96.670115) (xy 444.492508 -96.668078) (xy 444.437665 -96.657948)
			(xy 444.384881 -96.639941) (xy 444.335281 -96.61444) (xy 444.289923 -96.581989) (xy 444.249774 -96.54328)
			(xy 444.215688 -96.499137) (xy 444.188392 -96.450502) (xy 444.168469 -96.398411) (xy 444.156343 -96.343974)
			(xy 444.152272 -96.288352) (xy 443.480906 -96.288352) (xy 443.481975 -96.291904) (xy 443.490095 -96.34708)
			(xy 443.490604 -96.374966) (xy 443.490095 -96.402852) (xy 443.481975 -96.458028) (xy 443.465907 -96.511435)
			(xy 443.442235 -96.561932) (xy 443.411462 -96.608445) (xy 443.374245 -96.649982) (xy 443.331377 -96.685657)
			(xy 443.283771 -96.714711) (xy 443.232442 -96.736523) (xy 443.178485 -96.750629) (xy 443.123048 -96.756729)
			(xy 443.067314 -96.754692) (xy 443.012471 -96.744562) (xy 442.959687 -96.726555) (xy 442.910087 -96.701054)
			(xy 442.864729 -96.668603) (xy 442.82458 -96.629894) (xy 442.790494 -96.585751) (xy 442.763198 -96.537116)
			(xy 442.743275 -96.485025) (xy 442.731149 -96.430588) (xy 442.727078 -96.374966) (xy 417.348895 -96.374966)
			(xy 417.351222 -96.391149) (xy 417.351222 -96.445651) (xy 417.343466 -96.499598) (xy 417.328111 -96.551892)
			(xy 417.305471 -96.601468) (xy 417.276006 -96.647318) (xy 417.240315 -96.688508) (xy 417.199126 -96.7242)
			(xy 417.153277 -96.753666) (xy 417.103701 -96.776308) (xy 417.051407 -96.791664) (xy 416.997461 -96.799422)
			(xy 416.97021 -96.799908) (xy 416.941392 -96.79936) (xy 416.884412 -96.790679) (xy 416.829386 -96.773526)
			(xy 416.777566 -96.748294) (xy 416.730129 -96.715555) (xy 416.688156 -96.676054) (xy 416.652601 -96.630691)
			(xy 416.637978 -96.605852) (xy 416.630083 -96.592969) (xy 416.608212 -96.572143) (xy 416.581206 -96.558625)
			(xy 416.551428 -96.553597) (xy 416.521481 -96.557497) (xy 416.493985 -96.569986) (xy 416.471343 -96.589971)
			(xy 416.462972 -96.60255) (xy 416.447994 -96.625911) (xy 416.412311 -96.66841) (xy 416.370847 -96.70529)
			(xy 416.324476 -96.735773) (xy 416.274178 -96.759214) (xy 416.221014 -96.775121) (xy 416.166106 -96.783156)
			(xy 416.13836 -96.783652) (xy 416.111114 -96.783075) (xy 416.057177 -96.775315) (xy 416.004893 -96.759958)
			(xy 415.955326 -96.737317) (xy 415.909486 -96.707853) (xy 415.868306 -96.672166) (xy 415.832623 -96.630982)
			(xy 415.803164 -96.585138) (xy 415.780528 -96.53557) (xy 415.765177 -96.483284) (xy 415.757422 -96.429346)
			(xy 405.900307 -96.429346) (xy 405.900658 -96.431789) (xy 405.901144 -96.45904) (xy 405.900686 -96.48542)
			(xy 405.893422 -96.537679) (xy 405.879025 -96.588437) (xy 405.85777 -96.636727) (xy 405.830062 -96.681626)
			(xy 405.796431 -96.722278) (xy 405.757517 -96.757907) (xy 405.736044 -96.773238) (xy 405.724042 -96.782069)
			(xy 405.7054 -96.805302) (xy 405.694256 -96.832926) (xy 405.69156 -96.86259) (xy 405.697541 -96.89177)
			(xy 405.702523 -96.901) (xy 417.621972 -96.901) (xy 417.626043 -96.845378) (xy 417.638169 -96.790941)
			(xy 417.658092 -96.73885) (xy 417.685388 -96.690215) (xy 417.719474 -96.646072) (xy 417.759623 -96.607363)
			(xy 417.804981 -96.574912) (xy 417.854581 -96.549411) (xy 417.907365 -96.531404) (xy 417.962208 -96.521274)
			(xy 418.017942 -96.519237) (xy 418.073379 -96.525337) (xy 418.127336 -96.539443) (xy 418.178665 -96.561255)
			(xy 418.226271 -96.590309) (xy 418.269139 -96.625984) (xy 418.306356 -96.667521) (xy 418.337129 -96.714034)
			(xy 418.360801 -96.764531) (xy 418.376869 -96.817938) (xy 418.384989 -96.873114) (xy 418.385498 -96.901)
			(xy 420.073072 -96.901) (xy 420.077143 -96.845378) (xy 420.089269 -96.790941) (xy 420.109192 -96.73885)
			(xy 420.136488 -96.690215) (xy 420.170574 -96.646072) (xy 420.210723 -96.607363) (xy 420.256081 -96.574912)
			(xy 420.305681 -96.549411) (xy 420.358465 -96.531404) (xy 420.413308 -96.521274) (xy 420.469042 -96.519237)
			(xy 420.524479 -96.525337) (xy 420.578436 -96.539443) (xy 420.629765 -96.561255) (xy 420.677371 -96.590309)
			(xy 420.720239 -96.625984) (xy 420.757456 -96.667521) (xy 420.788229 -96.714034) (xy 420.811901 -96.764531)
			(xy 420.827969 -96.817938) (xy 420.836089 -96.873114) (xy 420.836598 -96.901) (xy 420.836089 -96.928886)
			(xy 420.827969 -96.984062) (xy 420.811901 -97.037469) (xy 420.810744 -97.039938) (xy 423.025568 -97.039938)
			(xy 423.029639 -96.984316) (xy 423.041765 -96.929879) (xy 423.061688 -96.877788) (xy 423.088984 -96.829153)
			(xy 423.12307 -96.78501) (xy 423.163219 -96.746301) (xy 423.208577 -96.71385) (xy 423.258177 -96.688349)
			(xy 423.310961 -96.670342) (xy 423.365804 -96.660212) (xy 423.421538 -96.658175) (xy 423.476975 -96.664275)
			(xy 423.530932 -96.678381) (xy 423.582261 -96.700193) (xy 423.629867 -96.729247) (xy 423.672735 -96.764922)
			(xy 423.709952 -96.806459) (xy 423.740725 -96.852972) (xy 423.764397 -96.903469) (xy 423.780465 -96.956876)
			(xy 423.788585 -97.012052) (xy 423.789094 -97.039938) (xy 423.788585 -97.067824) (xy 423.780465 -97.123)
			(xy 423.764397 -97.176407) (xy 423.740725 -97.226904) (xy 423.709952 -97.273417) (xy 423.672735 -97.314954)
			(xy 423.629867 -97.350629) (xy 423.582261 -97.379683) (xy 423.530932 -97.401495) (xy 423.476975 -97.415601)
			(xy 423.421538 -97.421701) (xy 423.365804 -97.419664) (xy 423.310961 -97.409534) (xy 423.258177 -97.391527)
			(xy 423.208577 -97.366026) (xy 423.163219 -97.333575) (xy 423.12307 -97.294866) (xy 423.088984 -97.250723)
			(xy 423.061688 -97.202088) (xy 423.041765 -97.149997) (xy 423.029639 -97.09556) (xy 423.025568 -97.039938)
			(xy 420.810744 -97.039938) (xy 420.788229 -97.087966) (xy 420.757456 -97.134479) (xy 420.720239 -97.176016)
			(xy 420.677371 -97.211691) (xy 420.629765 -97.240745) (xy 420.578436 -97.262557) (xy 420.524479 -97.276663)
			(xy 420.469042 -97.282763) (xy 420.413308 -97.280726) (xy 420.358465 -97.270596) (xy 420.305681 -97.252589)
			(xy 420.256081 -97.227088) (xy 420.210723 -97.194637) (xy 420.170574 -97.155928) (xy 420.136488 -97.111785)
			(xy 420.109192 -97.06315) (xy 420.089269 -97.011059) (xy 420.077143 -96.956622) (xy 420.073072 -96.901)
			(xy 418.385498 -96.901) (xy 418.384989 -96.928886) (xy 418.376869 -96.984062) (xy 418.360801 -97.037469)
			(xy 418.337129 -97.087966) (xy 418.306356 -97.134479) (xy 418.269139 -97.176016) (xy 418.226271 -97.211691)
			(xy 418.178665 -97.240745) (xy 418.127336 -97.262557) (xy 418.073379 -97.276663) (xy 418.017942 -97.282763)
			(xy 417.962208 -97.280726) (xy 417.907365 -97.270596) (xy 417.854581 -97.252589) (xy 417.804981 -97.227088)
			(xy 417.759623 -97.194637) (xy 417.719474 -97.155928) (xy 417.685388 -97.111785) (xy 417.658092 -97.06315)
			(xy 417.638169 -97.011059) (xy 417.626043 -96.956622) (xy 417.621972 -96.901) (xy 405.702523 -96.901)
			(xy 405.711689 -96.917983) (xy 405.732801 -96.938996) (xy 405.745696 -96.946466) (xy 405.771353 -96.960855)
			(xy 405.818304 -96.99629) (xy 405.859261 -97.03851) (xy 405.893254 -97.086516) (xy 405.919476 -97.13917)
			(xy 405.937308 -97.195224) (xy 405.946325 -97.253351) (xy 405.946864 -97.282762) (xy 405.946378 -97.310013)
			(xy 405.938622 -97.363961) (xy 405.923267 -97.416256) (xy 405.900625 -97.465833) (xy 405.871159 -97.511683)
			(xy 405.835468 -97.552874) (xy 405.794277 -97.588565) (xy 405.748427 -97.618031) (xy 405.700017 -97.64014)
			(xy 422.218102 -97.64014) (xy 422.222173 -97.584518) (xy 422.234299 -97.530081) (xy 422.254222 -97.47799)
			(xy 422.281518 -97.429355) (xy 422.315604 -97.385212) (xy 422.355753 -97.346503) (xy 422.401111 -97.314052)
			(xy 422.450711 -97.288551) (xy 422.503495 -97.270544) (xy 422.558338 -97.260414) (xy 422.614072 -97.258377)
			(xy 422.669509 -97.264477) (xy 422.723466 -97.278583) (xy 422.774795 -97.300395) (xy 422.822401 -97.329449)
			(xy 422.865269 -97.365124) (xy 422.902486 -97.406661) (xy 422.933259 -97.453174) (xy 422.956931 -97.503671)
			(xy 422.972999 -97.557078) (xy 422.981119 -97.612254) (xy 422.981628 -97.64014) (xy 422.981119 -97.668026)
			(xy 422.972999 -97.723202) (xy 422.956931 -97.776609) (xy 422.933259 -97.827106) (xy 422.902486 -97.873619)
			(xy 422.865269 -97.915156) (xy 422.822401 -97.950831) (xy 422.774795 -97.979885) (xy 422.723466 -98.001697)
			(xy 422.669509 -98.015803) (xy 422.614072 -98.021903) (xy 422.558338 -98.019866) (xy 422.503495 -98.009736)
			(xy 422.450711 -97.991729) (xy 422.401111 -97.966228) (xy 422.355753 -97.933777) (xy 422.315604 -97.895068)
			(xy 422.281518 -97.850925) (xy 422.254222 -97.80229) (xy 422.234299 -97.750199) (xy 422.222173 -97.695762)
			(xy 422.218102 -97.64014) (xy 405.700017 -97.64014) (xy 405.69885 -97.640673) (xy 405.646555 -97.656028)
			(xy 405.592607 -97.663784) (xy 405.538105 -97.663784) (xy 405.484157 -97.656028) (xy 405.431862 -97.640673)
			(xy 405.382285 -97.618031) (xy 405.336435 -97.588565) (xy 405.295244 -97.552874) (xy 405.259553 -97.511683)
			(xy 405.230087 -97.465833) (xy 405.207445 -97.416256) (xy 405.19209 -97.363961) (xy 405.184334 -97.310013)
			(xy 405.183848 -97.282762) (xy 405.184311 -97.256382) (xy 405.191575 -97.204124) (xy 405.205971 -97.153366)
			(xy 405.227225 -97.105076) (xy 405.254932 -97.060177) (xy 405.288563 -97.019524) (xy 405.327475 -96.983895)
			(xy 405.348948 -96.968564) (xy 405.36095 -96.959731) (xy 405.379593 -96.9365) (xy 405.390738 -96.908876)
			(xy 405.393434 -96.879211) (xy 405.387453 -96.85003) (xy 405.373304 -96.823818) (xy 405.352191 -96.802806)
			(xy 405.339296 -96.795336) (xy 405.313638 -96.780948) (xy 405.266688 -96.745513) (xy 405.225731 -96.703292)
			(xy 405.191739 -96.655286) (xy 405.165516 -96.602632) (xy 405.147685 -96.546578) (xy 405.138667 -96.488451)
			(xy 405.138128 -96.45904) (xy 403.615144 -96.45904) (xy 403.615144 -98.171) (xy 423.864022 -98.171)
			(xy 423.868093 -98.115378) (xy 423.880219 -98.060941) (xy 423.900142 -98.00885) (xy 423.927438 -97.960215)
			(xy 423.961524 -97.916072) (xy 424.001673 -97.877363) (xy 424.047031 -97.844912) (xy 424.096631 -97.819411)
			(xy 424.149415 -97.801404) (xy 424.204258 -97.791274) (xy 424.259992 -97.789237) (xy 424.315429 -97.795337)
			(xy 424.369386 -97.809443) (xy 424.420715 -97.831255) (xy 424.468321 -97.860309) (xy 424.511189 -97.895984)
			(xy 424.548406 -97.937521) (xy 424.579179 -97.984034) (xy 424.596812 -98.021648) (xy 426.469554 -98.021648)
			(xy 426.473625 -97.966026) (xy 426.485751 -97.911589) (xy 426.505674 -97.859498) (xy 426.53297 -97.810863)
			(xy 426.567056 -97.76672) (xy 426.607205 -97.728011) (xy 426.652563 -97.69556) (xy 426.702163 -97.670059)
			(xy 426.754947 -97.652052) (xy 426.80979 -97.641922) (xy 426.865524 -97.639885) (xy 426.920961 -97.645985)
			(xy 426.974918 -97.660091) (xy 427.026247 -97.681903) (xy 427.073853 -97.710957) (xy 427.116721 -97.746632)
			(xy 427.153938 -97.788169) (xy 427.184711 -97.834682) (xy 427.208383 -97.885179) (xy 427.224451 -97.938586)
			(xy 427.226657 -97.953576) (xy 436.643016 -97.953576) (xy 436.647087 -97.897954) (xy 436.659213 -97.843517)
			(xy 436.679136 -97.791426) (xy 436.706432 -97.742791) (xy 436.740518 -97.698648) (xy 436.780667 -97.659939)
			(xy 436.826025 -97.627488) (xy 436.875625 -97.601987) (xy 436.928409 -97.58398) (xy 436.983252 -97.57385)
			(xy 437.038986 -97.571813) (xy 437.094423 -97.577913) (xy 437.14838 -97.592019) (xy 437.199709 -97.613831)
			(xy 437.247315 -97.642885) (xy 437.290183 -97.67856) (xy 437.3274 -97.720097) (xy 437.358173 -97.76661)
			(xy 437.381845 -97.817107) (xy 437.383089 -97.821242) (xy 437.957466 -97.821242) (xy 437.961537 -97.76562)
			(xy 437.973663 -97.711183) (xy 437.993586 -97.659092) (xy 438.020882 -97.610457) (xy 438.054968 -97.566314)
			(xy 438.095117 -97.527605) (xy 438.140475 -97.495154) (xy 438.190075 -97.469653) (xy 438.242859 -97.451646)
			(xy 438.297702 -97.441516) (xy 438.353436 -97.439479) (xy 438.408873 -97.445579) (xy 438.46283 -97.459685)
			(xy 438.514159 -97.481497) (xy 438.561765 -97.510551) (xy 438.604633 -97.546226) (xy 438.64185 -97.587763)
			(xy 438.672623 -97.634276) (xy 438.696295 -97.684773) (xy 438.712363 -97.73818) (xy 438.720483 -97.793356)
			(xy 438.720992 -97.821242) (xy 438.720495 -97.848447) (xy 439.22852 -97.848447) (xy 439.22852 -97.793953)
			(xy 439.236275 -97.740012) (xy 439.251628 -97.687725) (xy 439.274265 -97.638154) (xy 439.303727 -97.592309)
			(xy 439.339413 -97.551124) (xy 439.380597 -97.515437) (xy 439.42644 -97.485973) (xy 439.47601 -97.463334)
			(xy 439.528297 -97.447979) (xy 439.582237 -97.440221) (xy 439.609484 -97.439734) (xy 439.638401 -97.440251)
			(xy 439.695573 -97.448978) (xy 439.750772 -97.466236) (xy 439.802734 -97.491628) (xy 439.850268 -97.524572)
			(xy 439.892284 -97.564314) (xy 439.910474 -97.5868) (xy 439.918102 -97.595585) (xy 439.938987 -97.605781)
			(xy 439.950606 -97.606358) (xy 440.030362 -97.606358) (xy 440.041999 -97.605855) (xy 440.062909 -97.595642)
			(xy 440.070494 -97.5868) (xy 440.088688 -97.564319) (xy 440.130707 -97.524584) (xy 440.178242 -97.491645)
			(xy 440.230202 -97.466256) (xy 440.285399 -97.448999) (xy 440.342568 -97.440269) (xy 440.371484 -97.439734)
			(xy 440.398741 -97.440112) (xy 440.452699 -97.447868) (xy 440.505005 -97.463224) (xy 440.554593 -97.485868)
			(xy 440.600453 -97.515339) (xy 440.641652 -97.551037) (xy 440.677351 -97.592234) (xy 440.706824 -97.638093)
			(xy 440.72947 -97.68768) (xy 440.744829 -97.739985) (xy 440.752587 -97.793943) (xy 440.752587 -97.821242)
			(xy 441.005466 -97.821242) (xy 441.009537 -97.76562) (xy 441.021663 -97.711183) (xy 441.041586 -97.659092)
			(xy 441.068882 -97.610457) (xy 441.102968 -97.566314) (xy 441.143117 -97.527605) (xy 441.188475 -97.495154)
			(xy 441.238075 -97.469653) (xy 441.290859 -97.451646) (xy 441.345702 -97.441516) (xy 441.401436 -97.439479)
			(xy 441.456873 -97.445579) (xy 441.51083 -97.459685) (xy 441.562159 -97.481497) (xy 441.609765 -97.510551)
			(xy 441.629968 -97.527364) (xy 442.639702 -97.527364) (xy 442.643773 -97.471742) (xy 442.655899 -97.417305)
			(xy 442.675822 -97.365214) (xy 442.703118 -97.316579) (xy 442.737204 -97.272436) (xy 442.777353 -97.233727)
			(xy 442.822711 -97.201276) (xy 442.872311 -97.175775) (xy 442.925095 -97.157768) (xy 442.979938 -97.147638)
			(xy 443.035672 -97.145601) (xy 443.091109 -97.151701) (xy 443.145066 -97.165807) (xy 443.196395 -97.187619)
			(xy 443.244001 -97.216673) (xy 443.286869 -97.252348) (xy 443.324086 -97.293885) (xy 443.354859 -97.340398)
			(xy 443.378531 -97.390895) (xy 443.394599 -97.444302) (xy 443.402719 -97.499478) (xy 443.403228 -97.527364)
			(xy 443.402719 -97.55525) (xy 443.394599 -97.610426) (xy 443.378531 -97.663833) (xy 443.354859 -97.71433)
			(xy 443.324086 -97.760843) (xy 443.286869 -97.80238) (xy 443.252606 -97.830894) (xy 443.498476 -97.830894)
			(xy 443.502547 -97.775272) (xy 443.514673 -97.720835) (xy 443.534596 -97.668744) (xy 443.561892 -97.620109)
			(xy 443.595978 -97.575966) (xy 443.636127 -97.537257) (xy 443.681485 -97.504806) (xy 443.731085 -97.479305)
			(xy 443.783869 -97.461298) (xy 443.838712 -97.451168) (xy 443.894446 -97.449131) (xy 443.949883 -97.455231)
			(xy 444.00384 -97.469337) (xy 444.055169 -97.491149) (xy 444.102775 -97.520203) (xy 444.145643 -97.555878)
			(xy 444.18286 -97.597415) (xy 444.213633 -97.643928) (xy 444.237305 -97.694425) (xy 444.253373 -97.747832)
			(xy 444.261493 -97.803008) (xy 444.262002 -97.830894) (xy 444.261493 -97.85878) (xy 444.253373 -97.913956)
			(xy 444.237305 -97.967363) (xy 444.213633 -98.01786) (xy 444.18286 -98.064373) (xy 444.145643 -98.10591)
			(xy 444.102775 -98.141585) (xy 444.101348 -98.142456) (xy 447.471271 -98.142456) (xy 447.47246 -98.089452)
			(xy 447.48098 -98.037123) (xy 447.496665 -97.986479) (xy 447.519214 -97.938496) (xy 447.548192 -97.894098)
			(xy 447.565272 -97.87382) (xy 447.571368 -97.866708) (xy 447.577718 -97.849944) (xy 447.577718 -97.79127)
			(xy 447.565272 -97.79127) (xy 447.565272 -97.749614) (xy 447.559684 -97.733866) (xy 447.55435 -97.727008)
			(xy 447.538691 -97.706687) (xy 447.512391 -97.662639) (xy 447.492238 -97.615462) (xy 447.478596 -97.566007)
			(xy 447.471711 -97.515169) (xy 447.471292 -97.489518) (xy 447.471778 -97.462267) (xy 447.479534 -97.408319)
			(xy 447.494889 -97.356024) (xy 447.517531 -97.306447) (xy 447.546997 -97.260597) (xy 447.582688 -97.219406)
			(xy 447.623879 -97.183715) (xy 447.669729 -97.154249) (xy 447.719306 -97.131607) (xy 447.771601 -97.116252)
			(xy 447.825549 -97.108496) (xy 447.880051 -97.108496) (xy 447.933999 -97.116252) (xy 447.986294 -97.131607)
			(xy 448.035871 -97.154249) (xy 448.081721 -97.183715) (xy 448.122912 -97.219406) (xy 448.158603 -97.260597)
			(xy 448.188069 -97.306447) (xy 448.210711 -97.356024) (xy 448.226066 -97.408319) (xy 448.233822 -97.462267)
			(xy 448.234308 -97.489518) (xy 448.233851 -97.516889) (xy 448.22603 -97.571068) (xy 448.210539 -97.623571)
			(xy 448.187696 -97.673318) (xy 448.15797 -97.719284) (xy 451.149452 -97.719284) (xy 451.150637 -97.666281)
			(xy 451.159154 -97.613953) (xy 451.174838 -97.56331) (xy 451.197387 -97.515328) (xy 451.226365 -97.470932)
			(xy 451.243446 -97.450656) (xy 451.249542 -97.443544) (xy 451.255892 -97.42678) (xy 451.255892 -97.368106)
			(xy 451.243446 -97.368106) (xy 451.243446 -97.32645) (xy 451.237858 -97.310702) (xy 451.232524 -97.303844)
			(xy 451.216878 -97.283513) (xy 451.190577 -97.239468) (xy 451.170421 -97.192293) (xy 451.156776 -97.14284)
			(xy 451.149887 -97.092004) (xy 451.149466 -97.066354) (xy 451.149952 -97.039103) (xy 451.157708 -96.985155)
			(xy 451.173063 -96.93286) (xy 451.195705 -96.883283) (xy 451.225171 -96.837433) (xy 451.260862 -96.796242)
			(xy 451.302053 -96.760551) (xy 451.347903 -96.731085) (xy 451.39748 -96.708443) (xy 451.449775 -96.693088)
			(xy 451.503723 -96.685332) (xy 451.558225 -96.685332) (xy 451.612173 -96.693088) (xy 451.664468 -96.708443)
			(xy 451.714045 -96.731085) (xy 451.759895 -96.760551) (xy 451.801086 -96.796242) (xy 451.836777 -96.837433)
			(xy 451.866243 -96.883283) (xy 451.888885 -96.93286) (xy 451.90424 -96.985155) (xy 451.911996 -97.039103)
			(xy 451.912482 -97.066354) (xy 451.911993 -97.093723) (xy 451.904182 -97.147902) (xy 451.888698 -97.200405)
			(xy 451.865861 -97.250152) (xy 451.836141 -97.29612) (xy 451.818502 -97.317052) (xy 451.812406 -97.324164)
			(xy 451.806056 -97.340928) (xy 451.806056 -97.399602) (xy 451.818502 -97.399602) (xy 451.818502 -97.441258)
			(xy 451.82409 -97.457006) (xy 451.829424 -97.463864) (xy 451.845585 -97.48488) (xy 451.872545 -97.530529)
			(xy 451.892922 -97.579473) (xy 451.906323 -97.630767) (xy 451.91249 -97.683423) (xy 451.911304 -97.736425)
			(xy 451.902787 -97.788752) (xy 451.887104 -97.839395) (xy 451.864557 -97.887378) (xy 451.835582 -97.931775)
			(xy 451.818502 -97.952052) (xy 451.812406 -97.959164) (xy 451.806056 -97.975928) (xy 451.806056 -98.034602)
			(xy 451.818502 -98.034602) (xy 451.818502 -98.076258) (xy 451.82409 -98.092006) (xy 451.829424 -98.098864)
			(xy 451.845066 -98.119198) (xy 451.871369 -98.163242) (xy 451.891526 -98.210416) (xy 451.905172 -98.259868)
			(xy 451.912061 -98.310704) (xy 451.912482 -98.336354) (xy 451.911996 -98.363605) (xy 451.90424 -98.417553)
			(xy 451.888885 -98.469848) (xy 451.866243 -98.519425) (xy 451.836777 -98.565275) (xy 451.801086 -98.606466)
			(xy 451.759895 -98.642157) (xy 451.714045 -98.671623) (xy 451.664468 -98.694265) (xy 451.612173 -98.70962)
			(xy 451.558225 -98.717376) (xy 451.503723 -98.717376) (xy 451.449775 -98.70962) (xy 451.39748 -98.694265)
			(xy 451.347903 -98.671623) (xy 451.302053 -98.642157) (xy 451.260862 -98.606466) (xy 451.225171 -98.565275)
			(xy 451.195705 -98.519425) (xy 451.173063 -98.469848) (xy 451.157708 -98.417553) (xy 451.149952 -98.363605)
			(xy 451.149466 -98.336354) (xy 451.149948 -98.308984) (xy 451.157759 -98.254805) (xy 451.173244 -98.202302)
			(xy 451.196082 -98.152554) (xy 451.225805 -98.106587) (xy 451.243446 -98.085656) (xy 451.249542 -98.078544)
			(xy 451.255892 -98.06178) (xy 451.255892 -98.003106) (xy 451.243446 -98.003106) (xy 451.243446 -97.96145)
			(xy 451.237858 -97.945702) (xy 451.232524 -97.938844) (xy 451.216368 -97.917823) (xy 451.189404 -97.872176)
			(xy 451.169024 -97.823234) (xy 451.15562 -97.77194) (xy 451.149452 -97.719284) (xy 448.15797 -97.719284)
			(xy 448.140328 -97.740216) (xy 448.134232 -97.747328) (xy 448.127882 -97.764092) (xy 448.127882 -97.822766)
			(xy 448.140328 -97.822766) (xy 448.140328 -97.864422) (xy 448.145916 -97.88017) (xy 448.15125 -97.887028)
			(xy 448.167374 -97.908072) (xy 448.194334 -97.953716) (xy 448.214712 -98.002655) (xy 448.228115 -98.053945)
			(xy 448.234285 -98.106596) (xy 448.233102 -98.159595) (xy 448.22459 -98.211919) (xy 448.208913 -98.26256)
			(xy 448.186373 -98.310542) (xy 448.157404 -98.354938) (xy 448.140328 -98.375216) (xy 448.134232 -98.382328)
			(xy 448.127882 -98.399092) (xy 448.127882 -98.475546) (xy 448.127963 -98.480019) (xy 448.129501 -98.488832)
			(xy 448.13093 -98.493072) (xy 448.134486 -98.502216) (xy 448.135631 -98.503552) (xy 449.126063 -98.503552)
			(xy 449.126063 -98.449048) (xy 449.13382 -98.395098) (xy 449.149176 -98.342801) (xy 449.171818 -98.293222)
			(xy 449.201286 -98.247369) (xy 449.236979 -98.206177) (xy 449.278171 -98.170485) (xy 449.324023 -98.141017)
			(xy 449.373603 -98.118375) (xy 449.4259 -98.10302) (xy 449.47985 -98.095263) (xy 449.507102 -98.0948)
			(xy 449.533416 -98.095266) (xy 449.585545 -98.102501) (xy 449.636187 -98.116821) (xy 449.684386 -98.137953)
			(xy 449.72923 -98.1655) (xy 449.769869 -98.198938) (xy 449.788026 -98.21799) (xy 449.79559 -98.22544)
			(xy 449.815014 -98.23396) (xy 449.825618 -98.2345) (xy 449.899786 -98.2345) (xy 449.910416 -98.234075)
			(xy 449.929881 -98.225537) (xy 449.937378 -98.21799) (xy 449.955549 -98.19895) (xy 449.996176 -98.165492)
			(xy 450.041013 -98.137931) (xy 450.089211 -98.11679) (xy 450.139855 -98.102469) (xy 450.191987 -98.095241)
			(xy 450.218302 -98.0948) (xy 450.245554 -98.09527) (xy 450.299502 -98.103027) (xy 450.351798 -98.118382)
			(xy 450.401376 -98.141024) (xy 450.447227 -98.170491) (xy 450.488418 -98.206183) (xy 450.52411 -98.247374)
			(xy 450.553577 -98.293226) (xy 450.576218 -98.342804) (xy 450.591574 -98.3951) (xy 450.59933 -98.449048)
			(xy 450.59933 -98.503552) (xy 450.591574 -98.5575) (xy 450.576218 -98.609796) (xy 450.553577 -98.659374)
			(xy 450.52411 -98.705226) (xy 450.488418 -98.746417) (xy 450.447227 -98.782109) (xy 450.401376 -98.811576)
			(xy 450.351798 -98.834218) (xy 450.299502 -98.849573) (xy 450.245554 -98.85733) (xy 450.218302 -98.857816)
			(xy 450.191988 -98.857342) (xy 450.13986 -98.850108) (xy 450.089218 -98.83579) (xy 450.041019 -98.814658)
			(xy 449.996175 -98.787114) (xy 449.955535 -98.753677) (xy 449.937378 -98.734626) (xy 449.92981 -98.72718)
			(xy 449.910389 -98.718657) (xy 449.899786 -98.718116) (xy 449.825618 -98.718116) (xy 449.814987 -98.718539)
			(xy 449.795523 -98.727078) (xy 449.788026 -98.734626) (xy 449.769856 -98.753667) (xy 449.729229 -98.787124)
			(xy 449.684391 -98.814685) (xy 449.636194 -98.835826) (xy 449.585549 -98.850146) (xy 449.533417 -98.857375)
			(xy 449.507102 -98.857816) (xy 449.47985 -98.857337) (xy 449.4259 -98.84958) (xy 449.373603 -98.834225)
			(xy 449.324023 -98.811583) (xy 449.278171 -98.782115) (xy 449.236979 -98.746423) (xy 449.201286 -98.705231)
			(xy 449.171818 -98.659378) (xy 449.149176 -98.609799) (xy 449.13382 -98.557502) (xy 449.126063 -98.503552)
			(xy 448.135631 -98.503552) (xy 448.140582 -98.509328) (xy 448.151444 -98.522014) (xy 448.171158 -98.548978)
			(xy 448.179952 -98.563176) (xy 448.18554 -98.57232) (xy 448.20205 -98.584258) (xy 448.284854 -98.602292)
			(xy 448.290142 -98.603288) (xy 448.300902 -98.603288) (xy 448.30619 -98.602292) (xy 448.316096 -98.60026)
			(xy 448.324732 -98.594418) (xy 448.324986 -98.594164) (xy 448.349044 -98.578232) (xy 448.400925 -98.552984)
			(xy 448.456012 -98.535821) (xy 448.513053 -98.527134) (xy 448.541902 -98.5266) (xy 448.569154 -98.52707)
			(xy 448.623102 -98.534827) (xy 448.675398 -98.550182) (xy 448.724976 -98.572824) (xy 448.770827 -98.602291)
			(xy 448.812018 -98.637983) (xy 448.84771 -98.679174) (xy 448.877177 -98.725026) (xy 448.899818 -98.774604)
			(xy 448.915174 -98.8269) (xy 448.92293 -98.880848) (xy 448.92293 -98.935352) (xy 448.915174 -98.9893)
			(xy 448.899818 -99.041596) (xy 448.877177 -99.091174) (xy 448.84771 -99.137026) (xy 448.812018 -99.178217)
			(xy 448.770827 -99.213909) (xy 448.724976 -99.243376) (xy 448.675398 -99.266018) (xy 448.623102 -99.281373)
			(xy 448.569154 -99.28913) (xy 448.541902 -99.289616) (xy 448.513821 -99.289156) (xy 448.458264 -99.28094)
			(xy 448.40451 -99.264671) (xy 448.353721 -99.2407) (xy 448.306994 -99.209544) (xy 448.265337 -99.171877)
			(xy 448.22965 -99.128511) (xy 448.21475 -99.104704) (xy 448.209416 -99.09556) (xy 448.192398 -99.083368)
			(xy 448.109848 -99.065334) (xy 448.10456 -99.064338) (xy 448.0938 -99.064338) (xy 448.088512 -99.065334)
			(xy 448.078606 -99.067366) (xy 448.06997 -99.073208) (xy 448.069716 -99.073462) (xy 448.04566 -99.089396)
			(xy 447.993778 -99.114643) (xy 447.93869 -99.131805) (xy 447.881649 -99.140492) (xy 447.8528 -99.141026)
			(xy 447.82555 -99.140522) (xy 447.771603 -99.132766) (xy 447.71931 -99.117412) (xy 447.669734 -99.094772)
			(xy 447.623885 -99.065308) (xy 447.582695 -99.029618) (xy 447.547003 -98.98843) (xy 447.517536 -98.942582)
			(xy 447.494894 -98.893007) (xy 447.479538 -98.840714) (xy 447.471779 -98.786768) (xy 447.471292 -98.759518)
			(xy 447.471771 -98.732148) (xy 447.479586 -98.67797) (xy 447.495072 -98.625467) (xy 447.517911 -98.57572)
			(xy 447.547632 -98.529752) (xy 447.565272 -98.50882) (xy 447.571368 -98.501708) (xy 447.577718 -98.484944)
			(xy 447.577718 -98.42627) (xy 447.565272 -98.42627) (xy 447.565272 -98.384614) (xy 447.559684 -98.368866)
			(xy 447.55435 -98.362008) (xy 447.538163 -98.341011) (xy 447.511206 -98.295358) (xy 447.490832 -98.246411)
			(xy 447.477434 -98.195115) (xy 447.471271 -98.142456) (xy 444.101348 -98.142456) (xy 444.055169 -98.170639)
			(xy 444.00384 -98.192451) (xy 443.949883 -98.206557) (xy 443.894446 -98.212657) (xy 443.838712 -98.21062)
			(xy 443.783869 -98.20049) (xy 443.731085 -98.182483) (xy 443.681485 -98.156982) (xy 443.636127 -98.124531)
			(xy 443.595978 -98.085822) (xy 443.561892 -98.041679) (xy 443.534596 -97.993044) (xy 443.514673 -97.940953)
			(xy 443.502547 -97.886516) (xy 443.498476 -97.830894) (xy 443.252606 -97.830894) (xy 443.244001 -97.838055)
			(xy 443.196395 -97.867109) (xy 443.145066 -97.888921) (xy 443.091109 -97.903027) (xy 443.035672 -97.909127)
			(xy 442.979938 -97.90709) (xy 442.925095 -97.89696) (xy 442.872311 -97.878953) (xy 442.822711 -97.853452)
			(xy 442.777353 -97.821001) (xy 442.737204 -97.782292) (xy 442.703118 -97.738149) (xy 442.675822 -97.689514)
			(xy 442.655899 -97.637423) (xy 442.643773 -97.582986) (xy 442.639702 -97.527364) (xy 441.629968 -97.527364)
			(xy 441.652633 -97.546226) (xy 441.68985 -97.587763) (xy 441.720623 -97.634276) (xy 441.744295 -97.684773)
			(xy 441.760363 -97.73818) (xy 441.768483 -97.793356) (xy 441.768992 -97.821242) (xy 441.768483 -97.849128)
			(xy 441.760363 -97.904304) (xy 441.744295 -97.957711) (xy 441.720623 -98.008208) (xy 441.68985 -98.054721)
			(xy 441.652633 -98.096258) (xy 441.609765 -98.131933) (xy 441.562159 -98.160987) (xy 441.51083 -98.182799)
			(xy 441.456873 -98.196905) (xy 441.401436 -98.203005) (xy 441.345702 -98.200968) (xy 441.290859 -98.190838)
			(xy 441.238075 -98.172831) (xy 441.188475 -98.14733) (xy 441.143117 -98.114879) (xy 441.102968 -98.07617)
			(xy 441.068882 -98.032027) (xy 441.041586 -97.983392) (xy 441.021663 -97.931301) (xy 441.009537 -97.876864)
			(xy 441.005466 -97.821242) (xy 440.752587 -97.821242) (xy 440.752587 -97.848457) (xy 440.744829 -97.902415)
			(xy 440.72947 -97.95472) (xy 440.706824 -98.004307) (xy 440.677351 -98.050166) (xy 440.641652 -98.091363)
			(xy 440.600453 -98.127061) (xy 440.554593 -98.156532) (xy 440.505005 -98.179176) (xy 440.452699 -98.194532)
			(xy 440.398741 -98.202288) (xy 440.371484 -98.20275) (xy 440.342568 -98.20219) (xy 440.285398 -98.193472)
			(xy 440.2302 -98.176224) (xy 440.178237 -98.15084) (xy 440.130702 -98.117903) (xy 440.088685 -98.078167)
			(xy 440.070494 -98.055684) (xy 440.062883 -98.046881) (xy 440.041985 -98.036696) (xy 440.030362 -98.036126)
			(xy 439.950606 -98.036126) (xy 439.938975 -98.036674) (xy 439.918065 -98.046856) (xy 439.910474 -98.055684)
			(xy 439.892294 -98.078177) (xy 439.850272 -98.117912) (xy 439.802735 -98.15085) (xy 439.750772 -98.176237)
			(xy 439.695572 -98.193491) (xy 439.638401 -98.202217) (xy 439.609484 -98.20275) (xy 439.582237 -98.202179)
			(xy 439.528297 -98.194421) (xy 439.47601 -98.179066) (xy 439.42644 -98.156427) (xy 439.380597 -98.126963)
			(xy 439.339413 -98.091276) (xy 439.303727 -98.050091) (xy 439.274265 -98.004246) (xy 439.251628 -97.954675)
			(xy 439.236275 -97.902388) (xy 439.22852 -97.848447) (xy 438.720495 -97.848447) (xy 438.720483 -97.849128)
			(xy 438.712363 -97.904304) (xy 438.696295 -97.957711) (xy 438.672623 -98.008208) (xy 438.64185 -98.054721)
			(xy 438.604633 -98.096258) (xy 438.561765 -98.131933) (xy 438.514159 -98.160987) (xy 438.46283 -98.182799)
			(xy 438.408873 -98.196905) (xy 438.353436 -98.203005) (xy 438.297702 -98.200968) (xy 438.242859 -98.190838)
			(xy 438.190075 -98.172831) (xy 438.140475 -98.14733) (xy 438.095117 -98.114879) (xy 438.054968 -98.07617)
			(xy 438.020882 -98.032027) (xy 437.993586 -97.983392) (xy 437.973663 -97.931301) (xy 437.961537 -97.876864)
			(xy 437.957466 -97.821242) (xy 437.383089 -97.821242) (xy 437.397913 -97.870514) (xy 437.406033 -97.92569)
			(xy 437.406542 -97.953576) (xy 437.406033 -97.981462) (xy 437.397913 -98.036638) (xy 437.381845 -98.090045)
			(xy 437.358173 -98.140542) (xy 437.3274 -98.187055) (xy 437.290183 -98.228592) (xy 437.247315 -98.264267)
			(xy 437.199709 -98.293321) (xy 437.14838 -98.315133) (xy 437.094423 -98.329239) (xy 437.038986 -98.335339)
			(xy 436.983252 -98.333302) (xy 436.928409 -98.323172) (xy 436.875625 -98.305165) (xy 436.826025 -98.279664)
			(xy 436.780667 -98.247213) (xy 436.740518 -98.208504) (xy 436.706432 -98.164361) (xy 436.679136 -98.115726)
			(xy 436.659213 -98.063635) (xy 436.647087 -98.009198) (xy 436.643016 -97.953576) (xy 427.226657 -97.953576)
			(xy 427.232571 -97.993762) (xy 427.23308 -98.021648) (xy 427.232571 -98.049534) (xy 427.224451 -98.10471)
			(xy 427.208383 -98.158117) (xy 427.184711 -98.208614) (xy 427.153938 -98.255127) (xy 427.116721 -98.296664)
			(xy 427.073853 -98.332339) (xy 427.026247 -98.361393) (xy 426.974918 -98.383205) (xy 426.920961 -98.397311)
			(xy 426.865524 -98.403411) (xy 426.80979 -98.401374) (xy 426.754947 -98.391244) (xy 426.702163 -98.373237)
			(xy 426.652563 -98.347736) (xy 426.607205 -98.315285) (xy 426.567056 -98.276576) (xy 426.53297 -98.232433)
			(xy 426.505674 -98.183798) (xy 426.485751 -98.131707) (xy 426.473625 -98.07727) (xy 426.469554 -98.021648)
			(xy 424.596812 -98.021648) (xy 424.602851 -98.034531) (xy 424.618919 -98.087938) (xy 424.627039 -98.143114)
			(xy 424.627548 -98.171) (xy 424.627039 -98.198886) (xy 424.618919 -98.254062) (xy 424.602851 -98.307469)
			(xy 424.579179 -98.357966) (xy 424.548406 -98.404479) (xy 424.511189 -98.446016) (xy 424.468321 -98.481691)
			(xy 424.420715 -98.510745) (xy 424.369386 -98.532557) (xy 424.328048 -98.543364) (xy 435.285894 -98.543364)
			(xy 435.289965 -98.487742) (xy 435.302091 -98.433305) (xy 435.322014 -98.381214) (xy 435.34931 -98.332579)
			(xy 435.383396 -98.288436) (xy 435.423545 -98.249727) (xy 435.468903 -98.217276) (xy 435.518503 -98.191775)
			(xy 435.571287 -98.173768) (xy 435.62613 -98.163638) (xy 435.681864 -98.161601) (xy 435.737301 -98.167701)
			(xy 435.791258 -98.181807) (xy 435.842587 -98.203619) (xy 435.890193 -98.232673) (xy 435.933061 -98.268348)
			(xy 435.970278 -98.309885) (xy 436.001051 -98.356398) (xy 436.024723 -98.406895) (xy 436.040791 -98.460302)
			(xy 436.048911 -98.515478) (xy 436.04942 -98.543364) (xy 436.048911 -98.57125) (xy 436.040791 -98.626426)
			(xy 436.024723 -98.679833) (xy 436.001051 -98.73033) (xy 435.970278 -98.776843) (xy 435.933061 -98.81838)
			(xy 435.890193 -98.854055) (xy 435.842587 -98.883109) (xy 435.791258 -98.904921) (xy 435.737301 -98.919027)
			(xy 435.681864 -98.925127) (xy 435.62613 -98.92309) (xy 435.571287 -98.91296) (xy 435.518503 -98.894953)
			(xy 435.468903 -98.869452) (xy 435.423545 -98.837001) (xy 435.383396 -98.798292) (xy 435.34931 -98.754149)
			(xy 435.322014 -98.705514) (xy 435.302091 -98.653423) (xy 435.289965 -98.598986) (xy 435.285894 -98.543364)
			(xy 424.328048 -98.543364) (xy 424.315429 -98.546663) (xy 424.259992 -98.552763) (xy 424.204258 -98.550726)
			(xy 424.149415 -98.540596) (xy 424.096631 -98.522589) (xy 424.047031 -98.497088) (xy 424.001673 -98.464637)
			(xy 423.961524 -98.425928) (xy 423.927438 -98.381785) (xy 423.900142 -98.33315) (xy 423.880219 -98.281059)
			(xy 423.868093 -98.226622) (xy 423.864022 -98.171) (xy 403.615144 -98.171) (xy 403.615144 -99.214251)
			(xy 417.622978 -99.214251) (xy 417.622978 -99.159749) (xy 417.630734 -99.105802) (xy 417.646089 -99.053508)
			(xy 417.668729 -99.003932) (xy 417.698194 -98.958082) (xy 417.733885 -98.916892) (xy 417.775074 -98.8812)
			(xy 417.820923 -98.851734) (xy 417.870499 -98.829092) (xy 417.922793 -98.813736) (xy 417.976739 -98.805978)
			(xy 418.00399 -98.805492) (xy 418.030594 -98.805952) (xy 418.083286 -98.813332) (xy 418.134441 -98.827965)
			(xy 418.183066 -98.849566) (xy 418.228216 -98.877715) (xy 418.269016 -98.911867) (xy 418.304672 -98.951359)
			(xy 418.319966 -98.973132) (xy 418.3283 -98.984612) (xy 418.350044 -99.002816) (xy 418.375957 -99.014334)
			(xy 418.40404 -99.018274) (xy 418.432123 -99.014334) (xy 418.458036 -99.002816) (xy 418.47978 -98.984612)
			(xy 418.488114 -98.973132) (xy 418.503386 -98.951345) (xy 418.539056 -98.911866) (xy 418.579864 -98.877725)
			(xy 418.625018 -98.849581) (xy 418.673643 -98.827982) (xy 418.724796 -98.813345) (xy 418.777487 -98.805954)
			(xy 418.80409 -98.805492) (xy 418.831343 -98.805955) (xy 418.885295 -98.81371) (xy 418.937594 -98.829066)
			(xy 418.987176 -98.851708) (xy 419.03303 -98.881175) (xy 419.074224 -98.916869) (xy 419.109919 -98.958062)
			(xy 419.139388 -99.003915) (xy 419.154793 -99.037648) (xy 426.469554 -99.037648) (xy 426.473625 -98.982026)
			(xy 426.485751 -98.927589) (xy 426.505674 -98.875498) (xy 426.53297 -98.826863) (xy 426.567056 -98.78272)
			(xy 426.607205 -98.744011) (xy 426.652563 -98.71156) (xy 426.702163 -98.686059) (xy 426.754947 -98.668052)
			(xy 426.80979 -98.657922) (xy 426.865524 -98.655885) (xy 426.920961 -98.661985) (xy 426.974918 -98.676091)
			(xy 427.026247 -98.697903) (xy 427.073853 -98.726957) (xy 427.116721 -98.762632) (xy 427.153938 -98.804169)
			(xy 427.184711 -98.850682) (xy 427.208383 -98.901179) (xy 427.224451 -98.954586) (xy 427.232571 -99.009762)
			(xy 427.23308 -99.037648) (xy 427.232571 -99.065534) (xy 427.224451 -99.12071) (xy 427.208383 -99.174117)
			(xy 427.184711 -99.224614) (xy 427.153938 -99.271127) (xy 427.116721 -99.312664) (xy 427.073853 -99.348339)
			(xy 427.026247 -99.377393) (xy 426.974918 -99.399205) (xy 426.920961 -99.413311) (xy 426.865524 -99.419411)
			(xy 426.80979 -99.417374) (xy 426.754947 -99.407244) (xy 426.702163 -99.389237) (xy 426.652563 -99.363736)
			(xy 426.607205 -99.331285) (xy 426.567056 -99.292576) (xy 426.53297 -99.248433) (xy 426.505674 -99.199798)
			(xy 426.485751 -99.147707) (xy 426.473625 -99.09327) (xy 426.469554 -99.037648) (xy 419.154793 -99.037648)
			(xy 419.162031 -99.053496) (xy 419.177387 -99.105795) (xy 419.185145 -99.159747) (xy 419.185145 -99.214253)
			(xy 419.177387 -99.268205) (xy 419.162031 -99.320504) (xy 419.139388 -99.370085) (xy 419.109919 -99.415938)
			(xy 419.089082 -99.439984) (xy 423.610022 -99.439984) (xy 423.614093 -99.384362) (xy 423.626219 -99.329925)
			(xy 423.646142 -99.277834) (xy 423.673438 -99.229199) (xy 423.707524 -99.185056) (xy 423.747673 -99.146347)
			(xy 423.793031 -99.113896) (xy 423.842631 -99.088395) (xy 423.895415 -99.070388) (xy 423.950258 -99.060258)
			(xy 424.005992 -99.058221) (xy 424.061429 -99.064321) (xy 424.115386 -99.078427) (xy 424.166715 -99.100239)
			(xy 424.214321 -99.129293) (xy 424.257189 -99.164968) (xy 424.294406 -99.206505) (xy 424.325179 -99.253018)
			(xy 424.348851 -99.303515) (xy 424.364919 -99.356922) (xy 424.373039 -99.412098) (xy 424.373548 -99.439984)
			(xy 424.373376 -99.449382) (xy 436.206136 -99.449382) (xy 436.210207 -99.39376) (xy 436.222333 -99.339323)
			(xy 436.242256 -99.287232) (xy 436.269552 -99.238597) (xy 436.303638 -99.194454) (xy 436.343787 -99.155745)
			(xy 436.389145 -99.123294) (xy 436.438745 -99.097793) (xy 436.491529 -99.079786) (xy 436.546372 -99.069656)
			(xy 436.602106 -99.067619) (xy 436.657543 -99.073719) (xy 436.7115 -99.087825) (xy 436.762829 -99.109637)
			(xy 436.810435 -99.138691) (xy 436.853303 -99.174366) (xy 436.89052 -99.215903) (xy 436.921293 -99.262416)
			(xy 436.944965 -99.312913) (xy 436.961033 -99.36632) (xy 436.969153 -99.421496) (xy 436.969662 -99.449382)
			(xy 436.969153 -99.477268) (xy 436.961033 -99.532444) (xy 436.944965 -99.585851) (xy 436.931543 -99.614482)
			(xy 438.639964 -99.614482) (xy 438.644035 -99.55886) (xy 438.656161 -99.504423) (xy 438.676084 -99.452332)
			(xy 438.70338 -99.403697) (xy 438.737466 -99.359554) (xy 438.777615 -99.320845) (xy 438.822973 -99.288394)
			(xy 438.872573 -99.262893) (xy 438.925357 -99.244886) (xy 438.9802 -99.234756) (xy 439.035934 -99.232719)
			(xy 439.091371 -99.238819) (xy 439.145328 -99.252925) (xy 439.196657 -99.274737) (xy 439.244263 -99.303791)
			(xy 439.287131 -99.339466) (xy 439.324348 -99.381003) (xy 439.355121 -99.427516) (xy 439.378793 -99.478013)
			(xy 439.394861 -99.53142) (xy 439.402981 -99.586596) (xy 439.40349 -99.614482) (xy 439.403281 -99.625912)
			(xy 439.80684 -99.625912) (xy 439.810911 -99.57029) (xy 439.823037 -99.515853) (xy 439.84296 -99.463762)
			(xy 439.870256 -99.415127) (xy 439.904342 -99.370984) (xy 439.944491 -99.332275) (xy 439.989849 -99.299824)
			(xy 440.039449 -99.274323) (xy 440.092233 -99.256316) (xy 440.147076 -99.246186) (xy 440.20281 -99.244149)
			(xy 440.258247 -99.250249) (xy 440.312204 -99.264355) (xy 440.363533 -99.286167) (xy 440.411139 -99.315221)
			(xy 440.454007 -99.350896) (xy 440.491224 -99.392433) (xy 440.521997 -99.438946) (xy 440.531176 -99.458526)
			(xy 441.938662 -99.458526) (xy 441.942733 -99.402904) (xy 441.954859 -99.348467) (xy 441.974782 -99.296376)
			(xy 442.002078 -99.247741) (xy 442.036164 -99.203598) (xy 442.076313 -99.164889) (xy 442.121671 -99.132438)
			(xy 442.171271 -99.106937) (xy 442.224055 -99.08893) (xy 442.278898 -99.0788) (xy 442.334632 -99.076763)
			(xy 442.390069 -99.082863) (xy 442.444026 -99.096969) (xy 442.495355 -99.118781) (xy 442.542961 -99.147835)
			(xy 442.585829 -99.18351) (xy 442.623046 -99.225047) (xy 442.653819 -99.27156) (xy 442.677491 -99.322057)
			(xy 442.693559 -99.375464) (xy 442.701679 -99.43064) (xy 442.702188 -99.458526) (xy 442.701679 -99.486412)
			(xy 442.693559 -99.541588) (xy 442.677491 -99.594995) (xy 442.653819 -99.645492) (xy 442.623046 -99.692005)
			(xy 442.585829 -99.733542) (xy 442.542961 -99.769217) (xy 442.495355 -99.798271) (xy 442.444026 -99.820083)
			(xy 442.390069 -99.834189) (xy 442.334632 -99.840289) (xy 442.278898 -99.838252) (xy 442.224055 -99.828122)
			(xy 442.171271 -99.810115) (xy 442.121671 -99.784614) (xy 442.076313 -99.752163) (xy 442.036164 -99.713454)
			(xy 442.002078 -99.669311) (xy 441.974782 -99.620676) (xy 441.954859 -99.568585) (xy 441.942733 -99.514148)
			(xy 441.938662 -99.458526) (xy 440.531176 -99.458526) (xy 440.545669 -99.489443) (xy 440.561737 -99.54285)
			(xy 440.569857 -99.598026) (xy 440.570366 -99.625912) (xy 440.569857 -99.653798) (xy 440.561737 -99.708974)
			(xy 440.545669 -99.762381) (xy 440.521997 -99.812878) (xy 440.491224 -99.859391) (xy 440.454007 -99.900928)
			(xy 440.411139 -99.936603) (xy 440.363533 -99.965657) (xy 440.312204 -99.987469) (xy 440.258247 -100.001575)
			(xy 440.20281 -100.007675) (xy 440.147076 -100.005638) (xy 440.092233 -99.995508) (xy 440.039449 -99.977501)
			(xy 439.989849 -99.952) (xy 439.944491 -99.919549) (xy 439.904342 -99.88084) (xy 439.870256 -99.836697)
			(xy 439.84296 -99.788062) (xy 439.823037 -99.735971) (xy 439.810911 -99.681534) (xy 439.80684 -99.625912)
			(xy 439.403281 -99.625912) (xy 439.402981 -99.642368) (xy 439.394861 -99.697544) (xy 439.378793 -99.750951)
			(xy 439.355121 -99.801448) (xy 439.324348 -99.847961) (xy 439.287131 -99.889498) (xy 439.244263 -99.925173)
			(xy 439.196657 -99.954227) (xy 439.145328 -99.976039) (xy 439.091371 -99.990145) (xy 439.035934 -99.996245)
			(xy 438.9802 -99.994208) (xy 438.925357 -99.984078) (xy 438.872573 -99.966071) (xy 438.822973 -99.94057)
			(xy 438.777615 -99.908119) (xy 438.737466 -99.86941) (xy 438.70338 -99.825267) (xy 438.676084 -99.776632)
			(xy 438.656161 -99.724541) (xy 438.644035 -99.670104) (xy 438.639964 -99.614482) (xy 436.931543 -99.614482)
			(xy 436.921293 -99.636348) (xy 436.89052 -99.682861) (xy 436.853303 -99.724398) (xy 436.810435 -99.760073)
			(xy 436.762829 -99.789127) (xy 436.7115 -99.810939) (xy 436.657543 -99.825045) (xy 436.602106 -99.831145)
			(xy 436.546372 -99.829108) (xy 436.491529 -99.818978) (xy 436.438745 -99.800971) (xy 436.389145 -99.77547)
			(xy 436.343787 -99.743019) (xy 436.303638 -99.70431) (xy 436.269552 -99.660167) (xy 436.242256 -99.611532)
			(xy 436.222333 -99.559441) (xy 436.210207 -99.505004) (xy 436.206136 -99.449382) (xy 424.373376 -99.449382)
			(xy 424.373039 -99.46787) (xy 424.364919 -99.523046) (xy 424.348851 -99.576453) (xy 424.325179 -99.62695)
			(xy 424.294406 -99.673463) (xy 424.257189 -99.715) (xy 424.214321 -99.750675) (xy 424.166715 -99.779729)
			(xy 424.115386 -99.801541) (xy 424.061429 -99.815647) (xy 424.005992 -99.821747) (xy 423.950258 -99.81971)
			(xy 423.895415 -99.80958) (xy 423.842631 -99.791573) (xy 423.793031 -99.766072) (xy 423.747673 -99.733621)
			(xy 423.707524 -99.694912) (xy 423.673438 -99.650769) (xy 423.646142 -99.602134) (xy 423.626219 -99.550043)
			(xy 423.614093 -99.495606) (xy 423.610022 -99.439984) (xy 419.089082 -99.439984) (xy 419.074224 -99.457131)
			(xy 419.03303 -99.492825) (xy 418.987176 -99.522292) (xy 418.937594 -99.544934) (xy 418.885295 -99.56029)
			(xy 418.831343 -99.568045) (xy 418.80409 -99.568508) (xy 418.777486 -99.568063) (xy 418.724793 -99.56068)
			(xy 418.673637 -99.546045) (xy 418.625012 -99.524442) (xy 418.579862 -99.49629) (xy 418.539063 -99.462135)
			(xy 418.503407 -99.422642) (xy 418.488114 -99.400868) (xy 418.47978 -99.389388) (xy 418.458036 -99.371184)
			(xy 418.432123 -99.359666) (xy 418.40404 -99.355726) (xy 418.375957 -99.359666) (xy 418.350044 -99.371184)
			(xy 418.3283 -99.389388) (xy 418.319966 -99.400868) (xy 418.304644 -99.422618) (xy 418.268982 -99.462097)
			(xy 418.228183 -99.496242) (xy 418.183038 -99.52439) (xy 418.134421 -99.545995) (xy 418.083275 -99.56064)
			(xy 418.030591 -99.568041) (xy 418.00399 -99.568508) (xy 417.976739 -99.568022) (xy 417.922793 -99.560264)
			(xy 417.870499 -99.544908) (xy 417.820923 -99.522266) (xy 417.775074 -99.4928) (xy 417.733885 -99.457108)
			(xy 417.698194 -99.415918) (xy 417.668729 -99.370068) (xy 417.646089 -99.320492) (xy 417.630734 -99.268198)
			(xy 417.622978 -99.214251) (xy 403.615144 -99.214251) (xy 403.615144 -99.750372) (xy 405.89784 -99.750372)
			(xy 405.901911 -99.69475) (xy 405.914037 -99.640313) (xy 405.93396 -99.588222) (xy 405.961256 -99.539587)
			(xy 405.995342 -99.495444) (xy 406.035491 -99.456735) (xy 406.080849 -99.424284) (xy 406.130449 -99.398783)
			(xy 406.183233 -99.380776) (xy 406.238076 -99.370646) (xy 406.29381 -99.368609) (xy 406.349247 -99.374709)
			(xy 406.403204 -99.388815) (xy 406.454533 -99.410627) (xy 406.502139 -99.439681) (xy 406.545007 -99.475356)
			(xy 406.582224 -99.516893) (xy 406.612997 -99.563406) (xy 406.636669 -99.613903) (xy 406.652737 -99.66731)
			(xy 406.660857 -99.722486) (xy 406.661366 -99.750372) (xy 406.660857 -99.778258) (xy 406.652737 -99.833434)
			(xy 406.636669 -99.886841) (xy 406.612997 -99.937338) (xy 406.582224 -99.983851) (xy 406.545007 -100.025388)
			(xy 406.527531 -100.039932) (xy 422.176954 -100.039932) (xy 422.181025 -99.98431) (xy 422.193151 -99.929873)
			(xy 422.213074 -99.877782) (xy 422.24037 -99.829147) (xy 422.274456 -99.785004) (xy 422.314605 -99.746295)
			(xy 422.359963 -99.713844) (xy 422.409563 -99.688343) (xy 422.462347 -99.670336) (xy 422.51719 -99.660206)
			(xy 422.572924 -99.658169) (xy 422.628361 -99.664269) (xy 422.682318 -99.678375) (xy 422.733647 -99.700187)
			(xy 422.781253 -99.729241) (xy 422.824121 -99.764916) (xy 422.861338 -99.806453) (xy 422.892111 -99.852966)
			(xy 422.915783 -99.903463) (xy 422.931851 -99.95687) (xy 422.939971 -100.012046) (xy 422.94048 -100.039932)
			(xy 422.940174 -100.056696) (xy 426.469554 -100.056696) (xy 426.473625 -100.001074) (xy 426.485751 -99.946637)
			(xy 426.505674 -99.894546) (xy 426.53297 -99.845911) (xy 426.567056 -99.801768) (xy 426.607205 -99.763059)
			(xy 426.652563 -99.730608) (xy 426.702163 -99.705107) (xy 426.754947 -99.6871) (xy 426.80979 -99.67697)
			(xy 426.865524 -99.674933) (xy 426.920961 -99.681033) (xy 426.974918 -99.695139) (xy 427.026247 -99.716951)
			(xy 427.073853 -99.746005) (xy 427.116721 -99.78168) (xy 427.153938 -99.823217) (xy 427.184711 -99.86973)
			(xy 427.208383 -99.920227) (xy 427.224451 -99.973634) (xy 427.232571 -100.02881) (xy 427.23308 -100.056696)
			(xy 427.232571 -100.084582) (xy 427.224451 -100.139758) (xy 427.208383 -100.193165) (xy 427.184711 -100.243662)
			(xy 427.153938 -100.290175) (xy 427.116721 -100.331712) (xy 427.073853 -100.367387) (xy 427.031898 -100.392992)
			(xy 443.67399 -100.392992) (xy 443.678061 -100.33737) (xy 443.690187 -100.282933) (xy 443.71011 -100.230842)
			(xy 443.737406 -100.182207) (xy 443.771492 -100.138064) (xy 443.811641 -100.099355) (xy 443.856999 -100.066904)
			(xy 443.906599 -100.041403) (xy 443.959383 -100.023396) (xy 444.014226 -100.013266) (xy 444.06996 -100.011229)
			(xy 444.125397 -100.017329) (xy 444.179354 -100.031435) (xy 444.230683 -100.053247) (xy 444.278289 -100.082301)
			(xy 444.321157 -100.117976) (xy 444.358374 -100.159513) (xy 444.389147 -100.206026) (xy 444.412819 -100.256523)
			(xy 444.428887 -100.30993) (xy 444.437007 -100.365106) (xy 444.437516 -100.392992) (xy 444.437007 -100.420878)
			(xy 444.428887 -100.476054) (xy 444.412819 -100.529461) (xy 444.389147 -100.579958) (xy 444.358374 -100.626471)
			(xy 444.321157 -100.668008) (xy 444.278289 -100.703683) (xy 444.230683 -100.732737) (xy 444.179354 -100.754549)
			(xy 444.125397 -100.768655) (xy 444.06996 -100.774755) (xy 444.014226 -100.772718) (xy 443.959383 -100.762588)
			(xy 443.906599 -100.744581) (xy 443.856999 -100.71908) (xy 443.811641 -100.686629) (xy 443.771492 -100.64792)
			(xy 443.737406 -100.603777) (xy 443.71011 -100.555142) (xy 443.690187 -100.503051) (xy 443.678061 -100.448614)
			(xy 443.67399 -100.392992) (xy 427.031898 -100.392992) (xy 427.026247 -100.396441) (xy 426.974918 -100.418253)
			(xy 426.920961 -100.432359) (xy 426.865524 -100.438459) (xy 426.80979 -100.436422) (xy 426.754947 -100.426292)
			(xy 426.702163 -100.408285) (xy 426.652563 -100.382784) (xy 426.607205 -100.350333) (xy 426.567056 -100.311624)
			(xy 426.53297 -100.267481) (xy 426.505674 -100.218846) (xy 426.485751 -100.166755) (xy 426.473625 -100.112318)
			(xy 426.469554 -100.056696) (xy 422.940174 -100.056696) (xy 422.939971 -100.067818) (xy 422.931851 -100.122994)
			(xy 422.915783 -100.176401) (xy 422.892111 -100.226898) (xy 422.861338 -100.273411) (xy 422.824121 -100.314948)
			(xy 422.781253 -100.350623) (xy 422.733647 -100.379677) (xy 422.682318 -100.401489) (xy 422.628361 -100.415595)
			(xy 422.572924 -100.421695) (xy 422.51719 -100.419658) (xy 422.462347 -100.409528) (xy 422.409563 -100.391521)
			(xy 422.359963 -100.36602) (xy 422.314605 -100.333569) (xy 422.274456 -100.29486) (xy 422.24037 -100.250717)
			(xy 422.213074 -100.202082) (xy 422.193151 -100.149991) (xy 422.181025 -100.095554) (xy 422.176954 -100.039932)
			(xy 406.527531 -100.039932) (xy 406.502139 -100.061063) (xy 406.454533 -100.090117) (xy 406.403204 -100.111929)
			(xy 406.349247 -100.126035) (xy 406.29381 -100.132135) (xy 406.238076 -100.130098) (xy 406.183233 -100.119968)
			(xy 406.130449 -100.101961) (xy 406.080849 -100.07646) (xy 406.035491 -100.044009) (xy 405.995342 -100.0053)
			(xy 405.961256 -99.961157) (xy 405.93396 -99.912522) (xy 405.914037 -99.860431) (xy 405.901911 -99.805994)
			(xy 405.89784 -99.750372) (xy 403.615144 -99.750372) (xy 403.615144 -101.240082) (xy 422.594022 -101.240082)
			(xy 422.598093 -101.18446) (xy 422.610219 -101.130023) (xy 422.630142 -101.077932) (xy 422.657438 -101.029297)
			(xy 422.691524 -100.985154) (xy 422.731673 -100.946445) (xy 422.777031 -100.913994) (xy 422.826631 -100.888493)
			(xy 422.879415 -100.870486) (xy 422.934258 -100.860356) (xy 422.989992 -100.858319) (xy 423.045429 -100.864419)
			(xy 423.099386 -100.878525) (xy 423.150715 -100.900337) (xy 423.198321 -100.929391) (xy 423.241189 -100.965066)
			(xy 423.278406 -101.006603) (xy 423.309179 -101.053116) (xy 423.316929 -101.069648) (xy 423.886374 -101.069648)
			(xy 423.890445 -101.014026) (xy 423.902571 -100.959589) (xy 423.922494 -100.907498) (xy 423.94979 -100.858863)
			(xy 423.983876 -100.81472) (xy 424.024025 -100.776011) (xy 424.069383 -100.74356) (xy 424.118983 -100.718059)
			(xy 424.171767 -100.700052) (xy 424.22661 -100.689922) (xy 424.282344 -100.687885) (xy 424.337781 -100.693985)
			(xy 424.391738 -100.708091) (xy 424.443067 -100.729903) (xy 424.490673 -100.758957) (xy 424.533541 -100.794632)
			(xy 424.541902 -100.803964) (xy 438.651394 -100.803964) (xy 438.655465 -100.748342) (xy 438.667591 -100.693905)
			(xy 438.687514 -100.641814) (xy 438.71481 -100.593179) (xy 438.748896 -100.549036) (xy 438.789045 -100.510327)
			(xy 438.834403 -100.477876) (xy 438.884003 -100.452375) (xy 438.936787 -100.434368) (xy 438.99163 -100.424238)
			(xy 439.047364 -100.422201) (xy 439.102801 -100.428301) (xy 439.156758 -100.442407) (xy 439.208087 -100.464219)
			(xy 439.255693 -100.493273) (xy 439.298561 -100.528948) (xy 439.335778 -100.570485) (xy 439.366551 -100.616998)
			(xy 439.390223 -100.667495) (xy 439.406291 -100.720902) (xy 439.414411 -100.776078) (xy 439.41492 -100.803964)
			(xy 439.818016 -100.803964) (xy 439.822087 -100.748342) (xy 439.834213 -100.693905) (xy 439.854136 -100.641814)
			(xy 439.881432 -100.593179) (xy 439.915518 -100.549036) (xy 439.955667 -100.510327) (xy 440.001025 -100.477876)
			(xy 440.050625 -100.452375) (xy 440.103409 -100.434368) (xy 440.158252 -100.424238) (xy 440.213986 -100.422201)
			(xy 440.269423 -100.428301) (xy 440.32338 -100.442407) (xy 440.374709 -100.464219) (xy 440.422315 -100.493273)
			(xy 440.465183 -100.528948) (xy 440.5024 -100.570485) (xy 440.533173 -100.616998) (xy 440.556845 -100.667495)
			(xy 440.572913 -100.720902) (xy 440.581033 -100.776078) (xy 440.581542 -100.803964) (xy 440.581033 -100.83185)
			(xy 440.572913 -100.887026) (xy 440.556845 -100.940433) (xy 440.533173 -100.99093) (xy 440.5024 -101.037443)
			(xy 440.465183 -101.07898) (xy 440.422315 -101.114655) (xy 440.374709 -101.143709) (xy 440.32338 -101.165521)
			(xy 440.269423 -101.179627) (xy 440.213986 -101.185727) (xy 440.158252 -101.18369) (xy 440.103409 -101.17356)
			(xy 440.050625 -101.155553) (xy 440.001025 -101.130052) (xy 439.955667 -101.097601) (xy 439.915518 -101.058892)
			(xy 439.881432 -101.014749) (xy 439.854136 -100.966114) (xy 439.834213 -100.914023) (xy 439.822087 -100.859586)
			(xy 439.818016 -100.803964) (xy 439.41492 -100.803964) (xy 439.414411 -100.83185) (xy 439.406291 -100.887026)
			(xy 439.390223 -100.940433) (xy 439.366551 -100.99093) (xy 439.335778 -101.037443) (xy 439.298561 -101.07898)
			(xy 439.255693 -101.114655) (xy 439.208087 -101.143709) (xy 439.156758 -101.165521) (xy 439.102801 -101.179627)
			(xy 439.047364 -101.185727) (xy 438.99163 -101.18369) (xy 438.936787 -101.17356) (xy 438.884003 -101.155553)
			(xy 438.834403 -101.130052) (xy 438.789045 -101.097601) (xy 438.748896 -101.058892) (xy 438.71481 -101.014749)
			(xy 438.687514 -100.966114) (xy 438.667591 -100.914023) (xy 438.655465 -100.859586) (xy 438.651394 -100.803964)
			(xy 424.541902 -100.803964) (xy 424.570758 -100.836169) (xy 424.601531 -100.882682) (xy 424.625203 -100.933179)
			(xy 424.641271 -100.986586) (xy 424.649391 -101.041762) (xy 424.6499 -101.069648) (xy 424.649391 -101.097534)
			(xy 424.641271 -101.15271) (xy 424.630097 -101.18985) (xy 445.29349 -101.18985) (xy 445.29349 -101.13535)
			(xy 445.301246 -101.081404) (xy 445.316601 -101.029111) (xy 445.339241 -100.979536) (xy 445.368706 -100.933687)
			(xy 445.404396 -100.892499) (xy 445.445584 -100.856808) (xy 445.491433 -100.827343) (xy 445.541008 -100.804702)
			(xy 445.5933 -100.789347) (xy 445.647246 -100.781591) (xy 445.674496 -100.781104) (xy 445.701866 -100.781571)
			(xy 445.756045 -100.789389) (xy 445.808548 -100.804877) (xy 445.858295 -100.827719) (xy 445.904262 -100.857443)
			(xy 445.925194 -100.875084) (xy 445.932306 -100.88118) (xy 445.94907 -100.88753) (xy 446.007744 -100.88753)
			(xy 446.007744 -100.875084) (xy 446.0494 -100.875084) (xy 446.065148 -100.869496) (xy 446.072006 -100.864162)
			(xy 446.092324 -100.848499) (xy 446.136372 -100.822199) (xy 446.183551 -100.802047) (xy 446.233006 -100.788406)
			(xy 446.283845 -100.781523) (xy 446.309496 -100.781104) (xy 446.33675 -100.781543) (xy 446.390703 -100.789299)
			(xy 446.443003 -100.804656) (xy 446.492585 -100.827299) (xy 446.53844 -100.856767) (xy 446.579635 -100.892462)
			(xy 446.61533 -100.933656) (xy 446.6448 -100.979511) (xy 446.667443 -101.029093) (xy 446.6828 -101.081393)
			(xy 446.690557 -101.135346) (xy 446.690557 -101.189854) (xy 446.6828 -101.243807) (xy 446.667443 -101.296107)
			(xy 446.650574 -101.333046) (xy 448.233798 -101.333046) (xy 448.237869 -101.277424) (xy 448.249995 -101.222987)
			(xy 448.269918 -101.170896) (xy 448.297214 -101.122261) (xy 448.3313 -101.078118) (xy 448.371449 -101.039409)
			(xy 448.416807 -101.006958) (xy 448.466407 -100.981457) (xy 448.519191 -100.96345) (xy 448.574034 -100.95332)
			(xy 448.629768 -100.951283) (xy 448.685205 -100.957383) (xy 448.739162 -100.971489) (xy 448.790491 -100.993301)
			(xy 448.838097 -101.022355) (xy 448.880965 -101.05803) (xy 448.918182 -101.099567) (xy 448.948955 -101.14608)
			(xy 448.972627 -101.196577) (xy 448.988695 -101.249984) (xy 448.996815 -101.30516) (xy 448.997324 -101.333046)
			(xy 448.996815 -101.360932) (xy 448.988695 -101.416108) (xy 448.972627 -101.469515) (xy 448.948955 -101.520012)
			(xy 448.918182 -101.566525) (xy 448.880965 -101.608062) (xy 448.838097 -101.643737) (xy 448.790491 -101.672791)
			(xy 448.739162 -101.694603) (xy 448.685205 -101.708709) (xy 448.629768 -101.714809) (xy 448.574034 -101.712772)
			(xy 448.519191 -101.702642) (xy 448.466407 -101.684635) (xy 448.416807 -101.659134) (xy 448.371449 -101.626683)
			(xy 448.3313 -101.587974) (xy 448.297214 -101.543831) (xy 448.269918 -101.495196) (xy 448.249995 -101.443105)
			(xy 448.237869 -101.388668) (xy 448.233798 -101.333046) (xy 446.650574 -101.333046) (xy 446.6448 -101.345689)
			(xy 446.61533 -101.391544) (xy 446.579635 -101.432738) (xy 446.53844 -101.468433) (xy 446.492585 -101.497901)
			(xy 446.443003 -101.520544) (xy 446.390703 -101.535901) (xy 446.33675 -101.543657) (xy 446.309496 -101.54412)
			(xy 446.282125 -101.543676) (xy 446.227944 -101.535856) (xy 446.17544 -101.520363) (xy 446.125693 -101.497515)
			(xy 446.079728 -101.467785) (xy 446.058798 -101.45014) (xy 446.051686 -101.444044) (xy 446.034922 -101.437694)
			(xy 445.976248 -101.437694) (xy 445.976248 -101.45014) (xy 445.934592 -101.45014) (xy 445.918844 -101.455728)
			(xy 445.911986 -101.461062) (xy 445.891673 -101.476732) (xy 445.847623 -101.50303) (xy 445.800443 -101.523181)
			(xy 445.750987 -101.536821) (xy 445.700147 -101.543703) (xy 445.674496 -101.54412) (xy 445.647246 -101.543609)
			(xy 445.5933 -101.535853) (xy 445.541008 -101.520498) (xy 445.491433 -101.497857) (xy 445.445584 -101.468392)
			(xy 445.404396 -101.432701) (xy 445.368706 -101.391513) (xy 445.339241 -101.345664) (xy 445.316601 -101.296089)
			(xy 445.301246 -101.243796) (xy 445.29349 -101.18985) (xy 424.630097 -101.18985) (xy 424.625203 -101.206117)
			(xy 424.601531 -101.256614) (xy 424.570758 -101.303127) (xy 424.533541 -101.344664) (xy 424.490673 -101.380339)
			(xy 424.443067 -101.409393) (xy 424.391738 -101.431205) (xy 424.337781 -101.445311) (xy 424.282344 -101.451411)
			(xy 424.22661 -101.449374) (xy 424.171767 -101.439244) (xy 424.118983 -101.421237) (xy 424.069383 -101.395736)
			(xy 424.024025 -101.363285) (xy 423.983876 -101.324576) (xy 423.94979 -101.280433) (xy 423.922494 -101.231798)
			(xy 423.902571 -101.179707) (xy 423.890445 -101.12527) (xy 423.886374 -101.069648) (xy 423.316929 -101.069648)
			(xy 423.332851 -101.103613) (xy 423.348919 -101.15702) (xy 423.357039 -101.212196) (xy 423.357548 -101.240082)
			(xy 423.357039 -101.267968) (xy 423.348919 -101.323144) (xy 423.332851 -101.376551) (xy 423.309179 -101.427048)
			(xy 423.278406 -101.473561) (xy 423.241189 -101.515098) (xy 423.198321 -101.550773) (xy 423.151788 -101.579172)
			(xy 436.070754 -101.579172) (xy 436.074825 -101.52355) (xy 436.086951 -101.469113) (xy 436.106874 -101.417022)
			(xy 436.13417 -101.368387) (xy 436.168256 -101.324244) (xy 436.208405 -101.285535) (xy 436.253763 -101.253084)
			(xy 436.303363 -101.227583) (xy 436.356147 -101.209576) (xy 436.41099 -101.199446) (xy 436.466724 -101.197409)
			(xy 436.522161 -101.203509) (xy 436.576118 -101.217615) (xy 436.627447 -101.239427) (xy 436.675053 -101.268481)
			(xy 436.717921 -101.304156) (xy 436.755138 -101.345693) (xy 436.785911 -101.392206) (xy 436.809583 -101.442703)
			(xy 436.825651 -101.49611) (xy 436.833771 -101.551286) (xy 436.83428 -101.579172) (xy 436.833771 -101.607058)
			(xy 436.825651 -101.662234) (xy 436.809583 -101.715641) (xy 436.785911 -101.766138) (xy 436.755138 -101.812651)
			(xy 436.717921 -101.854188) (xy 436.698003 -101.870764) (xy 441.53912 -101.870764) (xy 441.543191 -101.815142)
			(xy 441.555317 -101.760705) (xy 441.57524 -101.708614) (xy 441.602536 -101.659979) (xy 441.636622 -101.615836)
			(xy 441.676771 -101.577127) (xy 441.722129 -101.544676) (xy 441.771729 -101.519175) (xy 441.824513 -101.501168)
			(xy 441.879356 -101.491038) (xy 441.93509 -101.489001) (xy 441.990527 -101.495101) (xy 442.044484 -101.509207)
			(xy 442.095813 -101.531019) (xy 442.143419 -101.560073) (xy 442.186287 -101.595748) (xy 442.223504 -101.637285)
			(xy 442.254277 -101.683798) (xy 442.277949 -101.734295) (xy 442.294017 -101.787702) (xy 442.302137 -101.842878)
			(xy 442.302646 -101.870764) (xy 442.302137 -101.89865) (xy 442.294017 -101.953826) (xy 442.277949 -102.007233)
			(xy 442.254277 -102.05773) (xy 442.223504 -102.104243) (xy 442.200022 -102.130451) (xy 444.843152 -102.130451)
			(xy 444.843152 -102.075949) (xy 444.850908 -102.022002) (xy 444.866261 -101.969707) (xy 444.888901 -101.920129)
			(xy 444.918365 -101.874278) (xy 444.954054 -101.833086) (xy 444.995241 -101.797392) (xy 445.041089 -101.767923)
			(xy 445.090664 -101.745277) (xy 445.142957 -101.729917) (xy 445.196903 -101.722155) (xy 445.224154 -101.721666)
			(xy 445.251524 -101.722143) (xy 445.305703 -101.729956) (xy 445.358207 -101.745441) (xy 445.407954 -101.768281)
			(xy 445.453921 -101.798005) (xy 445.474852 -101.815646) (xy 445.481964 -101.821742) (xy 445.498728 -101.828092)
			(xy 445.557402 -101.828092) (xy 445.557402 -101.815646) (xy 445.599058 -101.815646) (xy 445.614806 -101.810058)
			(xy 445.621664 -101.804724) (xy 445.641992 -101.789075) (xy 445.686038 -101.762774) (xy 445.733214 -101.742619)
			(xy 445.782667 -101.728974) (xy 445.833504 -101.722087) (xy 445.859154 -101.721666) (xy 445.886407 -101.722178)
			(xy 445.940359 -101.729929) (xy 445.992659 -101.74528) (xy 446.042242 -101.767919) (xy 446.088097 -101.797383)
			(xy 446.129293 -101.833075) (xy 446.164989 -101.874266) (xy 446.194459 -101.920118) (xy 446.217104 -101.969698)
			(xy 446.232461 -102.021996) (xy 446.240219 -102.075947) (xy 446.240219 -102.095046) (xy 447.598798 -102.095046)
			(xy 447.602869 -102.039424) (xy 447.614995 -101.984987) (xy 447.634918 -101.932896) (xy 447.662214 -101.884261)
			(xy 447.6963 -101.840118) (xy 447.736449 -101.801409) (xy 447.781807 -101.768958) (xy 447.831407 -101.743457)
			(xy 447.884191 -101.72545) (xy 447.939034 -101.71532) (xy 447.994768 -101.713283) (xy 448.050205 -101.719383)
			(xy 448.104162 -101.733489) (xy 448.155491 -101.755301) (xy 448.203097 -101.784355) (xy 448.245965 -101.82003)
			(xy 448.283182 -101.861567) (xy 448.313955 -101.90808) (xy 448.337627 -101.958577) (xy 448.353695 -102.011984)
			(xy 448.361815 -102.06716) (xy 448.362324 -102.095046) (xy 448.361815 -102.122932) (xy 448.353695 -102.178108)
			(xy 448.337627 -102.231515) (xy 448.313955 -102.282012) (xy 448.303142 -102.298356) (xy 449.396523 -102.298356)
			(xy 449.396523 -102.243844) (xy 449.404281 -102.189888) (xy 449.419639 -102.137584) (xy 449.442284 -102.087999)
			(xy 449.471756 -102.042142) (xy 449.507454 -102.000945) (xy 449.548651 -101.965249) (xy 449.59451 -101.935778)
			(xy 449.644096 -101.913135) (xy 449.696399 -101.897778) (xy 449.750356 -101.890022) (xy 449.777612 -101.88956)
			(xy 449.804983 -101.890004) (xy 449.859164 -101.897825) (xy 449.911668 -101.913319) (xy 449.961414 -101.936165)
			(xy 450.00738 -101.965896) (xy 450.02831 -101.98354) (xy 450.035422 -101.989636) (xy 450.052186 -101.995986)
			(xy 450.11086 -101.995986) (xy 450.11086 -101.98354) (xy 450.152516 -101.98354) (xy 450.168264 -101.977952)
			(xy 450.175122 -101.972618) (xy 450.19543 -101.956941) (xy 450.239482 -101.930645) (xy 450.286663 -101.910496)
			(xy 450.33612 -101.896857) (xy 450.38696 -101.889977) (xy 450.412612 -101.88956) (xy 450.43986 -101.890111)
			(xy 450.493802 -101.897868) (xy 450.546091 -101.913223) (xy 450.595663 -101.935863) (xy 450.641508 -101.965327)
			(xy 450.682693 -102.001016) (xy 450.700783 -102.021894) (xy 451.256654 -102.021894) (xy 451.257103 -101.994523)
			(xy 451.264923 -101.940343) (xy 451.280415 -101.887839) (xy 451.303261 -101.838092) (xy 451.33299 -101.792127)
			(xy 451.350634 -101.771196) (xy 451.35673 -101.764084) (xy 451.36308 -101.74732) (xy 451.36308 -101.688646)
			(xy 451.350634 -101.688646) (xy 451.350634 -101.64699) (xy 451.345046 -101.631242) (xy 451.339712 -101.624384)
			(xy 451.323596 -101.603334) (xy 451.296631 -101.557692) (xy 451.276249 -101.508754) (xy 451.262842 -101.457465)
			(xy 451.25667 -101.404813) (xy 451.257852 -101.351814) (xy 451.266364 -101.299489) (xy 451.282042 -101.248849)
			(xy 451.304584 -101.200868) (xy 451.333556 -101.156472) (xy 451.350634 -101.136196) (xy 451.35673 -101.129084)
			(xy 451.36308 -101.11232) (xy 451.36308 -101.053646) (xy 451.350634 -101.053646) (xy 451.350634 -101.01199)
			(xy 451.345046 -100.996242) (xy 451.339712 -100.989384) (xy 451.324037 -100.969075) (xy 451.297741 -100.925023)
			(xy 451.277591 -100.877843) (xy 451.263952 -100.828385) (xy 451.257071 -100.777546) (xy 451.256654 -100.751894)
			(xy 451.25714 -100.724643) (xy 451.264896 -100.670695) (xy 451.280251 -100.6184) (xy 451.302893 -100.568823)
			(xy 451.332359 -100.522973) (xy 451.36805 -100.481782) (xy 451.409241 -100.446091) (xy 451.455091 -100.416625)
			(xy 451.504668 -100.393983) (xy 451.556963 -100.378628) (xy 451.610911 -100.370872) (xy 451.665413 -100.370872)
			(xy 451.719361 -100.378628) (xy 451.771656 -100.393983) (xy 451.821233 -100.416625) (xy 451.867083 -100.446091)
			(xy 451.908274 -100.481782) (xy 451.943965 -100.522973) (xy 451.973431 -100.568823) (xy 451.996073 -100.6184)
			(xy 452.011428 -100.670695) (xy 452.019184 -100.724643) (xy 452.01967 -100.751894) (xy 452.019208 -100.779264)
			(xy 452.01139 -100.833444) (xy 451.995901 -100.885947) (xy 451.973058 -100.935694) (xy 451.943332 -100.981661)
			(xy 451.92569 -101.002592) (xy 451.919594 -101.009704) (xy 451.913244 -101.026468) (xy 451.913244 -101.085142)
			(xy 451.92569 -101.085142) (xy 451.92569 -101.126798) (xy 451.931278 -101.142546) (xy 451.936612 -101.149404)
			(xy 451.952813 -101.170391) (xy 451.979772 -101.216045) (xy 452.000147 -101.264993) (xy 452.013546 -101.316292)
			(xy 452.019709 -101.368952) (xy 452.018518 -101.421958) (xy 452.009996 -101.474289) (xy 451.994308 -101.524934)
			(xy 451.971755 -101.572918) (xy 451.942773 -101.617315) (xy 451.92569 -101.637592) (xy 451.919594 -101.644704)
			(xy 451.913244 -101.661468) (xy 451.913244 -101.720142) (xy 451.92569 -101.720142) (xy 451.92569 -101.761798)
			(xy 451.931278 -101.777546) (xy 451.936612 -101.784404) (xy 451.95227 -101.804726) (xy 451.978571 -101.848773)
			(xy 451.998725 -101.89595) (xy 452.012368 -101.945405) (xy 452.019251 -101.996243) (xy 452.01967 -102.021894)
			(xy 452.019184 -102.049145) (xy 452.011428 -102.103093) (xy 451.996073 -102.155388) (xy 451.973431 -102.204965)
			(xy 451.943965 -102.250815) (xy 451.908274 -102.292006) (xy 451.867083 -102.327697) (xy 451.821233 -102.357163)
			(xy 451.771656 -102.379805) (xy 451.719361 -102.39516) (xy 451.665413 -102.402916) (xy 451.610911 -102.402916)
			(xy 451.556963 -102.39516) (xy 451.504668 -102.379805) (xy 451.455091 -102.357163) (xy 451.409241 -102.327697)
			(xy 451.36805 -102.292006) (xy 451.332359 -102.250815) (xy 451.302893 -102.204965) (xy 451.280251 -102.155388)
			(xy 451.264896 -102.103093) (xy 451.25714 -102.049145) (xy 451.256654 -102.021894) (xy 450.700783 -102.021894)
			(xy 450.71838 -102.042202) (xy 450.747843 -102.088048) (xy 450.770481 -102.13762) (xy 450.785834 -102.18991)
			(xy 450.79359 -102.243852) (xy 450.79359 -102.298348) (xy 450.785834 -102.35229) (xy 450.770481 -102.40458)
			(xy 450.747843 -102.454152) (xy 450.71838 -102.499998) (xy 450.682693 -102.541184) (xy 450.641508 -102.576873)
			(xy 450.595663 -102.606337) (xy 450.546091 -102.628977) (xy 450.493802 -102.644332) (xy 450.43986 -102.652089)
			(xy 450.412612 -102.652576) (xy 450.385242 -102.652109) (xy 450.331062 -102.644292) (xy 450.278559 -102.628804)
			(xy 450.228812 -102.605962) (xy 450.182846 -102.576237) (xy 450.161914 -102.558596) (xy 450.154802 -102.5525)
			(xy 450.138038 -102.54615) (xy 450.079364 -102.54615) (xy 450.079364 -102.558596) (xy 450.037708 -102.558596)
			(xy 450.02196 -102.564184) (xy 450.015102 -102.569518) (xy 449.994779 -102.585174) (xy 449.950732 -102.611476)
			(xy 449.903555 -102.63163) (xy 449.854101 -102.645273) (xy 449.803263 -102.652157) (xy 449.777612 -102.652576)
			(xy 449.750356 -102.652178) (xy 449.696399 -102.644422) (xy 449.644096 -102.629065) (xy 449.59451 -102.606422)
			(xy 449.548651 -102.576951) (xy 449.507454 -102.541255) (xy 449.471756 -102.500058) (xy 449.442284 -102.454201)
			(xy 449.419639 -102.404616) (xy 449.404281 -102.352312) (xy 449.396523 -102.298356) (xy 448.303142 -102.298356)
			(xy 448.283182 -102.328525) (xy 448.245965 -102.370062) (xy 448.203097 -102.405737) (xy 448.155491 -102.434791)
			(xy 448.104162 -102.456603) (xy 448.050205 -102.470709) (xy 447.994768 -102.476809) (xy 447.939034 -102.474772)
			(xy 447.884191 -102.464642) (xy 447.831407 -102.446635) (xy 447.781807 -102.421134) (xy 447.736449 -102.388683)
			(xy 447.6963 -102.349974) (xy 447.662214 -102.305831) (xy 447.634918 -102.257196) (xy 447.614995 -102.205105)
			(xy 447.602869 -102.150668) (xy 447.598798 -102.095046) (xy 446.240219 -102.095046) (xy 446.240219 -102.130453)
			(xy 446.232461 -102.184404) (xy 446.217104 -102.236702) (xy 446.194459 -102.286282) (xy 446.164989 -102.332134)
			(xy 446.129293 -102.373325) (xy 446.088097 -102.409017) (xy 446.042242 -102.438481) (xy 445.992659 -102.46112)
			(xy 445.940359 -102.476471) (xy 445.886407 -102.484222) (xy 445.859154 -102.484682) (xy 445.831785 -102.484189)
			(xy 445.777607 -102.476378) (xy 445.725104 -102.460896) (xy 445.675356 -102.43806) (xy 445.629388 -102.408341)
			(xy 445.608456 -102.390702) (xy 445.601344 -102.384606) (xy 445.58458 -102.378256) (xy 445.525906 -102.378256)
			(xy 445.525906 -102.390702) (xy 445.48425 -102.390702) (xy 445.468502 -102.39629) (xy 445.461644 -102.401624)
			(xy 445.441307 -102.417262) (xy 445.397264 -102.443566) (xy 445.350091 -102.463724) (xy 445.300639 -102.477371)
			(xy 445.249804 -102.48426) (xy 445.224154 -102.484682) (xy 445.196903 -102.484245) (xy 445.142957 -102.476483)
			(xy 445.090664 -102.461123) (xy 445.041089 -102.438477) (xy 444.995241 -102.409008) (xy 444.954054 -102.373314)
			(xy 444.918365 -102.332122) (xy 444.888901 -102.286271) (xy 444.866261 -102.236693) (xy 444.850908 -102.184398)
			(xy 444.843152 -102.130451) (xy 442.200022 -102.130451) (xy 442.186287 -102.14578) (xy 442.143419 -102.181455)
			(xy 442.095813 -102.210509) (xy 442.044484 -102.232321) (xy 441.990527 -102.246427) (xy 441.93509 -102.252527)
			(xy 441.879356 -102.25049) (xy 441.824513 -102.24036) (xy 441.771729 -102.222353) (xy 441.722129 -102.196852)
			(xy 441.676771 -102.164401) (xy 441.636622 -102.125692) (xy 441.602536 -102.081549) (xy 441.57524 -102.032914)
			(xy 441.555317 -101.980823) (xy 441.543191 -101.926386) (xy 441.53912 -101.870764) (xy 436.698003 -101.870764)
			(xy 436.675053 -101.889863) (xy 436.627447 -101.918917) (xy 436.576118 -101.940729) (xy 436.522161 -101.954835)
			(xy 436.466724 -101.960935) (xy 436.41099 -101.958898) (xy 436.356147 -101.948768) (xy 436.303363 -101.930761)
			(xy 436.253763 -101.90526) (xy 436.208405 -101.872809) (xy 436.168256 -101.8341) (xy 436.13417 -101.789957)
			(xy 436.106874 -101.741322) (xy 436.086951 -101.689231) (xy 436.074825 -101.634794) (xy 436.070754 -101.579172)
			(xy 423.151788 -101.579172) (xy 423.150715 -101.579827) (xy 423.099386 -101.601639) (xy 423.045429 -101.615745)
			(xy 422.989992 -101.621845) (xy 422.934258 -101.619808) (xy 422.879415 -101.609678) (xy 422.826631 -101.591671)
			(xy 422.777031 -101.56617) (xy 422.731673 -101.533719) (xy 422.691524 -101.49501) (xy 422.657438 -101.450867)
			(xy 422.630142 -101.402232) (xy 422.610219 -101.350141) (xy 422.598093 -101.295704) (xy 422.594022 -101.240082)
			(xy 403.615144 -101.240082) (xy 403.615144 -101.782372) (xy 405.89784 -101.782372) (xy 405.901911 -101.72675)
			(xy 405.914037 -101.672313) (xy 405.93396 -101.620222) (xy 405.961256 -101.571587) (xy 405.995342 -101.527444)
			(xy 406.035491 -101.488735) (xy 406.080849 -101.456284) (xy 406.130449 -101.430783) (xy 406.183233 -101.412776)
			(xy 406.238076 -101.402646) (xy 406.29381 -101.400609) (xy 406.349247 -101.406709) (xy 406.403204 -101.420815)
			(xy 406.454533 -101.442627) (xy 406.502139 -101.471681) (xy 406.545007 -101.507356) (xy 406.582224 -101.548893)
			(xy 406.612997 -101.595406) (xy 406.636669 -101.645903) (xy 406.652737 -101.69931) (xy 406.660857 -101.754486)
			(xy 406.661366 -101.782372) (xy 406.660857 -101.810258) (xy 406.652737 -101.865434) (xy 406.636669 -101.918841)
			(xy 406.612997 -101.969338) (xy 406.582224 -102.015851) (xy 406.545007 -102.057388) (xy 406.502139 -102.093063)
			(xy 406.454533 -102.122117) (xy 406.403204 -102.143929) (xy 406.349247 -102.158035) (xy 406.29381 -102.164135)
			(xy 406.238076 -102.162098) (xy 406.183233 -102.151968) (xy 406.130449 -102.133961) (xy 406.080849 -102.10846)
			(xy 406.035491 -102.076009) (xy 405.995342 -102.0373) (xy 405.961256 -101.993157) (xy 405.93396 -101.944522)
			(xy 405.914037 -101.892431) (xy 405.901911 -101.837994) (xy 405.89784 -101.782372) (xy 403.615144 -101.782372)
			(xy 403.615144 -102.798372) (xy 405.89784 -102.798372) (xy 405.901911 -102.74275) (xy 405.914037 -102.688313)
			(xy 405.93396 -102.636222) (xy 405.961256 -102.587587) (xy 405.995342 -102.543444) (xy 406.035491 -102.504735)
			(xy 406.080849 -102.472284) (xy 406.130449 -102.446783) (xy 406.183233 -102.428776) (xy 406.238076 -102.418646)
			(xy 406.29381 -102.416609) (xy 406.349247 -102.422709) (xy 406.403204 -102.436815) (xy 406.410647 -102.439978)
			(xy 415.230816 -102.439978) (xy 415.234887 -102.384356) (xy 415.247013 -102.329919) (xy 415.266936 -102.277828)
			(xy 415.294232 -102.229193) (xy 415.328318 -102.18505) (xy 415.368467 -102.146341) (xy 415.413825 -102.11389)
			(xy 415.463425 -102.088389) (xy 415.516209 -102.070382) (xy 415.571052 -102.060252) (xy 415.626786 -102.058215)
			(xy 415.682223 -102.064315) (xy 415.73618 -102.078421) (xy 415.787509 -102.100233) (xy 415.835115 -102.129287)
			(xy 415.877983 -102.164962) (xy 415.9152 -102.206499) (xy 415.945973 -102.253012) (xy 415.969645 -102.303509)
			(xy 415.985713 -102.356916) (xy 415.993833 -102.412092) (xy 415.994342 -102.439978) (xy 422.213022 -102.439978)
			(xy 422.217093 -102.384356) (xy 422.229219 -102.329919) (xy 422.249142 -102.277828) (xy 422.276438 -102.229193)
			(xy 422.310524 -102.18505) (xy 422.350673 -102.146341) (xy 422.396031 -102.11389) (xy 422.445631 -102.088389)
			(xy 422.498415 -102.070382) (xy 422.553258 -102.060252) (xy 422.608992 -102.058215) (xy 422.664429 -102.064315)
			(xy 422.718386 -102.078421) (xy 422.742566 -102.088696) (xy 426.469554 -102.088696) (xy 426.473625 -102.033074)
			(xy 426.485751 -101.978637) (xy 426.505674 -101.926546) (xy 426.53297 -101.877911) (xy 426.567056 -101.833768)
			(xy 426.607205 -101.795059) (xy 426.652563 -101.762608) (xy 426.702163 -101.737107) (xy 426.754947 -101.7191)
			(xy 426.80979 -101.70897) (xy 426.865524 -101.706933) (xy 426.920961 -101.713033) (xy 426.974918 -101.727139)
			(xy 427.026247 -101.748951) (xy 427.073853 -101.778005) (xy 427.116721 -101.81368) (xy 427.153938 -101.855217)
			(xy 427.184711 -101.90173) (xy 427.208383 -101.952227) (xy 427.224451 -102.005634) (xy 427.232571 -102.06081)
			(xy 427.23308 -102.088696) (xy 427.232571 -102.116582) (xy 427.224451 -102.171758) (xy 427.208383 -102.225165)
			(xy 427.184711 -102.275662) (xy 427.153938 -102.322175) (xy 427.116721 -102.363712) (xy 427.073853 -102.399387)
			(xy 427.026247 -102.428441) (xy 426.974918 -102.450253) (xy 426.920961 -102.464359) (xy 426.865524 -102.470459)
			(xy 426.80979 -102.468422) (xy 426.754947 -102.458292) (xy 426.702163 -102.440285) (xy 426.652563 -102.414784)
			(xy 426.607205 -102.382333) (xy 426.567056 -102.343624) (xy 426.53297 -102.299481) (xy 426.505674 -102.250846)
			(xy 426.485751 -102.198755) (xy 426.473625 -102.144318) (xy 426.469554 -102.088696) (xy 422.742566 -102.088696)
			(xy 422.769715 -102.100233) (xy 422.817321 -102.129287) (xy 422.860189 -102.164962) (xy 422.897406 -102.206499)
			(xy 422.928179 -102.253012) (xy 422.951851 -102.303509) (xy 422.967919 -102.356916) (xy 422.976039 -102.412092)
			(xy 422.976548 -102.439978) (xy 422.976039 -102.467864) (xy 422.972929 -102.489) (xy 423.102022 -102.489)
			(xy 423.106093 -102.433378) (xy 423.118219 -102.378941) (xy 423.138142 -102.32685) (xy 423.165438 -102.278215)
			(xy 423.199524 -102.234072) (xy 423.239673 -102.195363) (xy 423.285031 -102.162912) (xy 423.334631 -102.137411)
			(xy 423.387415 -102.119404) (xy 423.442258 -102.109274) (xy 423.497992 -102.107237) (xy 423.553429 -102.113337)
			(xy 423.607386 -102.127443) (xy 423.658715 -102.149255) (xy 423.706321 -102.178309) (xy 423.749189 -102.213984)
			(xy 423.786406 -102.255521) (xy 423.817179 -102.302034) (xy 423.840851 -102.352531) (xy 423.856919 -102.405938)
			(xy 423.865039 -102.461114) (xy 423.865548 -102.489) (xy 423.865039 -102.516886) (xy 423.856919 -102.572062)
			(xy 423.840851 -102.625469) (xy 423.817179 -102.675966) (xy 423.786406 -102.722479) (xy 423.749189 -102.764016)
			(xy 423.706321 -102.799691) (xy 423.658715 -102.828745) (xy 423.607386 -102.850557) (xy 423.553429 -102.864663)
			(xy 423.497992 -102.870763) (xy 423.442258 -102.868726) (xy 423.387415 -102.858596) (xy 423.334631 -102.840589)
			(xy 423.285031 -102.815088) (xy 423.239673 -102.782637) (xy 423.199524 -102.743928) (xy 423.165438 -102.699785)
			(xy 423.138142 -102.65115) (xy 423.118219 -102.599059) (xy 423.106093 -102.544622) (xy 423.102022 -102.489)
			(xy 422.972929 -102.489) (xy 422.967919 -102.52304) (xy 422.951851 -102.576447) (xy 422.928179 -102.626944)
			(xy 422.897406 -102.673457) (xy 422.860189 -102.714994) (xy 422.817321 -102.750669) (xy 422.769715 -102.779723)
			(xy 422.718386 -102.801535) (xy 422.664429 -102.815641) (xy 422.608992 -102.821741) (xy 422.553258 -102.819704)
			(xy 422.498415 -102.809574) (xy 422.445631 -102.791567) (xy 422.396031 -102.766066) (xy 422.350673 -102.733615)
			(xy 422.310524 -102.694906) (xy 422.276438 -102.650763) (xy 422.249142 -102.602128) (xy 422.229219 -102.550037)
			(xy 422.217093 -102.4956) (xy 422.213022 -102.439978) (xy 415.994342 -102.439978) (xy 415.993833 -102.467864)
			(xy 415.985713 -102.52304) (xy 415.969645 -102.576447) (xy 415.945973 -102.626944) (xy 415.9152 -102.673457)
			(xy 415.877983 -102.714994) (xy 415.835115 -102.750669) (xy 415.787509 -102.779723) (xy 415.73618 -102.801535)
			(xy 415.682223 -102.815641) (xy 415.626786 -102.821741) (xy 415.571052 -102.819704) (xy 415.516209 -102.809574)
			(xy 415.463425 -102.791567) (xy 415.413825 -102.766066) (xy 415.368467 -102.733615) (xy 415.328318 -102.694906)
			(xy 415.294232 -102.650763) (xy 415.266936 -102.602128) (xy 415.247013 -102.550037) (xy 415.234887 -102.4956)
			(xy 415.230816 -102.439978) (xy 406.410647 -102.439978) (xy 406.454533 -102.458627) (xy 406.502139 -102.487681)
			(xy 406.545007 -102.523356) (xy 406.582224 -102.564893) (xy 406.612997 -102.611406) (xy 406.636669 -102.661903)
			(xy 406.652737 -102.71531) (xy 406.660857 -102.770486) (xy 406.661366 -102.798372) (xy 406.660857 -102.826258)
			(xy 406.652737 -102.881434) (xy 406.636669 -102.934841) (xy 406.612997 -102.985338) (xy 406.582224 -103.031851)
			(xy 406.545007 -103.073388) (xy 406.507386 -103.104696) (xy 426.469554 -103.104696) (xy 426.473625 -103.049074)
			(xy 426.485751 -102.994637) (xy 426.505674 -102.942546) (xy 426.53297 -102.893911) (xy 426.567056 -102.849768)
			(xy 426.607205 -102.811059) (xy 426.652563 -102.778608) (xy 426.702163 -102.753107) (xy 426.754947 -102.7351)
			(xy 426.80979 -102.72497) (xy 426.865524 -102.722933) (xy 426.920961 -102.729033) (xy 426.974918 -102.743139)
			(xy 427.026247 -102.764951) (xy 427.073853 -102.794005) (xy 427.116721 -102.82968) (xy 427.153938 -102.871217)
			(xy 427.184711 -102.91773) (xy 427.208383 -102.968227) (xy 427.224451 -103.021634) (xy 427.232571 -103.07681)
			(xy 427.23308 -103.104696) (xy 427.232571 -103.132582) (xy 427.231591 -103.13924) (xy 437.807098 -103.13924)
			(xy 437.811169 -103.083618) (xy 437.823295 -103.029181) (xy 437.843218 -102.97709) (xy 437.870514 -102.928455)
			(xy 437.9046 -102.884312) (xy 437.944749 -102.845603) (xy 437.990107 -102.813152) (xy 438.039707 -102.787651)
			(xy 438.092491 -102.769644) (xy 438.147334 -102.759514) (xy 438.203068 -102.757477) (xy 438.258505 -102.763577)
			(xy 438.312462 -102.777683) (xy 438.363791 -102.799495) (xy 438.411397 -102.828549) (xy 438.454265 -102.864224)
			(xy 438.491482 -102.905761) (xy 438.522255 -102.952274) (xy 438.545927 -103.002771) (xy 438.561995 -103.056178)
			(xy 438.570115 -103.111354) (xy 438.570624 -103.13924) (xy 438.570115 -103.167126) (xy 438.561995 -103.222302)
			(xy 438.545927 -103.275709) (xy 438.522255 -103.326206) (xy 438.491482 -103.372719) (xy 438.454265 -103.414256)
			(xy 438.411397 -103.449931) (xy 438.363791 -103.478985) (xy 438.312462 -103.500797) (xy 438.258505 -103.514903)
			(xy 438.203068 -103.521003) (xy 438.147334 -103.518966) (xy 438.092491 -103.508836) (xy 438.039707 -103.490829)
			(xy 437.990107 -103.465328) (xy 437.944749 -103.432877) (xy 437.9046 -103.394168) (xy 437.870514 -103.350025)
			(xy 437.843218 -103.30139) (xy 437.823295 -103.249299) (xy 437.811169 -103.194862) (xy 437.807098 -103.13924)
			(xy 427.231591 -103.13924) (xy 427.224451 -103.187758) (xy 427.208383 -103.241165) (xy 427.184711 -103.291662)
			(xy 427.153938 -103.338175) (xy 427.116721 -103.379712) (xy 427.073853 -103.415387) (xy 427.026247 -103.444441)
			(xy 426.974918 -103.466253) (xy 426.920961 -103.480359) (xy 426.865524 -103.486459) (xy 426.80979 -103.484422)
			(xy 426.754947 -103.474292) (xy 426.702163 -103.456285) (xy 426.652563 -103.430784) (xy 426.607205 -103.398333)
			(xy 426.567056 -103.359624) (xy 426.53297 -103.315481) (xy 426.505674 -103.266846) (xy 426.485751 -103.214755)
			(xy 426.473625 -103.160318) (xy 426.469554 -103.104696) (xy 406.507386 -103.104696) (xy 406.502139 -103.109063)
			(xy 406.454533 -103.138117) (xy 406.403204 -103.159929) (xy 406.349247 -103.174035) (xy 406.29381 -103.180135)
			(xy 406.238076 -103.178098) (xy 406.183233 -103.167968) (xy 406.130449 -103.149961) (xy 406.080849 -103.12446)
			(xy 406.035491 -103.092009) (xy 405.995342 -103.0533) (xy 405.961256 -103.009157) (xy 405.93396 -102.960522)
			(xy 405.914037 -102.908431) (xy 405.901911 -102.853994) (xy 405.89784 -102.798372) (xy 403.615144 -102.798372)
			(xy 403.615144 -103.814372) (xy 405.89784 -103.814372) (xy 405.901911 -103.75875) (xy 405.914037 -103.704313)
			(xy 405.93396 -103.652222) (xy 405.961256 -103.603587) (xy 405.995342 -103.559444) (xy 406.035491 -103.520735)
			(xy 406.080849 -103.488284) (xy 406.130449 -103.462783) (xy 406.183233 -103.444776) (xy 406.238076 -103.434646)
			(xy 406.29381 -103.432609) (xy 406.349247 -103.438709) (xy 406.403204 -103.452815) (xy 406.454533 -103.474627)
			(xy 406.502139 -103.503681) (xy 406.545007 -103.539356) (xy 406.582224 -103.580893) (xy 406.612997 -103.627406)
			(xy 406.636669 -103.677903) (xy 406.652737 -103.73131) (xy 406.660857 -103.786486) (xy 406.661366 -103.814372)
			(xy 406.660857 -103.842258) (xy 406.652737 -103.897434) (xy 406.636669 -103.950841) (xy 406.612997 -104.001338)
			(xy 406.582224 -104.047851) (xy 406.545007 -104.089388) (xy 406.502139 -104.125063) (xy 406.454533 -104.154117)
			(xy 406.403204 -104.175929) (xy 406.349247 -104.190035) (xy 406.29381 -104.196135) (xy 406.238076 -104.194098)
			(xy 406.183233 -104.183968) (xy 406.130449 -104.165961) (xy 406.080849 -104.14046) (xy 406.035491 -104.108009)
			(xy 405.995342 -104.0693) (xy 405.961256 -104.025157) (xy 405.93396 -103.976522) (xy 405.914037 -103.924431)
			(xy 405.901911 -103.869994) (xy 405.89784 -103.814372) (xy 403.615144 -103.814372) (xy 403.615144 -104.240076)
			(xy 415.230816 -104.240076) (xy 415.234887 -104.184454) (xy 415.247013 -104.130017) (xy 415.266936 -104.077926)
			(xy 415.294232 -104.029291) (xy 415.328318 -103.985148) (xy 415.368467 -103.946439) (xy 415.413825 -103.913988)
			(xy 415.463425 -103.888487) (xy 415.516209 -103.87048) (xy 415.571052 -103.86035) (xy 415.626786 -103.858313)
			(xy 415.682223 -103.864413) (xy 415.73618 -103.878519) (xy 415.787509 -103.900331) (xy 415.835115 -103.929385)
			(xy 415.877983 -103.96506) (xy 415.9152 -104.006597) (xy 415.945973 -104.05311) (xy 415.969645 -104.103607)
			(xy 415.985713 -104.157014) (xy 415.993833 -104.21219) (xy 415.994342 -104.240076) (xy 422.213022 -104.240076)
			(xy 422.217093 -104.184454) (xy 422.229219 -104.130017) (xy 422.249142 -104.077926) (xy 422.276438 -104.029291)
			(xy 422.310524 -103.985148) (xy 422.350673 -103.946439) (xy 422.396031 -103.913988) (xy 422.445631 -103.888487)
			(xy 422.498415 -103.87048) (xy 422.553258 -103.86035) (xy 422.608992 -103.858313) (xy 422.664429 -103.864413)
			(xy 422.718386 -103.878519) (xy 422.735991 -103.886) (xy 423.610022 -103.886) (xy 423.614093 -103.830378)
			(xy 423.626219 -103.775941) (xy 423.646142 -103.72385) (xy 423.673438 -103.675215) (xy 423.707524 -103.631072)
			(xy 423.747673 -103.592363) (xy 423.793031 -103.559912) (xy 423.842631 -103.534411) (xy 423.895415 -103.516404)
			(xy 423.950258 -103.506274) (xy 424.005992 -103.504237) (xy 424.061429 -103.510337) (xy 424.115386 -103.524443)
			(xy 424.166715 -103.546255) (xy 424.214321 -103.575309) (xy 424.257189 -103.610984) (xy 424.294406 -103.652521)
			(xy 424.325179 -103.699034) (xy 424.348851 -103.749531) (xy 424.364919 -103.802938) (xy 424.373039 -103.858114)
			(xy 424.373548 -103.886) (xy 424.373039 -103.913886) (xy 424.364919 -103.969062) (xy 424.348851 -104.022469)
			(xy 424.325179 -104.072966) (xy 424.294406 -104.119479) (xy 424.293316 -104.120696) (xy 426.469554 -104.120696)
			(xy 426.473625 -104.065074) (xy 426.485751 -104.010637) (xy 426.505674 -103.958546) (xy 426.53297 -103.909911)
			(xy 426.567056 -103.865768) (xy 426.607205 -103.827059) (xy 426.652563 -103.794608) (xy 426.702163 -103.769107)
			(xy 426.754947 -103.7511) (xy 426.80979 -103.74097) (xy 426.865524 -103.738933) (xy 426.920961 -103.745033)
			(xy 426.974918 -103.759139) (xy 427.026247 -103.780951) (xy 427.073853 -103.810005) (xy 427.116721 -103.84568)
			(xy 427.153938 -103.887217) (xy 427.184711 -103.93373) (xy 427.208383 -103.984227) (xy 427.224451 -104.037634)
			(xy 427.232571 -104.09281) (xy 427.23308 -104.120696) (xy 427.232571 -104.148582) (xy 427.224451 -104.203758)
			(xy 427.208383 -104.257165) (xy 427.184711 -104.307662) (xy 427.153938 -104.354175) (xy 427.116721 -104.395712)
			(xy 427.073853 -104.431387) (xy 427.026247 -104.460441) (xy 426.974918 -104.482253) (xy 426.920961 -104.496359)
			(xy 426.865524 -104.502459) (xy 426.80979 -104.500422) (xy 426.754947 -104.490292) (xy 426.702163 -104.472285)
			(xy 426.652563 -104.446784) (xy 426.607205 -104.414333) (xy 426.567056 -104.375624) (xy 426.53297 -104.331481)
			(xy 426.505674 -104.282846) (xy 426.485751 -104.230755) (xy 426.473625 -104.176318) (xy 426.469554 -104.120696)
			(xy 424.293316 -104.120696) (xy 424.257189 -104.161016) (xy 424.214321 -104.196691) (xy 424.166715 -104.225745)
			(xy 424.115386 -104.247557) (xy 424.061429 -104.261663) (xy 424.005992 -104.267763) (xy 423.950258 -104.265726)
			(xy 423.895415 -104.255596) (xy 423.842631 -104.237589) (xy 423.793031 -104.212088) (xy 423.747673 -104.179637)
			(xy 423.707524 -104.140928) (xy 423.673438 -104.096785) (xy 423.646142 -104.04815) (xy 423.626219 -103.996059)
			(xy 423.614093 -103.941622) (xy 423.610022 -103.886) (xy 422.735991 -103.886) (xy 422.769715 -103.900331)
			(xy 422.817321 -103.929385) (xy 422.860189 -103.96506) (xy 422.897406 -104.006597) (xy 422.928179 -104.05311)
			(xy 422.951851 -104.103607) (xy 422.967919 -104.157014) (xy 422.976039 -104.21219) (xy 422.976548 -104.240076)
			(xy 422.976039 -104.267962) (xy 422.967919 -104.323138) (xy 422.951851 -104.376545) (xy 422.928179 -104.427042)
			(xy 422.897406 -104.473555) (xy 422.860189 -104.515092) (xy 422.817321 -104.550767) (xy 422.769715 -104.579821)
			(xy 422.718386 -104.601633) (xy 422.664429 -104.615739) (xy 422.608992 -104.621839) (xy 422.553258 -104.619802)
			(xy 422.498415 -104.609672) (xy 422.445631 -104.591665) (xy 422.396031 -104.566164) (xy 422.350673 -104.533713)
			(xy 422.310524 -104.495004) (xy 422.276438 -104.450861) (xy 422.249142 -104.402226) (xy 422.229219 -104.350135)
			(xy 422.217093 -104.295698) (xy 422.213022 -104.240076) (xy 415.994342 -104.240076) (xy 415.993833 -104.267962)
			(xy 415.985713 -104.323138) (xy 415.969645 -104.376545) (xy 415.945973 -104.427042) (xy 415.9152 -104.473555)
			(xy 415.877983 -104.515092) (xy 415.835115 -104.550767) (xy 415.787509 -104.579821) (xy 415.73618 -104.601633)
			(xy 415.682223 -104.615739) (xy 415.626786 -104.621839) (xy 415.571052 -104.619802) (xy 415.516209 -104.609672)
			(xy 415.463425 -104.591665) (xy 415.413825 -104.566164) (xy 415.368467 -104.533713) (xy 415.328318 -104.495004)
			(xy 415.294232 -104.450861) (xy 415.266936 -104.402226) (xy 415.247013 -104.350135) (xy 415.234887 -104.295698)
			(xy 415.230816 -104.240076) (xy 403.615144 -104.240076) (xy 403.615144 -104.830372) (xy 405.89784 -104.830372)
			(xy 405.901911 -104.77475) (xy 405.914037 -104.720313) (xy 405.93396 -104.668222) (xy 405.961256 -104.619587)
			(xy 405.995342 -104.575444) (xy 406.035491 -104.536735) (xy 406.080849 -104.504284) (xy 406.130449 -104.478783)
			(xy 406.183233 -104.460776) (xy 406.238076 -104.450646) (xy 406.29381 -104.448609) (xy 406.349247 -104.454709)
			(xy 406.403204 -104.468815) (xy 406.454533 -104.490627) (xy 406.502139 -104.519681) (xy 406.545007 -104.555356)
			(xy 406.582224 -104.596893) (xy 406.612997 -104.643406) (xy 406.627772 -104.674924) (xy 436.859424 -104.674924)
			(xy 436.863495 -104.619302) (xy 436.875621 -104.564865) (xy 436.895544 -104.512774) (xy 436.92284 -104.464139)
			(xy 436.956926 -104.419996) (xy 436.997075 -104.381287) (xy 437.042433 -104.348836) (xy 437.092033 -104.323335)
			(xy 437.144817 -104.305328) (xy 437.19966 -104.295198) (xy 437.255394 -104.293161) (xy 437.310831 -104.299261)
			(xy 437.364788 -104.313367) (xy 437.416117 -104.335179) (xy 437.463723 -104.364233) (xy 437.506591 -104.399908)
			(xy 437.543808 -104.441445) (xy 437.574581 -104.487958) (xy 437.598253 -104.538455) (xy 437.614321 -104.591862)
			(xy 437.622441 -104.647038) (xy 437.62295 -104.674924) (xy 437.622441 -104.70281) (xy 437.614321 -104.757986)
			(xy 437.598253 -104.811393) (xy 437.574581 -104.86189) (xy 437.543808 -104.908403) (xy 437.506591 -104.94994)
			(xy 437.463723 -104.985615) (xy 437.416117 -105.014669) (xy 437.364788 -105.036481) (xy 437.310831 -105.050587)
			(xy 437.255394 -105.056687) (xy 437.19966 -105.05465) (xy 437.144817 -105.04452) (xy 437.092033 -105.026513)
			(xy 437.042433 -105.001012) (xy 436.997075 -104.968561) (xy 436.956926 -104.929852) (xy 436.92284 -104.885709)
			(xy 436.895544 -104.837074) (xy 436.875621 -104.784983) (xy 436.863495 -104.730546) (xy 436.859424 -104.674924)
			(xy 406.627772 -104.674924) (xy 406.636669 -104.693903) (xy 406.652737 -104.74731) (xy 406.660857 -104.802486)
			(xy 406.661366 -104.830372) (xy 406.660857 -104.858258) (xy 406.652737 -104.913434) (xy 406.636669 -104.966841)
			(xy 406.612997 -105.017338) (xy 406.582224 -105.063851) (xy 406.545007 -105.105388) (xy 406.502139 -105.141063)
			(xy 406.454533 -105.170117) (xy 406.403204 -105.191929) (xy 406.349247 -105.206035) (xy 406.29381 -105.212135)
			(xy 406.238076 -105.210098) (xy 406.183233 -105.199968) (xy 406.130449 -105.181961) (xy 406.080849 -105.15646)
			(xy 406.035491 -105.124009) (xy 405.995342 -105.0853) (xy 405.961256 -105.041157) (xy 405.93396 -104.992522)
			(xy 405.914037 -104.940431) (xy 405.901911 -104.885994) (xy 405.89784 -104.830372) (xy 403.615144 -104.830372)
			(xy 403.615144 -107.210352) (xy 413.291526 -107.210352) (xy 413.295597 -107.15473) (xy 413.307723 -107.100293)
			(xy 413.327646 -107.048202) (xy 413.354942 -106.999567) (xy 413.389028 -106.955424) (xy 413.429177 -106.916715)
			(xy 413.474535 -106.884264) (xy 413.524135 -106.858763) (xy 413.576919 -106.840756) (xy 413.631762 -106.830626)
			(xy 413.687496 -106.828589) (xy 413.742933 -106.834689) (xy 413.79689 -106.848795) (xy 413.848219 -106.870607)
			(xy 413.895825 -106.899661) (xy 413.938693 -106.935336) (xy 413.97591 -106.976873) (xy 414.006683 -107.023386)
			(xy 414.030355 -107.073883) (xy 414.043754 -107.11842) (xy 415.137848 -107.11842) (xy 415.137848 -107.03152)
			(xy 415.145866 -106.944991) (xy 415.161834 -106.859571) (xy 415.185615 -106.775989) (xy 415.217007 -106.694957)
			(xy 415.255741 -106.617168) (xy 415.301488 -106.543284) (xy 415.353857 -106.473937) (xy 415.412401 -106.409717)
			(xy 415.476621 -106.351173) (xy 415.545968 -106.298804) (xy 415.619852 -106.253057) (xy 415.697641 -106.214323)
			(xy 415.778673 -106.182931) (xy 415.862255 -106.15915) (xy 415.947675 -106.143182) (xy 416.034204 -106.135164)
			(xy 416.121104 -106.135164) (xy 416.207633 -106.143182) (xy 416.293053 -106.15915) (xy 416.376635 -106.182931)
			(xy 416.457667 -106.214323) (xy 416.535456 -106.253057) (xy 416.60934 -106.298804) (xy 416.678687 -106.351173)
			(xy 416.742907 -106.409717) (xy 416.801451 -106.473937) (xy 416.85382 -106.543284) (xy 416.899567 -106.617168)
			(xy 416.938301 -106.694957) (xy 416.969693 -106.775989) (xy 416.993474 -106.859571) (xy 417.009442 -106.944991)
			(xy 417.01746 -107.03152) (xy 417.017962 -107.07497) (xy 417.01746 -107.11842) (xy 417.017458 -107.118439)
			(xy 417.390818 -107.118439) (xy 417.390818 -107.031561) (xy 417.398834 -106.945054) (xy 417.414797 -106.859655)
			(xy 417.438572 -106.776094) (xy 417.469956 -106.695082) (xy 417.50868 -106.617312) (xy 417.554415 -106.543447)
			(xy 417.60677 -106.474116) (xy 417.665298 -106.409912) (xy 417.729501 -106.351382) (xy 417.79883 -106.299026)
			(xy 417.872695 -106.25329) (xy 417.950464 -106.214564) (xy 418.031475 -106.183178) (xy 418.115036 -106.159402)
			(xy 418.200434 -106.143436) (xy 418.286941 -106.135419) (xy 418.33038 -106.134916) (xy 420.18458 -106.134916)
			(xy 420.228018 -106.135462) (xy 420.314524 -106.143476) (xy 420.399921 -106.159438) (xy 420.483481 -106.183211)
			(xy 420.564491 -106.214593) (xy 420.64226 -106.253316) (xy 420.716124 -106.299049) (xy 420.785453 -106.351403)
			(xy 420.849656 -106.40993) (xy 420.908185 -106.474132) (xy 420.96054 -106.54346) (xy 421.006275 -106.617323)
			(xy 421.044999 -106.695091) (xy 421.076383 -106.7761) (xy 421.100158 -106.85966) (xy 421.116121 -106.945057)
			(xy 421.124137 -107.031562) (xy 421.124137 -107.11842) (xy 422.507658 -107.11842) (xy 422.507658 -107.03152)
			(xy 422.515676 -106.944991) (xy 422.531644 -106.859571) (xy 422.555425 -106.775989) (xy 422.586817 -106.694957)
			(xy 422.625551 -106.617168) (xy 422.671298 -106.543284) (xy 422.723667 -106.473937) (xy 422.782211 -106.409717)
			(xy 422.846431 -106.351173) (xy 422.915778 -106.298804) (xy 422.989662 -106.253057) (xy 423.067451 -106.214323)
			(xy 423.148483 -106.182931) (xy 423.232065 -106.15915) (xy 423.317485 -106.143182) (xy 423.404014 -106.135164)
			(xy 423.490914 -106.135164) (xy 423.577443 -106.143182) (xy 423.662863 -106.15915) (xy 423.746445 -106.182931)
			(xy 423.827477 -106.214323) (xy 423.905266 -106.253057) (xy 423.97915 -106.298804) (xy 424.048497 -106.351173)
			(xy 424.085441 -106.384852) (xy 425.812964 -106.384852) (xy 425.817035 -106.32923) (xy 425.829161 -106.274793)
			(xy 425.849084 -106.222702) (xy 425.87638 -106.174067) (xy 425.910466 -106.129924) (xy 425.950615 -106.091215)
			(xy 425.995973 -106.058764) (xy 426.045573 -106.033263) (xy 426.098357 -106.015256) (xy 426.1532 -106.005126)
			(xy 426.208934 -106.003089) (xy 426.264371 -106.009189) (xy 426.318328 -106.023295) (xy 426.369657 -106.045107)
			(xy 426.417263 -106.074161) (xy 426.460131 -106.109836) (xy 426.497348 -106.151373) (xy 426.528121 -106.197886)
			(xy 426.551793 -106.248383) (xy 426.567861 -106.30179) (xy 426.575981 -106.356966) (xy 426.57649 -106.384852)
			(xy 426.575981 -106.412738) (xy 426.567861 -106.467914) (xy 426.551793 -106.521321) (xy 426.528121 -106.571818)
			(xy 426.497348 -106.618331) (xy 426.460131 -106.659868) (xy 426.417263 -106.695543) (xy 426.369657 -106.724597)
			(xy 426.318328 -106.746409) (xy 426.264371 -106.760515) (xy 426.208934 -106.766615) (xy 426.1532 -106.764578)
			(xy 426.098357 -106.754448) (xy 426.045573 -106.736441) (xy 425.995973 -106.71094) (xy 425.950615 -106.678489)
			(xy 425.910466 -106.63978) (xy 425.87638 -106.595637) (xy 425.849084 -106.547002) (xy 425.829161 -106.494911)
			(xy 425.817035 -106.440474) (xy 425.812964 -106.384852) (xy 424.085441 -106.384852) (xy 424.112717 -106.409717)
			(xy 424.171261 -106.473937) (xy 424.22363 -106.543284) (xy 424.269377 -106.617168) (xy 424.308111 -106.694957)
			(xy 424.339503 -106.775989) (xy 424.363284 -106.859571) (xy 424.379252 -106.944991) (xy 424.38727 -107.03152)
			(xy 424.387578 -107.058206) (xy 437.873902 -107.058206) (xy 437.874429 -107.029467) (xy 437.883051 -106.97264)
			(xy 437.9001 -106.917749) (xy 437.925191 -106.866037) (xy 437.957755 -106.818675) (xy 437.977026 -106.797348)
			(xy 437.983884 -106.790236) (xy 437.990742 -106.772456) (xy 437.990742 -106.683556) (xy 437.983884 -106.665776)
			(xy 437.977026 -106.658664) (xy 437.957761 -106.637332) (xy 437.925195 -106.589971) (xy 437.900103 -106.53826)
			(xy 437.883053 -106.48337) (xy 437.87443 -106.426543) (xy 437.874429 -106.369066) (xy 437.883051 -106.312239)
			(xy 437.9001 -106.257349) (xy 437.925191 -106.205637) (xy 437.957756 -106.158275) (xy 437.977026 -106.136948)
			(xy 437.983884 -106.129836) (xy 437.990742 -106.112056) (xy 437.990742 -106.023156) (xy 437.983884 -106.005376)
			(xy 437.977026 -105.998264) (xy 437.957756 -105.976936) (xy 437.92519 -105.929574) (xy 437.900098 -105.877863)
			(xy 437.883047 -105.822972) (xy 437.874423 -105.766145) (xy 437.873902 -105.737406) (xy 437.874388 -105.710155)
			(xy 437.882144 -105.656207) (xy 437.897499 -105.603912) (xy 437.920141 -105.554335) (xy 437.949607 -105.508485)
			(xy 437.985298 -105.467294) (xy 438.026489 -105.431603) (xy 438.072339 -105.402137) (xy 438.121916 -105.379495)
			(xy 438.174211 -105.36414) (xy 438.228159 -105.356384) (xy 438.282661 -105.356384) (xy 438.336609 -105.36414)
			(xy 438.388904 -105.379495) (xy 438.438481 -105.402137) (xy 438.484331 -105.431603) (xy 438.525522 -105.467294)
			(xy 438.561213 -105.508485) (xy 438.590679 -105.554335) (xy 438.613321 -105.603912) (xy 438.628676 -105.656207)
			(xy 438.636432 -105.710155) (xy 438.636918 -105.737406) (xy 438.636393 -105.766145) (xy 438.62777 -105.822972)
			(xy 438.61072 -105.877862) (xy 438.585629 -105.929574) (xy 438.553064 -105.976937) (xy 438.533794 -105.998264)
			(xy 438.526936 -106.005376) (xy 438.520078 -106.023156) (xy 438.520078 -106.112056) (xy 438.526936 -106.129836)
			(xy 438.533794 -106.136948) (xy 438.55307 -106.15827) (xy 438.585633 -106.205634) (xy 438.610724 -106.257346)
			(xy 438.627772 -106.312238) (xy 438.636394 -106.369065) (xy 438.636393 -106.426543) (xy 438.62777 -106.483371)
			(xy 438.61072 -106.538262) (xy 438.585629 -106.589974) (xy 438.553064 -106.637337) (xy 438.533794 -106.658664)
			(xy 438.526936 -106.665776) (xy 438.520078 -106.683556) (xy 438.520078 -106.772456) (xy 438.526936 -106.790236)
			(xy 438.533794 -106.797348) (xy 438.553056 -106.818683) (xy 438.585626 -106.866042) (xy 438.610721 -106.917751)
			(xy 438.627773 -106.972641) (xy 438.636397 -107.029467) (xy 438.636918 -107.058206) (xy 438.636432 -107.085457)
			(xy 438.628676 -107.139405) (xy 438.613321 -107.1917) (xy 438.590679 -107.241277) (xy 438.561213 -107.287127)
			(xy 438.525522 -107.328318) (xy 438.484331 -107.364009) (xy 438.438481 -107.393475) (xy 438.388904 -107.416117)
			(xy 438.336609 -107.431472) (xy 438.282661 -107.439228) (xy 438.228159 -107.439228) (xy 438.174211 -107.431472)
			(xy 438.121916 -107.416117) (xy 438.072339 -107.393475) (xy 438.026489 -107.364009) (xy 437.985298 -107.328318)
			(xy 437.949607 -107.287127) (xy 437.920141 -107.241277) (xy 437.897499 -107.1917) (xy 437.882144 -107.139405)
			(xy 437.874388 -107.085457) (xy 437.873902 -107.058206) (xy 424.387578 -107.058206) (xy 424.387772 -107.07497)
			(xy 424.38727 -107.11842) (xy 424.379252 -107.204949) (xy 424.363284 -107.290369) (xy 424.339503 -107.373951)
			(xy 424.308111 -107.454983) (xy 424.269377 -107.532772) (xy 424.22363 -107.606656) (xy 424.171261 -107.676003)
			(xy 424.112717 -107.740223) (xy 424.048497 -107.798767) (xy 423.97915 -107.851136) (xy 423.905266 -107.896883)
			(xy 423.827477 -107.935617) (xy 423.746445 -107.967009) (xy 423.662863 -107.99079) (xy 423.577443 -108.006758)
			(xy 423.490914 -108.014776) (xy 423.404014 -108.014776) (xy 423.317485 -108.006758) (xy 423.232065 -107.99079)
			(xy 423.148483 -107.967009) (xy 423.067451 -107.935617) (xy 422.989662 -107.896883) (xy 422.915778 -107.851136)
			(xy 422.846431 -107.798767) (xy 422.782211 -107.740223) (xy 422.723667 -107.676003) (xy 422.671298 -107.606656)
			(xy 422.625551 -107.532772) (xy 422.586817 -107.454983) (xy 422.555425 -107.373951) (xy 422.531644 -107.290369)
			(xy 422.515676 -107.204949) (xy 422.507658 -107.11842) (xy 421.124137 -107.11842) (xy 421.124137 -107.118438)
			(xy 421.116121 -107.204943) (xy 421.100158 -107.29034) (xy 421.076383 -107.3739) (xy 421.044999 -107.454909)
			(xy 421.006275 -107.532677) (xy 420.96054 -107.60654) (xy 420.908185 -107.675868) (xy 420.849656 -107.74007)
			(xy 420.785453 -107.798597) (xy 420.716124 -107.850951) (xy 420.64226 -107.896684) (xy 420.564491 -107.935407)
			(xy 420.483481 -107.966789) (xy 420.399921 -107.990562) (xy 420.314524 -108.006524) (xy 420.228018 -108.014538)
			(xy 420.18458 -108.015024) (xy 418.33038 -108.015024) (xy 418.286941 -108.014581) (xy 418.200434 -108.006564)
			(xy 418.115036 -107.990598) (xy 418.031475 -107.966822) (xy 417.950464 -107.935436) (xy 417.872695 -107.89671)
			(xy 417.79883 -107.850974) (xy 417.729501 -107.798618) (xy 417.665298 -107.740088) (xy 417.60677 -107.675884)
			(xy 417.554415 -107.606553) (xy 417.50868 -107.532688) (xy 417.469956 -107.454918) (xy 417.438572 -107.373906)
			(xy 417.414797 -107.290345) (xy 417.398834 -107.204946) (xy 417.390818 -107.118439) (xy 417.017458 -107.118439)
			(xy 417.009442 -107.204949) (xy 416.993474 -107.290369) (xy 416.969693 -107.373951) (xy 416.938301 -107.454983)
			(xy 416.899567 -107.532772) (xy 416.85382 -107.606656) (xy 416.801451 -107.676003) (xy 416.742907 -107.740223)
			(xy 416.678687 -107.798767) (xy 416.60934 -107.851136) (xy 416.535456 -107.896883) (xy 416.457667 -107.935617)
			(xy 416.376635 -107.967009) (xy 416.293053 -107.99079) (xy 416.207633 -108.006758) (xy 416.121104 -108.014776)
			(xy 416.034204 -108.014776) (xy 415.947675 -108.006758) (xy 415.862255 -107.99079) (xy 415.778673 -107.967009)
			(xy 415.697641 -107.935617) (xy 415.619852 -107.896883) (xy 415.545968 -107.851136) (xy 415.476621 -107.798767)
			(xy 415.412401 -107.740223) (xy 415.353857 -107.676003) (xy 415.301488 -107.606656) (xy 415.255741 -107.532772)
			(xy 415.217007 -107.454983) (xy 415.185615 -107.373951) (xy 415.161834 -107.290369) (xy 415.145866 -107.204949)
			(xy 415.137848 -107.11842) (xy 414.043754 -107.11842) (xy 414.046423 -107.12729) (xy 414.054543 -107.182466)
			(xy 414.055052 -107.210352) (xy 414.054543 -107.238238) (xy 414.046423 -107.293414) (xy 414.030355 -107.346821)
			(xy 414.006683 -107.397318) (xy 413.97591 -107.443831) (xy 413.938693 -107.485368) (xy 413.895825 -107.521043)
			(xy 413.848219 -107.550097) (xy 413.79689 -107.571909) (xy 413.742933 -107.586015) (xy 413.687496 -107.592115)
			(xy 413.631762 -107.590078) (xy 413.576919 -107.579948) (xy 413.524135 -107.561941) (xy 413.474535 -107.53644)
			(xy 413.429177 -107.503989) (xy 413.389028 -107.46528) (xy 413.354942 -107.421137) (xy 413.327646 -107.372502)
			(xy 413.307723 -107.320411) (xy 413.295597 -107.265974) (xy 413.291526 -107.210352) (xy 403.615144 -107.210352)
			(xy 403.615144 -108.462318) (xy 412.688022 -108.462318) (xy 412.692093 -108.406696) (xy 412.704219 -108.352259)
			(xy 412.724142 -108.300168) (xy 412.751438 -108.251533) (xy 412.785524 -108.20739) (xy 412.825673 -108.168681)
			(xy 412.871031 -108.13623) (xy 412.920631 -108.110729) (xy 412.973415 -108.092722) (xy 413.028258 -108.082592)
			(xy 413.083992 -108.080555) (xy 413.139429 -108.086655) (xy 413.193386 -108.100761) (xy 413.244715 -108.122573)
			(xy 413.292321 -108.151627) (xy 413.335189 -108.187302) (xy 413.372406 -108.228839) (xy 413.403179 -108.275352)
			(xy 413.426851 -108.325849) (xy 413.442844 -108.379006) (xy 438.762902 -108.379006) (xy 438.763429 -108.350267)
			(xy 438.772051 -108.29344) (xy 438.7891 -108.238549) (xy 438.814191 -108.186837) (xy 438.846755 -108.139475)
			(xy 438.866026 -108.118148) (xy 438.872884 -108.111036) (xy 438.879742 -108.093256) (xy 438.879742 -108.004356)
			(xy 438.872884 -107.986576) (xy 438.866026 -107.979464) (xy 438.846761 -107.958132) (xy 438.814195 -107.910771)
			(xy 438.789103 -107.85906) (xy 438.772053 -107.80417) (xy 438.76343 -107.747343) (xy 438.763429 -107.689866)
			(xy 438.772051 -107.633039) (xy 438.7891 -107.578149) (xy 438.814191 -107.526437) (xy 438.846756 -107.479075)
			(xy 438.866026 -107.457748) (xy 438.872884 -107.450636) (xy 438.879742 -107.432856) (xy 438.879742 -107.343956)
			(xy 438.872884 -107.326176) (xy 438.866026 -107.319064) (xy 438.846761 -107.297732) (xy 438.814195 -107.250371)
			(xy 438.789103 -107.19866) (xy 438.772053 -107.14377) (xy 438.76343 -107.086943) (xy 438.763429 -107.029466)
			(xy 438.772051 -106.972639) (xy 438.7891 -106.917749) (xy 438.814191 -106.866037) (xy 438.846756 -106.818675)
			(xy 438.866026 -106.797348) (xy 438.872884 -106.790236) (xy 438.879742 -106.772456) (xy 438.879742 -106.683556)
			(xy 438.872884 -106.665776) (xy 438.866026 -106.658664) (xy 438.846761 -106.637332) (xy 438.814195 -106.589971)
			(xy 438.789103 -106.53826) (xy 438.772053 -106.48337) (xy 438.76343 -106.426543) (xy 438.763429 -106.369066)
			(xy 438.772051 -106.312239) (xy 438.7891 -106.257349) (xy 438.814191 -106.205637) (xy 438.846756 -106.158275)
			(xy 438.866026 -106.136948) (xy 438.872884 -106.129836) (xy 438.879742 -106.112056) (xy 438.879742 -106.023156)
			(xy 438.872884 -106.005376) (xy 438.866026 -105.998264) (xy 438.846761 -105.976932) (xy 438.814195 -105.929571)
			(xy 438.789103 -105.87786) (xy 438.772053 -105.82297) (xy 438.76343 -105.766143) (xy 438.763429 -105.708666)
			(xy 438.772051 -105.651839) (xy 438.7891 -105.596949) (xy 438.814191 -105.545237) (xy 438.846756 -105.497875)
			(xy 438.866026 -105.476548) (xy 438.872884 -105.469436) (xy 438.879742 -105.451656) (xy 438.879742 -105.362756)
			(xy 438.872884 -105.344976) (xy 438.866026 -105.337864) (xy 438.846761 -105.316532) (xy 438.814195 -105.269171)
			(xy 438.789103 -105.21746) (xy 438.772053 -105.16257) (xy 438.76343 -105.105743) (xy 438.763429 -105.048266)
			(xy 438.772051 -104.991439) (xy 438.7891 -104.936549) (xy 438.814191 -104.884837) (xy 438.846756 -104.837475)
			(xy 438.866026 -104.816148) (xy 438.872884 -104.809036) (xy 438.879742 -104.791256) (xy 438.879742 -104.702356)
			(xy 438.872884 -104.684576) (xy 438.866026 -104.677464) (xy 438.846761 -104.656132) (xy 438.814195 -104.608771)
			(xy 438.789103 -104.55706) (xy 438.772053 -104.50217) (xy 438.76343 -104.445343) (xy 438.763429 -104.387866)
			(xy 438.772051 -104.331039) (xy 438.7891 -104.276149) (xy 438.814191 -104.224437) (xy 438.846756 -104.177075)
			(xy 438.866026 -104.155748) (xy 438.872884 -104.148636) (xy 438.879742 -104.130856) (xy 438.879742 -104.041956)
			(xy 438.872884 -104.024176) (xy 438.866026 -104.017064) (xy 438.846761 -103.995732) (xy 438.814195 -103.948371)
			(xy 438.789103 -103.89666) (xy 438.772053 -103.84177) (xy 438.76343 -103.784943) (xy 438.763429 -103.727466)
			(xy 438.772051 -103.670639) (xy 438.7891 -103.615749) (xy 438.814191 -103.564037) (xy 438.846756 -103.516675)
			(xy 438.866026 -103.495348) (xy 438.872884 -103.488236) (xy 438.879742 -103.470456) (xy 438.879742 -103.381556)
			(xy 438.872884 -103.363776) (xy 438.866026 -103.356664) (xy 438.846756 -103.335336) (xy 438.81419 -103.287974)
			(xy 438.789098 -103.236263) (xy 438.772047 -103.181372) (xy 438.763423 -103.124545) (xy 438.762902 -103.095806)
			(xy 438.763415 -103.068616) (xy 438.771143 -103.014787) (xy 438.786429 -102.962599) (xy 438.808965 -102.913107)
			(xy 438.838293 -102.867313) (xy 438.873821 -102.826143) (xy 438.91483 -102.790429) (xy 438.9374 -102.775258)
			(xy 438.945782 -102.769924) (xy 438.957212 -102.753922) (xy 438.968134 -102.706678) (xy 438.969404 -102.695248)
			(xy 438.969404 -102.643686) (xy 438.966102 -102.63124) (xy 438.9628 -102.625398) (xy 438.951099 -102.603899)
			(xy 438.932674 -102.55855) (xy 438.920211 -102.511216) (xy 438.913915 -102.462674) (xy 438.913524 -102.4382)
			(xy 438.913955 -102.410946) (xy 438.921713 -102.356992) (xy 438.937071 -102.304692) (xy 438.959716 -102.255109)
			(xy 438.989187 -102.209255) (xy 439.024884 -102.168061) (xy 439.06608 -102.132367) (xy 439.111937 -102.1029)
			(xy 439.161522 -102.08026) (xy 439.213823 -102.064906) (xy 439.267778 -102.057153) (xy 439.295032 -102.056692)
			(xy 439.324508 -102.057276) (xy 439.382759 -102.066335) (xy 439.438923 -102.084247) (xy 439.491663 -102.110587)
			(xy 439.539723 -102.144726) (xy 439.561224 -102.164896) (xy 439.561478 -102.16515) (xy 439.570284 -102.172837)
			(xy 439.592514 -102.179983) (xy 439.60415 -102.178866) (xy 439.695844 -102.165404) (xy 439.714894 -102.152196)
			(xy 439.720736 -102.141782) (xy 439.735307 -102.116819) (xy 439.770832 -102.071224) (xy 439.812829 -102.031512)
			(xy 439.860339 -101.998592) (xy 439.912271 -101.973218) (xy 439.967438 -101.955971) (xy 440.024576 -101.947246)
			(xy 440.053476 -101.94671) (xy 440.080731 -101.947135) (xy 440.134687 -101.95489) (xy 440.186991 -101.970245)
			(xy 440.236576 -101.992887) (xy 440.282435 -102.022356) (xy 440.323632 -102.058051) (xy 440.35933 -102.099246)
			(xy 440.388802 -102.145103) (xy 440.411447 -102.194687) (xy 440.426805 -102.246989) (xy 440.434563 -102.300945)
			(xy 440.434563 -102.355455) (xy 440.426805 -102.409411) (xy 440.411447 -102.461713) (xy 440.388802 -102.511297)
			(xy 440.35933 -102.557154) (xy 440.323632 -102.598349) (xy 440.282435 -102.634044) (xy 440.236576 -102.663513)
			(xy 440.186991 -102.686155) (xy 440.134687 -102.70151) (xy 440.080731 -102.709265) (xy 440.053476 -102.709726)
			(xy 440.023997 -102.709222) (xy 439.965741 -102.700147) (xy 439.909575 -102.682217) (xy 439.856836 -102.655859)
			(xy 439.808781 -102.621701) (xy 439.787284 -102.601522) (xy 439.78703 -102.601268) (xy 439.778219 -102.593587)
			(xy 439.755993 -102.586437) (xy 439.744358 -102.587552) (xy 439.652664 -102.601014) (xy 439.633614 -102.614222)
			(xy 439.627772 -102.624636) (xy 439.612128 -102.651362) (xy 439.573577 -102.699821) (xy 439.527707 -102.741419)
			(xy 439.502042 -102.758748) (xy 439.49366 -102.764082) (xy 439.48223 -102.780084) (xy 439.471308 -102.827328)
			(xy 439.470038 -102.838758) (xy 439.470038 -102.89032) (xy 439.47334 -102.902766) (xy 439.476642 -102.908608)
			(xy 439.48834 -102.930109) (xy 439.506767 -102.975456) (xy 439.519231 -103.022791) (xy 439.525528 -103.071332)
			(xy 439.525918 -103.095806) (xy 439.525393 -103.124545) (xy 439.51677 -103.181372) (xy 439.49972 -103.236262)
			(xy 439.474629 -103.287974) (xy 439.442064 -103.335337) (xy 439.422794 -103.356664) (xy 439.415936 -103.363776)
			(xy 439.409078 -103.381556) (xy 439.409078 -103.470456) (xy 439.415936 -103.488236) (xy 439.422794 -103.495348)
			(xy 439.44207 -103.51667) (xy 439.474633 -103.564034) (xy 439.499724 -103.615746) (xy 439.516772 -103.670638)
			(xy 439.525394 -103.727465) (xy 439.525393 -103.784943) (xy 439.51677 -103.841771) (xy 439.500507 -103.894128)
			(xy 440.513976 -103.894128) (xy 440.518047 -103.838506) (xy 440.530173 -103.784069) (xy 440.550096 -103.731978)
			(xy 440.577392 -103.683343) (xy 440.611478 -103.6392) (xy 440.651627 -103.600491) (xy 440.696985 -103.56804)
			(xy 440.746585 -103.542539) (xy 440.799369 -103.524532) (xy 440.854212 -103.514402) (xy 440.909946 -103.512365)
			(xy 440.965383 -103.518465) (xy 441.01934 -103.532571) (xy 441.070669 -103.554383) (xy 441.118275 -103.583437)
			(xy 441.161143 -103.619112) (xy 441.19836 -103.660649) (xy 441.229133 -103.707162) (xy 441.252805 -103.757659)
			(xy 441.268873 -103.811066) (xy 441.276993 -103.866242) (xy 441.277428 -103.890064) (xy 441.53912 -103.890064)
			(xy 441.543191 -103.834442) (xy 441.555317 -103.780005) (xy 441.57524 -103.727914) (xy 441.602536 -103.679279)
			(xy 441.636622 -103.635136) (xy 441.676771 -103.596427) (xy 441.722129 -103.563976) (xy 441.771729 -103.538475)
			(xy 441.824513 -103.520468) (xy 441.879356 -103.510338) (xy 441.93509 -103.508301) (xy 441.990527 -103.514401)
			(xy 442.044484 -103.528507) (xy 442.095813 -103.550319) (xy 442.143419 -103.579373) (xy 442.186287 -103.615048)
			(xy 442.223504 -103.656585) (xy 442.254277 -103.703098) (xy 442.277949 -103.753595) (xy 442.294017 -103.807002)
			(xy 442.302137 -103.862178) (xy 442.302646 -103.890064) (xy 442.302137 -103.91795) (xy 442.294017 -103.973126)
			(xy 442.27904 -104.022906) (xy 444.16599 -104.022906) (xy 444.166465 -103.996592) (xy 444.173698 -103.944464)
			(xy 444.188016 -103.893822) (xy 444.209147 -103.845623) (xy 444.236692 -103.800779) (xy 444.270129 -103.760139)
			(xy 444.28918 -103.741982) (xy 444.296625 -103.734413) (xy 444.305149 -103.714993) (xy 444.30569 -103.70439)
			(xy 444.30569 -103.630222) (xy 444.305263 -103.619592) (xy 444.296726 -103.600127) (xy 444.28918 -103.59263)
			(xy 444.270142 -103.574457) (xy 444.236684 -103.53383) (xy 444.209123 -103.488994) (xy 444.187982 -103.440796)
			(xy 444.173661 -103.390152) (xy 444.166431 -103.338021) (xy 444.16599 -103.311706) (xy 444.166461 -103.284453)
			(xy 444.174217 -103.230503) (xy 444.189572 -103.178205) (xy 444.212214 -103.128625) (xy 444.241681 -103.082772)
			(xy 444.277374 -103.04158) (xy 444.318566 -103.005886) (xy 444.364418 -102.976418) (xy 444.413998 -102.953775)
			(xy 444.466295 -102.938419) (xy 444.520245 -102.930661) (xy 444.547498 -102.930198) (xy 444.575175 -102.930707)
			(xy 444.629947 -102.938719) (xy 444.682987 -102.954561) (xy 444.733181 -102.977901) (xy 444.779476 -103.008248)
			(xy 444.820901 -103.044966) (xy 444.856585 -103.087283) (xy 444.871602 -103.110538) (xy 444.87838 -103.120127)
			(xy 444.898342 -103.13244) (xy 444.909956 -103.13416) (xy 444.989966 -103.142034) (xy 445.001255 -103.142558)
			(xy 445.022488 -103.134895) (xy 445.03086 -103.127302) (xy 445.031876 -103.126286) (xy 445.032384 -103.125778)
			(xy 445.050448 -103.107265) (xy 445.090739 -103.074829) (xy 445.135044 -103.048135) (xy 445.18255 -103.027673)
			(xy 445.232385 -103.01382) (xy 445.283635 -103.006829) (xy 445.309498 -103.006398) (xy 445.336751 -103.006857)
			(xy 445.390702 -103.014614) (xy 445.443001 -103.02997) (xy 445.492581 -103.052613) (xy 445.538435 -103.082081)
			(xy 445.579628 -103.117775) (xy 445.615321 -103.158969) (xy 445.644789 -103.204822) (xy 445.667431 -103.254403)
			(xy 445.682787 -103.306701) (xy 445.690543 -103.360653) (xy 445.691006 -103.387906) (xy 445.690542 -103.415276)
			(xy 445.682723 -103.469455) (xy 445.667234 -103.521958) (xy 445.644392 -103.571705) (xy 445.614667 -103.617672)
			(xy 445.597026 -103.638604) (xy 445.59093 -103.645716) (xy 445.58458 -103.66248) (xy 445.58458 -103.721154)
			(xy 445.597026 -103.721154) (xy 445.597026 -103.76281) (xy 445.602614 -103.778558) (xy 445.607948 -103.785416)
			(xy 445.623617 -103.805729) (xy 445.649916 -103.849779) (xy 445.670067 -103.896959) (xy 445.683707 -103.946415)
			(xy 445.690589 -103.997255) (xy 445.691006 -104.022906) (xy 445.690528 -104.050157) (xy 445.68277 -104.104106)
			(xy 445.67939 -104.115616) (xy 448.597274 -104.115616) (xy 448.59776 -104.089303) (xy 448.604993 -104.037175)
			(xy 448.619308 -103.986533) (xy 448.640437 -103.938335) (xy 448.66798 -103.893491) (xy 448.701414 -103.85285)
			(xy 448.720464 -103.834692) (xy 448.727902 -103.827117) (xy 448.73643 -103.807702) (xy 448.736974 -103.7971)
			(xy 448.736974 -103.722932) (xy 448.736601 -103.712296) (xy 448.728027 -103.692831) (xy 448.720464 -103.68534)
			(xy 448.701379 -103.667214) (xy 448.667926 -103.626577) (xy 448.640372 -103.58173) (xy 448.619239 -103.533524)
			(xy 448.604927 -103.482872) (xy 448.597709 -103.430734) (xy 448.597274 -103.404416) (xy 448.59776 -103.377165)
			(xy 448.605516 -103.323217) (xy 448.620871 -103.270922) (xy 448.643513 -103.221345) (xy 448.672979 -103.175495)
			(xy 448.70867 -103.134304) (xy 448.749861 -103.098613) (xy 448.795711 -103.069147) (xy 448.845288 -103.046505)
			(xy 448.897583 -103.03115) (xy 448.951531 -103.023394) (xy 449.006033 -103.023394) (xy 449.059981 -103.03115)
			(xy 449.112276 -103.046505) (xy 449.161853 -103.069147) (xy 449.207703 -103.098613) (xy 449.248894 -103.134304)
			(xy 449.284585 -103.175495) (xy 449.314051 -103.221345) (xy 449.336693 -103.270922) (xy 449.352048 -103.323217)
			(xy 449.359804 -103.377165) (xy 449.36029 -103.404416) (xy 449.359836 -103.43073) (xy 449.352599 -103.48286)
			(xy 449.338278 -103.533503) (xy 449.317143 -103.581702) (xy 449.289594 -103.626545) (xy 449.256153 -103.667184)
			(xy 449.2371 -103.68534) (xy 449.229642 -103.692898) (xy 449.221127 -103.712326) (xy 449.220725 -103.720256)
			(xy 451.873015 -103.720256) (xy 451.873015 -103.665744) (xy 451.880773 -103.611786) (xy 451.896131 -103.559482)
			(xy 451.918777 -103.509895) (xy 451.948249 -103.464037) (xy 451.983948 -103.42284) (xy 452.025147 -103.387142)
			(xy 452.071006 -103.357671) (xy 452.120593 -103.335027) (xy 452.172898 -103.319671) (xy 452.226856 -103.311914)
			(xy 452.254112 -103.311452) (xy 452.281483 -103.311898) (xy 452.335664 -103.319719) (xy 452.388167 -103.335212)
			(xy 452.437914 -103.358058) (xy 452.483879 -103.387788) (xy 452.50481 -103.405432) (xy 452.511922 -103.411528)
			(xy 452.528686 -103.417878) (xy 452.58736 -103.417878) (xy 452.58736 -103.405432) (xy 452.629016 -103.405432)
			(xy 452.644764 -103.399844) (xy 452.651622 -103.39451) (xy 452.672668 -103.378388) (xy 452.718311 -103.351424)
			(xy 452.767249 -103.331042) (xy 452.818539 -103.317636) (xy 452.871191 -103.311465) (xy 452.924191 -103.312647)
			(xy 452.976516 -103.321159) (xy 453.027157 -103.336838) (xy 453.075138 -103.359381) (xy 453.119533 -103.388354)
			(xy 453.13981 -103.405432) (xy 453.146922 -103.411528) (xy 453.163686 -103.417878) (xy 453.22236 -103.417878)
			(xy 453.22236 -103.405432) (xy 453.264016 -103.405432) (xy 453.279764 -103.399844) (xy 453.286622 -103.39451)
			(xy 453.306929 -103.378832) (xy 453.350981 -103.352536) (xy 453.398162 -103.332387) (xy 453.44762 -103.318749)
			(xy 453.49846 -103.311869) (xy 453.524112 -103.311452) (xy 453.55136 -103.312019) (xy 453.605301 -103.319776)
			(xy 453.657588 -103.335131) (xy 453.707159 -103.35777) (xy 453.753003 -103.387234) (xy 453.794187 -103.422921)
			(xy 453.829874 -103.464107) (xy 453.859336 -103.509952) (xy 453.881974 -103.559523) (xy 453.897326 -103.611811)
			(xy 453.905082 -103.665752) (xy 453.905082 -103.720248) (xy 453.897326 -103.774189) (xy 453.881974 -103.826477)
			(xy 453.859336 -103.876048) (xy 453.829874 -103.921893) (xy 453.794187 -103.963079) (xy 453.753003 -103.998766)
			(xy 453.707159 -104.02823) (xy 453.657588 -104.050869) (xy 453.605301 -104.066224) (xy 453.55136 -104.073981)
			(xy 453.524112 -104.074468) (xy 453.496742 -104.074003) (xy 453.442562 -104.066186) (xy 453.390059 -104.050697)
			(xy 453.340312 -104.027855) (xy 453.294345 -103.99813) (xy 453.273414 -103.980488) (xy 453.266302 -103.974392)
			(xy 453.249538 -103.968042) (xy 453.163686 -103.968042) (xy 453.146922 -103.974392) (xy 453.13981 -103.980488)
			(xy 453.118877 -103.998129) (xy 453.072909 -104.027853) (xy 453.023163 -104.050699) (xy 452.970661 -104.066195)
			(xy 452.916483 -104.074024) (xy 452.861741 -104.074024) (xy 452.807563 -104.066195) (xy 452.755061 -104.050699)
			(xy 452.705315 -104.027853) (xy 452.659347 -103.998129) (xy 452.638414 -103.980488) (xy 452.631302 -103.974392)
			(xy 452.614538 -103.968042) (xy 452.555864 -103.968042) (xy 452.555864 -103.980488) (xy 452.514208 -103.980488)
			(xy 452.49846 -103.986076) (xy 452.491602 -103.99141) (xy 452.471278 -104.007065) (xy 452.427232 -104.033367)
			(xy 452.380055 -104.053522) (xy 452.330601 -104.067164) (xy 452.279763 -104.074049) (xy 452.254112 -104.074468)
			(xy 452.226856 -104.074086) (xy 452.172898 -104.066329) (xy 452.120593 -104.050973) (xy 452.071006 -104.028329)
			(xy 452.025147 -103.998858) (xy 451.983948 -103.96316) (xy 451.948249 -103.921963) (xy 451.918777 -103.876105)
			(xy 451.896131 -103.826518) (xy 451.880773 -103.774214) (xy 451.873015 -103.720256) (xy 449.220725 -103.720256)
			(xy 449.22059 -103.722932) (xy 449.22059 -103.7971) (xy 449.221011 -103.807731) (xy 449.229552 -103.827195)
			(xy 449.2371 -103.834692) (xy 449.256145 -103.852859) (xy 449.289603 -103.893486) (xy 449.317163 -103.938324)
			(xy 449.338304 -103.986522) (xy 449.352623 -104.037168) (xy 449.35985 -104.0893) (xy 449.36029 -104.115616)
			(xy 449.359804 -104.142867) (xy 449.352048 -104.196815) (xy 449.336693 -104.24911) (xy 449.314051 -104.298687)
			(xy 449.284585 -104.344537) (xy 449.248894 -104.385728) (xy 449.207703 -104.421419) (xy 449.161853 -104.450885)
			(xy 449.112276 -104.473527) (xy 449.059981 -104.488882) (xy 449.006033 -104.496638) (xy 448.951531 -104.496638)
			(xy 448.897583 -104.488882) (xy 448.845288 -104.473527) (xy 448.795711 -104.450885) (xy 448.749861 -104.421419)
			(xy 448.70867 -104.385728) (xy 448.672979 -104.344537) (xy 448.643513 -104.298687) (xy 448.620871 -104.24911)
			(xy 448.605516 -104.196815) (xy 448.59776 -104.142867) (xy 448.597274 -104.115616) (xy 445.67939 -104.115616)
			(xy 445.667414 -104.156401) (xy 445.644772 -104.205978) (xy 445.615305 -104.251828) (xy 445.579613 -104.293019)
			(xy 445.538422 -104.32871) (xy 445.492571 -104.358176) (xy 445.442993 -104.380817) (xy 445.390698 -104.396172)
			(xy 445.336749 -104.403928) (xy 445.309498 -104.404414) (xy 445.280579 -104.40393) (xy 445.223405 -104.395198)
			(xy 445.168204 -104.377936) (xy 445.116242 -104.352538) (xy 445.068709 -104.319587) (xy 445.026696 -104.279838)
			(xy 445.008508 -104.257348) (xy 445.000897 -104.248546) (xy 444.979999 -104.238361) (xy 444.968376 -104.23779)
			(xy 444.88862 -104.23779) (xy 444.876992 -104.238359) (xy 444.856082 -104.248527) (xy 444.848488 -104.257348)
			(xy 444.830316 -104.279847) (xy 444.788291 -104.319579) (xy 444.740751 -104.352515) (xy 444.688787 -104.3779)
			(xy 444.633587 -104.395154) (xy 444.576415 -104.40388) (xy 444.547498 -104.404414) (xy 444.520247 -104.403924)
			(xy 444.4663 -104.396167) (xy 444.414005 -104.380812) (xy 444.364429 -104.358171) (xy 444.318578 -104.328706)
			(xy 444.277388 -104.293014) (xy 444.241697 -104.251825) (xy 444.21223 -104.205975) (xy 444.189589 -104.156398)
			(xy 444.174233 -104.104104) (xy 444.166476 -104.050157) (xy 444.16599 -104.022906) (xy 442.27904 -104.022906)
			(xy 442.277949 -104.026533) (xy 442.254277 -104.07703) (xy 442.223504 -104.123543) (xy 442.186287 -104.16508)
			(xy 442.143419 -104.200755) (xy 442.095813 -104.229809) (xy 442.044484 -104.251621) (xy 441.990527 -104.265727)
			(xy 441.93509 -104.271827) (xy 441.879356 -104.26979) (xy 441.824513 -104.25966) (xy 441.771729 -104.241653)
			(xy 441.722129 -104.216152) (xy 441.676771 -104.183701) (xy 441.636622 -104.144992) (xy 441.602536 -104.100849)
			(xy 441.57524 -104.052214) (xy 441.555317 -104.000123) (xy 441.543191 -103.945686) (xy 441.53912 -103.890064)
			(xy 441.277428 -103.890064) (xy 441.277502 -103.894128) (xy 441.276993 -103.922014) (xy 441.268873 -103.97719)
			(xy 441.252805 -104.030597) (xy 441.229133 -104.081094) (xy 441.19836 -104.127607) (xy 441.161143 -104.169144)
			(xy 441.118275 -104.204819) (xy 441.070669 -104.233873) (xy 441.01934 -104.255685) (xy 440.965383 -104.269791)
			(xy 440.909946 -104.275891) (xy 440.854212 -104.273854) (xy 440.799369 -104.263724) (xy 440.746585 -104.245717)
			(xy 440.696985 -104.220216) (xy 440.651627 -104.187765) (xy 440.611478 -104.149056) (xy 440.577392 -104.104913)
			(xy 440.550096 -104.056278) (xy 440.530173 -104.004187) (xy 440.518047 -103.94975) (xy 440.513976 -103.894128)
			(xy 439.500507 -103.894128) (xy 439.49972 -103.896662) (xy 439.474629 -103.948374) (xy 439.442064 -103.995737)
			(xy 439.422794 -104.017064) (xy 439.415936 -104.024176) (xy 439.409078 -104.041956) (xy 439.409078 -104.130856)
			(xy 439.415936 -104.148636) (xy 439.422794 -104.155748) (xy 439.44207 -104.17707) (xy 439.474633 -104.224434)
			(xy 439.499724 -104.276146) (xy 439.516772 -104.331038) (xy 439.525394 -104.387865) (xy 439.525393 -104.445343)
			(xy 439.51677 -104.502171) (xy 439.49972 -104.557062) (xy 439.474629 -104.608774) (xy 439.442064 -104.656137)
			(xy 439.422794 -104.677464) (xy 439.415936 -104.684576) (xy 439.409078 -104.702356) (xy 439.409078 -104.791256)
			(xy 439.415936 -104.809036) (xy 439.422794 -104.816148) (xy 439.44207 -104.83747) (xy 439.474633 -104.884834)
			(xy 439.499724 -104.936546) (xy 439.516772 -104.991438) (xy 439.525394 -105.048265) (xy 439.525393 -105.08445)
			(xy 444.044072 -105.08445) (xy 444.044072 -105.02995) (xy 444.051828 -104.976004) (xy 444.067181 -104.923711)
			(xy 444.089821 -104.874135) (xy 444.119285 -104.828285) (xy 444.154974 -104.787095) (xy 444.196161 -104.751403)
			(xy 444.242008 -104.721935) (xy 444.291582 -104.699292) (xy 444.343874 -104.683934) (xy 444.39782 -104.676174)
			(xy 444.42507 -104.675686) (xy 444.452439 -104.676173) (xy 444.506617 -104.683986) (xy 444.55912 -104.699471)
			(xy 444.608867 -104.722308) (xy 444.654835 -104.752027) (xy 444.675768 -104.769666) (xy 444.68288 -104.775762)
			(xy 444.699644 -104.782112) (xy 444.758318 -104.782112) (xy 444.758318 -104.769666) (xy 444.799974 -104.769666)
			(xy 444.815722 -104.764078) (xy 444.82258 -104.758744) (xy 444.843586 -104.742569) (xy 444.889237 -104.715612)
			(xy 444.938183 -104.695238) (xy 444.989478 -104.681839) (xy 445.042135 -104.675675) (xy 445.095138 -104.676863)
			(xy 445.147466 -104.685381) (xy 445.198109 -104.701064) (xy 445.246092 -104.723611) (xy 445.29049 -104.752587)
			(xy 445.310768 -104.769666) (xy 445.31788 -104.775762) (xy 445.334644 -104.782112) (xy 445.393318 -104.782112)
			(xy 445.393318 -104.769666) (xy 445.434974 -104.769666) (xy 445.450722 -104.764078) (xy 445.45758 -104.758744)
			(xy 445.478586 -104.742569) (xy 445.524237 -104.715612) (xy 445.573183 -104.695238) (xy 445.624478 -104.681839)
			(xy 445.677135 -104.675675) (xy 445.730138 -104.676863) (xy 445.782466 -104.685381) (xy 445.833109 -104.701064)
			(xy 445.881092 -104.723611) (xy 445.92549 -104.752587) (xy 445.945768 -104.769666) (xy 445.95288 -104.775762)
			(xy 445.969644 -104.782112) (xy 446.028318 -104.782112) (xy 446.028318 -104.769666) (xy 446.069974 -104.769666)
			(xy 446.085722 -104.764078) (xy 446.09258 -104.758744) (xy 446.112905 -104.74309) (xy 446.156951 -104.716789)
			(xy 446.204128 -104.696635) (xy 446.253582 -104.682992) (xy 446.304419 -104.676106) (xy 446.33007 -104.675686)
			(xy 446.357324 -104.676159) (xy 446.411277 -104.683913) (xy 446.463578 -104.699266) (xy 446.513161 -104.721906)
			(xy 446.559017 -104.751373) (xy 446.600213 -104.787066) (xy 446.635909 -104.828259) (xy 446.665379 -104.874113)
			(xy 446.688024 -104.923694) (xy 446.703381 -104.975994) (xy 446.711139 -105.029946) (xy 446.711139 -105.08445)
			(xy 447.967872 -105.08445) (xy 447.967872 -105.02995) (xy 447.975627 -104.976005) (xy 447.990981 -104.923712)
			(xy 448.01362 -104.874137) (xy 448.043083 -104.828287) (xy 448.078771 -104.787098) (xy 448.119957 -104.751406)
			(xy 448.165803 -104.721938) (xy 448.215377 -104.699294) (xy 448.267668 -104.683935) (xy 448.321612 -104.676174)
			(xy 448.348862 -104.675686) (xy 448.375177 -104.676117) (xy 448.427307 -104.68336) (xy 448.47795 -104.697686)
			(xy 448.526149 -104.718826) (xy 448.570992 -104.746378) (xy 448.61163 -104.779822) (xy 448.629786 -104.798876)
			(xy 448.637367 -104.806306) (xy 448.656778 -104.814839) (xy 448.667378 -104.815386) (xy 448.741546 -104.815386)
			(xy 448.752181 -104.814998) (xy 448.771645 -104.806434) (xy 448.779138 -104.798876) (xy 448.797277 -104.779804)
			(xy 448.837911 -104.74635) (xy 448.882755 -104.718793) (xy 448.930959 -104.697658) (xy 448.981609 -104.683344)
			(xy 449.033745 -104.676123) (xy 449.060062 -104.675686) (xy 449.087431 -104.676178) (xy 449.141609 -104.68399)
			(xy 449.194112 -104.699473) (xy 449.243859 -104.722309) (xy 449.289827 -104.752028) (xy 449.31076 -104.769666)
			(xy 449.317872 -104.775762) (xy 449.334636 -104.782112) (xy 449.39331 -104.782112) (xy 449.39331 -104.769666)
			(xy 449.434966 -104.769666) (xy 449.450714 -104.764078) (xy 449.457572 -104.758744) (xy 449.478584 -104.742577)
			(xy 449.524234 -104.71562) (xy 449.573178 -104.695245) (xy 449.624473 -104.681846) (xy 449.677129 -104.67568)
			(xy 449.730131 -104.676867) (xy 449.782459 -104.685384) (xy 449.833102 -104.701067) (xy 449.881085 -104.723613)
			(xy 449.925482 -104.752587) (xy 449.94576 -104.769666) (xy 449.952872 -104.775762) (xy 449.969636 -104.782112)
			(xy 450.02831 -104.782112) (xy 450.02831 -104.769666) (xy 450.069966 -104.769666) (xy 450.085714 -104.764078)
			(xy 450.092572 -104.758744) (xy 450.112899 -104.743094) (xy 450.156945 -104.716792) (xy 450.204121 -104.696637)
			(xy 450.253575 -104.682993) (xy 450.304411 -104.676106) (xy 450.330062 -104.675686) (xy 450.357316 -104.676159)
			(xy 450.41127 -104.683911) (xy 450.463572 -104.699264) (xy 450.513156 -104.721904) (xy 450.559013 -104.75137)
			(xy 450.60021 -104.787063) (xy 450.635907 -104.828256) (xy 450.665378 -104.874111) (xy 450.688023 -104.923692)
			(xy 450.703381 -104.975992) (xy 450.711139 -105.029946) (xy 450.711139 -105.084454) (xy 450.703381 -105.138408)
			(xy 450.688023 -105.190708) (xy 450.665378 -105.240289) (xy 450.635907 -105.286144) (xy 450.60021 -105.327337)
			(xy 450.559013 -105.36303) (xy 450.513156 -105.392496) (xy 450.463572 -105.415136) (xy 450.41127 -105.430489)
			(xy 450.357316 -105.438241) (xy 450.330062 -105.438702) (xy 450.302693 -105.438199) (xy 450.248516 -105.43039)
			(xy 450.196013 -105.41491) (xy 450.146265 -105.392076) (xy 450.100297 -105.362359) (xy 450.079364 -105.344722)
			(xy 450.072252 -105.338626) (xy 450.055488 -105.332276) (xy 449.969636 -105.332276) (xy 449.952872 -105.338626)
			(xy 449.94576 -105.344722) (xy 449.924827 -105.362363) (xy 449.878859 -105.392087) (xy 449.829113 -105.414933)
			(xy 449.776611 -105.430429) (xy 449.722433 -105.438258) (xy 449.667691 -105.438258) (xy 449.613513 -105.430429)
			(xy 449.561011 -105.414933) (xy 449.511265 -105.392087) (xy 449.465297 -105.362363) (xy 449.444364 -105.344722)
			(xy 449.437252 -105.338626) (xy 449.420488 -105.332276) (xy 449.361814 -105.332276) (xy 449.361814 -105.344722)
			(xy 449.320158 -105.344722) (xy 449.30441 -105.35031) (xy 449.297552 -105.355644) (xy 449.277215 -105.371282)
			(xy 449.233172 -105.397585) (xy 449.185998 -105.417743) (xy 449.136547 -105.43139) (xy 449.085712 -105.43828)
			(xy 449.060062 -105.438702) (xy 449.033747 -105.438259) (xy 448.981618 -105.431019) (xy 448.930974 -105.416695)
			(xy 448.882776 -105.395558) (xy 448.837933 -105.368008) (xy 448.797294 -105.334565) (xy 448.779138 -105.315512)
			(xy 448.77155 -105.308091) (xy 448.752144 -105.299554) (xy 448.741546 -105.299002) (xy 448.667378 -105.299002)
			(xy 448.656746 -105.299407) (xy 448.637281 -105.307959) (xy 448.629786 -105.315512) (xy 448.611633 -105.33457)
			(xy 448.571002 -105.368026) (xy 448.526161 -105.395585) (xy 448.47796 -105.416723) (xy 448.427312 -105.431039)
			(xy 448.375178 -105.438264) (xy 448.348862 -105.438702) (xy 448.321612 -105.438226) (xy 448.267668 -105.430465)
			(xy 448.215377 -105.415106) (xy 448.165803 -105.392462) (xy 448.119957 -105.362994) (xy 448.078771 -105.327302)
			(xy 448.043083 -105.286113) (xy 448.01362 -105.240263) (xy 447.990981 -105.190688) (xy 447.975627 -105.138395)
			(xy 447.967872 -105.08445) (xy 446.711139 -105.08445) (xy 446.711139 -105.084454) (xy 446.703381 -105.138406)
			(xy 446.688024 -105.190706) (xy 446.665379 -105.240287) (xy 446.635909 -105.286141) (xy 446.600213 -105.327334)
			(xy 446.559017 -105.363027) (xy 446.513161 -105.392494) (xy 446.463578 -105.415134) (xy 446.411277 -105.430487)
			(xy 446.357324 -105.438241) (xy 446.33007 -105.438702) (xy 446.302699 -105.438253) (xy 446.248519 -105.430431)
			(xy 446.196016 -105.414938) (xy 446.14627 -105.392092) (xy 446.100303 -105.362365) (xy 446.079372 -105.344722)
			(xy 446.07226 -105.338626) (xy 446.055496 -105.332276) (xy 445.969644 -105.332276) (xy 445.95288 -105.338626)
			(xy 445.945768 -105.344722) (xy 445.924835 -105.362363) (xy 445.878867 -105.392087) (xy 445.829121 -105.414933)
			(xy 445.776619 -105.430429) (xy 445.722441 -105.438258) (xy 445.667699 -105.438258) (xy 445.613521 -105.430429)
			(xy 445.561019 -105.414933) (xy 445.511273 -105.392087) (xy 445.465305 -105.362363) (xy 445.444372 -105.344722)
			(xy 445.43726 -105.338626) (xy 445.420496 -105.332276) (xy 445.361822 -105.332276) (xy 445.361822 -105.344722)
			(xy 445.320166 -105.344722) (xy 445.304418 -105.35031) (xy 445.29756 -105.355644) (xy 445.276525 -105.37178)
			(xy 445.230879 -105.39874) (xy 445.181939 -105.419118) (xy 445.130648 -105.43252) (xy 445.077995 -105.438689)
			(xy 445.024995 -105.437505) (xy 444.97267 -105.428991) (xy 444.922028 -105.413312) (xy 444.874046 -105.39077)
			(xy 444.82965 -105.361799) (xy 444.809372 -105.344722) (xy 444.80226 -105.338626) (xy 444.785496 -105.332276)
			(xy 444.726822 -105.332276) (xy 444.726822 -105.344722) (xy 444.685166 -105.344722) (xy 444.669418 -105.35031)
			(xy 444.66256 -105.355644) (xy 444.642254 -105.371324) (xy 444.598202 -105.397621) (xy 444.551021 -105.41777)
			(xy 444.501563 -105.431407) (xy 444.450722 -105.438286) (xy 444.42507 -105.438702) (xy 444.39782 -105.438226)
			(xy 444.343874 -105.430466) (xy 444.291582 -105.415108) (xy 444.242008 -105.392465) (xy 444.196161 -105.362997)
			(xy 444.154974 -105.327305) (xy 444.119285 -105.286115) (xy 444.089821 -105.240265) (xy 444.067181 -105.190689)
			(xy 444.051828 -105.138396) (xy 444.044072 -105.08445) (xy 439.525393 -105.08445) (xy 439.525393 -105.105743)
			(xy 439.51677 -105.162571) (xy 439.49972 -105.217462) (xy 439.474629 -105.269174) (xy 439.442064 -105.316537)
			(xy 439.422794 -105.337864) (xy 439.415936 -105.344976) (xy 439.409078 -105.362756) (xy 439.409078 -105.451656)
			(xy 439.415936 -105.469436) (xy 439.422794 -105.476548) (xy 439.44207 -105.49787) (xy 439.474633 -105.545234)
			(xy 439.499724 -105.596946) (xy 439.516772 -105.651838) (xy 439.525394 -105.708665) (xy 439.525393 -105.766143)
			(xy 439.51677 -105.822971) (xy 439.49972 -105.877862) (xy 439.474629 -105.929574) (xy 439.442064 -105.976937)
			(xy 439.422794 -105.998264) (xy 439.415936 -106.005376) (xy 439.409078 -106.023156) (xy 439.409078 -106.112056)
			(xy 439.415936 -106.129836) (xy 439.422794 -106.136948) (xy 439.44207 -106.15827) (xy 439.474633 -106.205634)
			(xy 439.499724 -106.257346) (xy 439.516772 -106.312238) (xy 439.525394 -106.369065) (xy 439.525393 -106.426543)
			(xy 439.51677 -106.483371) (xy 439.49972 -106.538262) (xy 439.474629 -106.589974) (xy 439.442064 -106.637337)
			(xy 439.422794 -106.658664) (xy 439.415936 -106.665776) (xy 439.409078 -106.683556) (xy 439.409078 -106.772456)
			(xy 439.415936 -106.790236) (xy 439.422794 -106.797348) (xy 439.431564 -106.807049) (xy 451.9031 -106.807049)
			(xy 451.9031 -106.752551) (xy 451.910856 -106.698608) (xy 451.926209 -106.646318) (xy 451.948848 -106.596744)
			(xy 451.978311 -106.550897) (xy 452.013999 -106.50971) (xy 452.055185 -106.474021) (xy 452.10103 -106.444556)
			(xy 452.150603 -106.421915) (xy 452.202892 -106.406559) (xy 452.256835 -106.398801) (xy 452.284084 -106.398314)
			(xy 452.311454 -106.398786) (xy 452.365633 -106.406602) (xy 452.418136 -106.422089) (xy 452.467883 -106.44493)
			(xy 452.51385 -106.474653) (xy 452.534782 -106.492294) (xy 452.541894 -106.49839) (xy 452.558658 -106.50474)
			(xy 452.617332 -106.50474) (xy 452.617332 -106.492294) (xy 452.658988 -106.492294) (xy 452.674736 -106.486706)
			(xy 452.681594 -106.481372) (xy 452.702589 -106.465182) (xy 452.748242 -106.438223) (xy 452.797189 -106.417848)
			(xy 452.848486 -106.40445) (xy 452.901145 -106.398286) (xy 452.95415 -106.399476) (xy 453.006479 -106.407996)
			(xy 453.057124 -106.423683) (xy 453.105107 -106.446233) (xy 453.149505 -106.475213) (xy 453.169782 -106.492294)
			(xy 453.176894 -106.49839) (xy 453.193658 -106.50474) (xy 453.252332 -106.50474) (xy 453.252332 -106.492294)
			(xy 453.293988 -106.492294) (xy 453.309736 -106.486706) (xy 453.316594 -106.481372) (xy 453.336917 -106.465716)
			(xy 453.380964 -106.439415) (xy 453.428141 -106.419261) (xy 453.477596 -106.405618) (xy 453.528433 -106.398733)
			(xy 453.554084 -106.398314) (xy 453.581339 -106.398732) (xy 453.635295 -106.406487) (xy 453.687598 -106.421843)
			(xy 453.737183 -106.444486) (xy 453.783041 -106.473955) (xy 453.824238 -106.509651) (xy 453.859935 -106.550846)
			(xy 453.889406 -106.596703) (xy 453.912051 -106.646287) (xy 453.927409 -106.698589) (xy 453.935167 -106.752545)
			(xy 453.935167 -106.807055) (xy 453.927409 -106.861011) (xy 453.912051 -106.913313) (xy 453.889406 -106.962897)
			(xy 453.859935 -107.008754) (xy 453.824238 -107.049949) (xy 453.783041 -107.085645) (xy 453.737183 -107.115114)
			(xy 453.687598 -107.137757) (xy 453.635295 -107.153113) (xy 453.581339 -107.160868) (xy 453.554084 -107.16133)
			(xy 453.526713 -107.16089) (xy 453.472532 -107.153069) (xy 453.420028 -107.137574) (xy 453.370281 -107.114726)
			(xy 453.324316 -107.084995) (xy 453.303386 -107.06735) (xy 453.296274 -107.061254) (xy 453.27951 -107.054904)
			(xy 453.193658 -107.054904) (xy 453.176894 -107.061254) (xy 453.169782 -107.06735) (xy 453.148849 -107.084991)
			(xy 453.102881 -107.114715) (xy 453.053135 -107.137561) (xy 453.000633 -107.153057) (xy 452.946455 -107.160886)
			(xy 452.891713 -107.160886) (xy 452.837535 -107.153057) (xy 452.785033 -107.137561) (xy 452.735287 -107.114715)
			(xy 452.689319 -107.084991) (xy 452.668386 -107.06735) (xy 452.661274 -107.061254) (xy 452.64451 -107.054904)
			(xy 452.585836 -107.054904) (xy 452.585836 -107.06735) (xy 452.54418 -107.06735) (xy 452.528432 -107.072938)
			(xy 452.521574 -107.078272) (xy 452.501267 -107.093949) (xy 452.457215 -107.120246) (xy 452.410034 -107.140395)
			(xy 452.360576 -107.154033) (xy 452.309736 -107.160913) (xy 452.284084 -107.16133) (xy 452.256835 -107.160799)
			(xy 452.202892 -107.153041) (xy 452.150603 -107.137685) (xy 452.10103 -107.115044) (xy 452.055185 -107.085579)
			(xy 452.013999 -107.04989) (xy 451.978311 -107.008703) (xy 451.948848 -106.962856) (xy 451.926209 -106.913282)
			(xy 451.910856 -106.860992) (xy 451.9031 -106.807049) (xy 439.431564 -106.807049) (xy 439.44207 -106.81867)
			(xy 439.474633 -106.866034) (xy 439.499724 -106.917746) (xy 439.516772 -106.972638) (xy 439.525394 -107.029465)
			(xy 439.525393 -107.086943) (xy 439.51677 -107.143771) (xy 439.49972 -107.198662) (xy 439.474629 -107.250374)
			(xy 439.442064 -107.297737) (xy 439.422794 -107.319064) (xy 439.415936 -107.326176) (xy 439.409078 -107.343956)
			(xy 439.409078 -107.432856) (xy 439.415936 -107.450636) (xy 439.422794 -107.457748) (xy 439.44207 -107.47907)
			(xy 439.474633 -107.526434) (xy 439.499724 -107.578146) (xy 439.516772 -107.633038) (xy 439.525394 -107.689865)
			(xy 439.525393 -107.740249) (xy 443.984396 -107.740249) (xy 443.984396 -107.685751) (xy 443.992152 -107.631808)
			(xy 444.007505 -107.579517) (xy 444.030144 -107.529944) (xy 444.059607 -107.484096) (xy 444.095294 -107.442909)
			(xy 444.13648 -107.407219) (xy 444.182326 -107.377753) (xy 444.231898 -107.355112) (xy 444.284188 -107.339756)
			(xy 444.338131 -107.331998) (xy 444.36538 -107.33151) (xy 444.39275 -107.331985) (xy 444.446929 -107.339801)
			(xy 444.499432 -107.355287) (xy 444.549179 -107.378127) (xy 444.595146 -107.40785) (xy 444.616078 -107.42549)
			(xy 444.62319 -107.431586) (xy 444.639954 -107.437936) (xy 444.698628 -107.437936) (xy 444.698628 -107.42549)
			(xy 444.740284 -107.42549) (xy 444.756032 -107.419902) (xy 444.76289 -107.414568) (xy 444.783888 -107.398382)
			(xy 444.82954 -107.371424) (xy 444.878487 -107.351049) (xy 444.929784 -107.33765) (xy 444.982442 -107.331486)
			(xy 445.035447 -107.332675) (xy 445.087775 -107.341195) (xy 445.13842 -107.356881) (xy 445.186403 -107.37943)
			(xy 445.230801 -107.408409) (xy 445.251078 -107.42549) (xy 445.25819 -107.431586) (xy 445.274954 -107.437936)
			(xy 445.333628 -107.437936) (xy 445.333628 -107.42549) (xy 445.375284 -107.42549) (xy 445.391032 -107.419902)
			(xy 445.39789 -107.414568) (xy 445.418888 -107.398382) (xy 445.46454 -107.371424) (xy 445.513487 -107.351049)
			(xy 445.564784 -107.33765) (xy 445.617442 -107.331486) (xy 445.670447 -107.332675) (xy 445.722775 -107.341195)
			(xy 445.77342 -107.356881) (xy 445.821403 -107.37943) (xy 445.865801 -107.408409) (xy 445.886078 -107.42549)
			(xy 445.89319 -107.431586) (xy 445.909954 -107.437936) (xy 445.968628 -107.437936) (xy 445.968628 -107.42549)
			(xy 446.010284 -107.42549) (xy 446.026032 -107.419902) (xy 446.03289 -107.414568) (xy 446.053214 -107.398913)
			(xy 446.097261 -107.372612) (xy 446.144438 -107.352458) (xy 446.193892 -107.338815) (xy 446.244729 -107.33193)
			(xy 446.27038 -107.33151) (xy 446.297635 -107.331936) (xy 446.351591 -107.339691) (xy 446.403894 -107.355046)
			(xy 446.453479 -107.377688) (xy 446.499336 -107.407157) (xy 446.540534 -107.442852) (xy 446.576231 -107.484047)
			(xy 446.605702 -107.529904) (xy 446.628347 -107.579488) (xy 446.643705 -107.63179) (xy 446.651463 -107.685745)
			(xy 446.651463 -107.709056) (xy 447.952531 -107.709056) (xy 447.952531 -107.654544) (xy 447.960289 -107.600588)
			(xy 447.975647 -107.548285) (xy 447.998293 -107.4987) (xy 448.027765 -107.452843) (xy 448.063463 -107.411647)
			(xy 448.104661 -107.375951) (xy 448.15052 -107.346482) (xy 448.200106 -107.323839) (xy 448.25241 -107.308484)
			(xy 448.306366 -107.300729) (xy 448.333622 -107.300268) (xy 448.359936 -107.300731) (xy 448.412064 -107.307968)
			(xy 448.462707 -107.322289) (xy 448.510905 -107.343422) (xy 448.555749 -107.370969) (xy 448.596389 -107.404407)
			(xy 448.614546 -107.423458) (xy 448.622107 -107.430912) (xy 448.641533 -107.439431) (xy 448.652138 -107.439968)
			(xy 448.726306 -107.439968) (xy 448.736939 -107.439563) (xy 448.756403 -107.431011) (xy 448.763898 -107.423458)
			(xy 448.782053 -107.404402) (xy 448.822684 -107.370947) (xy 448.867525 -107.343389) (xy 448.915725 -107.322251)
			(xy 448.966372 -107.307933) (xy 449.018506 -107.300707) (xy 449.044822 -107.300268) (xy 449.072193 -107.300705)
			(xy 449.126375 -107.308527) (xy 449.178879 -107.324022) (xy 449.228625 -107.346871) (xy 449.27459 -107.376603)
			(xy 449.29552 -107.394248) (xy 449.302632 -107.400344) (xy 449.319396 -107.406694) (xy 449.37807 -107.406694)
			(xy 449.37807 -107.394248) (xy 449.419726 -107.394248) (xy 449.435474 -107.38866) (xy 449.442332 -107.383326)
			(xy 449.46337 -107.367193) (xy 449.509014 -107.340228) (xy 449.557954 -107.319846) (xy 449.609245 -107.306441)
			(xy 449.661898 -107.30027) (xy 449.714899 -107.301453) (xy 449.767225 -107.309967) (xy 449.817867 -107.325648)
			(xy 449.865849 -107.348193) (xy 449.910244 -107.377169) (xy 449.93052 -107.394248) (xy 449.937632 -107.400344)
			(xy 449.954396 -107.406694) (xy 450.01307 -107.406694) (xy 450.01307 -107.394248) (xy 450.054726 -107.394248)
			(xy 450.070474 -107.38866) (xy 450.077332 -107.383326) (xy 450.097637 -107.367646) (xy 450.14169 -107.34135)
			(xy 450.188871 -107.321201) (xy 450.238329 -107.307564) (xy 450.28917 -107.300684) (xy 450.314822 -107.300268)
			(xy 450.34207 -107.300804) (xy 450.396012 -107.308562) (xy 450.448301 -107.323918) (xy 450.497872 -107.346559)
			(xy 450.543717 -107.376024) (xy 450.584902 -107.411714) (xy 450.620589 -107.452901) (xy 450.650051 -107.498747)
			(xy 450.672689 -107.54832) (xy 450.688042 -107.600609) (xy 450.695798 -107.654551) (xy 450.695798 -107.709048)
			(xy 450.688042 -107.762991) (xy 450.672689 -107.81528) (xy 450.650051 -107.864853) (xy 450.620589 -107.910699)
			(xy 450.584902 -107.951886) (xy 450.543717 -107.987576) (xy 450.497872 -108.017041) (xy 450.448301 -108.039682)
			(xy 450.396012 -108.055038) (xy 450.34207 -108.062796) (xy 450.314822 -108.063284) (xy 450.287452 -108.062809)
			(xy 450.233273 -108.054994) (xy 450.18077 -108.039507) (xy 450.131023 -108.016667) (xy 450.085056 -107.986944)
			(xy 450.064124 -107.969304) (xy 450.057012 -107.963208) (xy 450.040248 -107.956858) (xy 449.954396 -107.956858)
			(xy 449.937632 -107.963208) (xy 449.93052 -107.969304) (xy 449.909587 -107.986945) (xy 449.863619 -108.016669)
			(xy 449.813873 -108.039515) (xy 449.761371 -108.055011) (xy 449.707193 -108.06284) (xy 449.652451 -108.06284)
			(xy 449.598273 -108.055011) (xy 449.545771 -108.039515) (xy 449.496025 -108.016669) (xy 449.450057 -107.986945)
			(xy 449.429124 -107.969304) (xy 449.422012 -107.963208) (xy 449.405248 -107.956858) (xy 449.346574 -107.956858)
			(xy 449.346574 -107.969304) (xy 449.304918 -107.969304) (xy 449.28917 -107.974892) (xy 449.282312 -107.980226)
			(xy 449.261986 -107.995879) (xy 449.21794 -108.022181) (xy 449.170764 -108.042335) (xy 449.12131 -108.055979)
			(xy 449.070473 -108.062864) (xy 449.044822 -108.063284) (xy 449.018508 -108.062807) (xy 448.96638 -108.055575)
			(xy 448.915737 -108.041258) (xy 448.867538 -108.020127) (xy 448.822694 -107.992583) (xy 448.782055 -107.959145)
			(xy 448.763898 -107.940094) (xy 448.756327 -107.932652) (xy 448.736908 -107.924128) (xy 448.726306 -107.923584)
			(xy 448.652138 -107.923584) (xy 448.641504 -107.923973) (xy 448.62204 -107.932537) (xy 448.614546 -107.940094)
			(xy 448.596409 -107.959168) (xy 448.555775 -107.992623) (xy 448.510931 -108.02018) (xy 448.462727 -108.041315)
			(xy 448.412076 -108.055629) (xy 448.359939 -108.062848) (xy 448.333622 -108.063284) (xy 448.306366 -108.062871)
			(xy 448.25241 -108.055116) (xy 448.200106 -108.039761) (xy 448.15052 -108.017118) (xy 448.104661 -107.987649)
			(xy 448.063463 -107.951953) (xy 448.027765 -107.910757) (xy 447.998293 -107.8649) (xy 447.975647 -107.815315)
			(xy 447.960289 -107.763012) (xy 447.952531 -107.709056) (xy 446.651463 -107.709056) (xy 446.651463 -107.740255)
			(xy 446.643705 -107.79421) (xy 446.628347 -107.846512) (xy 446.605702 -107.896096) (xy 446.576231 -107.941953)
			(xy 446.540534 -107.983148) (xy 446.499336 -108.018843) (xy 446.453479 -108.048312) (xy 446.403894 -108.070954)
			(xy 446.351591 -108.086309) (xy 446.297635 -108.094064) (xy 446.27038 -108.094526) (xy 446.243008 -108.09409)
			(xy 446.188827 -108.086267) (xy 446.136323 -108.070772) (xy 446.086577 -108.047924) (xy 446.040612 -108.018191)
			(xy 446.019682 -108.000546) (xy 446.01257 -107.99445) (xy 445.995806 -107.9881) (xy 445.909954 -107.9881)
			(xy 445.89319 -107.99445) (xy 445.886078 -108.000546) (xy 445.865145 -108.018187) (xy 445.819177 -108.047911)
			(xy 445.769431 -108.070757) (xy 445.716929 -108.086253) (xy 445.662751 -108.094082) (xy 445.608009 -108.094082)
			(xy 445.553831 -108.086253) (xy 445.501329 -108.070757) (xy 445.451583 -108.047911) (xy 445.405615 -108.018187)
			(xy 445.384682 -108.000546) (xy 445.37757 -107.99445) (xy 445.360806 -107.9881) (xy 445.302132 -107.9881)
			(xy 445.302132 -108.000546) (xy 445.260476 -108.000546) (xy 445.244728 -108.006134) (xy 445.23787 -108.011468)
			(xy 445.216831 -108.027599) (xy 445.171187 -108.054565) (xy 445.122248 -108.074947) (xy 445.070957 -108.088353)
			(xy 445.018303 -108.094524) (xy 444.965302 -108.093341) (xy 444.912976 -108.084827) (xy 444.862334 -108.069146)
			(xy 444.814353 -108.046601) (xy 444.769958 -108.017626) (xy 444.749682 -108.000546) (xy 444.74257 -107.99445)
			(xy 444.725806 -107.9881) (xy 444.667132 -107.9881) (xy 444.667132 -108.000546) (xy 444.625476 -108.000546)
			(xy 444.609728 -108.006134) (xy 444.60287 -108.011468) (xy 444.582563 -108.027146) (xy 444.538512 -108.053443)
			(xy 444.49133 -108.073592) (xy 444.441872 -108.08723) (xy 444.391032 -108.09411) (xy 444.36538 -108.094526)
			(xy 444.338131 -108.094002) (xy 444.284188 -108.086244) (xy 444.231898 -108.070888) (xy 444.182326 -108.048247)
			(xy 444.13648 -108.018781) (xy 444.095294 -107.983091) (xy 444.059607 -107.941904) (xy 444.030144 -107.896056)
			(xy 444.007505 -107.846483) (xy 443.992152 -107.794192) (xy 443.984396 -107.740249) (xy 439.525393 -107.740249)
			(xy 439.525393 -107.747343) (xy 439.51677 -107.804171) (xy 439.49972 -107.859062) (xy 439.474629 -107.910774)
			(xy 439.442064 -107.958137) (xy 439.422794 -107.979464) (xy 439.415936 -107.986576) (xy 439.409078 -108.004356)
			(xy 439.409078 -108.093256) (xy 439.415936 -108.111036) (xy 439.422794 -108.118148) (xy 439.442056 -108.139483)
			(xy 439.474626 -108.186842) (xy 439.499721 -108.238551) (xy 439.516773 -108.293441) (xy 439.525397 -108.350267)
			(xy 439.525918 -108.379006) (xy 439.525687 -108.39196) (xy 452.52767 -108.39196) (xy 452.528154 -108.36459)
			(xy 452.535965 -108.310411) (xy 452.551449 -108.257908) (xy 452.574287 -108.20816) (xy 452.604009 -108.162193)
			(xy 452.62165 -108.141262) (xy 452.627746 -108.13415) (xy 452.634096 -108.117386) (xy 452.634096 -108.058712)
			(xy 452.62165 -108.058712) (xy 452.62165 -108.017056) (xy 452.616062 -108.001308) (xy 452.610728 -107.99445)
			(xy 452.595086 -107.974117) (xy 452.568783 -107.930072) (xy 452.548627 -107.882898) (xy 452.534981 -107.833446)
			(xy 452.528092 -107.78261) (xy 452.52767 -107.75696) (xy 452.528156 -107.729709) (xy 452.535912 -107.675761)
			(xy 452.551267 -107.623466) (xy 452.573909 -107.573889) (xy 452.603375 -107.528039) (xy 452.639066 -107.486848)
			(xy 452.680257 -107.451157) (xy 452.726107 -107.421691) (xy 452.775684 -107.399049) (xy 452.827979 -107.383694)
			(xy 452.881927 -107.375938) (xy 452.936429 -107.375938) (xy 452.990377 -107.383694) (xy 453.042672 -107.399049)
			(xy 453.092249 -107.421691) (xy 453.138099 -107.451157) (xy 453.17929 -107.486848) (xy 453.214981 -107.528039)
			(xy 453.244447 -107.573889) (xy 453.267089 -107.623466) (xy 453.282444 -107.675761) (xy 453.2902 -107.729709)
			(xy 453.290686 -107.75696) (xy 453.2902 -107.78433) (xy 453.282387 -107.838508) (xy 453.266903 -107.891011)
			(xy 453.244066 -107.940758) (xy 453.214345 -107.986726) (xy 453.196706 -108.007658) (xy 453.19061 -108.01477)
			(xy 453.18426 -108.031534) (xy 453.18426 -108.090208) (xy 453.196706 -108.090208) (xy 453.196706 -108.131864)
			(xy 453.202294 -108.147612) (xy 453.207628 -108.15447) (xy 453.223273 -108.174801) (xy 453.249576 -108.218846)
			(xy 453.269732 -108.266021) (xy 453.283377 -108.315474) (xy 453.290265 -108.36631) (xy 453.290686 -108.39196)
			(xy 453.2902 -108.419211) (xy 453.282444 -108.473159) (xy 453.267089 -108.525454) (xy 453.244447 -108.575031)
			(xy 453.214981 -108.620881) (xy 453.17929 -108.662072) (xy 453.138099 -108.697763) (xy 453.092249 -108.727229)
			(xy 453.042672 -108.749871) (xy 452.990377 -108.765226) (xy 452.936429 -108.772982) (xy 452.881927 -108.772982)
			(xy 452.827979 -108.765226) (xy 452.775684 -108.749871) (xy 452.726107 -108.727229) (xy 452.680257 -108.697763)
			(xy 452.639066 -108.662072) (xy 452.603375 -108.620881) (xy 452.573909 -108.575031) (xy 452.551267 -108.525454)
			(xy 452.535912 -108.473159) (xy 452.528156 -108.419211) (xy 452.52767 -108.39196) (xy 439.525687 -108.39196)
			(xy 439.525432 -108.406257) (xy 439.517676 -108.460205) (xy 439.502321 -108.5125) (xy 439.479679 -108.562077)
			(xy 439.450213 -108.607927) (xy 439.414522 -108.649118) (xy 439.373331 -108.684809) (xy 439.327481 -108.714275)
			(xy 439.277904 -108.736917) (xy 439.225609 -108.752272) (xy 439.171661 -108.760028) (xy 439.117159 -108.760028)
			(xy 439.063211 -108.752272) (xy 439.010916 -108.736917) (xy 438.961339 -108.714275) (xy 438.915489 -108.684809)
			(xy 438.874298 -108.649118) (xy 438.838607 -108.607927) (xy 438.809141 -108.562077) (xy 438.786499 -108.5125)
			(xy 438.771144 -108.460205) (xy 438.763388 -108.406257) (xy 438.762902 -108.379006) (xy 413.442844 -108.379006)
			(xy 413.442919 -108.379256) (xy 413.451039 -108.434432) (xy 413.451548 -108.462318) (xy 413.451039 -108.490204)
			(xy 413.442919 -108.54538) (xy 413.426851 -108.598787) (xy 413.403179 -108.649284) (xy 413.372406 -108.695797)
			(xy 413.335189 -108.737334) (xy 413.292321 -108.773009) (xy 413.244715 -108.802063) (xy 413.193386 -108.823875)
			(xy 413.139429 -108.837981) (xy 413.083992 -108.844081) (xy 413.028258 -108.842044) (xy 412.973415 -108.831914)
			(xy 412.920631 -108.813907) (xy 412.871031 -108.788406) (xy 412.825673 -108.755955) (xy 412.785524 -108.717246)
			(xy 412.751438 -108.673103) (xy 412.724142 -108.624468) (xy 412.704219 -108.572377) (xy 412.692093 -108.51794)
			(xy 412.688022 -108.462318) (xy 403.615144 -108.462318) (xy 403.615144 -109.481366) (xy 412.60979 -109.481366)
			(xy 412.613861 -109.425744) (xy 412.625987 -109.371307) (xy 412.64591 -109.319216) (xy 412.673206 -109.270581)
			(xy 412.707292 -109.226438) (xy 412.747441 -109.187729) (xy 412.792799 -109.155278) (xy 412.842399 -109.129777)
			(xy 412.895183 -109.11177) (xy 412.950026 -109.10164) (xy 413.00576 -109.099603) (xy 413.061197 -109.105703)
			(xy 413.115154 -109.119809) (xy 413.166483 -109.141621) (xy 413.214089 -109.170675) (xy 413.256957 -109.20635)
			(xy 413.294174 -109.247887) (xy 413.324947 -109.2944) (xy 413.348619 -109.344897) (xy 413.364687 -109.398304)
			(xy 413.372807 -109.45348) (xy 413.373316 -109.481366) (xy 413.372807 -109.509252) (xy 413.364687 -109.564428)
			(xy 413.348619 -109.617835) (xy 413.324947 -109.668332) (xy 413.294174 -109.714845) (xy 413.256957 -109.756382)
			(xy 413.214089 -109.792057) (xy 413.166483 -109.821111) (xy 413.115154 -109.842923) (xy 413.061197 -109.857029)
			(xy 413.00576 -109.863129) (xy 412.950026 -109.861092) (xy 412.895183 -109.850962) (xy 412.842399 -109.832955)
			(xy 412.792799 -109.807454) (xy 412.747441 -109.775003) (xy 412.707292 -109.736294) (xy 412.673206 -109.692151)
			(xy 412.64591 -109.643516) (xy 412.625987 -109.591425) (xy 412.613861 -109.536988) (xy 412.60979 -109.481366)
			(xy 403.615144 -109.481366) (xy 403.615144 -111.993172) (xy 403.615582 -112.003235) (xy 403.623319 -112.021817)
			(xy 403.63013 -112.02924) (xy 407.490422 -115.889532) (xy 407.497834 -115.896216) (xy 407.516267 -115.903813)
			(xy 407.536205 -115.903813) (xy 407.554638 -115.896216) (xy 407.56205 -115.889532) (xy 412.531814 -110.919768)
			(xy 412.54299 -110.908846) (xy 412.543752 -110.908338) (xy 412.54426 -110.90783) (xy 412.552388 -110.899956)
			(xy 412.560516 -110.87862) (xy 412.55823 -110.848902) (xy 412.557044 -110.84008) (xy 412.549514 -110.823966)
			(xy 412.543498 -110.817406) (xy 412.536386 -110.810294) (xy 412.533084 -110.808008) (xy 412.512217 -110.792597)
			(xy 412.474446 -110.757039) (xy 412.441843 -110.716689) (xy 412.415008 -110.672294) (xy 412.394438 -110.624672)
			(xy 412.380512 -110.574701) (xy 412.373486 -110.523304) (xy 412.373064 -110.497366) (xy 412.37355 -110.470115)
			(xy 412.381306 -110.416167) (xy 412.396661 -110.363872) (xy 412.419303 -110.314295) (xy 412.448769 -110.268445)
			(xy 412.48446 -110.227254) (xy 412.525651 -110.191563) (xy 412.571501 -110.162097) (xy 412.621078 -110.139455)
			(xy 412.673373 -110.1241) (xy 412.727321 -110.116344) (xy 412.781823 -110.116344) (xy 412.835771 -110.1241)
			(xy 412.888066 -110.139455) (xy 412.937643 -110.162097) (xy 412.983493 -110.191563) (xy 413.024684 -110.227254)
			(xy 413.060375 -110.268445) (xy 413.089841 -110.314295) (xy 413.112483 -110.363872) (xy 413.127838 -110.416167)
			(xy 413.135594 -110.470115) (xy 413.13608 -110.497366) (xy 413.135567 -110.525323) (xy 413.127371 -110.580634)
			(xy 413.111207 -110.634162) (xy 413.099758 -110.659672) (xy 413.095186 -110.669324) (xy 413.094678 -110.690152)
			(xy 413.121094 -110.756446) (xy 413.12545 -110.766182) (xy 413.14071 -110.781055) (xy 413.150558 -110.785148)
			(xy 413.183709 -110.798056) (xy 413.246878 -110.830784) (xy 413.305618 -110.870922) (xy 413.359063 -110.91788)
			(xy 413.406426 -110.970966) (xy 413.447011 -111.029398) (xy 413.480218 -111.092316) (xy 413.505561 -111.158793)
			(xy 413.522664 -111.22785) (xy 413.531276 -111.29847) (xy 413.531812 -111.334042) (xy 413.531812 -111.334296)
			(xy 413.531352 -111.36715) (xy 413.523996 -111.432444) (xy 413.509376 -111.496505) (xy 413.487676 -111.558525)
			(xy 413.459169 -111.617727) (xy 413.424212 -111.673364) (xy 413.383247 -111.724739) (xy 413.360362 -111.748316)
			(xy 413.323768 -111.784892) (xy 415.468562 -111.784892) (xy 415.469008 -111.757521) (xy 415.476829 -111.70334)
			(xy 415.492321 -111.650836) (xy 415.515168 -111.60109) (xy 415.544898 -111.555124) (xy 415.562542 -111.534194)
			(xy 415.568638 -111.527082) (xy 415.574988 -111.510318) (xy 415.574988 -111.451644) (xy 415.562542 -111.451644)
			(xy 415.562542 -111.409988) (xy 415.556954 -111.39424) (xy 415.55162 -111.387382) (xy 415.535502 -111.366334)
			(xy 415.508536 -111.320691) (xy 415.488154 -111.271754) (xy 415.474747 -111.220464) (xy 415.468575 -111.167812)
			(xy 415.469757 -111.114812) (xy 415.478269 -111.062487) (xy 415.493948 -111.011846) (xy 415.516491 -110.963865)
			(xy 415.545464 -110.91947) (xy 415.562542 -110.899194) (xy 415.568638 -110.892082) (xy 415.574988 -110.875318)
			(xy 415.574988 -110.816644) (xy 415.562542 -110.816644) (xy 415.562542 -110.774988) (xy 415.556954 -110.75924)
			(xy 415.55162 -110.752382) (xy 415.535502 -110.731334) (xy 415.508536 -110.685691) (xy 415.488154 -110.636754)
			(xy 415.474747 -110.585464) (xy 415.468575 -110.532812) (xy 415.469757 -110.479812) (xy 415.478269 -110.427487)
			(xy 415.493948 -110.376846) (xy 415.516491 -110.328865) (xy 415.545464 -110.28447) (xy 415.562542 -110.264194)
			(xy 415.568638 -110.257082) (xy 415.574988 -110.240318) (xy 415.574988 -110.181644) (xy 415.562542 -110.181644)
			(xy 415.562542 -110.139988) (xy 415.556954 -110.12424) (xy 415.55162 -110.117382) (xy 415.535502 -110.096334)
			(xy 415.508536 -110.050691) (xy 415.488154 -110.001754) (xy 415.474747 -109.950464) (xy 415.468575 -109.897812)
			(xy 415.469757 -109.844812) (xy 415.478269 -109.792487) (xy 415.493948 -109.741846) (xy 415.516491 -109.693865)
			(xy 415.545464 -109.64947) (xy 415.562542 -109.629194) (xy 415.568638 -109.622082) (xy 415.574988 -109.605318)
			(xy 415.574988 -109.546644) (xy 415.562542 -109.546644) (xy 415.562542 -109.504988) (xy 415.556954 -109.48924)
			(xy 415.55162 -109.482382) (xy 415.535945 -109.462073) (xy 415.509649 -109.418021) (xy 415.489499 -109.370841)
			(xy 415.47586 -109.321383) (xy 415.468979 -109.270544) (xy 415.468562 -109.244892) (xy 415.469048 -109.217641)
			(xy 415.476804 -109.163693) (xy 415.492159 -109.111398) (xy 415.514801 -109.061821) (xy 415.544267 -109.015971)
			(xy 415.579958 -108.97478) (xy 415.621149 -108.939089) (xy 415.666999 -108.909623) (xy 415.716576 -108.886981)
			(xy 415.768871 -108.871626) (xy 415.822819 -108.86387) (xy 415.877321 -108.86387) (xy 415.931269 -108.871626)
			(xy 415.983564 -108.886981) (xy 416.033141 -108.909623) (xy 416.078991 -108.939089) (xy 416.120182 -108.97478)
			(xy 416.155873 -109.015971) (xy 416.185339 -109.061821) (xy 416.207981 -109.111398) (xy 416.223336 -109.163693)
			(xy 416.231092 -109.217641) (xy 416.231578 -109.244892) (xy 416.231113 -109.272262) (xy 416.223295 -109.326442)
			(xy 416.207806 -109.378945) (xy 416.192151 -109.41304) (xy 420.129462 -109.41304) (xy 420.129948 -109.385789)
			(xy 420.137704 -109.331841) (xy 420.153059 -109.279546) (xy 420.175701 -109.229969) (xy 420.205167 -109.184119)
			(xy 420.240858 -109.142928) (xy 420.282049 -109.107237) (xy 420.327899 -109.077771) (xy 420.377476 -109.055129)
			(xy 420.429771 -109.039774) (xy 420.483719 -109.032018) (xy 420.538221 -109.032018) (xy 420.592169 -109.039774)
			(xy 420.644464 -109.055129) (xy 420.694041 -109.077771) (xy 420.739891 -109.107237) (xy 420.781082 -109.142928)
			(xy 420.816773 -109.184119) (xy 420.846239 -109.229969) (xy 420.868881 -109.279546) (xy 420.884236 -109.331841)
			(xy 420.891992 -109.385789) (xy 420.892478 -109.41304) (xy 420.892057 -109.439235) (xy 420.884888 -109.491133)
			(xy 420.87069 -109.541564) (xy 420.84973 -109.589579) (xy 420.822401 -109.634277) (xy 420.789218 -109.674819)
			(xy 420.770304 -109.692948) (xy 420.762176 -109.700314) (xy 420.754048 -109.719618) (xy 420.754556 -109.816392)
			(xy 420.763192 -109.83595) (xy 420.77132 -109.843062) (xy 420.790878 -109.861206) (xy 420.825207 -109.902044)
			(xy 420.853508 -109.947268) (xy 420.875229 -109.995995) (xy 420.889946 -110.047275) (xy 420.897372 -110.100105)
			(xy 420.897812 -110.12678) (xy 420.897326 -110.154031) (xy 420.88957 -110.207979) (xy 420.874215 -110.260274)
			(xy 420.851573 -110.309851) (xy 420.822107 -110.355701) (xy 420.786416 -110.396892) (xy 420.745225 -110.432583)
			(xy 420.699375 -110.462049) (xy 420.649798 -110.484691) (xy 420.597503 -110.500046) (xy 420.543555 -110.507802)
			(xy 420.489053 -110.507802) (xy 420.435105 -110.500046) (xy 420.38281 -110.484691) (xy 420.333233 -110.462049)
			(xy 420.287383 -110.432583) (xy 420.246192 -110.396892) (xy 420.210501 -110.355701) (xy 420.181035 -110.309851)
			(xy 420.158393 -110.260274) (xy 420.143038 -110.207979) (xy 420.135282 -110.154031) (xy 420.134796 -110.12678)
			(xy 420.135239 -110.100585) (xy 420.142405 -110.048689) (xy 420.156599 -109.998259) (xy 420.177555 -109.950244)
			(xy 420.204879 -109.905545) (xy 420.238059 -109.865002) (xy 420.25697 -109.846872) (xy 420.265098 -109.839506)
			(xy 420.273226 -109.820202) (xy 420.272718 -109.723428) (xy 420.264082 -109.70387) (xy 420.255954 -109.696758)
			(xy 420.2364 -109.678609) (xy 420.202072 -109.637772) (xy 420.173771 -109.592549) (xy 420.152049 -109.543822)
			(xy 420.137331 -109.492544) (xy 420.129904 -109.439715) (xy 420.129462 -109.41304) (xy 416.192151 -109.41304)
			(xy 416.184964 -109.428692) (xy 416.15524 -109.474658) (xy 416.137598 -109.49559) (xy 416.131502 -109.502702)
			(xy 416.125152 -109.519466) (xy 416.125152 -109.57814) (xy 416.137598 -109.57814) (xy 416.137598 -109.619796)
			(xy 416.143186 -109.635544) (xy 416.14852 -109.642402) (xy 416.164719 -109.663391) (xy 416.191677 -109.709044)
			(xy 416.212052 -109.757992) (xy 416.22545 -109.809291) (xy 416.231613 -109.861951) (xy 416.230423 -109.914957)
			(xy 416.221901 -109.967287) (xy 416.206214 -110.017932) (xy 416.183662 -110.065915) (xy 416.15468 -110.110313)
			(xy 416.137598 -110.13059) (xy 416.131502 -110.137702) (xy 416.125152 -110.154466) (xy 416.125152 -110.21314)
			(xy 416.137598 -110.21314) (xy 416.137598 -110.254796) (xy 416.143186 -110.270544) (xy 416.14852 -110.277402)
			(xy 416.164719 -110.298391) (xy 416.191677 -110.344044) (xy 416.212052 -110.392992) (xy 416.22545 -110.444291)
			(xy 416.231613 -110.496951) (xy 416.230868 -110.530132) (xy 418.729158 -110.530132) (xy 418.733229 -110.47451)
			(xy 418.745355 -110.420073) (xy 418.765278 -110.367982) (xy 418.792574 -110.319347) (xy 418.82666 -110.275204)
			(xy 418.866809 -110.236495) (xy 418.912167 -110.204044) (xy 418.961767 -110.178543) (xy 419.014551 -110.160536)
			(xy 419.069394 -110.150406) (xy 419.125128 -110.148369) (xy 419.180565 -110.154469) (xy 419.234522 -110.168575)
			(xy 419.285851 -110.190387) (xy 419.333457 -110.219441) (xy 419.376325 -110.255116) (xy 419.413542 -110.296653)
			(xy 419.444315 -110.343166) (xy 419.467987 -110.393663) (xy 419.484055 -110.44707) (xy 419.492175 -110.502246)
			(xy 419.492684 -110.530132) (xy 419.492175 -110.558018) (xy 419.484055 -110.613194) (xy 419.467987 -110.666601)
			(xy 419.444315 -110.717098) (xy 419.413542 -110.763611) (xy 419.376325 -110.805148) (xy 419.333457 -110.840823)
			(xy 419.285851 -110.869877) (xy 419.234522 -110.891689) (xy 419.180565 -110.905795) (xy 419.125128 -110.911895)
			(xy 419.069394 -110.909858) (xy 419.014551 -110.899728) (xy 418.961767 -110.881721) (xy 418.912167 -110.85622)
			(xy 418.866809 -110.823769) (xy 418.82666 -110.78506) (xy 418.792574 -110.740917) (xy 418.765278 -110.692282)
			(xy 418.745355 -110.640191) (xy 418.733229 -110.585754) (xy 418.729158 -110.530132) (xy 416.230868 -110.530132)
			(xy 416.230423 -110.549957) (xy 416.221901 -110.602287) (xy 416.206214 -110.652932) (xy 416.183662 -110.700915)
			(xy 416.15468 -110.745313) (xy 416.137598 -110.76559) (xy 416.131502 -110.772702) (xy 416.125152 -110.789466)
			(xy 416.125152 -110.84814) (xy 416.137598 -110.84814) (xy 416.137598 -110.889796) (xy 416.143186 -110.905544)
			(xy 416.14852 -110.912402) (xy 416.164719 -110.933391) (xy 416.191677 -110.979044) (xy 416.20718 -111.016288)
			(xy 420.08806 -111.016288) (xy 420.088546 -110.989037) (xy 420.096302 -110.935089) (xy 420.111657 -110.882794)
			(xy 420.134299 -110.833217) (xy 420.163765 -110.787367) (xy 420.199456 -110.746176) (xy 420.240647 -110.710485)
			(xy 420.286497 -110.681019) (xy 420.336074 -110.658377) (xy 420.388369 -110.643022) (xy 420.442317 -110.635266)
			(xy 420.496819 -110.635266) (xy 420.550767 -110.643022) (xy 420.603062 -110.658377) (xy 420.652639 -110.681019)
			(xy 420.698489 -110.710485) (xy 420.73968 -110.746176) (xy 420.775371 -110.787367) (xy 420.804837 -110.833217)
			(xy 420.827479 -110.882794) (xy 420.842834 -110.935089) (xy 420.85059 -110.989037) (xy 420.851076 -111.016288)
			(xy 420.850612 -111.043308) (xy 420.842999 -111.09681) (xy 420.82791 -111.148701) (xy 420.805647 -111.197942)
			(xy 420.776656 -111.243548) (xy 420.741517 -111.284604) (xy 420.721536 -111.3028) (xy 420.714771 -111.309271)
			(xy 420.70605 -111.325822) (xy 420.704518 -111.335058) (xy 420.704264 -111.341916) (xy 420.705788 -111.430054)
			(xy 420.715186 -111.45012) (xy 420.723822 -111.457232) (xy 420.74495 -111.475468) (xy 420.782229 -111.517001)
			(xy 420.813056 -111.563525) (xy 420.836771 -111.614046) (xy 420.852868 -111.667484) (xy 420.861004 -111.722697)
			(xy 420.86149 -111.750602) (xy 420.860869 -111.780394) (xy 420.851619 -111.839255) (xy 420.833329 -111.895962)
			(xy 420.806445 -111.949136) (xy 420.783689 -111.980726) (xy 422.201594 -111.980726) (xy 422.202135 -111.951988)
			(xy 422.210754 -111.895161) (xy 422.2278 -111.840271) (xy 422.252887 -111.788559) (xy 422.285449 -111.741195)
			(xy 422.304718 -111.719868) (xy 422.311576 -111.712756) (xy 422.318434 -111.694976) (xy 422.318434 -111.606076)
			(xy 422.311576 -111.588296) (xy 422.304718 -111.581184) (xy 422.285473 -111.559835) (xy 422.252908 -111.512476)
			(xy 422.227815 -111.460768) (xy 422.210763 -111.405881) (xy 422.202139 -111.349056) (xy 422.202136 -111.291581)
			(xy 422.210755 -111.234756) (xy 422.227801 -111.179868) (xy 422.252889 -111.128157) (xy 422.285449 -111.080795)
			(xy 422.304718 -111.059468) (xy 422.311576 -111.052356) (xy 422.318434 -111.034576) (xy 422.318434 -110.945676)
			(xy 422.311576 -110.927896) (xy 422.304718 -110.920784) (xy 422.285473 -110.899435) (xy 422.252908 -110.852076)
			(xy 422.227815 -110.800368) (xy 422.210763 -110.745481) (xy 422.202139 -110.688656) (xy 422.202136 -110.631181)
			(xy 422.210755 -110.574356) (xy 422.227801 -110.519468) (xy 422.252889 -110.467757) (xy 422.285449 -110.420395)
			(xy 422.304718 -110.399068) (xy 422.311576 -110.391956) (xy 422.318434 -110.374176) (xy 422.318434 -110.285276)
			(xy 422.311576 -110.267496) (xy 422.304718 -110.260384) (xy 422.285473 -110.239035) (xy 422.252908 -110.191676)
			(xy 422.227815 -110.139968) (xy 422.210763 -110.085081) (xy 422.202139 -110.028256) (xy 422.202136 -109.970781)
			(xy 422.210755 -109.913956) (xy 422.227801 -109.859068) (xy 422.252889 -109.807357) (xy 422.285449 -109.759995)
			(xy 422.304718 -109.738668) (xy 422.311576 -109.731556) (xy 422.318434 -109.713776) (xy 422.318434 -109.624876)
			(xy 422.311576 -109.607096) (xy 422.304718 -109.599984) (xy 422.285456 -109.578649) (xy 422.252889 -109.531289)
			(xy 422.227796 -109.479579) (xy 422.210743 -109.42469) (xy 422.202117 -109.367864) (xy 422.201594 -109.339126)
			(xy 422.20208 -109.311874) (xy 422.209833 -109.257923) (xy 422.225186 -109.205626) (xy 422.247825 -109.156046)
			(xy 422.277291 -109.110192) (xy 422.312982 -109.068999) (xy 422.354173 -109.033305) (xy 422.400025 -109.003837)
			(xy 422.449603 -108.981194) (xy 422.5019 -108.965838) (xy 422.55585 -108.958081) (xy 422.583102 -108.957618)
			(xy 422.609416 -108.958078) (xy 422.661545 -108.965314) (xy 422.712188 -108.979634) (xy 422.760388 -109.000768)
			(xy 422.805231 -109.028315) (xy 422.84587 -109.061756) (xy 422.864026 -109.080808) (xy 422.871588 -109.08826)
			(xy 422.891013 -109.096779) (xy 422.901618 -109.097318) (xy 422.975786 -109.097318) (xy 422.986415 -109.096887)
			(xy 423.00588 -109.088352) (xy 423.013378 -109.080808) (xy 423.031553 -109.061772) (xy 423.072178 -109.028312)
			(xy 423.117014 -109.000751) (xy 423.165211 -108.979609) (xy 423.215856 -108.965288) (xy 423.267987 -108.958059)
			(xy 423.294302 -108.957618) (xy 423.321556 -108.958054) (xy 423.375509 -108.965811) (xy 423.427809 -108.981169)
			(xy 423.477391 -109.003814) (xy 423.523246 -109.033284) (xy 423.564439 -109.068981) (xy 423.600132 -109.110177)
			(xy 423.6296 -109.156033) (xy 423.652241 -109.205617) (xy 423.667594 -109.257918) (xy 423.675348 -109.311872)
			(xy 423.67581 -109.339126) (xy 423.675299 -109.367865) (xy 423.666673 -109.424693) (xy 423.64962 -109.479584)
			(xy 423.624526 -109.531295) (xy 423.591958 -109.578657) (xy 423.572686 -109.599984) (xy 423.565828 -109.607096)
			(xy 423.55897 -109.624876) (xy 423.55897 -109.713776) (xy 423.565828 -109.731556) (xy 423.572686 -109.738668)
			(xy 423.591982 -109.759973) (xy 423.624546 -109.807339) (xy 423.649635 -109.859055) (xy 423.666683 -109.913949)
			(xy 423.675303 -109.970779) (xy 423.6753 -110.028259) (xy 423.666674 -110.085088) (xy 423.649621 -110.139981)
			(xy 423.624527 -110.191694) (xy 423.591958 -110.239057) (xy 423.572686 -110.260384) (xy 423.565828 -110.267496)
			(xy 423.55897 -110.285276) (xy 423.55897 -110.374176) (xy 423.565828 -110.391956) (xy 423.572686 -110.399068)
			(xy 423.591982 -110.420373) (xy 423.624546 -110.467739) (xy 423.649635 -110.519455) (xy 423.666683 -110.574349)
			(xy 423.673846 -110.621572) (xy 438.8612 -110.621572) (xy 438.861649 -110.595257) (xy 438.868887 -110.543128)
			(xy 438.88321 -110.492485) (xy 438.904346 -110.444286) (xy 438.931895 -110.399443) (xy 438.965337 -110.358804)
			(xy 438.98439 -110.340648) (xy 438.991852 -110.333093) (xy 439.000365 -110.313663) (xy 439.0009 -110.303056)
			(xy 439.0009 -110.228888) (xy 439.000489 -110.218256) (xy 438.991941 -110.198792) (xy 438.98439 -110.191296)
			(xy 438.965338 -110.173137) (xy 438.931881 -110.132508) (xy 438.904321 -110.087668) (xy 438.883182 -110.039468)
			(xy 438.868864 -109.988821) (xy 438.861639 -109.936688) (xy 438.8612 -109.910372) (xy 438.861686 -109.883121)
			(xy 438.869442 -109.829173) (xy 438.884797 -109.776878) (xy 438.907439 -109.727301) (xy 438.936905 -109.681451)
			(xy 438.972596 -109.64026) (xy 439.013787 -109.604569) (xy 439.059637 -109.575103) (xy 439.109214 -109.552461)
			(xy 439.161509 -109.537106) (xy 439.215457 -109.52935) (xy 439.269959 -109.52935) (xy 439.323907 -109.537106)
			(xy 439.376202 -109.552461) (xy 439.425779 -109.575103) (xy 439.471629 -109.604569) (xy 439.51282 -109.64026)
			(xy 439.548511 -109.681451) (xy 439.577977 -109.727301) (xy 439.600619 -109.776878) (xy 439.615974 -109.829173)
			(xy 439.62373 -109.883121) (xy 439.624216 -109.910372) (xy 439.623791 -109.936687) (xy 439.616547 -109.988818)
			(xy 439.602219 -110.039461) (xy 439.581079 -110.08766) (xy 439.553525 -110.132502) (xy 439.52008 -110.17314)
			(xy 439.501026 -110.191296) (xy 439.493592 -110.198874) (xy 439.485062 -110.218287) (xy 439.484516 -110.228888)
			(xy 439.484516 -110.303056) (xy 439.484898 -110.313691) (xy 439.493466 -110.333156) (xy 439.501026 -110.340648)
			(xy 439.520103 -110.358782) (xy 439.553557 -110.399417) (xy 439.581113 -110.444262) (xy 439.602247 -110.492467)
			(xy 439.61656 -110.543118) (xy 439.62378 -110.595255) (xy 439.624216 -110.621572) (xy 439.62373 -110.648823)
			(xy 439.615974 -110.702771) (xy 439.600619 -110.755066) (xy 439.577977 -110.804643) (xy 439.548511 -110.850493)
			(xy 439.51282 -110.891684) (xy 439.471629 -110.927375) (xy 439.425779 -110.956841) (xy 439.376202 -110.979483)
			(xy 439.323907 -110.994838) (xy 439.269959 -111.002594) (xy 439.215457 -111.002594) (xy 439.161509 -110.994838)
			(xy 439.109214 -110.979483) (xy 439.059637 -110.956841) (xy 439.013787 -110.927375) (xy 438.972596 -110.891684)
			(xy 438.936905 -110.850493) (xy 438.907439 -110.804643) (xy 438.884797 -110.755066) (xy 438.869442 -110.702771)
			(xy 438.861686 -110.648823) (xy 438.8612 -110.621572) (xy 423.673846 -110.621572) (xy 423.675303 -110.631179)
			(xy 423.6753 -110.688659) (xy 423.666674 -110.745488) (xy 423.649621 -110.800381) (xy 423.624527 -110.852094)
			(xy 423.591958 -110.899457) (xy 423.572686 -110.920784) (xy 423.565828 -110.927896) (xy 423.55897 -110.945676)
			(xy 423.55897 -111.034576) (xy 423.565828 -111.052356) (xy 423.572686 -111.059468) (xy 423.591982 -111.080773)
			(xy 423.624546 -111.128139) (xy 423.649635 -111.179855) (xy 423.666683 -111.234749) (xy 423.675303 -111.291579)
			(xy 423.6753 -111.349059) (xy 423.666674 -111.405888) (xy 423.649621 -111.460781) (xy 423.624527 -111.512494)
			(xy 423.591958 -111.559857) (xy 423.572686 -111.581184) (xy 423.565828 -111.588296) (xy 423.55897 -111.606076)
			(xy 423.55897 -111.694976) (xy 423.565828 -111.712756) (xy 423.572686 -111.719868) (xy 423.591973 -111.741181)
			(xy 423.624536 -111.788547) (xy 423.649625 -111.840262) (xy 423.666672 -111.895156) (xy 423.675291 -111.951986)
			(xy 423.67581 -111.980726) (xy 423.675346 -112.007978) (xy 423.667586 -112.061926) (xy 423.652228 -112.114221)
			(xy 423.629584 -112.163798) (xy 423.600115 -112.209649) (xy 423.564421 -112.250838) (xy 423.523229 -112.28653)
			(xy 423.477377 -112.315996) (xy 423.427799 -112.338636) (xy 423.375503 -112.353991) (xy 423.321554 -112.361748)
			(xy 423.294302 -112.362234) (xy 423.267989 -112.361754) (xy 423.215861 -112.35452) (xy 423.165219 -112.340203)
			(xy 423.11702 -112.319073) (xy 423.072176 -112.291529) (xy 423.031536 -112.258094) (xy 423.013378 -112.239044)
			(xy 423.005808 -112.231601) (xy 422.986389 -112.223075) (xy 422.975786 -112.222534) (xy 422.901618 -112.222534)
			(xy 422.890987 -112.222952) (xy 422.871522 -112.231494) (xy 422.864026 -112.239044) (xy 422.845859 -112.258088)
			(xy 422.805231 -112.291545) (xy 422.760393 -112.319104) (xy 422.712194 -112.340244) (xy 422.661549 -112.354564)
			(xy 422.609417 -112.361793) (xy 422.583102 -112.362234) (xy 422.555852 -112.36172) (xy 422.501907 -112.353965)
			(xy 422.449614 -112.338611) (xy 422.400038 -112.315972) (xy 422.354189 -112.286509) (xy 422.313 -112.25082)
			(xy 422.277308 -112.209633) (xy 422.247841 -112.163786) (xy 422.225198 -112.114212) (xy 422.209841 -112.061921)
			(xy 422.202082 -112.007976) (xy 422.201594 -111.980726) (xy 420.783689 -111.980726) (xy 420.771619 -111.997482)
			(xy 420.729699 -112.039825) (xy 420.706042 -112.057942) (xy 420.695374 -112.065816) (xy 420.684452 -112.089692)
			(xy 420.693088 -112.20196) (xy 420.707566 -112.223804) (xy 420.71925 -112.2299) (xy 420.742035 -112.242309)
			(xy 420.784282 -112.27243) (xy 420.822057 -112.307997) (xy 420.854664 -112.348356) (xy 420.881501 -112.39276)
			(xy 420.884443 -112.399572) (xy 438.8612 -112.399572) (xy 438.861649 -112.373257) (xy 438.868887 -112.321128)
			(xy 438.88321 -112.270485) (xy 438.904346 -112.222286) (xy 438.931895 -112.177443) (xy 438.965337 -112.136804)
			(xy 438.98439 -112.118648) (xy 438.991852 -112.111093) (xy 439.000365 -112.091663) (xy 439.0009 -112.081056)
			(xy 439.0009 -112.006888) (xy 439.000489 -111.996256) (xy 438.991941 -111.976792) (xy 438.98439 -111.969296)
			(xy 438.965338 -111.951137) (xy 438.931881 -111.910508) (xy 438.904321 -111.865668) (xy 438.883182 -111.817468)
			(xy 438.868864 -111.766821) (xy 438.861639 -111.714688) (xy 438.8612 -111.688372) (xy 438.861686 -111.661121)
			(xy 438.869442 -111.607173) (xy 438.884797 -111.554878) (xy 438.907439 -111.505301) (xy 438.936905 -111.459451)
			(xy 438.972596 -111.41826) (xy 439.013787 -111.382569) (xy 439.059637 -111.353103) (xy 439.109214 -111.330461)
			(xy 439.161509 -111.315106) (xy 439.215457 -111.30735) (xy 439.269959 -111.30735) (xy 439.323907 -111.315106)
			(xy 439.376202 -111.330461) (xy 439.425779 -111.353103) (xy 439.471629 -111.382569) (xy 439.51282 -111.41826)
			(xy 439.548511 -111.459451) (xy 439.577977 -111.505301) (xy 439.600619 -111.554878) (xy 439.615974 -111.607173)
			(xy 439.62373 -111.661121) (xy 439.624216 -111.688372) (xy 439.623791 -111.714687) (xy 439.616547 -111.766818)
			(xy 439.602219 -111.817461) (xy 439.581079 -111.86566) (xy 439.553525 -111.910502) (xy 439.52008 -111.95114)
			(xy 439.501026 -111.969296) (xy 439.493592 -111.976874) (xy 439.485062 -111.996287) (xy 439.484516 -112.006888)
			(xy 439.484516 -112.081056) (xy 439.484898 -112.091691) (xy 439.493466 -112.111156) (xy 439.501026 -112.118648)
			(xy 439.520103 -112.136782) (xy 439.553557 -112.177417) (xy 439.581113 -112.222262) (xy 439.602247 -112.270467)
			(xy 439.610019 -112.297972) (xy 441.369958 -112.297972) (xy 441.370388 -112.271657) (xy 441.377628 -112.219526)
			(xy 441.391953 -112.168882) (xy 441.413093 -112.120682) (xy 441.440646 -112.07584) (xy 441.474093 -112.035203)
			(xy 441.493148 -112.017048) (xy 441.500603 -112.009488) (xy 441.509122 -111.990061) (xy 441.509658 -111.979456)
			(xy 441.509658 -111.905288) (xy 441.509229 -111.894659) (xy 441.500692 -111.875195) (xy 441.493148 -111.867696)
			(xy 441.474088 -111.849546) (xy 441.440633 -111.808914) (xy 441.413076 -111.764072) (xy 441.391939 -111.71587)
			(xy 441.377622 -111.665222) (xy 441.370397 -111.613088) (xy 441.369958 -111.586772) (xy 441.370444 -111.559521)
			(xy 441.3782 -111.505573) (xy 441.393555 -111.453278) (xy 441.416197 -111.403701) (xy 441.445663 -111.357851)
			(xy 441.481354 -111.31666) (xy 441.522545 -111.280969) (xy 441.568395 -111.251503) (xy 441.617972 -111.228861)
			(xy 441.670267 -111.213506) (xy 441.724215 -111.20575) (xy 441.778717 -111.20575) (xy 441.832665 -111.213506)
			(xy 441.88496 -111.228861) (xy 441.934537 -111.251503) (xy 441.980387 -111.280969) (xy 442.021578 -111.31666)
			(xy 442.057269 -111.357851) (xy 442.086735 -111.403701) (xy 442.109377 -111.453278) (xy 442.124732 -111.505573)
			(xy 442.132488 -111.559521) (xy 442.132974 -111.586772) (xy 442.132563 -111.613088) (xy 442.125318 -111.665219)
			(xy 442.110988 -111.715863) (xy 442.089845 -111.764062) (xy 442.062289 -111.808904) (xy 442.02884 -111.849541)
			(xy 442.009784 -111.867696) (xy 442.002343 -111.875268) (xy 441.993818 -111.894686) (xy 441.993274 -111.905288)
			(xy 441.993274 -111.979456) (xy 441.993669 -111.990089) (xy 442.002229 -112.009553) (xy 442.009784 -112.017048)
			(xy 442.028853 -112.03519) (xy 442.062309 -112.075823) (xy 442.089867 -112.120665) (xy 442.111003 -112.168869)
			(xy 442.125317 -112.219519) (xy 442.132538 -112.271655) (xy 442.132974 -112.297972) (xy 443.401958 -112.297972)
			(xy 443.402388 -112.271657) (xy 443.409628 -112.219526) (xy 443.423953 -112.168882) (xy 443.445093 -112.120682)
			(xy 443.472646 -112.07584) (xy 443.506093 -112.035203) (xy 443.525148 -112.017048) (xy 443.532603 -112.009488)
			(xy 443.541122 -111.990061) (xy 443.541658 -111.979456) (xy 443.541658 -111.905288) (xy 443.541229 -111.894659)
			(xy 443.532692 -111.875195) (xy 443.525148 -111.867696) (xy 443.506088 -111.849546) (xy 443.472633 -111.808914)
			(xy 443.445076 -111.764072) (xy 443.423939 -111.71587) (xy 443.409622 -111.665222) (xy 443.402397 -111.613088)
			(xy 443.401958 -111.586772) (xy 443.402444 -111.559521) (xy 443.4102 -111.505573) (xy 443.425555 -111.453278)
			(xy 443.448197 -111.403701) (xy 443.477663 -111.357851) (xy 443.513354 -111.31666) (xy 443.554545 -111.280969)
			(xy 443.600395 -111.251503) (xy 443.649972 -111.228861) (xy 443.702267 -111.213506) (xy 443.756215 -111.20575)
			(xy 443.810717 -111.20575) (xy 443.864665 -111.213506) (xy 443.91696 -111.228861) (xy 443.966537 -111.251503)
			(xy 444.012387 -111.280969) (xy 444.053578 -111.31666) (xy 444.089269 -111.357851) (xy 444.118735 -111.403701)
			(xy 444.141377 -111.453278) (xy 444.156732 -111.505573) (xy 444.164488 -111.559521) (xy 444.164974 -111.586772)
			(xy 444.164563 -111.613088) (xy 444.157318 -111.665219) (xy 444.142988 -111.715863) (xy 444.121845 -111.764062)
			(xy 444.094289 -111.808904) (xy 444.06084 -111.849541) (xy 444.041784 -111.867696) (xy 444.034343 -111.875268)
			(xy 444.025818 -111.894686) (xy 444.025274 -111.905288) (xy 444.025274 -111.979456) (xy 444.025669 -111.990089)
			(xy 444.034229 -112.009553) (xy 444.041784 -112.017048) (xy 444.060853 -112.03519) (xy 444.06285 -112.037615)
			(xy 445.856202 -112.037615) (xy 445.860515 -111.980345) (xy 445.87336 -111.924368) (xy 445.894448 -111.870948)
			(xy 445.923303 -111.821291) (xy 445.959273 -111.776519) (xy 445.980058 -111.756698) (xy 445.987493 -111.74912)
			(xy 445.996023 -111.729707) (xy 445.996568 -111.719106) (xy 445.996568 -111.644938) (xy 445.996194 -111.634302)
			(xy 445.987621 -111.614837) (xy 445.980058 -111.607346) (xy 445.960975 -111.589218) (xy 445.927522 -111.548581)
			(xy 445.899968 -111.503735) (xy 445.878834 -111.455529) (xy 445.864523 -111.404877) (xy 445.857304 -111.35274)
			(xy 445.856868 -111.326422) (xy 445.857354 -111.299171) (xy 445.86511 -111.245223) (xy 445.880465 -111.192928)
			(xy 445.903107 -111.143351) (xy 445.932573 -111.097501) (xy 445.968264 -111.05631) (xy 446.009455 -111.020619)
			(xy 446.055305 -110.991153) (xy 446.104882 -110.968511) (xy 446.157177 -110.953156) (xy 446.211125 -110.9454)
			(xy 446.265627 -110.9454) (xy 446.319575 -110.953156) (xy 446.37187 -110.968511) (xy 446.421447 -110.991153)
			(xy 446.467297 -111.020619) (xy 446.508488 -111.05631) (xy 446.544179 -111.097501) (xy 446.573645 -111.143351)
			(xy 446.596287 -111.192928) (xy 446.611642 -111.245223) (xy 446.619398 -111.299171) (xy 446.619884 -111.326422)
			(xy 446.619436 -111.352737) (xy 446.612198 -111.404866) (xy 446.597876 -111.45551) (xy 446.576739 -111.503709)
			(xy 446.54919 -111.548552) (xy 446.515747 -111.58919) (xy 446.496694 -111.607346) (xy 446.489233 -111.614901)
			(xy 446.48072 -111.634332) (xy 446.480184 -111.644938) (xy 446.480184 -111.719106) (xy 446.480603 -111.729737)
			(xy 446.489146 -111.749201) (xy 446.496694 -111.756698) (xy 446.517505 -111.776495) (xy 446.553482 -111.82127)
			(xy 446.582343 -111.870931) (xy 446.603436 -111.924356) (xy 446.616284 -111.980339) (xy 446.620598 -112.037615)
			(xy 448.394417 -112.037615) (xy 448.39873 -111.980345) (xy 448.411576 -111.924367) (xy 448.432666 -111.870947)
			(xy 448.461522 -111.82129) (xy 448.497494 -111.776518) (xy 448.51828 -111.756698) (xy 448.525718 -111.749123)
			(xy 448.534246 -111.729708) (xy 448.53479 -111.719106) (xy 448.53479 -111.644938) (xy 448.534409 -111.634303)
			(xy 448.52584 -111.614838) (xy 448.51828 -111.607346) (xy 448.499201 -111.589214) (xy 448.465747 -111.548578)
			(xy 448.438192 -111.503733) (xy 448.417057 -111.455528) (xy 448.402745 -111.404877) (xy 448.395526 -111.352739)
			(xy 448.39509 -111.326422) (xy 448.395576 -111.299171) (xy 448.403332 -111.245223) (xy 448.418687 -111.192928)
			(xy 448.441329 -111.143351) (xy 448.470795 -111.097501) (xy 448.506486 -111.05631) (xy 448.547677 -111.020619)
			(xy 448.593527 -110.991153) (xy 448.643104 -110.968511) (xy 448.695399 -110.953156) (xy 448.749347 -110.9454)
			(xy 448.803849 -110.9454) (xy 448.857797 -110.953156) (xy 448.910092 -110.968511) (xy 448.959669 -110.991153)
			(xy 449.005519 -111.020619) (xy 449.04671 -111.05631) (xy 449.082401 -111.097501) (xy 449.111867 -111.143351)
			(xy 449.134509 -111.192928) (xy 449.149864 -111.245223) (xy 449.15762 -111.299171) (xy 449.158106 -111.326422)
			(xy 449.157651 -111.352736) (xy 449.150414 -111.404865) (xy 449.136092 -111.455508) (xy 449.114957 -111.503707)
			(xy 449.087409 -111.54855) (xy 449.053968 -111.58919) (xy 449.034916 -111.607346) (xy 449.027458 -111.614904)
			(xy 449.018942 -111.634332) (xy 449.018406 -111.644938) (xy 449.018406 -111.719106) (xy 449.018819 -111.729738)
			(xy 449.027365 -111.749202) (xy 449.034916 -111.756698) (xy 449.055726 -111.776496) (xy 449.091701 -111.821271)
			(xy 449.12056 -111.870932) (xy 449.141652 -111.924357) (xy 449.154499 -111.98034) (xy 449.155522 -111.993923)
			(xy 452.597351 -111.993923) (xy 452.601664 -111.936653) (xy 452.61451 -111.880675) (xy 452.6356 -111.827255)
			(xy 452.664458 -111.777599) (xy 452.700431 -111.732829) (xy 452.721218 -111.71301) (xy 452.728656 -111.705436)
			(xy 452.737183 -111.68602) (xy 452.737728 -111.675418) (xy 452.737728 -111.60125) (xy 452.737329 -111.590617)
			(xy 452.728772 -111.571153) (xy 452.721218 -111.563658) (xy 452.700462 -111.543805) (xy 452.664484 -111.499039)
			(xy 452.63562 -111.449386) (xy 452.614523 -111.395969) (xy 452.60167 -111.339993) (xy 452.597351 -111.282723)
			(xy 452.601664 -111.225453) (xy 452.61451 -111.169475) (xy 452.6356 -111.116055) (xy 452.664458 -111.066399)
			(xy 452.700431 -111.021629) (xy 452.721218 -111.00181) (xy 452.728656 -110.994236) (xy 452.737183 -110.97482)
			(xy 452.737728 -110.964218) (xy 452.737728 -110.89005) (xy 452.737329 -110.879417) (xy 452.728772 -110.859953)
			(xy 452.721218 -110.852458) (xy 452.702153 -110.834312) (xy 452.668696 -110.793681) (xy 452.641137 -110.748839)
			(xy 452.620001 -110.700636) (xy 452.605686 -110.649986) (xy 452.598464 -110.597851) (xy 452.598028 -110.571534)
			(xy 452.598487 -110.54428) (xy 452.60624 -110.490327) (xy 452.621594 -110.438027) (xy 452.644235 -110.388445)
			(xy 452.673703 -110.34259) (xy 452.709397 -110.301396) (xy 452.750591 -110.265702) (xy 452.796447 -110.236234)
			(xy 452.846029 -110.213593) (xy 452.898329 -110.19824) (xy 452.952282 -110.190487) (xy 452.979536 -110.190026)
			(xy 453.005851 -110.190461) (xy 453.057981 -110.197701) (xy 453.108625 -110.212026) (xy 453.156824 -110.233165)
			(xy 453.201667 -110.260717) (xy 453.242305 -110.294162) (xy 453.26046 -110.313216) (xy 453.268045 -110.320641)
			(xy 453.287453 -110.329175) (xy 453.298052 -110.329726) (xy 453.37222 -110.329726) (xy 453.382851 -110.329312)
			(xy 453.402315 -110.320765) (xy 453.409812 -110.313216) (xy 453.427972 -110.294165) (xy 453.4686 -110.260707)
			(xy 453.51344 -110.233147) (xy 453.56164 -110.212007) (xy 453.612286 -110.197689) (xy 453.66442 -110.190464)
			(xy 453.690736 -110.190026) (xy 453.71799 -110.190444) (xy 453.771942 -110.198207) (xy 453.82424 -110.213568)
			(xy 453.873819 -110.236216) (xy 453.919671 -110.265689) (xy 453.960862 -110.301388) (xy 453.996553 -110.342585)
			(xy 454.026018 -110.388442) (xy 454.048656 -110.438026) (xy 454.064008 -110.490327) (xy 454.071761 -110.54428)
			(xy 454.072244 -110.571534) (xy 454.071817 -110.59785) (xy 454.064577 -110.649981) (xy 454.050251 -110.700625)
			(xy 454.029111 -110.748824) (xy 454.001557 -110.793666) (xy 453.96811 -110.834303) (xy 453.949054 -110.852458)
			(xy 453.941641 -110.860054) (xy 453.933098 -110.879453) (xy 453.932544 -110.89005) (xy 453.932544 -110.964218)
			(xy 453.932969 -110.974848) (xy 453.941509 -110.994311) (xy 453.949054 -111.00181) (xy 453.969874 -111.021597)
			(xy 454.005846 -111.066375) (xy 454.034702 -111.116038) (xy 454.05579 -111.169465) (xy 454.068636 -111.225447)
			(xy 454.072947 -111.282723) (xy 454.068629 -111.339998) (xy 454.055777 -111.395979) (xy 454.034681 -111.449403)
			(xy 454.00582 -111.499063) (xy 453.969843 -111.543837) (xy 453.949054 -111.563658) (xy 453.941641 -111.571254)
			(xy 453.933098 -111.590653) (xy 453.932544 -111.60125) (xy 453.932544 -111.675418) (xy 453.932969 -111.686048)
			(xy 453.941509 -111.705511) (xy 453.949054 -111.71301) (xy 453.969874 -111.732797) (xy 454.005846 -111.777575)
			(xy 454.034702 -111.827238) (xy 454.05579 -111.880665) (xy 454.068636 -111.936647) (xy 454.072947 -111.993923)
			(xy 454.068629 -112.051198) (xy 454.055777 -112.107179) (xy 454.034681 -112.160603) (xy 454.00582 -112.210263)
			(xy 453.969843 -112.255037) (xy 453.949054 -112.274858) (xy 453.941641 -112.282454) (xy 453.933098 -112.301853)
			(xy 453.932544 -112.31245) (xy 453.932544 -112.386618) (xy 453.932969 -112.397248) (xy 453.941509 -112.416711)
			(xy 453.949054 -112.42421) (xy 453.968118 -112.442357) (xy 454.001572 -112.48299) (xy 454.029129 -112.527832)
			(xy 454.050265 -112.576034) (xy 454.064581 -112.626683) (xy 454.071806 -112.678818) (xy 454.072244 -112.705134)
			(xy 454.071754 -112.732384) (xy 454.063994 -112.78633) (xy 454.048636 -112.838623) (xy 454.025994 -112.888198)
			(xy 453.996527 -112.934046) (xy 453.960836 -112.975235) (xy 453.919648 -113.010926) (xy 453.873799 -113.040393)
			(xy 453.824224 -113.063035) (xy 453.771932 -113.078393) (xy 453.717986 -113.086154) (xy 453.690736 -113.086642)
			(xy 453.66442 -113.086236) (xy 453.612288 -113.078991) (xy 453.561643 -113.064661) (xy 453.513444 -113.043517)
			(xy 453.468602 -113.01596) (xy 453.427966 -112.982509) (xy 453.409812 -112.963452) (xy 453.402228 -112.956025)
			(xy 453.38282 -112.94749) (xy 453.37222 -112.946942) (xy 453.298052 -112.946942) (xy 453.28742 -112.947351)
			(xy 453.267957 -112.955902) (xy 453.26046 -112.963452) (xy 453.242327 -112.98253) (xy 453.201691 -113.015983)
			(xy 453.156846 -113.043538) (xy 453.108641 -113.064672) (xy 453.05799 -113.078985) (xy 453.005853 -113.086206)
			(xy 452.979536 -113.086642) (xy 452.952286 -113.086111) (xy 452.898339 -113.07836) (xy 452.846044 -113.06301)
			(xy 452.796467 -113.040375) (xy 452.750615 -113.010913) (xy 452.709423 -112.975227) (xy 452.673729 -112.934041)
			(xy 452.644259 -112.888195) (xy 452.621614 -112.838621) (xy 452.606255 -112.78633) (xy 452.598494 -112.732384)
			(xy 452.598028 -112.705134) (xy 452.598442 -112.678818) (xy 452.605687 -112.626687) (xy 452.620016 -112.576043)
			(xy 452.641158 -112.527844) (xy 452.668714 -112.483002) (xy 452.702162 -112.442365) (xy 452.721218 -112.42421)
			(xy 452.728656 -112.416636) (xy 452.737183 -112.39722) (xy 452.737728 -112.386618) (xy 452.737728 -112.31245)
			(xy 452.737329 -112.301817) (xy 452.728772 -112.282353) (xy 452.721218 -112.274858) (xy 452.700462 -112.255005)
			(xy 452.664484 -112.210239) (xy 452.63562 -112.160586) (xy 452.614523 -112.107169) (xy 452.60167 -112.051193)
			(xy 452.597351 -111.993923) (xy 449.155522 -111.993923) (xy 449.158813 -112.037615) (xy 449.154495 -112.09489)
			(xy 449.141643 -112.150871) (xy 449.120547 -112.204294) (xy 449.091684 -112.253953) (xy 449.055706 -112.298726)
			(xy 449.034916 -112.318546) (xy 449.027458 -112.326104) (xy 449.018942 -112.345532) (xy 449.018406 -112.356138)
			(xy 449.018406 -112.430306) (xy 449.018819 -112.440938) (xy 449.027365 -112.460402) (xy 449.034916 -112.467898)
			(xy 449.053967 -112.486058) (xy 449.087424 -112.526687) (xy 449.114983 -112.571527) (xy 449.136122 -112.619727)
			(xy 449.15044 -112.670373) (xy 449.157667 -112.722506) (xy 449.158106 -112.748822) (xy 449.15762 -112.776073)
			(xy 449.149864 -112.830021) (xy 449.134509 -112.882316) (xy 449.111867 -112.931893) (xy 449.082401 -112.977743)
			(xy 449.04671 -113.018934) (xy 449.005519 -113.054625) (xy 448.959669 -113.084091) (xy 448.910092 -113.106733)
			(xy 448.857797 -113.122088) (xy 448.803849 -113.129844) (xy 448.749347 -113.129844) (xy 448.695399 -113.122088)
			(xy 448.643104 -113.106733) (xy 448.593527 -113.084091) (xy 448.547677 -113.054625) (xy 448.506486 -113.018934)
			(xy 448.470795 -112.977743) (xy 448.441329 -112.931893) (xy 448.418687 -112.882316) (xy 448.403332 -112.830021)
			(xy 448.395576 -112.776073) (xy 448.39509 -112.748822) (xy 448.395575 -112.722509) (xy 448.402807 -112.670381)
			(xy 448.417123 -112.619739) (xy 448.438252 -112.57154) (xy 448.465795 -112.526696) (xy 448.49923 -112.486055)
			(xy 448.51828 -112.467898) (xy 448.525718 -112.460323) (xy 448.534246 -112.440908) (xy 448.53479 -112.430306)
			(xy 448.53479 -112.356138) (xy 448.534409 -112.345503) (xy 448.52584 -112.326038) (xy 448.51828 -112.318546)
			(xy 448.497514 -112.298704) (xy 448.461539 -112.253935) (xy 448.432679 -112.20428) (xy 448.411585 -112.150861)
			(xy 448.398734 -112.094885) (xy 448.394417 -112.037615) (xy 446.620598 -112.037615) (xy 446.61628 -112.094891)
			(xy 446.603427 -112.150872) (xy 446.58233 -112.204296) (xy 446.553465 -112.253954) (xy 446.517485 -112.298727)
			(xy 446.496694 -112.318546) (xy 446.489233 -112.326101) (xy 446.48072 -112.345532) (xy 446.480184 -112.356138)
			(xy 446.480184 -112.430306) (xy 446.480603 -112.440937) (xy 446.489146 -112.460401) (xy 446.496694 -112.467898)
			(xy 446.51574 -112.486063) (xy 446.549199 -112.52669) (xy 446.576759 -112.571529) (xy 446.597899 -112.619728)
			(xy 446.612218 -112.670374) (xy 446.619445 -112.722506) (xy 446.619884 -112.748822) (xy 446.619398 -112.776073)
			(xy 446.611642 -112.830021) (xy 446.596287 -112.882316) (xy 446.573645 -112.931893) (xy 446.544179 -112.977743)
			(xy 446.508488 -113.018934) (xy 446.467297 -113.054625) (xy 446.421447 -113.084091) (xy 446.37187 -113.106733)
			(xy 446.319575 -113.122088) (xy 446.265627 -113.129844) (xy 446.211125 -113.129844) (xy 446.157177 -113.122088)
			(xy 446.104882 -113.106733) (xy 446.055305 -113.084091) (xy 446.009455 -113.054625) (xy 445.968264 -113.018934)
			(xy 445.932573 -112.977743) (xy 445.903107 -112.931893) (xy 445.880465 -112.882316) (xy 445.86511 -112.830021)
			(xy 445.857354 -112.776073) (xy 445.856868 -112.748822) (xy 445.85736 -112.722509) (xy 445.864592 -112.670382)
			(xy 445.878906 -112.61974) (xy 445.900034 -112.571541) (xy 445.927575 -112.526697) (xy 445.961009 -112.486056)
			(xy 445.980058 -112.467898) (xy 445.987493 -112.46032) (xy 445.996023 -112.440907) (xy 445.996568 -112.430306)
			(xy 445.996568 -112.356138) (xy 445.996194 -112.345502) (xy 445.987621 -112.326037) (xy 445.980058 -112.318546)
			(xy 445.959293 -112.298703) (xy 445.92332 -112.253933) (xy 445.894462 -112.204279) (xy 445.873369 -112.15086)
			(xy 445.860519 -112.094884) (xy 445.856202 -112.037615) (xy 444.06285 -112.037615) (xy 444.094309 -112.075823)
			(xy 444.121867 -112.120665) (xy 444.143003 -112.168869) (xy 444.157317 -112.219519) (xy 444.164538 -112.271655)
			(xy 444.164974 -112.297972) (xy 444.164488 -112.325223) (xy 444.156732 -112.379171) (xy 444.141377 -112.431466)
			(xy 444.118735 -112.481043) (xy 444.089269 -112.526893) (xy 444.053578 -112.568084) (xy 444.012387 -112.603775)
			(xy 443.966537 -112.633241) (xy 443.91696 -112.655883) (xy 443.864665 -112.671238) (xy 443.810717 -112.678994)
			(xy 443.756215 -112.678994) (xy 443.702267 -112.671238) (xy 443.649972 -112.655883) (xy 443.600395 -112.633241)
			(xy 443.554545 -112.603775) (xy 443.513354 -112.568084) (xy 443.477663 -112.526893) (xy 443.448197 -112.481043)
			(xy 443.425555 -112.431466) (xy 443.4102 -112.379171) (xy 443.402444 -112.325223) (xy 443.401958 -112.297972)
			(xy 442.132974 -112.297972) (xy 442.132488 -112.325223) (xy 442.124732 -112.379171) (xy 442.109377 -112.431466)
			(xy 442.086735 -112.481043) (xy 442.057269 -112.526893) (xy 442.021578 -112.568084) (xy 441.980387 -112.603775)
			(xy 441.934537 -112.633241) (xy 441.88496 -112.655883) (xy 441.832665 -112.671238) (xy 441.778717 -112.678994)
			(xy 441.724215 -112.678994) (xy 441.670267 -112.671238) (xy 441.617972 -112.655883) (xy 441.568395 -112.633241)
			(xy 441.522545 -112.603775) (xy 441.481354 -112.568084) (xy 441.445663 -112.526893) (xy 441.416197 -112.481043)
			(xy 441.393555 -112.431466) (xy 441.3782 -112.379171) (xy 441.370444 -112.325223) (xy 441.369958 -112.297972)
			(xy 439.610019 -112.297972) (xy 439.61656 -112.321118) (xy 439.62378 -112.373255) (xy 439.624216 -112.399572)
			(xy 439.62373 -112.426823) (xy 439.615974 -112.480771) (xy 439.600619 -112.533066) (xy 439.577977 -112.582643)
			(xy 439.548511 -112.628493) (xy 439.51282 -112.669684) (xy 439.471629 -112.705375) (xy 439.425779 -112.734841)
			(xy 439.376202 -112.757483) (xy 439.323907 -112.772838) (xy 439.269959 -112.780594) (xy 439.215457 -112.780594)
			(xy 439.161509 -112.772838) (xy 439.109214 -112.757483) (xy 439.059637 -112.734841) (xy 439.013787 -112.705375)
			(xy 438.972596 -112.669684) (xy 438.936905 -112.628493) (xy 438.907439 -112.582643) (xy 438.884797 -112.533066)
			(xy 438.869442 -112.480771) (xy 438.861686 -112.426823) (xy 438.8612 -112.399572) (xy 420.884443 -112.399572)
			(xy 420.902075 -112.440391) (xy 420.916004 -112.490371) (xy 420.923031 -112.541778) (xy 420.923466 -112.56772)
			(xy 420.92298 -112.594971) (xy 420.915224 -112.648919) (xy 420.899869 -112.701214) (xy 420.877227 -112.750791)
			(xy 420.847761 -112.796641) (xy 420.81207 -112.837832) (xy 420.770879 -112.873523) (xy 420.725029 -112.902989)
			(xy 420.675452 -112.925631) (xy 420.623157 -112.940986) (xy 420.569209 -112.948742) (xy 420.514707 -112.948742)
			(xy 420.460759 -112.940986) (xy 420.408464 -112.925631) (xy 420.358887 -112.902989) (xy 420.313037 -112.873523)
			(xy 420.271846 -112.837832) (xy 420.236155 -112.796641) (xy 420.206689 -112.750791) (xy 420.184047 -112.701214)
			(xy 420.168692 -112.648919) (xy 420.160936 -112.594971) (xy 420.16045 -112.56772) (xy 420.160998 -112.537925)
			(xy 420.170261 -112.47906) (xy 420.188564 -112.42235) (xy 420.215462 -112.369177) (xy 420.250302 -112.320833)
			(xy 420.292235 -112.278494) (xy 420.315898 -112.26038) (xy 420.326566 -112.252506) (xy 420.337488 -112.22863)
			(xy 420.328852 -112.116362) (xy 420.314374 -112.094518) (xy 420.30269 -112.088422) (xy 420.279923 -112.07598)
			(xy 420.237676 -112.045865) (xy 420.199899 -112.010303) (xy 420.167289 -111.96995) (xy 420.140449 -111.92555)
			(xy 420.119873 -111.877923) (xy 420.105941 -111.827946) (xy 420.09891 -111.776543) (xy 420.098474 -111.750602)
			(xy 420.098914 -111.723581) (xy 420.10653 -111.670077) (xy 420.121622 -111.618185) (xy 420.14389 -111.568943)
			(xy 420.172886 -111.523338) (xy 420.20803 -111.482284) (xy 420.228014 -111.46409) (xy 420.234775 -111.457615)
			(xy 420.243499 -111.441068) (xy 420.245032 -111.431832) (xy 420.245286 -111.424974) (xy 420.243762 -111.336836)
			(xy 420.234364 -111.31677) (xy 420.225728 -111.309658) (xy 420.204585 -111.291438) (xy 420.167309 -111.2499)
			(xy 420.136486 -111.203373) (xy 420.112774 -111.152849) (xy 420.096679 -111.099409) (xy 420.088546 -111.044194)
			(xy 420.08806 -111.016288) (xy 416.20718 -111.016288) (xy 416.212052 -111.027992) (xy 416.22545 -111.079291)
			(xy 416.231613 -111.131951) (xy 416.230423 -111.184957) (xy 416.221901 -111.237287) (xy 416.206214 -111.287932)
			(xy 416.183662 -111.335915) (xy 416.15468 -111.380313) (xy 416.137598 -111.40059) (xy 416.131502 -111.407702)
			(xy 416.125152 -111.424466) (xy 416.125152 -111.48314) (xy 416.137598 -111.48314) (xy 416.137598 -111.524796)
			(xy 416.143186 -111.540544) (xy 416.14852 -111.547402) (xy 416.164178 -111.567723) (xy 416.190479 -111.611771)
			(xy 416.210633 -111.658948) (xy 416.224275 -111.708403) (xy 416.231159 -111.759241) (xy 416.231578 -111.784892)
			(xy 416.231092 -111.812143) (xy 416.223336 -111.866091) (xy 416.218017 -111.884206) (xy 418.664388 -111.884206)
			(xy 418.668459 -111.828584) (xy 418.680585 -111.774147) (xy 418.700508 -111.722056) (xy 418.727804 -111.673421)
			(xy 418.76189 -111.629278) (xy 418.802039 -111.590569) (xy 418.847397 -111.558118) (xy 418.896997 -111.532617)
			(xy 418.949781 -111.51461) (xy 419.004624 -111.50448) (xy 419.060358 -111.502443) (xy 419.115795 -111.508543)
			(xy 419.169752 -111.522649) (xy 419.221081 -111.544461) (xy 419.268687 -111.573515) (xy 419.311555 -111.60919)
			(xy 419.348772 -111.650727) (xy 419.379545 -111.69724) (xy 419.403217 -111.747737) (xy 419.419285 -111.801144)
			(xy 419.427405 -111.85632) (xy 419.427914 -111.884206) (xy 419.427405 -111.912092) (xy 419.419285 -111.967268)
			(xy 419.403217 -112.020675) (xy 419.379545 -112.071172) (xy 419.348772 -112.117685) (xy 419.311555 -112.159222)
			(xy 419.268687 -112.194897) (xy 419.221081 -112.223951) (xy 419.169752 -112.245763) (xy 419.115795 -112.259869)
			(xy 419.060358 -112.265969) (xy 419.004624 -112.263932) (xy 418.949781 -112.253802) (xy 418.896997 -112.235795)
			(xy 418.847397 -112.210294) (xy 418.802039 -112.177843) (xy 418.76189 -112.139134) (xy 418.727804 -112.094991)
			(xy 418.700508 -112.046356) (xy 418.680585 -111.994265) (xy 418.668459 -111.939828) (xy 418.664388 -111.884206)
			(xy 416.218017 -111.884206) (xy 416.207981 -111.918386) (xy 416.185339 -111.967963) (xy 416.155873 -112.013813)
			(xy 416.120182 -112.055004) (xy 416.078991 -112.090695) (xy 416.033141 -112.120161) (xy 415.983564 -112.142803)
			(xy 415.931269 -112.158158) (xy 415.877321 -112.165914) (xy 415.822819 -112.165914) (xy 415.768871 -112.158158)
			(xy 415.716576 -112.142803) (xy 415.666999 -112.120161) (xy 415.621149 -112.090695) (xy 415.579958 -112.055004)
			(xy 415.544267 -112.013813) (xy 415.514801 -111.967963) (xy 415.492159 -111.918386) (xy 415.476804 -111.866091)
			(xy 415.469048 -111.812143) (xy 415.468562 -111.784892) (xy 413.323768 -111.784892) (xy 412.83255 -112.275874)
			(xy 412.825305 -112.283808) (xy 412.817667 -112.30387) (xy 412.818901 -112.325301) (xy 412.823406 -112.335056)
			(xy 412.823406 -112.33531) (xy 412.83683 -112.362555) (xy 412.855829 -112.420239) (xy 412.86546 -112.480204)
			(xy 412.865566 -112.485424) (xy 414.951162 -112.485424) (xy 414.955233 -112.429802) (xy 414.967359 -112.375365)
			(xy 414.987282 -112.323274) (xy 415.014578 -112.274639) (xy 415.048664 -112.230496) (xy 415.088813 -112.191787)
			(xy 415.134171 -112.159336) (xy 415.183771 -112.133835) (xy 415.236555 -112.115828) (xy 415.291398 -112.105698)
			(xy 415.347132 -112.103661) (xy 415.402569 -112.109761) (xy 415.456526 -112.123867) (xy 415.507855 -112.145679)
			(xy 415.555461 -112.174733) (xy 415.598329 -112.210408) (xy 415.635546 -112.251945) (xy 415.666319 -112.298458)
			(xy 415.689991 -112.348955) (xy 415.706059 -112.402362) (xy 415.714179 -112.457538) (xy 415.714688 -112.485424)
			(xy 415.714179 -112.51331) (xy 415.706059 -112.568486) (xy 415.689991 -112.621893) (xy 415.666319 -112.67239)
			(xy 415.635546 -112.718903) (xy 415.598329 -112.76044) (xy 415.555461 -112.796115) (xy 415.507855 -112.825169)
			(xy 415.456526 -112.846981) (xy 415.402569 -112.861087) (xy 415.347132 -112.867187) (xy 415.291398 -112.86515)
			(xy 415.236555 -112.85502) (xy 415.183771 -112.837013) (xy 415.134171 -112.811512) (xy 415.088813 -112.779061)
			(xy 415.048664 -112.740352) (xy 415.014578 -112.696209) (xy 414.987282 -112.647574) (xy 414.967359 -112.595483)
			(xy 414.955233 -112.541046) (xy 414.951162 -112.485424) (xy 412.865566 -112.485424) (xy 412.866078 -112.51057)
			(xy 412.866078 -112.510824) (xy 412.865613 -112.538075) (xy 412.857853 -112.592022) (xy 412.842495 -112.644315)
			(xy 412.81985 -112.69389) (xy 412.790381 -112.739738) (xy 412.754687 -112.780925) (xy 412.713495 -112.816614)
			(xy 412.667643 -112.846076) (xy 412.618064 -112.868714) (xy 412.565769 -112.884065) (xy 412.511821 -112.891817)
			(xy 412.48457 -112.892332) (xy 412.484316 -112.892332) (xy 412.453904 -112.891764) (xy 412.393847 -112.882151)
			(xy 412.336078 -112.86312) (xy 412.308802 -112.84966) (xy 412.29407 -112.841786) (xy 412.261558 -112.846866)
			(xy 412.11882 -112.989614) (xy 418.74008 -112.989614) (xy 418.744151 -112.933992) (xy 418.756277 -112.879555)
			(xy 418.7762 -112.827464) (xy 418.803496 -112.778829) (xy 418.837582 -112.734686) (xy 418.877731 -112.695977)
			(xy 418.923089 -112.663526) (xy 418.972689 -112.638025) (xy 419.025473 -112.620018) (xy 419.080316 -112.609888)
			(xy 419.13605 -112.607851) (xy 419.191487 -112.613951) (xy 419.245444 -112.628057) (xy 419.296773 -112.649869)
			(xy 419.344379 -112.678923) (xy 419.387247 -112.714598) (xy 419.424464 -112.756135) (xy 419.455237 -112.802648)
			(xy 419.478909 -112.853145) (xy 419.494977 -112.906552) (xy 419.503097 -112.961728) (xy 419.503606 -112.989614)
			(xy 419.503097 -113.0175) (xy 419.494977 -113.072676) (xy 419.478909 -113.126083) (xy 419.455237 -113.17658)
			(xy 419.424464 -113.223093) (xy 419.390829 -113.260632) (xy 423.7388 -113.260632) (xy 423.742871 -113.20501)
			(xy 423.754997 -113.150573) (xy 423.77492 -113.098482) (xy 423.802216 -113.049847) (xy 423.836302 -113.005704)
			(xy 423.876451 -112.966995) (xy 423.921809 -112.934544) (xy 423.971409 -112.909043) (xy 424.024193 -112.891036)
			(xy 424.079036 -112.880906) (xy 424.13477 -112.878869) (xy 424.190207 -112.884969) (xy 424.244164 -112.899075)
			(xy 424.295493 -112.920887) (xy 424.343099 -112.949941) (xy 424.385967 -112.985616) (xy 424.423184 -113.027153)
			(xy 424.453957 -113.073666) (xy 424.477629 -113.124163) (xy 424.493697 -113.17757) (xy 424.501398 -113.229898)
			(xy 424.7421 -113.229898) (xy 424.746171 -113.174276) (xy 424.758297 -113.119839) (xy 424.77822 -113.067748)
			(xy 424.805516 -113.019113) (xy 424.839602 -112.97497) (xy 424.879751 -112.936261) (xy 424.925109 -112.90381)
			(xy 424.974709 -112.878309) (xy 425.027493 -112.860302) (xy 425.082336 -112.850172) (xy 425.13807 -112.848135)
			(xy 425.193507 -112.854235) (xy 425.247464 -112.868341) (xy 425.298793 -112.890153) (xy 425.346399 -112.919207)
			(xy 425.389267 -112.954882) (xy 425.426484 -112.996419) (xy 425.457257 -113.042932) (xy 425.480929 -113.093429)
			(xy 425.496997 -113.146836) (xy 425.505117 -113.202012) (xy 425.505626 -113.229898) (xy 425.505117 -113.257784)
			(xy 425.496997 -113.31296) (xy 425.480929 -113.366367) (xy 425.457257 -113.416864) (xy 425.426484 -113.463377)
			(xy 425.389267 -113.504914) (xy 425.346399 -113.540589) (xy 425.298793 -113.569643) (xy 425.247464 -113.591455)
			(xy 425.193507 -113.605561) (xy 425.13807 -113.611661) (xy 425.082336 -113.609624) (xy 425.027493 -113.599494)
			(xy 424.974709 -113.581487) (xy 424.925109 -113.555986) (xy 424.879751 -113.523535) (xy 424.839602 -113.484826)
			(xy 424.805516 -113.440683) (xy 424.77822 -113.392048) (xy 424.758297 -113.339957) (xy 424.746171 -113.28552)
			(xy 424.7421 -113.229898) (xy 424.501398 -113.229898) (xy 424.501817 -113.232746) (xy 424.502326 -113.260632)
			(xy 424.501817 -113.288518) (xy 424.493697 -113.343694) (xy 424.477629 -113.397101) (xy 424.453957 -113.447598)
			(xy 424.423184 -113.494111) (xy 424.385967 -113.535648) (xy 424.343099 -113.571323) (xy 424.295493 -113.600377)
			(xy 424.244164 -113.622189) (xy 424.190207 -113.636295) (xy 424.13477 -113.642395) (xy 424.079036 -113.640358)
			(xy 424.024193 -113.630228) (xy 423.971409 -113.612221) (xy 423.921809 -113.58672) (xy 423.876451 -113.554269)
			(xy 423.836302 -113.51556) (xy 423.802216 -113.471417) (xy 423.77492 -113.422782) (xy 423.754997 -113.370691)
			(xy 423.742871 -113.316254) (xy 423.7388 -113.260632) (xy 419.390829 -113.260632) (xy 419.387247 -113.26463)
			(xy 419.344379 -113.300305) (xy 419.296773 -113.329359) (xy 419.245444 -113.351171) (xy 419.191487 -113.365277)
			(xy 419.13605 -113.371377) (xy 419.080316 -113.36934) (xy 419.025473 -113.35921) (xy 418.972689 -113.341203)
			(xy 418.923089 -113.315702) (xy 418.877731 -113.283251) (xy 418.837582 -113.244542) (xy 418.803496 -113.200399)
			(xy 418.7762 -113.151764) (xy 418.756277 -113.099673) (xy 418.744151 -113.045236) (xy 418.74008 -112.989614)
			(xy 412.11882 -112.989614) (xy 411.673335 -113.43513) (xy 414.954972 -113.43513) (xy 414.959043 -113.379508)
			(xy 414.971169 -113.325071) (xy 414.991092 -113.27298) (xy 415.018388 -113.224345) (xy 415.052474 -113.180202)
			(xy 415.092623 -113.141493) (xy 415.137981 -113.109042) (xy 415.187581 -113.083541) (xy 415.240365 -113.065534)
			(xy 415.295208 -113.055404) (xy 415.350942 -113.053367) (xy 415.406379 -113.059467) (xy 415.460336 -113.073573)
			(xy 415.511665 -113.095385) (xy 415.559271 -113.124439) (xy 415.602139 -113.160114) (xy 415.639356 -113.201651)
			(xy 415.670129 -113.248164) (xy 415.693801 -113.298661) (xy 415.709869 -113.352068) (xy 415.717989 -113.407244)
			(xy 415.718498 -113.43513) (xy 415.717989 -113.463016) (xy 415.709869 -113.518192) (xy 415.693801 -113.571599)
			(xy 415.670129 -113.622096) (xy 415.644096 -113.661444) (xy 436.170322 -113.661444) (xy 436.174393 -113.605822)
			(xy 436.186519 -113.551385) (xy 436.206442 -113.499294) (xy 436.233738 -113.450659) (xy 436.267824 -113.406516)
			(xy 436.307973 -113.367807) (xy 436.353331 -113.335356) (xy 436.402931 -113.309855) (xy 436.455715 -113.291848)
			(xy 436.510558 -113.281718) (xy 436.566292 -113.279681) (xy 436.621729 -113.285781) (xy 436.675686 -113.299887)
			(xy 436.727015 -113.321699) (xy 436.774621 -113.350753) (xy 436.817489 -113.386428) (xy 436.854706 -113.427965)
			(xy 436.885479 -113.474478) (xy 436.909151 -113.524975) (xy 436.925219 -113.578382) (xy 436.933339 -113.633558)
			(xy 436.933848 -113.661444) (xy 436.933339 -113.68933) (xy 436.925219 -113.744506) (xy 436.909151 -113.797913)
			(xy 436.885479 -113.84841) (xy 436.854706 -113.894923) (xy 436.817489 -113.93646) (xy 436.774621 -113.972135)
			(xy 436.727015 -114.001189) (xy 436.675686 -114.023001) (xy 436.621729 -114.037107) (xy 436.566292 -114.043207)
			(xy 436.510558 -114.04117) (xy 436.455715 -114.03104) (xy 436.402931 -114.013033) (xy 436.353331 -113.987532)
			(xy 436.307973 -113.955081) (xy 436.267824 -113.916372) (xy 436.233738 -113.872229) (xy 436.206442 -113.823594)
			(xy 436.186519 -113.771503) (xy 436.174393 -113.717066) (xy 436.170322 -113.661444) (xy 415.644096 -113.661444)
			(xy 415.639356 -113.668609) (xy 415.602139 -113.710146) (xy 415.559271 -113.745821) (xy 415.511665 -113.774875)
			(xy 415.460336 -113.796687) (xy 415.406379 -113.810793) (xy 415.350942 -113.816893) (xy 415.295208 -113.814856)
			(xy 415.240365 -113.804726) (xy 415.187581 -113.786719) (xy 415.137981 -113.761218) (xy 415.092623 -113.728767)
			(xy 415.052474 -113.690058) (xy 415.018388 -113.645915) (xy 414.991092 -113.59728) (xy 414.971169 -113.545189)
			(xy 414.959043 -113.490752) (xy 414.954972 -113.43513) (xy 411.673335 -113.43513) (xy 410.84078 -114.267742)
			(xy 412.606234 -114.267742) (xy 412.610305 -114.21212) (xy 412.622431 -114.157683) (xy 412.642354 -114.105592)
			(xy 412.66965 -114.056957) (xy 412.703736 -114.012814) (xy 412.743885 -113.974105) (xy 412.789243 -113.941654)
			(xy 412.838843 -113.916153) (xy 412.891627 -113.898146) (xy 412.94647 -113.888016) (xy 413.002204 -113.885979)
			(xy 413.057641 -113.892079) (xy 413.111598 -113.906185) (xy 413.162927 -113.927997) (xy 413.210533 -113.957051)
			(xy 413.253401 -113.992726) (xy 413.290618 -114.034263) (xy 413.321391 -114.080776) (xy 413.345063 -114.131273)
			(xy 413.361131 -114.18468) (xy 413.369251 -114.239856) (xy 413.36976 -114.267742) (xy 413.369251 -114.295628)
			(xy 413.361131 -114.350804) (xy 413.345063 -114.404211) (xy 413.321391 -114.454708) (xy 413.290618 -114.501221)
			(xy 413.253401 -114.542758) (xy 413.210533 -114.578433) (xy 413.162927 -114.607487) (xy 413.111598 -114.629299)
			(xy 413.057641 -114.643405) (xy 413.002204 -114.649505) (xy 412.94647 -114.647468) (xy 412.891627 -114.637338)
			(xy 412.838843 -114.619331) (xy 412.789243 -114.59383) (xy 412.743885 -114.561379) (xy 412.703736 -114.52267)
			(xy 412.66965 -114.478527) (xy 412.642354 -114.429892) (xy 412.622431 -114.377801) (xy 412.610305 -114.323364)
			(xy 412.606234 -114.267742) (xy 410.84078 -114.267742) (xy 410.233254 -114.87531) (xy 414.257488 -114.87531)
			(xy 414.261559 -114.819688) (xy 414.273685 -114.765251) (xy 414.293608 -114.71316) (xy 414.320904 -114.664525)
			(xy 414.35499 -114.620382) (xy 414.395139 -114.581673) (xy 414.440497 -114.549222) (xy 414.490097 -114.523721)
			(xy 414.542881 -114.505714) (xy 414.597724 -114.495584) (xy 414.653458 -114.493547) (xy 414.708895 -114.499647)
			(xy 414.762852 -114.513753) (xy 414.814181 -114.535565) (xy 414.861787 -114.564619) (xy 414.904655 -114.600294)
			(xy 414.941872 -114.641831) (xy 414.972645 -114.688344) (xy 414.996317 -114.738841) (xy 415.012385 -114.792248)
			(xy 415.020505 -114.847424) (xy 415.021014 -114.87531) (xy 415.020505 -114.903196) (xy 415.012385 -114.958372)
			(xy 414.996317 -115.011779) (xy 414.972645 -115.062276) (xy 414.941872 -115.108789) (xy 414.904655 -115.150326)
			(xy 414.861787 -115.186001) (xy 414.814181 -115.215055) (xy 414.762852 -115.236867) (xy 414.708895 -115.250973)
			(xy 414.653458 -115.257073) (xy 414.597724 -115.255036) (xy 414.542881 -115.244906) (xy 414.490097 -115.226899)
			(xy 414.440497 -115.201398) (xy 414.395139 -115.168947) (xy 414.35499 -115.130238) (xy 414.320904 -115.086095)
			(xy 414.293608 -115.03746) (xy 414.273685 -114.985369) (xy 414.261559 -114.930932) (xy 414.257488 -114.87531)
			(xy 410.233254 -114.87531) (xy 409.822818 -115.285774) (xy 415.231326 -115.285774) (xy 415.231897 -115.256692)
			(xy 415.240744 -115.199204) (xy 415.258214 -115.143724) (xy 415.283901 -115.091539) (xy 415.317212 -115.043857)
			(xy 415.357373 -115.001783) (xy 415.403455 -114.966293) (xy 415.45439 -114.938207) (xy 415.508997 -114.918177)
			(xy 415.537396 -114.911886) (xy 415.548572 -114.9096) (xy 415.566606 -114.896392) (xy 415.614866 -114.808)
			(xy 415.616136 -114.785394) (xy 415.612072 -114.77498) (xy 415.603645 -114.752619) (xy 415.591787 -114.706328)
			(xy 415.585791 -114.658919) (xy 415.585402 -114.635026) (xy 415.585888 -114.607775) (xy 415.593644 -114.553827)
			(xy 415.608999 -114.501532) (xy 415.631641 -114.451955) (xy 415.661107 -114.406105) (xy 415.696798 -114.364914)
			(xy 415.737989 -114.329223) (xy 415.783839 -114.299757) (xy 415.833416 -114.277115) (xy 415.885711 -114.26176)
			(xy 415.939659 -114.254004) (xy 415.994161 -114.254004) (xy 416.048109 -114.26176) (xy 416.100404 -114.277115)
			(xy 416.128823 -114.290094) (xy 418.660324 -114.290094) (xy 418.664395 -114.234472) (xy 418.676521 -114.180035)
			(xy 418.696444 -114.127944) (xy 418.72374 -114.079309) (xy 418.757826 -114.035166) (xy 418.797975 -113.996457)
			(xy 418.843333 -113.964006) (xy 418.892933 -113.938505) (xy 418.945717 -113.920498) (xy 419.00056 -113.910368)
			(xy 419.056294 -113.908331) (xy 419.111731 -113.914431) (xy 419.165688 -113.928537) (xy 419.217017 -113.950349)
			(xy 419.264623 -113.979403) (xy 419.307491 -114.015078) (xy 419.344708 -114.056615) (xy 419.363231 -114.084613)
			(xy 437.749383 -114.084613) (xy 437.749388 -114.030111) (xy 437.75715 -113.976165) (xy 437.77251 -113.923872)
			(xy 437.795156 -113.874298) (xy 437.824627 -113.828451) (xy 437.860322 -113.787265) (xy 437.901515 -113.751579)
			(xy 437.947368 -113.722118) (xy 437.996947 -113.699482) (xy 438.049243 -113.684133) (xy 438.103191 -113.676382)
			(xy 438.130442 -113.675922) (xy 438.130696 -113.675922) (xy 438.160133 -113.676472) (xy 438.218307 -113.685537)
			(xy 438.24652 -113.693956) (xy 438.246774 -113.693956) (xy 438.258481 -113.697027) (xy 438.282343 -113.693181)
			(xy 438.292494 -113.68659) (xy 438.358534 -113.637568) (xy 438.367722 -113.629923) (xy 438.37846 -113.608607)
			(xy 438.379108 -113.596674) (xy 438.379108 -113.591086) (xy 438.379542 -113.563832) (xy 438.387301 -113.509879)
			(xy 438.40266 -113.45758) (xy 438.425305 -113.407998) (xy 438.454776 -113.362145) (xy 438.490473 -113.320952)
			(xy 438.531669 -113.285258) (xy 438.577525 -113.255791) (xy 438.627108 -113.233149) (xy 438.679409 -113.217795)
			(xy 438.733362 -113.21004) (xy 438.760616 -113.209578) (xy 438.789532 -113.210127) (xy 438.846703 -113.218846)
			(xy 438.901903 -113.236096) (xy 438.953865 -113.261481) (xy 439.0014 -113.294421) (xy 439.043416 -113.33416)
			(xy 439.061606 -113.356644) (xy 439.069213 -113.365451) (xy 439.090114 -113.375633) (xy 439.101738 -113.376202)
			(xy 439.181494 -113.376202) (xy 439.193124 -113.375645) (xy 439.214033 -113.365469) (xy 439.221626 -113.356644)
			(xy 439.239813 -113.334157) (xy 439.281833 -113.29442) (xy 439.329368 -113.26148) (xy 439.38133 -113.236092)
			(xy 439.436529 -113.218837) (xy 439.4937 -113.210111) (xy 439.522616 -113.209578) (xy 439.549867 -113.210063)
			(xy 439.603814 -113.217821) (xy 439.656108 -113.233178) (xy 439.705684 -113.25582) (xy 439.751534 -113.285286)
			(xy 439.792724 -113.320978) (xy 439.828415 -113.362168) (xy 439.857881 -113.408017) (xy 439.880523 -113.457594)
			(xy 439.895879 -113.509888) (xy 439.903637 -113.563835) (xy 439.904124 -113.591086) (xy 439.903603 -113.618461)
			(xy 439.895786 -113.672651) (xy 439.880296 -113.725164) (xy 439.857452 -113.774921) (xy 439.827723 -113.820897)
			(xy 439.791723 -113.862147) (xy 439.750191 -113.897822) (xy 439.72734 -113.912904) (xy 439.717688 -113.919)
			(xy 439.70575 -113.937796) (xy 439.692034 -114.037364) (xy 439.698638 -114.0587) (xy 439.706512 -114.067336)
			(xy 439.724546 -114.088672) (xy 439.732131 -114.097502) (xy 439.753049 -114.10767) (xy 439.764678 -114.10823)
			(xy 439.844434 -114.10823) (xy 439.85607 -114.107721) (xy 439.876981 -114.097513) (xy 439.884566 -114.088672)
			(xy 439.902769 -114.066199) (xy 439.944787 -114.026464) (xy 439.99232 -113.993525) (xy 440.044279 -113.968135)
			(xy 440.099474 -113.950876) (xy 440.156641 -113.942143) (xy 440.185556 -113.941606) (xy 440.212801 -113.942054)
			(xy 440.266735 -113.949818) (xy 440.319015 -113.965181) (xy 440.368575 -113.987829) (xy 440.414407 -114.017302)
			(xy 440.455577 -114.052998) (xy 440.491247 -114.094191) (xy 440.506358 -114.116866) (xy 440.512887 -114.125977)
			(xy 440.531885 -114.137828) (xy 440.542934 -114.139726) (xy 440.54903 -114.140234) (xy 440.634882 -114.140234)
			(xy 440.640978 -114.139726) (xy 440.652011 -114.137795) (xy 440.670982 -114.125936) (xy 440.677554 -114.116866)
			(xy 440.69264 -114.094173) (xy 440.728311 -114.052978) (xy 440.769484 -114.017282) (xy 440.815321 -113.987813)
			(xy 440.864886 -113.965171) (xy 440.917171 -113.949817) (xy 440.97111 -113.942066) (xy 440.998356 -113.941606)
			(xy 441.029091 -113.942244) (xy 441.089767 -113.952094) (xy 441.148079 -113.971547) (xy 441.202516 -114.000098)
			(xy 441.227464 -114.01806) (xy 441.237624 -114.02568) (xy 441.262008 -114.029744) (xy 441.365132 -113.995962)
			(xy 441.382404 -113.978182) (xy 441.38596 -113.966244) (xy 441.393711 -113.941881) (xy 441.414807 -113.89531)
			(xy 441.441935 -113.851975) (xy 441.474609 -113.812653) (xy 441.493148 -113.795048) (xy 441.500603 -113.787488)
			(xy 441.509122 -113.768061) (xy 441.509658 -113.757456) (xy 441.509658 -113.683288) (xy 441.509229 -113.672659)
			(xy 441.500692 -113.653195) (xy 441.493148 -113.645696) (xy 441.474088 -113.627546) (xy 441.440633 -113.586914)
			(xy 441.413076 -113.542072) (xy 441.391939 -113.49387) (xy 441.377622 -113.443222) (xy 441.370397 -113.391088)
			(xy 441.369958 -113.364772) (xy 441.370444 -113.337521) (xy 441.3782 -113.283573) (xy 441.393555 -113.231278)
			(xy 441.416197 -113.181701) (xy 441.445663 -113.135851) (xy 441.481354 -113.09466) (xy 441.522545 -113.058969)
			(xy 441.568395 -113.029503) (xy 441.617972 -113.006861) (xy 441.670267 -112.991506) (xy 441.724215 -112.98375)
			(xy 441.778717 -112.98375) (xy 441.832665 -112.991506) (xy 441.88496 -113.006861) (xy 441.934537 -113.029503)
			(xy 441.980387 -113.058969) (xy 442.021578 -113.09466) (xy 442.057269 -113.135851) (xy 442.086735 -113.181701)
			(xy 442.109377 -113.231278) (xy 442.124732 -113.283573) (xy 442.132488 -113.337521) (xy 442.132974 -113.364772)
			(xy 442.132563 -113.391088) (xy 442.125318 -113.443219) (xy 442.110988 -113.493863) (xy 442.089845 -113.542062)
			(xy 442.062289 -113.586904) (xy 442.02884 -113.627541) (xy 442.009784 -113.645696) (xy 442.002343 -113.653268)
			(xy 441.993818 -113.672686) (xy 441.993274 -113.683288) (xy 441.993274 -113.757456) (xy 441.993669 -113.768089)
			(xy 442.002229 -113.787553) (xy 442.009784 -113.795048) (xy 442.028853 -113.81319) (xy 442.062309 -113.853823)
			(xy 442.089867 -113.898665) (xy 442.111003 -113.946869) (xy 442.125317 -113.997519) (xy 442.132538 -114.049655)
			(xy 442.132974 -114.075972) (xy 443.401958 -114.075972) (xy 443.402388 -114.049657) (xy 443.409628 -113.997526)
			(xy 443.423953 -113.946882) (xy 443.445093 -113.898682) (xy 443.472646 -113.85384) (xy 443.506093 -113.813203)
			(xy 443.525148 -113.795048) (xy 443.532603 -113.787488) (xy 443.541122 -113.768061) (xy 443.541658 -113.757456)
			(xy 443.541658 -113.683288) (xy 443.541229 -113.672659) (xy 443.532692 -113.653195) (xy 443.525148 -113.645696)
			(xy 443.506088 -113.627546) (xy 443.472633 -113.586914) (xy 443.445076 -113.542072) (xy 443.423939 -113.49387)
			(xy 443.409622 -113.443222) (xy 443.402397 -113.391088) (xy 443.401958 -113.364772) (xy 443.402444 -113.337521)
			(xy 443.4102 -113.283573) (xy 443.425555 -113.231278) (xy 443.448197 -113.181701) (xy 443.477663 -113.135851)
			(xy 443.513354 -113.09466) (xy 443.554545 -113.058969) (xy 443.600395 -113.029503) (xy 443.649972 -113.006861)
			(xy 443.702267 -112.991506) (xy 443.756215 -112.98375) (xy 443.810717 -112.98375) (xy 443.864665 -112.991506)
			(xy 443.91696 -113.006861) (xy 443.966537 -113.029503) (xy 444.012387 -113.058969) (xy 444.053578 -113.09466)
			(xy 444.089269 -113.135851) (xy 444.118735 -113.181701) (xy 444.141377 -113.231278) (xy 444.156732 -113.283573)
			(xy 444.164488 -113.337521) (xy 444.164974 -113.364772) (xy 444.164563 -113.391088) (xy 444.157318 -113.443219)
			(xy 444.142988 -113.493863) (xy 444.121845 -113.542062) (xy 444.094289 -113.586904) (xy 444.06084 -113.627541)
			(xy 444.041784 -113.645696) (xy 444.034343 -113.653268) (xy 444.025818 -113.672686) (xy 444.025274 -113.683288)
			(xy 444.025274 -113.757456) (xy 444.025669 -113.768089) (xy 444.034229 -113.787553) (xy 444.041784 -113.795048)
			(xy 444.060853 -113.81319) (xy 444.094309 -113.853823) (xy 444.121867 -113.898665) (xy 444.143003 -113.946869)
			(xy 444.157317 -113.997519) (xy 444.164538 -114.049655) (xy 444.164974 -114.075972) (xy 444.164488 -114.103223)
			(xy 444.156732 -114.157171) (xy 444.141377 -114.209466) (xy 444.118735 -114.259043) (xy 444.089269 -114.304893)
			(xy 444.053578 -114.346084) (xy 444.012387 -114.381775) (xy 443.966537 -114.411241) (xy 443.91696 -114.433883)
			(xy 443.864665 -114.449238) (xy 443.810717 -114.456994) (xy 443.756215 -114.456994) (xy 443.702267 -114.449238)
			(xy 443.649972 -114.433883) (xy 443.600395 -114.411241) (xy 443.554545 -114.381775) (xy 443.513354 -114.346084)
			(xy 443.477663 -114.304893) (xy 443.448197 -114.259043) (xy 443.425555 -114.209466) (xy 443.4102 -114.157171)
			(xy 443.402444 -114.103223) (xy 443.401958 -114.075972) (xy 442.132974 -114.075972) (xy 442.132519 -114.103226)
			(xy 442.124764 -114.157179) (xy 442.10941 -114.209479) (xy 442.086769 -114.259061) (xy 442.0573 -114.304916)
			(xy 442.021606 -114.34611) (xy 441.980411 -114.381804) (xy 441.934556 -114.411271) (xy 441.884973 -114.433912)
			(xy 441.832673 -114.449266) (xy 441.77872 -114.457019) (xy 441.751466 -114.45748) (xy 441.720729 -114.456886)
			(xy 441.660051 -114.447023) (xy 441.60174 -114.427557) (xy 441.547304 -114.398994) (xy 441.522358 -114.381026)
			(xy 441.512198 -114.373406) (xy 441.487814 -114.369342) (xy 441.38469 -114.403124) (xy 441.367418 -114.420904)
			(xy 441.363862 -114.432842) (xy 441.355607 -114.458687) (xy 441.332789 -114.507909) (xy 441.303231 -114.553404)
			(xy 441.267527 -114.594254) (xy 441.226397 -114.629635) (xy 441.180671 -114.658835) (xy 441.13127 -114.681264)
			(xy 441.079191 -114.696471) (xy 441.025483 -114.704149) (xy 440.998356 -114.704622) (xy 440.971112 -114.704152)
			(xy 440.917179 -114.69639) (xy 440.864901 -114.68103) (xy 440.815341 -114.658385) (xy 440.769508 -114.628917)
			(xy 440.728338 -114.593224) (xy 440.692666 -114.552035) (xy 440.677554 -114.529362) (xy 440.671013 -114.520261)
			(xy 440.652024 -114.508403) (xy 440.640978 -114.506502) (xy 440.634882 -114.505994) (xy 440.54903 -114.505994)
			(xy 440.542934 -114.506502) (xy 440.5319 -114.508428) (xy 440.512929 -114.52029) (xy 440.506358 -114.529362)
			(xy 440.491273 -114.552055) (xy 440.455601 -114.593249) (xy 440.414427 -114.628944) (xy 440.368591 -114.658413)
			(xy 440.319025 -114.681055) (xy 440.26674 -114.696409) (xy 440.212802 -114.704162) (xy 440.185556 -114.704622)
			(xy 440.156639 -114.704093) (xy 440.099467 -114.69537) (xy 440.044267 -114.678116) (xy 439.992305 -114.652727)
			(xy 439.944771 -114.619784) (xy 439.902755 -114.580042) (xy 439.884566 -114.557556) (xy 439.876971 -114.548736)
			(xy 439.856061 -114.538561) (xy 439.844434 -114.537998) (xy 439.764678 -114.537998) (xy 439.753046 -114.53854)
			(xy 439.732137 -114.548727) (xy 439.724546 -114.557556) (xy 439.706318 -114.580008) (xy 439.664307 -114.619747)
			(xy 439.61678 -114.652691) (xy 439.564826 -114.678086) (xy 439.509635 -114.695348) (xy 439.45247 -114.704084)
			(xy 439.423556 -114.704622) (xy 439.396304 -114.704163) (xy 439.342356 -114.696401) (xy 439.290062 -114.681041)
			(xy 439.240486 -114.658396) (xy 439.194636 -114.628926) (xy 439.153447 -114.593232) (xy 439.117756 -114.55204)
			(xy 439.08829 -114.506188) (xy 439.065648 -114.45661) (xy 439.050293 -114.404314) (xy 439.042535 -114.350366)
			(xy 439.042048 -114.323114) (xy 439.042536 -114.295737) (xy 439.050355 -114.241545) (xy 439.065848 -114.189029)
			(xy 439.088697 -114.139271) (xy 439.118431 -114.093295) (xy 439.154439 -114.052047) (xy 439.195978 -114.016376)
			(xy 439.218832 -114.001296) (xy 439.228484 -113.9952) (xy 439.240422 -113.976404) (xy 439.254138 -113.876836)
			(xy 439.247534 -113.8555) (xy 439.23966 -113.846864) (xy 439.221626 -113.825528) (xy 439.21401 -113.816731)
			(xy 439.193116 -113.806545) (xy 439.181494 -113.80597) (xy 439.101738 -113.80597) (xy 439.0901 -113.806463)
			(xy 439.069189 -113.816682) (xy 439.061606 -113.825528) (xy 439.043419 -113.848014) (xy 439.001397 -113.887748)
			(xy 438.953861 -113.920686) (xy 438.9019 -113.946074) (xy 438.846702 -113.96333) (xy 438.789532 -113.972059)
			(xy 438.760616 -113.972594) (xy 438.760362 -113.972594) (xy 438.730925 -113.97203) (xy 438.672752 -113.962975)
			(xy 438.644538 -113.95456) (xy 438.644284 -113.95456) (xy 438.632571 -113.951525) (xy 438.608716 -113.955347)
			(xy 438.598564 -113.961926) (xy 438.532524 -114.010948) (xy 438.523322 -114.018578) (xy 438.512593 -114.039906)
			(xy 438.51195 -114.051842) (xy 438.51195 -114.05743) (xy 438.511413 -114.084681) (xy 438.503652 -114.138627)
			(xy 438.488293 -114.19092) (xy 438.465648 -114.240495) (xy 438.436178 -114.286342) (xy 438.400484 -114.327529)
			(xy 438.359291 -114.363217) (xy 438.313439 -114.392679) (xy 438.26386 -114.415315) (xy 438.211565 -114.430665)
			(xy 438.157617 -114.438417) (xy 438.103115 -114.438412) (xy 438.049169 -114.430651) (xy 437.996876 -114.415291)
			(xy 437.947302 -114.392646) (xy 437.901455 -114.363176) (xy 437.860268 -114.327481) (xy 437.824581 -114.286288)
			(xy 437.79512 -114.240435) (xy 437.772483 -114.190856) (xy 437.757134 -114.138561) (xy 437.749383 -114.084613)
			(xy 419.363231 -114.084613) (xy 419.375481 -114.103128) (xy 419.399153 -114.153625) (xy 419.415221 -114.207032)
			(xy 419.423341 -114.262208) (xy 419.42385 -114.290094) (xy 419.423341 -114.31798) (xy 419.415221 -114.373156)
			(xy 419.399153 -114.426563) (xy 419.375481 -114.47706) (xy 419.344708 -114.523573) (xy 419.307491 -114.56511)
			(xy 419.264623 -114.600785) (xy 419.217017 -114.629839) (xy 419.165688 -114.651651) (xy 419.111731 -114.665757)
			(xy 419.056294 -114.671857) (xy 419.00056 -114.66982) (xy 418.945717 -114.65969) (xy 418.892933 -114.641683)
			(xy 418.843333 -114.616182) (xy 418.797975 -114.583731) (xy 418.757826 -114.545022) (xy 418.72374 -114.500879)
			(xy 418.696444 -114.452244) (xy 418.676521 -114.400153) (xy 418.664395 -114.345716) (xy 418.660324 -114.290094)
			(xy 416.128823 -114.290094) (xy 416.149981 -114.299757) (xy 416.195831 -114.329223) (xy 416.237022 -114.364914)
			(xy 416.272713 -114.406105) (xy 416.302179 -114.451955) (xy 416.324821 -114.501532) (xy 416.340176 -114.553827)
			(xy 416.347932 -114.607775) (xy 416.348418 -114.635026) (xy 416.347812 -114.664106) (xy 416.338966 -114.721591)
			(xy 416.321499 -114.777068) (xy 416.304024 -114.812572) (xy 420.150798 -114.812572) (xy 420.151284 -114.785321)
			(xy 420.15904 -114.731373) (xy 420.174395 -114.679078) (xy 420.197037 -114.629501) (xy 420.226503 -114.583651)
			(xy 420.262194 -114.54246) (xy 420.303385 -114.506769) (xy 420.349235 -114.477303) (xy 420.398812 -114.454661)
			(xy 420.451107 -114.439306) (xy 420.505055 -114.43155) (xy 420.559557 -114.43155) (xy 420.613505 -114.439306)
			(xy 420.6658 -114.454661) (xy 420.715377 -114.477303) (xy 420.761227 -114.506769) (xy 420.802418 -114.54246)
			(xy 420.838109 -114.583651) (xy 420.867575 -114.629501) (xy 420.890217 -114.679078) (xy 420.905572 -114.731373)
			(xy 420.913328 -114.785321) (xy 420.913814 -114.812572) (xy 420.913248 -114.842263) (xy 420.904038 -114.900927)
			(xy 420.885853 -114.957456) (xy 420.859132 -115.010487) (xy 420.824518 -115.058738) (xy 420.804086 -115.080288)
			(xy 420.79672 -115.087654) (xy 420.789354 -115.10645) (xy 420.791132 -115.199922) (xy 420.799514 -115.218718)
			(xy 420.807134 -115.22583) (xy 420.825953 -115.243926) (xy 420.858928 -115.284405) (xy 420.886079 -115.329)
			(xy 420.906899 -115.376879) (xy 420.913619 -115.400836) (xy 435.560722 -115.400836) (xy 435.564793 -115.345214)
			(xy 435.576919 -115.290777) (xy 435.596842 -115.238686) (xy 435.624138 -115.190051) (xy 435.658224 -115.145908)
			(xy 435.698373 -115.107199) (xy 435.743731 -115.074748) (xy 435.793331 -115.049247) (xy 435.846115 -115.03124)
			(xy 435.900958 -115.02111) (xy 435.956692 -115.019073) (xy 436.012129 -115.025173) (xy 436.066086 -115.039279)
			(xy 436.117415 -115.061091) (xy 436.165021 -115.090145) (xy 436.207889 -115.12582) (xy 436.245106 -115.167357)
			(xy 436.275879 -115.21387) (xy 436.299551 -115.264367) (xy 436.315619 -115.317774) (xy 436.323357 -115.370356)
			(xy 437.661302 -115.370356) (xy 437.665373 -115.314734) (xy 437.677499 -115.260297) (xy 437.697422 -115.208206)
			(xy 437.724718 -115.159571) (xy 437.758804 -115.115428) (xy 437.798953 -115.076719) (xy 437.844311 -115.044268)
			(xy 437.893911 -115.018767) (xy 437.946695 -115.00076) (xy 438.001538 -114.99063) (xy 438.057272 -114.988593)
			(xy 438.112709 -114.994693) (xy 438.166666 -115.008799) (xy 438.217995 -115.030611) (xy 438.265601 -115.059665)
			(xy 438.308469 -115.09534) (xy 438.345686 -115.136877) (xy 438.376459 -115.18339) (xy 438.400131 -115.233887)
			(xy 438.416199 -115.287294) (xy 438.424319 -115.34247) (xy 438.424828 -115.370356) (xy 438.424319 -115.398242)
			(xy 438.416199 -115.453418) (xy 438.400131 -115.506825) (xy 438.376459 -115.557322) (xy 438.345686 -115.603835)
			(xy 438.308469 -115.645372) (xy 438.265601 -115.681047) (xy 438.217995 -115.710101) (xy 438.166666 -115.731913)
			(xy 438.112709 -115.746019) (xy 438.057272 -115.752119) (xy 438.001538 -115.750082) (xy 437.946695 -115.739952)
			(xy 437.893911 -115.721945) (xy 437.844311 -115.696444) (xy 437.798953 -115.663993) (xy 437.758804 -115.625284)
			(xy 437.724718 -115.581141) (xy 437.697422 -115.532506) (xy 437.677499 -115.480415) (xy 437.665373 -115.425978)
			(xy 437.661302 -115.370356) (xy 436.323357 -115.370356) (xy 436.323739 -115.37295) (xy 436.324248 -115.400836)
			(xy 436.323739 -115.428722) (xy 436.315619 -115.483898) (xy 436.299551 -115.537305) (xy 436.275879 -115.587802)
			(xy 436.245106 -115.634315) (xy 436.207889 -115.675852) (xy 436.165021 -115.711527) (xy 436.117415 -115.740581)
			(xy 436.066086 -115.762393) (xy 436.012129 -115.776499) (xy 435.956692 -115.782599) (xy 435.900958 -115.780562)
			(xy 435.846115 -115.770432) (xy 435.793331 -115.752425) (xy 435.743731 -115.726924) (xy 435.698373 -115.694473)
			(xy 435.658224 -115.655764) (xy 435.624138 -115.611621) (xy 435.596842 -115.562986) (xy 435.576919 -115.510895)
			(xy 435.564793 -115.456458) (xy 435.560722 -115.400836) (xy 420.913619 -115.400836) (xy 420.920999 -115.427149)
			(xy 420.928118 -115.478871) (xy 420.928546 -115.504976) (xy 420.92806 -115.532227) (xy 420.920304 -115.586175)
			(xy 420.904949 -115.63847) (xy 420.882307 -115.688047) (xy 420.852841 -115.733897) (xy 420.81715 -115.775088)
			(xy 420.775959 -115.810779) (xy 420.741949 -115.832636) (xy 441.279788 -115.832636) (xy 441.280305 -115.80408)
			(xy 441.288801 -115.747602) (xy 441.305623 -115.693023) (xy 441.330395 -115.641563) (xy 441.362564 -115.594371)
			(xy 441.40141 -115.552504) (xy 441.446064 -115.516897) (xy 441.470542 -115.502182) (xy 441.483422 -115.494082)
			(xy 441.504093 -115.471776) (xy 441.517278 -115.444371) (xy 441.521806 -115.414299) (xy 441.517277 -115.384227)
			(xy 441.504092 -115.356823) (xy 441.483421 -115.334517) (xy 441.470542 -115.326414) (xy 441.446086 -115.311668)
			(xy 441.401448 -115.276053) (xy 441.362613 -115.234185) (xy 441.33045 -115.186999) (xy 441.305675 -115.135547)
			(xy 441.288842 -115.080979) (xy 441.280325 -115.024513) (xy 441.279788 -114.99596) (xy 441.280274 -114.968709)
			(xy 441.28803 -114.914761) (xy 441.303385 -114.862466) (xy 441.326027 -114.812889) (xy 441.355493 -114.767039)
			(xy 441.391184 -114.725848) (xy 441.432375 -114.690157) (xy 441.478225 -114.660691) (xy 441.527802 -114.638049)
			(xy 441.580097 -114.622694) (xy 441.634045 -114.614938) (xy 441.688547 -114.614938) (xy 441.742495 -114.622694)
			(xy 441.79479 -114.638049) (xy 441.844367 -114.660691) (xy 441.890217 -114.690157) (xy 441.931408 -114.725848)
			(xy 441.967099 -114.767039) (xy 441.996565 -114.812889) (xy 442.019207 -114.862466) (xy 442.034562 -114.914761)
			(xy 442.042318 -114.968709) (xy 442.042804 -114.99596) (xy 442.042288 -115.024517) (xy 442.033792 -115.080994)
			(xy 442.01697 -115.135573) (xy 441.992198 -115.187034) (xy 441.960029 -115.234225) (xy 441.921183 -115.276092)
			(xy 441.876528 -115.311699) (xy 441.85205 -115.326414) (xy 441.839164 -115.334513) (xy 441.818475 -115.356813)
			(xy 441.805278 -115.38422) (xy 441.803731 -115.394486) (xy 443.447168 -115.394486) (xy 443.451239 -115.338864)
			(xy 443.463365 -115.284427) (xy 443.483288 -115.232336) (xy 443.510584 -115.183701) (xy 443.54467 -115.139558)
			(xy 443.584819 -115.100849) (xy 443.630177 -115.068398) (xy 443.679777 -115.042897) (xy 443.732561 -115.02489)
			(xy 443.787404 -115.01476) (xy 443.843138 -115.012723) (xy 443.898575 -115.018823) (xy 443.909232 -115.021609)
			(xy 445.856196 -115.021609) (xy 445.86051 -114.964339) (xy 445.873356 -114.908361) (xy 445.894446 -114.854941)
			(xy 445.923301 -114.805283) (xy 445.959272 -114.760511) (xy 445.980058 -114.74069) (xy 445.987496 -114.733115)
			(xy 445.996024 -114.7137) (xy 445.996568 -114.703098) (xy 445.996568 -114.62893) (xy 445.996143 -114.618299)
			(xy 445.987606 -114.598834) (xy 445.980058 -114.591338) (xy 445.960971 -114.573214) (xy 445.927519 -114.532576)
			(xy 445.899965 -114.487729) (xy 445.878832 -114.439522) (xy 445.864521 -114.38887) (xy 445.857303 -114.336732)
			(xy 445.856868 -114.310414) (xy 445.857354 -114.283163) (xy 445.86511 -114.229215) (xy 445.880465 -114.17692)
			(xy 445.903107 -114.127343) (xy 445.932573 -114.081493) (xy 445.968264 -114.040302) (xy 446.009455 -114.004611)
			(xy 446.055305 -113.975145) (xy 446.104882 -113.952503) (xy 446.157177 -113.937148) (xy 446.211125 -113.929392)
			(xy 446.265627 -113.929392) (xy 446.319575 -113.937148) (xy 446.37187 -113.952503) (xy 446.421447 -113.975145)
			(xy 446.467297 -114.004611) (xy 446.508488 -114.040302) (xy 446.544179 -114.081493) (xy 446.573645 -114.127343)
			(xy 446.596287 -114.17692) (xy 446.611642 -114.229215) (xy 446.619398 -114.283163) (xy 446.619884 -114.310414)
			(xy 446.619431 -114.336729) (xy 446.612194 -114.388858) (xy 446.597872 -114.439501) (xy 446.576737 -114.4877)
			(xy 446.549188 -114.532543) (xy 446.515747 -114.573182) (xy 446.496694 -114.591338) (xy 446.489236 -114.598896)
			(xy 446.480721 -114.618324) (xy 446.480184 -114.62893) (xy 446.480184 -114.703098) (xy 446.480608 -114.713728)
			(xy 446.489147 -114.733192) (xy 446.496694 -114.74069) (xy 446.517497 -114.760495) (xy 446.553474 -114.805269)
			(xy 446.582335 -114.854929) (xy 446.603429 -114.908353) (xy 446.616278 -114.964334) (xy 446.620592 -115.021609)
			(xy 448.394411 -115.021609) (xy 448.398725 -114.964338) (xy 448.411572 -114.90836) (xy 448.432663 -114.854939)
			(xy 448.46152 -114.805282) (xy 448.497493 -114.76051) (xy 448.51828 -114.74069) (xy 448.525722 -114.733118)
			(xy 448.534247 -114.713701) (xy 448.53479 -114.703098) (xy 448.53479 -114.62893) (xy 448.534359 -114.6183)
			(xy 448.525825 -114.598836) (xy 448.51828 -114.591338) (xy 448.499198 -114.57321) (xy 448.465744 -114.532574)
			(xy 448.438189 -114.487727) (xy 448.417055 -114.439521) (xy 448.402743 -114.388869) (xy 448.395525 -114.336732)
			(xy 448.39509 -114.310414) (xy 448.395576 -114.283163) (xy 448.403332 -114.229215) (xy 448.418687 -114.17692)
			(xy 448.441329 -114.127343) (xy 448.470795 -114.081493) (xy 448.506486 -114.040302) (xy 448.547677 -114.004611)
			(xy 448.593527 -113.975145) (xy 448.643104 -113.952503) (xy 448.695399 -113.937148) (xy 448.749347 -113.929392)
			(xy 448.803849 -113.929392) (xy 448.857797 -113.937148) (xy 448.910092 -113.952503) (xy 448.959669 -113.975145)
			(xy 449.005519 -114.004611) (xy 449.033059 -114.028474) (xy 453.305162 -114.028474) (xy 453.309233 -113.972852)
			(xy 453.321359 -113.918415) (xy 453.341282 -113.866324) (xy 453.368578 -113.817689) (xy 453.402664 -113.773546)
			(xy 453.442813 -113.734837) (xy 453.488171 -113.702386) (xy 453.537771 -113.676885) (xy 453.590555 -113.658878)
			(xy 453.645398 -113.648748) (xy 453.701132 -113.646711) (xy 453.756569 -113.652811) (xy 453.810526 -113.666917)
			(xy 453.861855 -113.688729) (xy 453.909461 -113.717783) (xy 453.952329 -113.753458) (xy 453.989546 -113.794995)
			(xy 454.020319 -113.841508) (xy 454.043991 -113.892005) (xy 454.060059 -113.945412) (xy 454.068179 -114.000588)
			(xy 454.068688 -114.028474) (xy 454.068179 -114.05636) (xy 454.060059 -114.111536) (xy 454.043991 -114.164943)
			(xy 454.020319 -114.21544) (xy 453.989546 -114.261953) (xy 453.952329 -114.30349) (xy 453.909461 -114.339165)
			(xy 453.861855 -114.368219) (xy 453.810526 -114.390031) (xy 453.756569 -114.404137) (xy 453.701132 -114.410237)
			(xy 453.645398 -114.4082) (xy 453.590555 -114.39807) (xy 453.537771 -114.380063) (xy 453.488171 -114.354562)
			(xy 453.442813 -114.322111) (xy 453.402664 -114.283402) (xy 453.368578 -114.239259) (xy 453.341282 -114.190624)
			(xy 453.321359 -114.138533) (xy 453.309233 -114.084096) (xy 453.305162 -114.028474) (xy 449.033059 -114.028474)
			(xy 449.04671 -114.040302) (xy 449.082401 -114.081493) (xy 449.111867 -114.127343) (xy 449.134509 -114.17692)
			(xy 449.149864 -114.229215) (xy 449.15762 -114.283163) (xy 449.158106 -114.310414) (xy 449.157646 -114.336728)
			(xy 449.150409 -114.388857) (xy 449.136089 -114.4395) (xy 449.114955 -114.487699) (xy 449.087408 -114.532542)
			(xy 449.053968 -114.573181) (xy 449.034916 -114.591338) (xy 449.027461 -114.598899) (xy 449.018943 -114.618325)
			(xy 449.018406 -114.62893) (xy 449.018406 -114.703098) (xy 449.018823 -114.713729) (xy 449.027367 -114.733194)
			(xy 449.034916 -114.74069) (xy 449.055718 -114.760496) (xy 449.091693 -114.80527) (xy 449.120553 -114.85493)
			(xy 449.141645 -114.908354) (xy 449.154493 -114.964335) (xy 449.158807 -115.021609) (xy 449.15449 -115.078884)
			(xy 449.141639 -115.134864) (xy 449.120544 -115.188287) (xy 449.091682 -115.237945) (xy 449.055705 -115.282718)
			(xy 449.034916 -115.302538) (xy 449.027461 -115.310099) (xy 449.018943 -115.329525) (xy 449.018406 -115.34013)
			(xy 449.018406 -115.414298) (xy 449.018823 -115.424929) (xy 449.027367 -115.444394) (xy 449.034916 -115.45189)
			(xy 449.053963 -115.470054) (xy 449.08742 -115.510683) (xy 449.11498 -115.555521) (xy 449.125675 -115.579906)
			(xy 453.443084 -115.579906) (xy 453.447155 -115.524284) (xy 453.459281 -115.469847) (xy 453.479204 -115.417756)
			(xy 453.5065 -115.369121) (xy 453.540586 -115.324978) (xy 453.580735 -115.286269) (xy 453.626093 -115.253818)
			(xy 453.675693 -115.228317) (xy 453.728477 -115.21031) (xy 453.78332 -115.20018) (xy 453.839054 -115.198143)
			(xy 453.894491 -115.204243) (xy 453.948448 -115.218349) (xy 453.999777 -115.240161) (xy 454.047383 -115.269215)
			(xy 454.090251 -115.30489) (xy 454.127468 -115.346427) (xy 454.158241 -115.39294) (xy 454.181913 -115.443437)
			(xy 454.197981 -115.496844) (xy 454.206101 -115.55202) (xy 454.20661 -115.579906) (xy 454.206101 -115.607792)
			(xy 454.197981 -115.662968) (xy 454.181913 -115.716375) (xy 454.158241 -115.766872) (xy 454.127468 -115.813385)
			(xy 454.090251 -115.854922) (xy 454.047383 -115.890597) (xy 453.999777 -115.919651) (xy 453.948448 -115.941463)
			(xy 453.894491 -115.955569) (xy 453.839054 -115.961669) (xy 453.78332 -115.959632) (xy 453.728477 -115.949502)
			(xy 453.675693 -115.931495) (xy 453.626093 -115.905994) (xy 453.580735 -115.873543) (xy 453.540586 -115.834834)
			(xy 453.5065 -115.790691) (xy 453.479204 -115.742056) (xy 453.459281 -115.689965) (xy 453.447155 -115.635528)
			(xy 453.443084 -115.579906) (xy 449.125675 -115.579906) (xy 449.13612 -115.60372) (xy 449.150439 -115.654366)
			(xy 449.157666 -115.706498) (xy 449.158106 -115.732814) (xy 449.15762 -115.760065) (xy 449.149864 -115.814013)
			(xy 449.134509 -115.866308) (xy 449.111867 -115.915885) (xy 449.082401 -115.961735) (xy 449.04671 -116.002926)
			(xy 449.005519 -116.038617) (xy 448.959669 -116.068083) (xy 448.910092 -116.090725) (xy 448.857797 -116.10608)
			(xy 448.803849 -116.113836) (xy 448.749347 -116.113836) (xy 448.695399 -116.10608) (xy 448.643104 -116.090725)
			(xy 448.593527 -116.068083) (xy 448.547677 -116.038617) (xy 448.506486 -116.002926) (xy 448.470795 -115.961735)
			(xy 448.441329 -115.915885) (xy 448.418687 -115.866308) (xy 448.403332 -115.814013) (xy 448.395576 -115.760065)
			(xy 448.39509 -115.732814) (xy 448.39557 -115.706501) (xy 448.402803 -115.654373) (xy 448.41712 -115.60373)
			(xy 448.43825 -115.555531) (xy 448.465793 -115.510688) (xy 448.49923 -115.470047) (xy 448.51828 -115.45189)
			(xy 448.525722 -115.444318) (xy 448.534247 -115.424901) (xy 448.53479 -115.414298) (xy 448.53479 -115.34013)
			(xy 448.534359 -115.3295) (xy 448.525825 -115.310036) (xy 448.51828 -115.302538) (xy 448.497506 -115.282704)
			(xy 448.461531 -115.237933) (xy 448.432671 -115.188278) (xy 448.411578 -115.134858) (xy 448.398728 -115.07888)
			(xy 448.394411 -115.021609) (xy 446.620592 -115.021609) (xy 446.616275 -115.078884) (xy 446.603423 -115.134865)
			(xy 446.582327 -115.188288) (xy 446.553463 -115.237947) (xy 446.517484 -115.282719) (xy 446.496694 -115.302538)
			(xy 446.489236 -115.310096) (xy 446.480721 -115.329524) (xy 446.480184 -115.34013) (xy 446.480184 -115.414298)
			(xy 446.480608 -115.424928) (xy 446.489147 -115.444392) (xy 446.496694 -115.45189) (xy 446.515737 -115.470059)
			(xy 446.549195 -115.510685) (xy 446.576756 -115.555523) (xy 446.597897 -115.603721) (xy 446.612217 -115.654366)
			(xy 446.619444 -115.706499) (xy 446.619884 -115.732814) (xy 446.619398 -115.760065) (xy 446.611642 -115.814013)
			(xy 446.596287 -115.866308) (xy 446.573645 -115.915885) (xy 446.544179 -115.961735) (xy 446.508488 -116.002926)
			(xy 446.467297 -116.038617) (xy 446.421447 -116.068083) (xy 446.37187 -116.090725) (xy 446.319575 -116.10608)
			(xy 446.265627 -116.113836) (xy 446.211125 -116.113836) (xy 446.157177 -116.10608) (xy 446.104882 -116.090725)
			(xy 446.055305 -116.068083) (xy 446.009455 -116.038617) (xy 445.968264 -116.002926) (xy 445.932573 -115.961735)
			(xy 445.903107 -115.915885) (xy 445.880465 -115.866308) (xy 445.86511 -115.814013) (xy 445.857354 -115.760065)
			(xy 445.856868 -115.732814) (xy 445.857355 -115.706501) (xy 445.864587 -115.654374) (xy 445.878903 -115.603732)
			(xy 445.900032 -115.555533) (xy 445.927574 -115.510689) (xy 445.961009 -115.470048) (xy 445.980058 -115.45189)
			(xy 445.987496 -115.444315) (xy 445.996024 -115.4249) (xy 445.996568 -115.414298) (xy 445.996568 -115.34013)
			(xy 445.996143 -115.329499) (xy 445.987606 -115.310034) (xy 445.980058 -115.302538) (xy 445.959285 -115.282703)
			(xy 445.923312 -115.237932) (xy 445.894454 -115.188276) (xy 445.873362 -115.134857) (xy 445.860513 -115.07888)
			(xy 445.856196 -115.021609) (xy 443.909232 -115.021609) (xy 443.952532 -115.032929) (xy 444.003861 -115.054741)
			(xy 444.051467 -115.083795) (xy 444.094335 -115.11947) (xy 444.131552 -115.161007) (xy 444.162325 -115.20752)
			(xy 444.185997 -115.258017) (xy 444.202065 -115.311424) (xy 444.210185 -115.3666) (xy 444.210694 -115.394486)
			(xy 444.210185 -115.422372) (xy 444.202065 -115.477548) (xy 444.185997 -115.530955) (xy 444.162325 -115.581452)
			(xy 444.131552 -115.627965) (xy 444.094335 -115.669502) (xy 444.051467 -115.705177) (xy 444.003861 -115.734231)
			(xy 443.952532 -115.756043) (xy 443.898575 -115.770149) (xy 443.843138 -115.776249) (xy 443.787404 -115.774212)
			(xy 443.732561 -115.764082) (xy 443.679777 -115.746075) (xy 443.630177 -115.720574) (xy 443.584819 -115.688123)
			(xy 443.54467 -115.649414) (xy 443.510584 -115.605271) (xy 443.483288 -115.556636) (xy 443.463365 -115.504545)
			(xy 443.451239 -115.450108) (xy 443.447168 -115.394486) (xy 441.803731 -115.394486) (xy 441.800744 -115.414299)
			(xy 441.805277 -115.444378) (xy 441.818474 -115.471785) (xy 441.839162 -115.494085) (xy 441.85205 -115.502182)
			(xy 441.876503 -115.516934) (xy 441.921141 -115.552548) (xy 441.959976 -115.594415) (xy 441.99214 -115.6416)
			(xy 442.016915 -115.69305) (xy 442.033749 -115.747617) (xy 442.042266 -115.804084) (xy 442.042804 -115.832636)
			(xy 442.042318 -115.859887) (xy 442.034562 -115.913835) (xy 442.019207 -115.96613) (xy 441.996565 -116.015707)
			(xy 441.967099 -116.061557) (xy 441.931408 -116.102748) (xy 441.890217 -116.138439) (xy 441.844367 -116.167905)
			(xy 441.79479 -116.190547) (xy 441.742495 -116.205902) (xy 441.688547 -116.213658) (xy 441.634045 -116.213658)
			(xy 441.580097 -116.205902) (xy 441.527802 -116.190547) (xy 441.478225 -116.167905) (xy 441.432375 -116.138439)
			(xy 441.391184 -116.102748) (xy 441.355493 -116.061557) (xy 441.326027 -116.015707) (xy 441.303385 -115.96613)
			(xy 441.28803 -115.913835) (xy 441.280274 -115.859887) (xy 441.279788 -115.832636) (xy 420.741949 -115.832636)
			(xy 420.730109 -115.840245) (xy 420.680532 -115.862887) (xy 420.628237 -115.878242) (xy 420.574289 -115.885998)
			(xy 420.519787 -115.885998) (xy 420.465839 -115.878242) (xy 420.413544 -115.862887) (xy 420.363967 -115.840245)
			(xy 420.318117 -115.810779) (xy 420.276926 -115.775088) (xy 420.241235 -115.733897) (xy 420.211769 -115.688047)
			(xy 420.189127 -115.63847) (xy 420.173772 -115.586175) (xy 420.166016 -115.532227) (xy 420.16553 -115.504976)
			(xy 420.166114 -115.475285) (xy 420.175317 -115.416622) (xy 420.193497 -115.360092) (xy 420.220215 -115.307061)
			(xy 420.254826 -115.25881) (xy 420.275258 -115.23726) (xy 420.282624 -115.229894) (xy 420.28999 -115.211098)
			(xy 420.288212 -115.117626) (xy 420.27983 -115.09883) (xy 420.27221 -115.091718) (xy 420.253422 -115.07359)
			(xy 420.220443 -115.033119) (xy 420.193287 -114.988531) (xy 420.172461 -114.940658) (xy 420.158354 -114.890394)
			(xy 420.151229 -114.838675) (xy 420.150798 -114.812572) (xy 416.304024 -114.812572) (xy 416.295815 -114.829251)
			(xy 416.262509 -114.876931) (xy 416.222352 -114.919005) (xy 416.176276 -114.954498) (xy 416.125347 -114.982586)
			(xy 416.070745 -115.00262) (xy 416.042348 -115.008914) (xy 416.031172 -115.0112) (xy 416.013138 -115.024408)
			(xy 415.964878 -115.1128) (xy 415.963608 -115.135406) (xy 415.967672 -115.14582) (xy 415.976096 -115.168182)
			(xy 415.987956 -115.214473) (xy 415.993953 -115.261881) (xy 415.994342 -115.285774) (xy 415.993856 -115.313025)
			(xy 415.9861 -115.366973) (xy 415.970745 -115.419268) (xy 415.948103 -115.468845) (xy 415.918637 -115.514695)
			(xy 415.882946 -115.555886) (xy 415.841755 -115.591577) (xy 415.795905 -115.621043) (xy 415.746328 -115.643685)
			(xy 415.694033 -115.65904) (xy 415.640085 -115.666796) (xy 415.585583 -115.666796) (xy 415.531635 -115.65904)
			(xy 415.47934 -115.643685) (xy 415.429763 -115.621043) (xy 415.383913 -115.591577) (xy 415.342722 -115.555886)
			(xy 415.307031 -115.514695) (xy 415.277565 -115.468845) (xy 415.254923 -115.419268) (xy 415.239568 -115.366973)
			(xy 415.231812 -115.313025) (xy 415.231326 -115.285774) (xy 409.822818 -115.285774) (xy 409.186592 -115.922044)
			(xy 411.503366 -115.922044) (xy 411.507437 -115.866422) (xy 411.519563 -115.811985) (xy 411.539486 -115.759894)
			(xy 411.566782 -115.711259) (xy 411.600868 -115.667116) (xy 411.641017 -115.628407) (xy 411.686375 -115.595956)
			(xy 411.735975 -115.570455) (xy 411.788759 -115.552448) (xy 411.843602 -115.542318) (xy 411.899336 -115.540281)
			(xy 411.954773 -115.546381) (xy 412.00873 -115.560487) (xy 412.060059 -115.582299) (xy 412.107665 -115.611353)
			(xy 412.150533 -115.647028) (xy 412.18775 -115.688565) (xy 412.218523 -115.735078) (xy 412.242195 -115.785575)
			(xy 412.258263 -115.838982) (xy 412.266383 -115.894158) (xy 412.266892 -115.922044) (xy 412.266383 -115.94993)
			(xy 412.258263 -116.005106) (xy 412.242195 -116.058513) (xy 412.218523 -116.10901) (xy 412.18775 -116.155523)
			(xy 412.150533 -116.19706) (xy 412.107665 -116.232735) (xy 412.060059 -116.261789) (xy 412.00873 -116.283601)
			(xy 411.954773 -116.297707) (xy 411.899336 -116.303807) (xy 411.843602 -116.30177) (xy 411.788759 -116.29164)
			(xy 411.735975 -116.273633) (xy 411.686375 -116.248132) (xy 411.641017 -116.215681) (xy 411.600868 -116.176972)
			(xy 411.566782 -116.132829) (xy 411.539486 -116.084194) (xy 411.519563 -116.032103) (xy 411.507437 -115.977666)
			(xy 411.503366 -115.922044) (xy 409.186592 -115.922044) (xy 408.661102 -116.44757) (xy 414.457132 -116.44757)
			(xy 414.461203 -116.391948) (xy 414.473329 -116.337511) (xy 414.493252 -116.28542) (xy 414.520548 -116.236785)
			(xy 414.554634 -116.192642) (xy 414.594783 -116.153933) (xy 414.640141 -116.121482) (xy 414.689741 -116.095981)
			(xy 414.742525 -116.077974) (xy 414.797368 -116.067844) (xy 414.853102 -116.065807) (xy 414.908539 -116.071907)
			(xy 414.962496 -116.086013) (xy 415.013825 -116.107825) (xy 415.061431 -116.136879) (xy 415.104299 -116.172554)
			(xy 415.141516 -116.214091) (xy 415.172289 -116.260604) (xy 415.195961 -116.311101) (xy 415.212029 -116.364508)
			(xy 415.220149 -116.419684) (xy 415.220431 -116.435124) (xy 415.584892 -116.435124) (xy 415.588963 -116.379502)
			(xy 415.601089 -116.325065) (xy 415.621012 -116.272974) (xy 415.648308 -116.224339) (xy 415.682394 -116.180196)
			(xy 415.722543 -116.141487) (xy 415.767901 -116.109036) (xy 415.817501 -116.083535) (xy 415.870285 -116.065528)
			(xy 415.925128 -116.055398) (xy 415.980862 -116.053361) (xy 416.036299 -116.059461) (xy 416.090256 -116.073567)
			(xy 416.141585 -116.095379) (xy 416.189191 -116.124433) (xy 416.232059 -116.160108) (xy 416.269276 -116.201645)
			(xy 416.300049 -116.248158) (xy 416.323721 -116.298655) (xy 416.339789 -116.352062) (xy 416.347909 -116.407238)
			(xy 416.348418 -116.435124) (xy 416.347909 -116.46301) (xy 416.341796 -116.50455) (xy 419.605466 -116.50455)
			(xy 419.605466 -116.45005) (xy 419.613221 -116.396104) (xy 419.628575 -116.343811) (xy 419.651214 -116.294234)
			(xy 419.680677 -116.248385) (xy 419.716366 -116.207194) (xy 419.757552 -116.171501) (xy 419.803399 -116.142033)
			(xy 419.852973 -116.119389) (xy 419.905265 -116.10403) (xy 419.95921 -116.096269) (xy 419.98646 -116.09578)
			(xy 420.014531 -116.096281) (xy 420.070064 -116.104525) (xy 420.123791 -116.120812) (xy 420.174554 -116.144791)
			(xy 420.221259 -116.175945) (xy 420.262898 -116.213603) (xy 420.298574 -116.256951) (xy 420.327518 -116.305057)
			(xy 420.349106 -116.356882) (xy 420.362872 -116.411309) (xy 420.36619 -116.439188) (xy 420.3681 -116.453141)
			(xy 420.378439 -116.479322) (xy 420.395535 -116.501683) (xy 420.418088 -116.518525) (xy 420.444384 -116.528566)
			(xy 420.472423 -116.531043) (xy 420.486332 -116.52885) (xy 420.504131 -116.525653) (xy 420.540132 -116.522218)
			(xy 420.558214 -116.521992) (xy 420.558468 -116.521992) (xy 420.585722 -116.522453) (xy 420.639677 -116.530206)
			(xy 420.691978 -116.54556) (xy 420.741563 -116.5682) (xy 420.78742 -116.597667) (xy 420.828616 -116.633361)
			(xy 420.864313 -116.674555) (xy 420.893784 -116.720409) (xy 420.916429 -116.769992) (xy 420.931787 -116.822292)
			(xy 420.939545 -116.876246) (xy 420.939545 -116.930754) (xy 420.931787 -116.984708) (xy 420.916429 -117.037008)
			(xy 420.893784 -117.086591) (xy 420.864313 -117.132445) (xy 420.828616 -117.173639) (xy 420.78742 -117.209333)
			(xy 420.741563 -117.2388) (xy 420.691978 -117.26144) (xy 420.639677 -117.276794) (xy 420.585722 -117.284547)
			(xy 420.558468 -117.285008) (xy 420.530395 -117.284584) (xy 420.474858 -117.276329) (xy 420.421129 -117.260032)
			(xy 420.370365 -117.236043) (xy 420.32366 -117.204881) (xy 420.282021 -117.167215) (xy 420.246347 -117.123859)
			(xy 420.217404 -117.075746) (xy 420.195819 -117.023915) (xy 420.182055 -116.969481) (xy 420.178738 -116.9416)
			(xy 420.176919 -116.92763) (xy 420.166568 -116.901438) (xy 420.149455 -116.879071) (xy 420.126882 -116.86223)
			(xy 420.100567 -116.852197) (xy 420.072512 -116.849735) (xy 420.058596 -116.851938) (xy 420.040797 -116.855131)
			(xy 420.004796 -116.858569) (xy 419.986714 -116.858796) (xy 419.98646 -116.858796) (xy 419.95921 -116.858331)
			(xy 419.905265 -116.85057) (xy 419.852973 -116.835211) (xy 419.803399 -116.812567) (xy 419.757552 -116.783099)
			(xy 419.716366 -116.747406) (xy 419.680677 -116.706215) (xy 419.651214 -116.660366) (xy 419.628575 -116.610789)
			(xy 419.613221 -116.558496) (xy 419.605466 -116.50455) (xy 416.341796 -116.50455) (xy 416.339789 -116.518186)
			(xy 416.323721 -116.571593) (xy 416.300049 -116.62209) (xy 416.269276 -116.668603) (xy 416.232059 -116.71014)
			(xy 416.189191 -116.745815) (xy 416.141585 -116.774869) (xy 416.090256 -116.796681) (xy 416.036299 -116.810787)
			(xy 415.980862 -116.816887) (xy 415.925128 -116.81485) (xy 415.870285 -116.80472) (xy 415.817501 -116.786713)
			(xy 415.767901 -116.761212) (xy 415.722543 -116.728761) (xy 415.682394 -116.690052) (xy 415.648308 -116.645909)
			(xy 415.621012 -116.597274) (xy 415.601089 -116.545183) (xy 415.588963 -116.490746) (xy 415.584892 -116.435124)
			(xy 415.220431 -116.435124) (xy 415.220658 -116.44757) (xy 415.220149 -116.475456) (xy 415.212029 -116.530632)
			(xy 415.195961 -116.584039) (xy 415.172289 -116.634536) (xy 415.141516 -116.681049) (xy 415.104299 -116.722586)
			(xy 415.061431 -116.758261) (xy 415.013825 -116.787315) (xy 414.962496 -116.809127) (xy 414.908539 -116.823233)
			(xy 414.853102 -116.829333) (xy 414.797368 -116.827296) (xy 414.742525 -116.817166) (xy 414.689741 -116.799159)
			(xy 414.640141 -116.773658) (xy 414.594783 -116.741207) (xy 414.554634 -116.702498) (xy 414.520548 -116.658355)
			(xy 414.493252 -116.60972) (xy 414.473329 -116.557629) (xy 414.461203 -116.503192) (xy 414.457132 -116.44757)
			(xy 408.661102 -116.44757) (xy 408.572462 -116.536216) (xy 408.565096 -116.543328) (xy 408.557476 -116.562124)
			(xy 408.557476 -116.93525) (xy 408.557908 -116.945317) (xy 408.565632 -116.96391) (xy 408.572462 -116.971318)
			(xy 410.414724 -118.813834) (xy 410.417264 -118.816628) (xy 410.420312 -118.818914) (xy 410.428509 -118.825251)
			(xy 410.444142 -118.838852) (xy 410.451554 -118.846092) (xy 410.755846 -119.150384) (xy 410.763289 -119.157085)
			(xy 410.781791 -119.164701) (xy 410.801798 -119.164703) (xy 410.811218 -119.161306) (xy 410.825442 -119.155464)
			(xy 410.84246 -119.130064) (xy 410.84246 -118.735094) (xy 410.842992 -118.709072) (xy 410.851166 -118.657673)
			(xy 410.867267 -118.608182) (xy 410.890899 -118.561812) (xy 410.921482 -118.519701) (xy 410.939488 -118.500906)
			(xy 411.20568 -118.234714) (xy 411.21203 -118.2243) (xy 411.213808 -118.218458) (xy 411.222241 -118.192921)
			(xy 411.245281 -118.144328) (xy 411.274921 -118.099454) (xy 411.310572 -118.059189) (xy 411.351526 -118.024333)
			(xy 411.396971 -117.995577) (xy 411.446006 -117.973492) (xy 411.497657 -117.958514) (xy 411.550901 -117.950943)
			(xy 411.57779 -117.950488) (xy 411.605043 -117.950951) (xy 411.658996 -117.958706) (xy 411.711295 -117.974062)
			(xy 411.760877 -117.996703) (xy 411.806731 -118.026171) (xy 411.847925 -118.061865) (xy 411.88362 -118.103058)
			(xy 411.91309 -118.148911) (xy 411.935734 -118.198492) (xy 411.951091 -118.250791) (xy 411.958848 -118.304743)
			(xy 411.959298 -118.331996) (xy 411.958836 -118.358885) (xy 411.951276 -118.41213) (xy 411.936306 -118.463782)
			(xy 411.914223 -118.512818) (xy 411.885466 -118.558262) (xy 411.850606 -118.599211) (xy 411.810335 -118.634853)
			(xy 411.765453 -118.66448) (xy 411.716852 -118.687503) (xy 411.691328 -118.695978) (xy 411.685232 -118.69801)
			(xy 411.675072 -118.704106) (xy 411.520894 -118.85803) (xy 411.513528 -118.865142) (xy 411.505908 -118.883938)
			(xy 411.505908 -119.883936) (xy 411.506338 -119.894003) (xy 411.514062 -119.912597) (xy 411.520894 -119.920004)
			(xy 412.958534 -121.357644) (xy 412.965977 -121.364334) (xy 412.984473 -121.371924) (xy 413.004466 -121.371896)
			(xy 413.013906 -121.368566) (xy 413.02813 -121.362724) (xy 413.045148 -121.337324) (xy 413.045148 -120.503696)
			(xy 413.045656 -120.48363) (xy 413.045656 -120.471091) (xy 413.03501 -120.448423) (xy 413.025336 -120.44045)
			(xy 413.004508 -120.422416) (xy 412.99384 -120.41505) (xy 412.993332 -120.41505) (xy 412.985934 -120.41171)
			(xy 412.969879 -120.409385) (xy 412.961836 -120.410478) (xy 412.944963 -120.41333) (xy 412.910876 -120.416383)
			(xy 412.893764 -120.416574) (xy 412.891478 -120.416574) (xy 412.864322 -120.41595) (xy 412.810595 -120.407961)
			(xy 412.758545 -120.392431) (xy 412.709223 -120.369675) (xy 412.663628 -120.340153) (xy 412.622682 -120.304462)
			(xy 412.587213 -120.263324) (xy 412.557937 -120.217571) (xy 412.535447 -120.168128) (xy 412.520198 -120.115994)
			(xy 412.512498 -120.062225) (xy 412.512002 -120.035066) (xy 412.512491 -120.007817) (xy 412.520251 -119.953873)
			(xy 412.535609 -119.901583) (xy 412.558252 -119.852011) (xy 412.58772 -119.806166) (xy 412.623411 -119.76498)
			(xy 412.664601 -119.729293) (xy 412.71045 -119.699831) (xy 412.760024 -119.677194) (xy 412.812316 -119.661842)
			(xy 412.866261 -119.654087) (xy 412.89351 -119.653558) (xy 412.920517 -119.654027) (xy 412.973992 -119.661644)
			(xy 413.025858 -119.676725) (xy 413.07508 -119.698968) (xy 413.120674 -119.72793) (xy 413.161729 -119.76303)
			(xy 413.197424 -119.803569) (xy 413.227048 -119.848736) (xy 413.250007 -119.897628) (xy 413.265842 -119.949269)
			(xy 413.270446 -119.975884) (xy 413.272224 -119.986552) (xy 413.2834 -120.004332) (xy 413.364172 -120.057672)
			(xy 413.384746 -120.061482) (xy 413.395414 -120.058942) (xy 413.421926 -120.05289) (xy 413.475919 -120.046394)
			(xy 413.50311 -120.045988) (xy 413.530299 -120.046425) (xy 413.584289 -120.052921) (xy 413.610806 -120.058942)
			(xy 413.621474 -120.061482) (xy 413.642048 -120.057672) (xy 413.72282 -120.004332) (xy 413.733996 -119.986552)
			(xy 413.735774 -119.975884) (xy 413.740423 -119.949276) (xy 413.756239 -119.897628) (xy 413.779183 -119.848728)
			(xy 413.808796 -119.803554) (xy 413.844485 -119.76301) (xy 413.885538 -119.727905) (xy 413.931132 -119.698944)
			(xy 413.980356 -119.676704) (xy 414.032225 -119.661631) (xy 414.085702 -119.654026) (xy 414.11271 -119.653558)
			(xy 414.140044 -119.654028) (xy 414.194151 -119.661834) (xy 414.24659 -119.677284) (xy 414.296286 -119.700062)
			(xy 414.342221 -119.729701) (xy 414.363154 -119.747284) (xy 414.363662 -119.747792) (xy 414.370747 -119.753384)
			(xy 414.387664 -119.759639) (xy 414.396682 -119.759984) (xy 414.463484 -119.759984) (xy 414.467894 -119.759893)
			(xy 414.476579 -119.758355) (xy 414.480756 -119.756936) (xy 414.490154 -119.753634) (xy 414.497266 -119.747284)
			(xy 414.518194 -119.729696) (xy 414.564133 -119.700065) (xy 414.613831 -119.677295) (xy 414.66627 -119.661852)
			(xy 414.720377 -119.654051) (xy 414.74771 -119.653558) (xy 414.747964 -119.653558) (xy 414.764949 -119.653755)
			(xy 414.798782 -119.656809) (xy 414.815528 -119.659654) (xy 414.826958 -119.661686) (xy 414.849056 -119.65559)
			(xy 414.89122 -119.619268) (xy 414.900364 -119.597932) (xy 414.899856 -119.586248) (xy 414.899348 -119.567198)
			(xy 414.899348 -118.703598) (xy 414.899856 -118.683532) (xy 414.899856 -118.670993) (xy 414.889211 -118.648324)
			(xy 414.879536 -118.640352) (xy 414.858708 -118.622318) (xy 414.84804 -118.614952) (xy 414.847532 -118.614952)
			(xy 414.840134 -118.611612) (xy 414.824079 -118.609287) (xy 414.816036 -118.61038) (xy 414.799163 -118.613232)
			(xy 414.765076 -118.616285) (xy 414.747964 -118.616476) (xy 414.745678 -118.616476) (xy 414.718522 -118.615852)
			(xy 414.664795 -118.607863) (xy 414.612744 -118.592333) (xy 414.563423 -118.569577) (xy 414.517828 -118.540055)
			(xy 414.476881 -118.504364) (xy 414.441412 -118.463226) (xy 414.412136 -118.417473) (xy 414.389646 -118.36803)
			(xy 414.374396 -118.315896) (xy 414.366696 -118.262127) (xy 414.366202 -118.234968) (xy 414.36669 -118.207719)
			(xy 414.374451 -118.153775) (xy 414.389809 -118.101485) (xy 414.412452 -118.051912) (xy 414.441919 -118.006066)
			(xy 414.477611 -117.964881) (xy 414.5188 -117.929194) (xy 414.564649 -117.899732) (xy 414.614224 -117.877094)
			(xy 414.666516 -117.861742) (xy 414.72046 -117.853987) (xy 414.74771 -117.85346) (xy 414.774694 -117.85392)
			(xy 414.828126 -117.861513) (xy 414.879955 -117.876559) (xy 414.929146 -117.898758) (xy 414.974718 -117.927668)
			(xy 415.015762 -117.962711) (xy 415.051458 -118.003187) (xy 415.081094 -118.048291) (xy 415.104078 -118.09712)
			(xy 415.119952 -118.148701) (xy 415.124646 -118.175278) (xy 415.12617 -118.185692) (xy 415.1376 -118.204234)
			(xy 415.209228 -118.251732) (xy 415.213443 -118.254402) (xy 415.222652 -118.258241) (xy 415.227516 -118.259352)
			(xy 415.238946 -118.261384) (xy 415.253558 -118.257549) (xy 415.283173 -118.251576) (xy 415.298128 -118.249446)
			(xy 415.298636 -118.249446) (xy 415.301684 -118.249192) (xy 415.315534 -118.247563) (xy 415.343366 -118.245782)
			(xy 415.35731 -118.245636) (xy 415.375615 -118.245817) (xy 415.412107 -118.248744) (xy 415.430208 -118.251478)
			(xy 415.430462 -118.251478) (xy 415.465006 -118.258844) (xy 415.475674 -118.261384) (xy 415.496248 -118.257828)
			(xy 415.56813 -118.21033) (xy 415.575496 -118.204234) (xy 415.580243 -118.199345) (xy 415.587187 -118.187627)
			(xy 415.589212 -118.18112) (xy 415.593307 -118.155381) (xy 415.607619 -118.105265) (xy 415.628631 -118.057569)
			(xy 415.65595 -118.013183) (xy 415.689066 -117.972936) (xy 415.72736 -117.937581) (xy 415.74847 -117.922294)
			(xy 415.759646 -117.914674) (xy 415.771076 -117.891052) (xy 415.767012 -117.823234) (xy 415.767012 -117.822726)
			(xy 415.765488 -117.791992) (xy 415.764579 -117.782323) (xy 415.756484 -117.764689) (xy 415.74974 -117.757702)
			(xy 415.745168 -117.753384) (xy 415.739072 -117.749828) (xy 415.738564 -117.749574) (xy 415.713293 -117.735053)
			(xy 415.667082 -117.699541) (xy 415.626805 -117.657417) (xy 415.593398 -117.609662) (xy 415.567636 -117.557384)
			(xy 415.550119 -117.501798) (xy 415.541253 -117.444196) (xy 415.540698 -117.415056) (xy 415.541184 -117.387805)
			(xy 415.54894 -117.333857) (xy 415.564295 -117.281562) (xy 415.586937 -117.231985) (xy 415.616403 -117.186135)
			(xy 415.652094 -117.144944) (xy 415.693285 -117.109253) (xy 415.739135 -117.079787) (xy 415.788712 -117.057145)
			(xy 415.841007 -117.04179) (xy 415.894955 -117.034034) (xy 415.949457 -117.034034) (xy 416.003405 -117.04179)
			(xy 416.0557 -117.057145) (xy 416.105277 -117.079787) (xy 416.151127 -117.109253) (xy 416.192318 -117.144944)
			(xy 416.228009 -117.186135) (xy 416.257475 -117.231985) (xy 416.280117 -117.281562) (xy 416.295472 -117.333857)
			(xy 416.303228 -117.387805) (xy 416.303714 -117.415056) (xy 416.303276 -117.441251) (xy 416.296096 -117.493148)
			(xy 416.281878 -117.543573) (xy 416.260891 -117.591576) (xy 416.23353 -117.636255) (xy 416.20031 -117.676767)
			(xy 416.161856 -117.712349) (xy 416.140646 -117.72773) (xy 416.12947 -117.73535) (xy 416.11804 -117.758972)
			(xy 416.122104 -117.82679) (xy 416.122104 -117.827298) (xy 416.123628 -117.858032) (xy 416.124541 -117.867698)
			(xy 416.132644 -117.885325) (xy 416.139376 -117.892322) (xy 416.143948 -117.89664) (xy 416.150044 -117.900196)
			(xy 416.150552 -117.90045) (xy 416.175821 -117.914972) (xy 416.222028 -117.950486) (xy 416.262301 -117.992611)
			(xy 416.295704 -118.040366) (xy 416.321461 -118.092644) (xy 416.338974 -118.148228) (xy 416.347836 -118.205829)
			(xy 416.348418 -118.234968) (xy 416.347957 -118.262223) (xy 416.340204 -118.316178) (xy 416.324851 -118.36848)
			(xy 416.323765 -118.370858) (xy 417.566602 -118.370858) (xy 417.567092 -118.342073) (xy 417.575748 -118.285159)
			(xy 417.592856 -118.23019) (xy 417.618028 -118.178416) (xy 417.650692 -118.131011) (xy 417.690109 -118.089052)
			(xy 417.735381 -118.053491) (xy 417.785482 -118.025135) (xy 417.839275 -118.004628) (xy 417.895539 -117.992436)
			(xy 417.924234 -117.990112) (xy 417.924488 -117.990112) (xy 417.936218 -117.988678) (xy 417.956598 -117.976768)
			(xy 417.963604 -117.967252) (xy 418.014658 -117.88902) (xy 418.017452 -117.865652) (xy 418.013134 -117.854222)
			(xy 418.002487 -117.822768) (xy 417.99099 -117.757373) (xy 417.990274 -117.724174) (xy 417.990274 -117.723666)
			(xy 417.99076 -117.696415) (xy 417.998516 -117.642467) (xy 418.013871 -117.590172) (xy 418.036513 -117.540595)
			(xy 418.065979 -117.494745) (xy 418.10167 -117.453554) (xy 418.142861 -117.417863) (xy 418.188711 -117.388397)
			(xy 418.238288 -117.365755) (xy 418.290583 -117.3504) (xy 418.344531 -117.342644) (xy 418.399033 -117.342644)
			(xy 418.452981 -117.3504) (xy 418.505276 -117.365755) (xy 418.554853 -117.388397) (xy 418.600703 -117.417863)
			(xy 418.641894 -117.453554) (xy 418.677585 -117.494745) (xy 418.707051 -117.540595) (xy 418.729693 -117.590172)
			(xy 418.745048 -117.642467) (xy 418.752804 -117.696415) (xy 418.75329 -117.723666) (xy 418.752829 -117.752452)
			(xy 418.74417 -117.809368) (xy 418.727059 -117.864337) (xy 418.701883 -117.916112) (xy 418.669215 -117.963517)
			(xy 418.629795 -118.005476) (xy 418.58452 -118.041037) (xy 418.534416 -118.069392) (xy 418.48062 -118.089898)
			(xy 418.424354 -118.102089) (xy 418.395658 -118.104412) (xy 418.395404 -118.104412) (xy 418.383671 -118.105833)
			(xy 418.363291 -118.117751) (xy 418.356288 -118.127272) (xy 418.305234 -118.20525) (xy 418.30244 -118.228872)
			(xy 418.304607 -118.234968) (xy 420.185086 -118.234968) (xy 420.189157 -118.179346) (xy 420.201283 -118.124909)
			(xy 420.221206 -118.072818) (xy 420.248502 -118.024183) (xy 420.282588 -117.98004) (xy 420.322737 -117.941331)
			(xy 420.368095 -117.90888) (xy 420.417695 -117.883379) (xy 420.470479 -117.865372) (xy 420.525322 -117.855242)
			(xy 420.581056 -117.853205) (xy 420.636493 -117.859305) (xy 420.69045 -117.873411) (xy 420.741779 -117.895223)
			(xy 420.789385 -117.924277) (xy 420.832253 -117.959952) (xy 420.86947 -118.001489) (xy 420.900243 -118.048002)
			(xy 420.923915 -118.098499) (xy 420.939983 -118.151906) (xy 420.948103 -118.207082) (xy 420.948612 -118.234968)
			(xy 420.948114 -118.262255) (xy 422.167223 -118.262255) (xy 422.167223 -118.207745) (xy 422.174981 -118.153789)
			(xy 422.190338 -118.101486) (xy 422.212983 -118.051902) (xy 422.242454 -118.006044) (xy 422.278151 -117.964848)
			(xy 422.319348 -117.929151) (xy 422.365205 -117.899681) (xy 422.41479 -117.877037) (xy 422.467093 -117.86168)
			(xy 422.521049 -117.853923) (xy 422.548304 -117.85346) (xy 422.548812 -117.85346) (xy 422.573678 -117.853882)
			(xy 422.622984 -117.860379) (xy 422.64711 -117.866414) (xy 422.647364 -117.866414) (xy 422.658864 -117.86888)
			(xy 422.681897 -117.864232) (xy 422.69156 -117.857524) (xy 422.76522 -117.799866) (xy 422.775634 -117.777768)
			(xy 422.775126 -117.765322) (xy 422.774872 -117.759226) (xy 422.774872 -116.895626) (xy 422.776142 -116.861844)
			(xy 422.777158 -116.848636) (xy 422.76649 -116.825268) (xy 422.720262 -116.791232) (xy 422.694862 -116.787676)
			(xy 422.68267 -116.792248) (xy 422.650303 -116.803576) (xy 422.582841 -116.81584) (xy 422.548558 -116.816632)
			(xy 422.548304 -116.816632) (xy 422.521053 -116.816121) (xy 422.467105 -116.808365) (xy 422.41481 -116.79301)
			(xy 422.365232 -116.770369) (xy 422.319381 -116.740903) (xy 422.278191 -116.705212) (xy 422.242499 -116.664022)
			(xy 422.213033 -116.618171) (xy 422.190391 -116.568594) (xy 422.175036 -116.516299) (xy 422.167279 -116.462351)
			(xy 422.167279 -116.407849) (xy 422.175036 -116.353901) (xy 422.190391 -116.301606) (xy 422.213033 -116.252029)
			(xy 422.242499 -116.206178) (xy 422.278191 -116.164988) (xy 422.319381 -116.129297) (xy 422.365232 -116.099831)
			(xy 422.41481 -116.07719) (xy 422.467105 -116.061835) (xy 422.521053 -116.054079) (xy 422.548304 -116.053616)
			(xy 422.575893 -116.054153) (xy 422.630493 -116.062116) (xy 422.683377 -116.077861) (xy 422.733441 -116.10106)
			(xy 422.779641 -116.131228) (xy 422.821014 -116.167737) (xy 422.856696 -116.209825) (xy 422.885944 -116.256614)
			(xy 422.908146 -116.307128) (xy 422.922841 -116.360313) (xy 422.926764 -116.387626) (xy 422.928288 -116.39931)
			(xy 422.939669 -116.416836) (xy 435.560722 -116.416836) (xy 435.564793 -116.361214) (xy 435.576919 -116.306777)
			(xy 435.596842 -116.254686) (xy 435.624138 -116.206051) (xy 435.658224 -116.161908) (xy 435.698373 -116.123199)
			(xy 435.743731 -116.090748) (xy 435.793331 -116.065247) (xy 435.846115 -116.04724) (xy 435.900958 -116.03711)
			(xy 435.956692 -116.035073) (xy 436.012129 -116.041173) (xy 436.066086 -116.055279) (xy 436.117415 -116.077091)
			(xy 436.165021 -116.106145) (xy 436.207889 -116.14182) (xy 436.245106 -116.183357) (xy 436.275879 -116.22987)
			(xy 436.299551 -116.280367) (xy 436.315619 -116.333774) (xy 436.323739 -116.38895) (xy 436.324248 -116.416836)
			(xy 436.323739 -116.444722) (xy 436.315619 -116.499898) (xy 436.299551 -116.553305) (xy 436.275879 -116.603802)
			(xy 436.245106 -116.650315) (xy 436.22763 -116.66982) (xy 437.67324 -116.66982) (xy 437.677311 -116.614198)
			(xy 437.689437 -116.559761) (xy 437.70936 -116.50767) (xy 437.736656 -116.459035) (xy 437.770742 -116.414892)
			(xy 437.810891 -116.376183) (xy 437.856249 -116.343732) (xy 437.905849 -116.318231) (xy 437.958633 -116.300224)
			(xy 438.013476 -116.290094) (xy 438.06921 -116.288057) (xy 438.124647 -116.294157) (xy 438.178604 -116.308263)
			(xy 438.229933 -116.330075) (xy 438.277539 -116.359129) (xy 438.320407 -116.394804) (xy 438.334458 -116.410486)
			(xy 443.447168 -116.410486) (xy 443.451239 -116.354864) (xy 443.463365 -116.300427) (xy 443.483288 -116.248336)
			(xy 443.510584 -116.199701) (xy 443.54467 -116.155558) (xy 443.584819 -116.116849) (xy 443.630177 -116.084398)
			(xy 443.679777 -116.058897) (xy 443.732561 -116.04089) (xy 443.787404 -116.03076) (xy 443.843138 -116.028723)
			(xy 443.898575 -116.034823) (xy 443.952532 -116.048929) (xy 444.003861 -116.070741) (xy 444.051467 -116.099795)
			(xy 444.094335 -116.13547) (xy 444.131552 -116.177007) (xy 444.162325 -116.22352) (xy 444.185997 -116.274017)
			(xy 444.202065 -116.327424) (xy 444.210185 -116.3826) (xy 444.210694 -116.410486) (xy 444.210185 -116.438372)
			(xy 444.202065 -116.493548) (xy 444.185997 -116.546955) (xy 444.162325 -116.597452) (xy 444.141334 -116.62918)
			(xy 453.438004 -116.62918) (xy 453.442075 -116.573558) (xy 453.454201 -116.519121) (xy 453.474124 -116.46703)
			(xy 453.50142 -116.418395) (xy 453.535506 -116.374252) (xy 453.575655 -116.335543) (xy 453.621013 -116.303092)
			(xy 453.670613 -116.277591) (xy 453.723397 -116.259584) (xy 453.77824 -116.249454) (xy 453.833974 -116.247417)
			(xy 453.889411 -116.253517) (xy 453.943368 -116.267623) (xy 453.994697 -116.289435) (xy 454.042303 -116.318489)
			(xy 454.085171 -116.354164) (xy 454.122388 -116.395701) (xy 454.153161 -116.442214) (xy 454.176833 -116.492711)
			(xy 454.192901 -116.546118) (xy 454.201021 -116.601294) (xy 454.20153 -116.62918) (xy 454.201021 -116.657066)
			(xy 454.192901 -116.712242) (xy 454.176833 -116.765649) (xy 454.153161 -116.816146) (xy 454.122388 -116.862659)
			(xy 454.085171 -116.904196) (xy 454.042303 -116.939871) (xy 453.994697 -116.968925) (xy 453.943368 -116.990737)
			(xy 453.889411 -117.004843) (xy 453.833974 -117.010943) (xy 453.77824 -117.008906) (xy 453.723397 -116.998776)
			(xy 453.670613 -116.980769) (xy 453.621013 -116.955268) (xy 453.575655 -116.922817) (xy 453.535506 -116.884108)
			(xy 453.50142 -116.839965) (xy 453.474124 -116.79133) (xy 453.454201 -116.739239) (xy 453.442075 -116.684802)
			(xy 453.438004 -116.62918) (xy 444.141334 -116.62918) (xy 444.131552 -116.643965) (xy 444.094335 -116.685502)
			(xy 444.051467 -116.721177) (xy 444.003861 -116.750231) (xy 443.952532 -116.772043) (xy 443.898575 -116.786149)
			(xy 443.843138 -116.792249) (xy 443.787404 -116.790212) (xy 443.732561 -116.780082) (xy 443.679777 -116.762075)
			(xy 443.630177 -116.736574) (xy 443.584819 -116.704123) (xy 443.54467 -116.665414) (xy 443.510584 -116.621271)
			(xy 443.483288 -116.572636) (xy 443.463365 -116.520545) (xy 443.451239 -116.466108) (xy 443.447168 -116.410486)
			(xy 438.334458 -116.410486) (xy 438.357624 -116.436341) (xy 438.388397 -116.482854) (xy 438.412069 -116.533351)
			(xy 438.428137 -116.586758) (xy 438.436257 -116.641934) (xy 438.436766 -116.66982) (xy 438.436257 -116.697706)
			(xy 438.428137 -116.752882) (xy 438.412069 -116.806289) (xy 438.388397 -116.856786) (xy 438.357624 -116.903299)
			(xy 438.320407 -116.944836) (xy 438.277539 -116.980511) (xy 438.229933 -117.009565) (xy 438.178604 -117.031377)
			(xy 438.124647 -117.045483) (xy 438.06921 -117.051583) (xy 438.013476 -117.049546) (xy 437.958633 -117.039416)
			(xy 437.905849 -117.021409) (xy 437.856249 -116.995908) (xy 437.810891 -116.963457) (xy 437.770742 -116.924748)
			(xy 437.736656 -116.880605) (xy 437.70936 -116.83197) (xy 437.689437 -116.779879) (xy 437.677311 -116.725442)
			(xy 437.67324 -116.66982) (xy 436.22763 -116.66982) (xy 436.207889 -116.691852) (xy 436.165021 -116.727527)
			(xy 436.117415 -116.756581) (xy 436.066086 -116.778393) (xy 436.012129 -116.792499) (xy 435.956692 -116.798599)
			(xy 435.900958 -116.796562) (xy 435.846115 -116.786432) (xy 435.793331 -116.768425) (xy 435.743731 -116.742924)
			(xy 435.698373 -116.710473) (xy 435.658224 -116.671764) (xy 435.624138 -116.627621) (xy 435.596842 -116.578986)
			(xy 435.576919 -116.526895) (xy 435.564793 -116.472458) (xy 435.560722 -116.416836) (xy 422.939669 -116.416836)
			(xy 422.940988 -116.418868) (xy 423.020236 -116.466112) (xy 423.030502 -116.471574) (xy 423.053644 -116.473566)
			(xy 423.064686 -116.469922) (xy 423.064686 -116.469668) (xy 423.065194 -116.469668) (xy 423.091978 -116.459566)
			(xy 423.147424 -116.445337) (xy 423.204213 -116.438137) (xy 423.232834 -116.437664) (xy 423.26282 -116.438096)
			(xy 423.322279 -116.445929) (xy 423.380207 -116.461455) (xy 423.435612 -116.484409) (xy 423.487548 -116.514399)
			(xy 423.535125 -116.550911) (xy 423.577529 -116.593321) (xy 423.614035 -116.640902) (xy 423.644017 -116.692842)
			(xy 423.666965 -116.74825) (xy 423.682483 -116.80618) (xy 423.690308 -116.86564) (xy 423.690796 -116.895626)
			(xy 423.690796 -117.102636) (xy 441.279278 -117.102636) (xy 441.283349 -117.047014) (xy 441.295475 -116.992577)
			(xy 441.315398 -116.940486) (xy 441.342694 -116.891851) (xy 441.37678 -116.847708) (xy 441.416929 -116.808999)
			(xy 441.462287 -116.776548) (xy 441.511887 -116.751047) (xy 441.564671 -116.73304) (xy 441.619514 -116.72291)
			(xy 441.675248 -116.720873) (xy 441.730685 -116.726973) (xy 441.784642 -116.741079) (xy 441.835971 -116.762891)
			(xy 441.883577 -116.791945) (xy 441.926445 -116.82762) (xy 441.963662 -116.869157) (xy 441.994435 -116.91567)
			(xy 442.018107 -116.966167) (xy 442.034175 -117.019574) (xy 442.042295 -117.07475) (xy 442.042804 -117.102636)
			(xy 442.042295 -117.130522) (xy 442.034175 -117.185698) (xy 442.018107 -117.239105) (xy 441.994435 -117.289602)
			(xy 441.963662 -117.336115) (xy 441.926445 -117.377652) (xy 441.883577 -117.413327) (xy 441.862016 -117.426486)
			(xy 443.447168 -117.426486) (xy 443.451239 -117.370864) (xy 443.463365 -117.316427) (xy 443.483288 -117.264336)
			(xy 443.510584 -117.215701) (xy 443.54467 -117.171558) (xy 443.584819 -117.132849) (xy 443.630177 -117.100398)
			(xy 443.679777 -117.074897) (xy 443.732561 -117.05689) (xy 443.787404 -117.04676) (xy 443.843138 -117.044723)
			(xy 443.898575 -117.050823) (xy 443.952532 -117.064929) (xy 444.003861 -117.086741) (xy 444.051467 -117.115795)
			(xy 444.094335 -117.15147) (xy 444.131552 -117.193007) (xy 444.162325 -117.23952) (xy 444.185997 -117.290017)
			(xy 444.202065 -117.343424) (xy 444.210185 -117.3986) (xy 444.210694 -117.426486) (xy 444.210185 -117.454372)
			(xy 444.202065 -117.509548) (xy 444.185997 -117.562955) (xy 444.162325 -117.613452) (xy 444.131552 -117.659965)
			(xy 444.094335 -117.701502) (xy 444.051467 -117.737177) (xy 444.003861 -117.766231) (xy 443.952532 -117.788043)
			(xy 443.898575 -117.802149) (xy 443.843138 -117.808249) (xy 443.787404 -117.806212) (xy 443.732561 -117.796082)
			(xy 443.679777 -117.778075) (xy 443.630177 -117.752574) (xy 443.584819 -117.720123) (xy 443.54467 -117.681414)
			(xy 443.510584 -117.637271) (xy 443.483288 -117.588636) (xy 443.463365 -117.536545) (xy 443.451239 -117.482108)
			(xy 443.447168 -117.426486) (xy 441.862016 -117.426486) (xy 441.835971 -117.442381) (xy 441.784642 -117.464193)
			(xy 441.730685 -117.478299) (xy 441.675248 -117.484399) (xy 441.619514 -117.482362) (xy 441.564671 -117.472232)
			(xy 441.511887 -117.454225) (xy 441.462287 -117.428724) (xy 441.416929 -117.396273) (xy 441.37678 -117.357564)
			(xy 441.342694 -117.313421) (xy 441.315398 -117.264786) (xy 441.295475 -117.212695) (xy 441.283349 -117.158258)
			(xy 441.279278 -117.102636) (xy 423.690796 -117.102636) (xy 423.690796 -117.759226) (xy 423.690296 -117.789209)
			(xy 423.682466 -117.848663) (xy 423.666944 -117.906586) (xy 423.643994 -117.961988) (xy 423.61401 -118.01392)
			(xy 423.577504 -118.061495) (xy 423.535101 -118.103899) (xy 423.487527 -118.140405) (xy 423.435595 -118.17039)
			(xy 423.380194 -118.193341) (xy 423.322271 -118.208865) (xy 423.262817 -118.216696) (xy 423.232834 -118.217188)
			(xy 423.204398 -118.216753) (xy 423.147967 -118.209669) (xy 423.092847 -118.195656) (xy 423.06621 -118.185692)
			(xy 423.054973 -118.181919) (xy 423.031391 -118.184053) (xy 423.020998 -118.189756) (xy 422.94175 -118.238778)
			(xy 422.929304 -118.258844) (xy 422.928034 -118.270782) (xy 422.92496 -118.298802) (xy 422.911482 -118.353537)
			(xy 422.890093 -118.405691) (xy 422.861261 -118.454129) (xy 422.825613 -118.497795) (xy 422.783926 -118.535738)
			(xy 422.737107 -118.567132) (xy 422.686178 -118.591292) (xy 422.632247 -118.607693) (xy 422.576489 -118.615976)
			(xy 422.548304 -118.616476) (xy 422.521049 -118.616077) (xy 422.467093 -118.60832) (xy 422.41479 -118.592963)
			(xy 422.365205 -118.570319) (xy 422.319348 -118.540849) (xy 422.278151 -118.505152) (xy 422.242454 -118.463956)
			(xy 422.212983 -118.418098) (xy 422.190338 -118.368514) (xy 422.174981 -118.316211) (xy 422.167223 -118.262255)
			(xy 420.948114 -118.262255) (xy 420.948103 -118.262854) (xy 420.939983 -118.31803) (xy 420.923915 -118.371437)
			(xy 420.900243 -118.421934) (xy 420.86947 -118.468447) (xy 420.832253 -118.509984) (xy 420.789385 -118.545659)
			(xy 420.741779 -118.574713) (xy 420.69045 -118.596525) (xy 420.636493 -118.610631) (xy 420.581056 -118.616731)
			(xy 420.525322 -118.614694) (xy 420.470479 -118.604564) (xy 420.417695 -118.586557) (xy 420.368095 -118.561056)
			(xy 420.322737 -118.528605) (xy 420.282588 -118.489896) (xy 420.248502 -118.445753) (xy 420.221206 -118.397118)
			(xy 420.201283 -118.345027) (xy 420.189157 -118.29059) (xy 420.185086 -118.234968) (xy 418.304607 -118.234968)
			(xy 418.306504 -118.240302) (xy 418.314124 -118.263162) (xy 418.316664 -118.272306) (xy 418.32784 -118.287038)
			(xy 418.401246 -118.333012) (xy 418.41928 -118.336568) (xy 418.428678 -118.335044) (xy 418.444245 -118.33257)
			(xy 418.475655 -118.329899) (xy 418.491416 -118.32971) (xy 418.518668 -118.330161) (xy 418.572616 -118.33792)
			(xy 418.624912 -118.353277) (xy 418.674489 -118.37592) (xy 418.72034 -118.405388) (xy 418.76153 -118.441081)
			(xy 418.797221 -118.482273) (xy 418.826688 -118.528125) (xy 418.849329 -118.577703) (xy 418.864684 -118.629999)
			(xy 418.87244 -118.683948) (xy 418.87244 -118.738452) (xy 418.864684 -118.792401) (xy 418.849329 -118.844697)
			(xy 418.826688 -118.894275) (xy 418.797221 -118.940127) (xy 418.76153 -118.981319) (xy 418.72034 -119.017012)
			(xy 418.674489 -119.04648) (xy 418.624912 -119.069123) (xy 418.572616 -119.08448) (xy 418.518668 -119.092239)
			(xy 418.491416 -119.092726) (xy 418.464168 -119.09218) (xy 418.410229 -119.084415) (xy 418.357943 -119.069055)
			(xy 418.308374 -119.046412) (xy 418.262531 -119.016947) (xy 418.221347 -118.98126) (xy 418.185659 -118.940076)
			(xy 418.156193 -118.894234) (xy 418.133548 -118.844666) (xy 418.125402 -118.81866) (xy 418.122862 -118.80977)
			(xy 418.111686 -118.795038) (xy 418.03828 -118.749064) (xy 418.020246 -118.745508) (xy 418.010848 -118.747032)
			(xy 417.99528 -118.749502) (xy 417.963871 -118.752176) (xy 417.94811 -118.752366) (xy 417.920855 -118.751935)
			(xy 417.866901 -118.744179) (xy 417.8146 -118.728822) (xy 417.765017 -118.706177) (xy 417.719162 -118.676706)
			(xy 417.677968 -118.641009) (xy 417.642274 -118.599812) (xy 417.612807 -118.553955) (xy 417.590167 -118.50437)
			(xy 417.574815 -118.452067) (xy 417.567062 -118.398113) (xy 417.566602 -118.370858) (xy 416.323765 -118.370858)
			(xy 416.30221 -118.418065) (xy 416.272743 -118.463923) (xy 416.23705 -118.50512) (xy 416.195856 -118.540818)
			(xy 416.150002 -118.57029) (xy 416.100419 -118.592936) (xy 416.048119 -118.608295) (xy 415.994165 -118.616054)
			(xy 415.96691 -118.616476) (xy 415.966656 -118.616476) (xy 415.95019 -118.616325) (xy 415.917378 -118.613529)
			(xy 415.901124 -118.610888) (xy 415.898838 -118.61038) (xy 415.893758 -118.609872) (xy 415.883705 -118.609619)
			(xy 415.864627 -118.615908) (xy 415.856674 -118.622064) (xy 415.8234 -118.650766) (xy 415.814256 -118.672102)
			(xy 415.814764 -118.683786) (xy 415.815272 -118.703598) (xy 415.815272 -119.441722) (xy 419.609775 -119.441722)
			(xy 419.609779 -119.387219) (xy 419.61754 -119.333271) (xy 419.6329 -119.280977) (xy 419.655545 -119.231401)
			(xy 419.685016 -119.185552) (xy 419.720711 -119.144365) (xy 419.761905 -119.108676) (xy 419.807759 -119.079214)
			(xy 419.857339 -119.056577) (xy 419.909636 -119.041226) (xy 419.963585 -119.033475) (xy 420.018088 -119.03348)
			(xy 420.072036 -119.041242) (xy 420.12433 -119.056602) (xy 420.173905 -119.079249) (xy 420.219753 -119.10872)
			(xy 420.260941 -119.144417) (xy 420.296628 -119.185611) (xy 420.32609 -119.231465) (xy 420.348726 -119.281046)
			(xy 420.364075 -119.333343) (xy 420.371826 -119.387292) (xy 420.372286 -119.414544) (xy 420.372286 -119.415052)
			(xy 420.371684 -119.445494) (xy 420.361985 -119.5056) (xy 420.352982 -119.534686) (xy 420.349128 -119.547705)
			(xy 420.347749 -119.574814) (xy 420.353562 -119.601328) (xy 420.366156 -119.625373) (xy 420.384641 -119.64525)
			(xy 420.40771 -119.659553) (xy 420.433732 -119.667273) (xy 420.460869 -119.667863) (xy 420.47414 -119.664988)
			(xy 420.496883 -119.659663) (xy 420.543241 -119.653928) (xy 420.566596 -119.653558) (xy 420.567104 -119.653558)
			(xy 420.594357 -119.65406) (xy 420.648308 -119.661817) (xy 420.700606 -119.677174) (xy 420.750186 -119.699818)
			(xy 420.796039 -119.729287) (xy 420.837231 -119.764982) (xy 420.872924 -119.806175) (xy 420.902391 -119.85203)
			(xy 420.925032 -119.901611) (xy 420.940386 -119.953909) (xy 420.948142 -120.007861) (xy 420.948141 -120.035066)
			(xy 422.166286 -120.035066) (xy 422.170357 -119.979444) (xy 422.182483 -119.925007) (xy 422.202406 -119.872916)
			(xy 422.229702 -119.824281) (xy 422.263788 -119.780138) (xy 422.303937 -119.741429) (xy 422.349295 -119.708978)
			(xy 422.398895 -119.683477) (xy 422.451679 -119.66547) (xy 422.506522 -119.65534) (xy 422.562256 -119.653303)
			(xy 422.617693 -119.659403) (xy 422.67165 -119.673509) (xy 422.722979 -119.695321) (xy 422.770585 -119.724375)
			(xy 422.813453 -119.76005) (xy 422.85067 -119.801587) (xy 422.881443 -119.8481) (xy 422.905115 -119.898597)
			(xy 422.921183 -119.952004) (xy 422.929303 -120.00718) (xy 422.929812 -120.035066) (xy 422.929303 -120.062952)
			(xy 422.921183 -120.118128) (xy 422.905115 -120.171535) (xy 422.881443 -120.222032) (xy 422.85067 -120.268545)
			(xy 422.813453 -120.310082) (xy 422.770585 -120.345757) (xy 422.722979 -120.374811) (xy 422.67165 -120.396623)
			(xy 422.617693 -120.410729) (xy 422.562256 -120.416829) (xy 422.506522 -120.414792) (xy 422.451679 -120.404662)
			(xy 422.398895 -120.386655) (xy 422.349295 -120.361154) (xy 422.303937 -120.328703) (xy 422.263788 -120.289994)
			(xy 422.229702 -120.245851) (xy 422.202406 -120.197216) (xy 422.182483 -120.145125) (xy 422.170357 -120.090688)
			(xy 422.166286 -120.035066) (xy 420.948141 -120.035066) (xy 420.94814 -120.062367) (xy 420.940381 -120.116318)
			(xy 420.925022 -120.168615) (xy 420.902377 -120.218195) (xy 420.872907 -120.264047) (xy 420.837211 -120.305238)
			(xy 420.796016 -120.34093) (xy 420.750162 -120.370396) (xy 420.70058 -120.393036) (xy 420.648281 -120.408389)
			(xy 420.594329 -120.416142) (xy 420.539823 -120.416139) (xy 420.485872 -120.408378) (xy 420.433575 -120.393019)
			(xy 420.383996 -120.370373) (xy 420.338145 -120.340901) (xy 420.296955 -120.305204) (xy 420.261264 -120.264008)
			(xy 420.2318 -120.218153) (xy 420.209161 -120.16857) (xy 420.193809 -120.116271) (xy 420.186057 -120.062319)
			(xy 420.185596 -120.035066) (xy 420.185596 -120.034558) (xy 420.186201 -120.004116) (xy 420.195898 -119.94401)
			(xy 420.2049 -119.914924) (xy 420.208764 -119.901906) (xy 420.210146 -119.874795) (xy 420.204334 -119.848278)
			(xy 420.191739 -119.82423) (xy 420.173252 -119.804352) (xy 420.15018 -119.790048) (xy 420.124154 -119.78233)
			(xy 420.097014 -119.781744) (xy 420.083742 -119.784622) (xy 420.061 -119.789951) (xy 420.014641 -119.795683)
			(xy 419.991286 -119.796052) (xy 419.990778 -119.796052) (xy 419.963526 -119.795521) (xy 419.909578 -119.787761)
			(xy 419.857284 -119.772403) (xy 419.807707 -119.749758) (xy 419.761858 -119.720289) (xy 419.72067 -119.684594)
			(xy 419.684981 -119.643401) (xy 419.655517 -119.597547) (xy 419.632879 -119.547968) (xy 419.617528 -119.495671)
			(xy 419.609775 -119.441722) (xy 415.815272 -119.441722) (xy 415.815272 -119.567198) (xy 415.814764 -119.585486)
			(xy 415.814764 -119.588788) (xy 415.815301 -119.599808) (xy 415.824512 -119.619832) (xy 415.832544 -119.627396)
			(xy 415.848292 -119.640858) (xy 415.849054 -119.64162) (xy 415.85642 -119.64797) (xy 415.865464 -119.654969)
			(xy 415.887484 -119.661027) (xy 415.898838 -119.659654) (xy 415.915648 -119.65681) (xy 415.949608 -119.653757)
			(xy 415.966656 -119.653558) (xy 415.968942 -119.653558) (xy 415.996099 -119.654183) (xy 416.049827 -119.662174)
			(xy 416.101879 -119.677705) (xy 416.151203 -119.700461) (xy 416.1968 -119.729982) (xy 416.237749 -119.765672)
			(xy 416.273223 -119.806809) (xy 416.302504 -119.852561) (xy 416.325001 -119.902003) (xy 416.340257 -119.954136)
			(xy 416.347966 -120.007906) (xy 416.348418 -120.035066) (xy 416.347957 -120.062321) (xy 416.340204 -120.116276)
			(xy 416.324851 -120.168578) (xy 416.302211 -120.218164) (xy 416.272744 -120.264022) (xy 416.237051 -120.305219)
			(xy 416.195857 -120.340918) (xy 416.150002 -120.37039) (xy 416.10042 -120.393036) (xy 416.048119 -120.408395)
			(xy 415.994165 -120.416154) (xy 415.96691 -120.416574) (xy 415.93996 -120.41611) (xy 415.886596 -120.408522)
			(xy 415.834832 -120.393496) (xy 415.7857 -120.371331) (xy 415.740178 -120.34247) (xy 415.699173 -120.307486)
			(xy 415.663502 -120.267078) (xy 415.633876 -120.22205) (xy 415.610885 -120.173298) (xy 415.594987 -120.121796)
			(xy 415.590228 -120.095264) (xy 415.590228 -120.09501) (xy 415.58845 -120.084088) (xy 415.582608 -120.075198)
			(xy 415.579686 -120.070888) (xy 415.572388 -120.063463) (xy 415.56813 -120.060466) (xy 415.496502 -120.012968)
			(xy 415.475928 -120.009412) (xy 415.465514 -120.011952) (xy 415.438882 -120.018082) (xy 415.384634 -120.0247)
			(xy 415.35731 -120.02516) (xy 415.329986 -120.0247) (xy 415.27574 -120.018072) (xy 415.249106 -120.011952)
			(xy 415.238692 -120.009412) (xy 415.218118 -120.012968) (xy 415.14649 -120.060466) (xy 415.142237 -120.063469)
			(xy 415.134949 -120.070899) (xy 415.132012 -120.075198) (xy 415.12617 -120.084088) (xy 415.124392 -120.09501)
			(xy 415.124392 -120.095264) (xy 415.119677 -120.121802) (xy 415.10376 -120.173298) (xy 415.080754 -120.222042)
			(xy 415.051118 -120.267063) (xy 415.015441 -120.307465) (xy 414.974434 -120.342445) (xy 414.928912 -120.371307)
			(xy 414.879782 -120.393475) (xy 414.828021 -120.408509) (xy 414.77466 -120.416109) (xy 414.74771 -120.416574)
			(xy 414.720376 -120.416105) (xy 414.666267 -120.408303) (xy 414.613825 -120.392856) (xy 414.564126 -120.370081)
			(xy 414.518188 -120.340445) (xy 414.497266 -120.322848) (xy 414.496758 -120.32234) (xy 414.489675 -120.316743)
			(xy 414.472758 -120.310476) (xy 414.463738 -120.310148) (xy 414.396936 -120.310148) (xy 414.392526 -120.310237)
			(xy 414.38384 -120.311773) (xy 414.379664 -120.313196) (xy 414.370266 -120.316498) (xy 414.363154 -120.322848)
			(xy 414.342226 -120.340436) (xy 414.296287 -120.370066) (xy 414.246589 -120.392837) (xy 414.19415 -120.408282)
			(xy 414.140043 -120.416085) (xy 414.11271 -120.416574) (xy 414.112456 -120.416574) (xy 414.09599 -120.416423)
			(xy 414.063178 -120.413627) (xy 414.046924 -120.410986) (xy 414.044638 -120.410478) (xy 414.039558 -120.40997)
			(xy 414.029505 -120.409717) (xy 414.010427 -120.416006) (xy 414.002474 -120.422162) (xy 413.9692 -120.450864)
			(xy 413.960056 -120.4722) (xy 413.960564 -120.483884) (xy 413.961072 -120.503696) (xy 413.961072 -120.716548)
			(xy 417.60216 -120.716548) (xy 417.606231 -120.660926) (xy 417.618357 -120.606489) (xy 417.63828 -120.554398)
			(xy 417.665576 -120.505763) (xy 417.699662 -120.46162) (xy 417.739811 -120.422911) (xy 417.785169 -120.39046)
			(xy 417.834769 -120.364959) (xy 417.887553 -120.346952) (xy 417.942396 -120.336822) (xy 417.99813 -120.334785)
			(xy 418.053567 -120.340885) (xy 418.107524 -120.354991) (xy 418.158853 -120.376803) (xy 418.206459 -120.405857)
			(xy 418.249327 -120.441532) (xy 418.286544 -120.483069) (xy 418.317317 -120.529582) (xy 418.340989 -120.580079)
			(xy 418.357057 -120.633486) (xy 418.365177 -120.688662) (xy 418.365686 -120.716548) (xy 418.365177 -120.744434)
			(xy 418.357057 -120.79961) (xy 418.340989 -120.853017) (xy 418.317317 -120.903514) (xy 418.286544 -120.950027)
			(xy 418.249327 -120.991564) (xy 418.206459 -121.027239) (xy 418.158853 -121.056293) (xy 418.107524 -121.078105)
			(xy 418.053567 -121.092211) (xy 417.99813 -121.098311) (xy 417.942396 -121.096274) (xy 417.887553 -121.086144)
			(xy 417.834769 -121.068137) (xy 417.785169 -121.042636) (xy 417.739811 -121.010185) (xy 417.699662 -120.971476)
			(xy 417.665576 -120.927333) (xy 417.63828 -120.878698) (xy 417.618357 -120.826607) (xy 417.606231 -120.77217)
			(xy 417.60216 -120.716548) (xy 413.961072 -120.716548) (xy 413.961072 -121.367296) (xy 413.960564 -121.385584)
			(xy 413.960564 -121.388886) (xy 413.961101 -121.399907) (xy 413.970312 -121.419931) (xy 413.978344 -121.427494)
			(xy 413.994092 -121.440956) (xy 413.994854 -121.441718) (xy 414.00222 -121.448068) (xy 414.011264 -121.455067)
			(xy 414.033284 -121.461126) (xy 414.044638 -121.459752) (xy 414.061448 -121.456908) (xy 414.095408 -121.453855)
			(xy 414.112456 -121.453656) (xy 414.114742 -121.453656) (xy 414.125502 -121.453825) (xy 414.146977 -121.455223)
			(xy 414.157668 -121.45645) (xy 414.185951 -121.460314) (xy 414.240999 -121.475419) (xy 414.293174 -121.498575)
			(xy 414.341305 -121.529264) (xy 414.363154 -121.547636) (xy 414.363662 -121.54789) (xy 414.370747 -121.553482)
			(xy 414.387664 -121.559738) (xy 414.396682 -121.560082) (xy 414.463484 -121.560082) (xy 414.467894 -121.559991)
			(xy 414.476579 -121.558453) (xy 414.480756 -121.557034) (xy 414.490154 -121.553732) (xy 414.497266 -121.547382)
			(xy 414.518194 -121.529794) (xy 414.564133 -121.500164) (xy 414.613831 -121.477394) (xy 414.66627 -121.46195)
			(xy 414.720377 -121.454149) (xy 414.74771 -121.453656) (xy 414.760448 -121.453735) (xy 414.785869 -121.455389)
			(xy 414.79851 -121.456958) (xy 414.825331 -121.461046) (xy 414.877534 -121.475817) (xy 414.927121 -121.497828)
			(xy 414.973093 -121.526635) (xy 415.014525 -121.56166) (xy 415.050583 -121.602196) (xy 415.08054 -121.647428)
			(xy 415.103794 -121.696444) (xy 415.119875 -121.748258) (xy 415.124646 -121.774966) (xy 415.12617 -121.785888)
			(xy 415.1376 -121.804176) (xy 415.218118 -121.857516) (xy 415.238946 -121.861326) (xy 415.24936 -121.858786)
			(xy 415.275872 -121.852737) (xy 415.329865 -121.846245) (xy 415.357056 -121.845832) (xy 415.35731 -121.845832)
			(xy 415.384499 -121.846269) (xy 415.438488 -121.852766) (xy 415.465006 -121.858786) (xy 415.475674 -121.861326)
			(xy 415.496248 -121.857516) (xy 415.57702 -121.804176) (xy 415.588196 -121.786396) (xy 415.589974 -121.775728)
			(xy 415.594626 -121.749122) (xy 415.610448 -121.697481) (xy 415.633395 -121.648588) (xy 415.663011 -121.60342)
			(xy 415.698701 -121.562882) (xy 415.739753 -121.527784) (xy 415.785345 -121.498827) (xy 415.834566 -121.476591)
			(xy 415.886432 -121.461521) (xy 415.939905 -121.453918) (xy 415.96691 -121.453402) (xy 415.99416 -121.453889)
			(xy 416.048105 -121.461646) (xy 416.100397 -121.477002) (xy 416.149972 -121.499643) (xy 416.19582 -121.529109)
			(xy 416.237008 -121.564799) (xy 416.272697 -121.605988) (xy 416.302162 -121.651837) (xy 416.324802 -121.701412)
			(xy 416.340156 -121.753705) (xy 416.347912 -121.80765) (xy 416.347912 -121.83491) (xy 420.185086 -121.83491)
			(xy 420.189157 -121.779288) (xy 420.201283 -121.724851) (xy 420.221206 -121.67276) (xy 420.248502 -121.624125)
			(xy 420.282588 -121.579982) (xy 420.322737 -121.541273) (xy 420.368095 -121.508822) (xy 420.417695 -121.483321)
			(xy 420.470479 -121.465314) (xy 420.525322 -121.455184) (xy 420.581056 -121.453147) (xy 420.636493 -121.459247)
			(xy 420.69045 -121.473353) (xy 420.741779 -121.495165) (xy 420.789385 -121.524219) (xy 420.832253 -121.559894)
			(xy 420.86947 -121.601431) (xy 420.900243 -121.647944) (xy 420.923915 -121.698441) (xy 420.939983 -121.751848)
			(xy 420.948103 -121.807024) (xy 420.948612 -121.83491) (xy 422.166286 -121.83491) (xy 422.170357 -121.779288)
			(xy 422.182483 -121.724851) (xy 422.202406 -121.67276) (xy 422.229702 -121.624125) (xy 422.263788 -121.579982)
			(xy 422.303937 -121.541273) (xy 422.349295 -121.508822) (xy 422.398895 -121.483321) (xy 422.451679 -121.465314)
			(xy 422.506522 -121.455184) (xy 422.562256 -121.453147) (xy 422.617693 -121.459247) (xy 422.67165 -121.473353)
			(xy 422.722979 -121.495165) (xy 422.770585 -121.524219) (xy 422.813453 -121.559894) (xy 422.85067 -121.601431)
			(xy 422.881443 -121.647944) (xy 422.905115 -121.698441) (xy 422.921183 -121.751848) (xy 422.929303 -121.807024)
			(xy 422.929812 -121.83491) (xy 422.929303 -121.862796) (xy 422.921183 -121.917972) (xy 422.905115 -121.971379)
			(xy 422.881443 -122.021876) (xy 422.85067 -122.068389) (xy 422.813453 -122.109926) (xy 422.770585 -122.145601)
			(xy 422.722979 -122.174655) (xy 422.67165 -122.196467) (xy 422.617693 -122.210573) (xy 422.562256 -122.216673)
			(xy 422.506522 -122.214636) (xy 422.451679 -122.204506) (xy 422.398895 -122.186499) (xy 422.349295 -122.160998)
			(xy 422.303937 -122.128547) (xy 422.263788 -122.089838) (xy 422.229702 -122.045695) (xy 422.202406 -121.99706)
			(xy 422.182483 -121.944969) (xy 422.170357 -121.890532) (xy 422.166286 -121.83491) (xy 420.948612 -121.83491)
			(xy 420.948103 -121.862796) (xy 420.939983 -121.917972) (xy 420.923915 -121.971379) (xy 420.900243 -122.021876)
			(xy 420.86947 -122.068389) (xy 420.832253 -122.109926) (xy 420.789385 -122.145601) (xy 420.741779 -122.174655)
			(xy 420.69045 -122.196467) (xy 420.636493 -122.210573) (xy 420.581056 -122.216673) (xy 420.525322 -122.214636)
			(xy 420.470479 -122.204506) (xy 420.417695 -122.186499) (xy 420.368095 -122.160998) (xy 420.322737 -122.128547)
			(xy 420.282588 -122.089838) (xy 420.248502 -122.045695) (xy 420.221206 -121.99706) (xy 420.201283 -121.944969)
			(xy 420.189157 -121.890532) (xy 420.185086 -121.83491) (xy 416.347912 -121.83491) (xy 416.347912 -121.86215)
			(xy 416.340156 -121.916095) (xy 416.324802 -121.968388) (xy 416.302162 -122.017963) (xy 416.272697 -122.063812)
			(xy 416.237008 -122.105001) (xy 416.19582 -122.140691) (xy 416.149972 -122.170157) (xy 416.100397 -122.192798)
			(xy 416.048105 -122.208154) (xy 415.99416 -122.215911) (xy 415.96691 -122.216418) (xy 415.966656 -122.216418)
			(xy 415.95019 -122.216267) (xy 415.917378 -122.21347) (xy 415.901124 -122.21083) (xy 415.898838 -122.210322)
			(xy 415.893758 -122.209814) (xy 415.883704 -122.20956) (xy 415.864622 -122.215843) (xy 415.856674 -122.222006)
			(xy 415.8234 -122.250708) (xy 415.814256 -122.272044) (xy 415.814764 -122.283728) (xy 415.815272 -122.30354)
			(xy 415.815272 -122.597164) (xy 417.60216 -122.597164) (xy 417.606231 -122.541542) (xy 417.618357 -122.487105)
			(xy 417.63828 -122.435014) (xy 417.665576 -122.386379) (xy 417.699662 -122.342236) (xy 417.739811 -122.303527)
			(xy 417.785169 -122.271076) (xy 417.834769 -122.245575) (xy 417.887553 -122.227568) (xy 417.942396 -122.217438)
			(xy 417.99813 -122.215401) (xy 418.053567 -122.221501) (xy 418.107524 -122.235607) (xy 418.158853 -122.257419)
			(xy 418.206459 -122.286473) (xy 418.249327 -122.322148) (xy 418.286544 -122.363685) (xy 418.317317 -122.410198)
			(xy 418.340989 -122.460695) (xy 418.357057 -122.514102) (xy 418.365177 -122.569278) (xy 418.365686 -122.597164)
			(xy 418.365177 -122.62505) (xy 418.357057 -122.680226) (xy 418.340989 -122.733633) (xy 418.317317 -122.78413)
			(xy 418.286544 -122.830643) (xy 418.249327 -122.87218) (xy 418.206459 -122.907855) (xy 418.158853 -122.936909)
			(xy 418.107524 -122.958721) (xy 418.053567 -122.972827) (xy 417.99813 -122.978927) (xy 417.942396 -122.97689)
			(xy 417.887553 -122.96676) (xy 417.834769 -122.948753) (xy 417.785169 -122.923252) (xy 417.739811 -122.890801)
			(xy 417.699662 -122.852092) (xy 417.665576 -122.807949) (xy 417.63828 -122.759314) (xy 417.618357 -122.707223)
			(xy 417.606231 -122.652786) (xy 417.60216 -122.597164) (xy 415.815272 -122.597164) (xy 415.815272 -123.16714)
			(xy 415.814764 -123.185428) (xy 415.814764 -123.18873) (xy 415.815309 -123.199746) (xy 415.824531 -123.219757)
			(xy 415.832544 -123.227338) (xy 415.848292 -123.2408) (xy 415.849054 -123.241562) (xy 415.85642 -123.247912)
			(xy 415.865465 -123.254906) (xy 415.887484 -123.26096) (xy 415.898838 -123.259596) (xy 415.915648 -123.256752)
			(xy 415.949608 -123.253698) (xy 415.966656 -123.2535) (xy 415.968942 -123.2535) (xy 415.996098 -123.254125)
			(xy 416.049824 -123.262116) (xy 416.101874 -123.277648) (xy 416.151194 -123.300404) (xy 416.196789 -123.329926)
			(xy 416.237735 -123.365617) (xy 416.273204 -123.406754) (xy 416.302481 -123.452506) (xy 416.324972 -123.501948)
			(xy 416.340224 -123.554081) (xy 416.347927 -123.607849) (xy 416.348418 -123.635008) (xy 420.185086 -123.635008)
			(xy 420.189157 -123.579386) (xy 420.201283 -123.524949) (xy 420.221206 -123.472858) (xy 420.248502 -123.424223)
			(xy 420.282588 -123.38008) (xy 420.322737 -123.341371) (xy 420.368095 -123.30892) (xy 420.417695 -123.283419)
			(xy 420.470479 -123.265412) (xy 420.525322 -123.255282) (xy 420.581056 -123.253245) (xy 420.636493 -123.259345)
			(xy 420.69045 -123.273451) (xy 420.741779 -123.295263) (xy 420.789385 -123.324317) (xy 420.832253 -123.359992)
			(xy 420.86947 -123.401529) (xy 420.900243 -123.448042) (xy 420.923915 -123.498539) (xy 420.939983 -123.551946)
			(xy 420.948103 -123.607122) (xy 420.948612 -123.635008) (xy 422.166286 -123.635008) (xy 422.170357 -123.579386)
			(xy 422.182483 -123.524949) (xy 422.202406 -123.472858) (xy 422.229702 -123.424223) (xy 422.263788 -123.38008)
			(xy 422.303937 -123.341371) (xy 422.349295 -123.30892) (xy 422.398895 -123.283419) (xy 422.451679 -123.265412)
			(xy 422.506522 -123.255282) (xy 422.562256 -123.253245) (xy 422.617693 -123.259345) (xy 422.67165 -123.273451)
			(xy 422.722979 -123.295263) (xy 422.770585 -123.324317) (xy 422.813453 -123.359992) (xy 422.85067 -123.401529)
			(xy 422.881443 -123.448042) (xy 422.905115 -123.498539) (xy 422.921183 -123.551946) (xy 422.929303 -123.607122)
			(xy 422.929812 -123.635008) (xy 422.929303 -123.662894) (xy 422.921183 -123.71807) (xy 422.905115 -123.771477)
			(xy 422.881443 -123.821974) (xy 422.85067 -123.868487) (xy 422.813453 -123.910024) (xy 422.770585 -123.945699)
			(xy 422.722979 -123.974753) (xy 422.67165 -123.996565) (xy 422.617693 -124.010671) (xy 422.562256 -124.016771)
			(xy 422.506522 -124.014734) (xy 422.451679 -124.004604) (xy 422.398895 -123.986597) (xy 422.349295 -123.961096)
			(xy 422.303937 -123.928645) (xy 422.263788 -123.889936) (xy 422.229702 -123.845793) (xy 422.202406 -123.797158)
			(xy 422.182483 -123.745067) (xy 422.170357 -123.69063) (xy 422.166286 -123.635008) (xy 420.948612 -123.635008)
			(xy 420.948103 -123.662894) (xy 420.939983 -123.71807) (xy 420.923915 -123.771477) (xy 420.900243 -123.821974)
			(xy 420.86947 -123.868487) (xy 420.832253 -123.910024) (xy 420.789385 -123.945699) (xy 420.741779 -123.974753)
			(xy 420.69045 -123.996565) (xy 420.636493 -124.010671) (xy 420.581056 -124.016771) (xy 420.525322 -124.014734)
			(xy 420.470479 -124.004604) (xy 420.417695 -123.986597) (xy 420.368095 -123.961096) (xy 420.322737 -123.928645)
			(xy 420.282588 -123.889936) (xy 420.248502 -123.845793) (xy 420.221206 -123.797158) (xy 420.201283 -123.745067)
			(xy 420.189157 -123.69063) (xy 420.185086 -123.635008) (xy 416.348418 -123.635008) (xy 416.347932 -123.662259)
			(xy 416.340174 -123.716207) (xy 416.324819 -123.768501) (xy 416.302177 -123.818078) (xy 416.272711 -123.863928)
			(xy 416.237019 -123.905118) (xy 416.195829 -123.94081) (xy 416.14998 -123.970276) (xy 416.100403 -123.992918)
			(xy 416.048108 -124.008274) (xy 415.994161 -124.016032) (xy 415.96691 -124.016516) (xy 415.939959 -124.016052)
			(xy 415.886593 -124.008464) (xy 415.834828 -123.993439) (xy 415.785693 -123.971275) (xy 415.740168 -123.942415)
			(xy 415.69916 -123.907432) (xy 415.663485 -123.867025) (xy 415.633855 -123.821997) (xy 415.610859 -123.773247)
			(xy 415.594955 -123.721744) (xy 415.590228 -123.695206) (xy 415.590228 -123.694952) (xy 415.58845 -123.68403)
			(xy 415.582608 -123.67514) (xy 415.579683 -123.670833) (xy 415.57238 -123.663416) (xy 415.56813 -123.660408)
			(xy 415.496502 -123.61291) (xy 415.475928 -123.609354) (xy 415.465514 -123.611894) (xy 415.4424 -123.616974)
			(xy 415.42843 -123.619768) (xy 415.407602 -123.63831) (xy 415.376868 -123.737624) (xy 415.374532 -123.746574)
			(xy 415.3757 -123.76502) (xy 415.383315 -123.781862) (xy 415.389568 -123.788678) (xy 416.191192 -124.590302)
			(xy 416.19859 -124.59715) (xy 416.217188 -124.604887) (xy 416.22726 -124.605288)
		)
		(stroke
			(width 0)
			(type solid)
		)
		(fill yes)
		(layer "In9.Cu")
		(net "P3V3_NIC7")
	)
	(gr_poly
		(pts
			(xy 166.34587 -304.283872) (xy 166.354663 -304.283507) (xy 166.371213 -304.277563) (xy 166.384773 -304.266365)
			(xy 166.389558 -304.25898) (xy 166.44112 -304.172112) (xy 166.441628 -304.145442) (xy 166.435024 -304.133504)
			(xy 166.422246 -304.109015) (xy 166.404135 -304.056835) (xy 166.394948 -304.002371) (xy 166.394384 -303.974754)
			(xy 166.394894 -303.948767) (xy 166.403024 -303.897432) (xy 166.419085 -303.848002) (xy 166.442681 -303.801692)
			(xy 166.473231 -303.759644) (xy 166.509982 -303.722893) (xy 166.55203 -303.692343) (xy 166.59834 -303.668747)
			(xy 166.64777 -303.652686) (xy 166.699105 -303.644556) (xy 166.751079 -303.644556) (xy 166.802414 -303.652686)
			(xy 166.851844 -303.668747) (xy 166.898154 -303.692343) (xy 166.940202 -303.722893) (xy 166.976953 -303.759644)
			(xy 167.007503 -303.801692) (xy 167.031099 -303.848002) (xy 167.04716 -303.897432) (xy 167.05529 -303.948767)
			(xy 167.0558 -303.974754) (xy 167.055246 -304.002372) (xy 167.046066 -304.05684) (xy 167.027952 -304.109021)
			(xy 167.01516 -304.133504) (xy 167.008556 -304.145442) (xy 167.009064 -304.172112) (xy 167.060626 -304.25898)
			(xy 167.065425 -304.266354) (xy 167.078979 -304.277552) (xy 167.095523 -304.283499) (xy 167.104314 -304.283872)
			(xy 167.29583 -304.283872) (xy 167.304618 -304.283498) (xy 167.321153 -304.27754) (xy 167.334696 -304.266338)
			(xy 167.339518 -304.25898) (xy 167.39108 -304.172112) (xy 167.391588 -304.145442) (xy 167.384984 -304.133504)
			(xy 167.372204 -304.109015) (xy 167.35409 -304.056836) (xy 167.3449 -304.002371) (xy 167.344344 -303.974754)
			(xy 167.344854 -303.948767) (xy 167.352984 -303.897432) (xy 167.369045 -303.848002) (xy 167.392641 -303.801692)
			(xy 167.423191 -303.759644) (xy 167.459942 -303.722893) (xy 167.50199 -303.692343) (xy 167.5483 -303.668747)
			(xy 167.59773 -303.652686) (xy 167.649065 -303.644556) (xy 167.701039 -303.644556) (xy 167.752374 -303.652686)
			(xy 167.801804 -303.668747) (xy 167.848114 -303.692343) (xy 167.890162 -303.722893) (xy 167.926913 -303.759644)
			(xy 167.957463 -303.801692) (xy 167.981059 -303.848002) (xy 167.99712 -303.897432) (xy 168.00525 -303.948767)
			(xy 168.00576 -303.974754) (xy 168.005206 -304.002372) (xy 167.996024 -304.056839) (xy 167.977909 -304.10902)
			(xy 167.96512 -304.133504) (xy 167.958516 -304.145442) (xy 167.959024 -304.172112) (xy 168.010586 -304.25898)
			(xy 168.015383 -304.266359) (xy 168.028935 -304.277567) (xy 168.045481 -304.283527) (xy 168.054274 -304.283872)
			(xy 168.24579 -304.283872) (xy 168.254581 -304.283504) (xy 168.271127 -304.277555) (xy 168.284681 -304.266356)
			(xy 168.289478 -304.25898) (xy 168.34104 -304.172112) (xy 168.341548 -304.145442) (xy 168.334944 -304.133504)
			(xy 168.322166 -304.109015) (xy 168.304054 -304.056835) (xy 168.294865 -304.002371) (xy 168.294304 -303.974754)
			(xy 168.294814 -303.948767) (xy 168.302944 -303.897432) (xy 168.319005 -303.848002) (xy 168.342601 -303.801692)
			(xy 168.373151 -303.759644) (xy 168.409902 -303.722893) (xy 168.45195 -303.692343) (xy 168.49826 -303.668747)
			(xy 168.54769 -303.652686) (xy 168.599025 -303.644556) (xy 168.650999 -303.644556) (xy 168.702334 -303.652686)
			(xy 168.751764 -303.668747) (xy 168.798074 -303.692343) (xy 168.840122 -303.722893) (xy 168.876873 -303.759644)
			(xy 168.907423 -303.801692) (xy 168.931019 -303.848002) (xy 168.94708 -303.897432) (xy 168.95521 -303.948767)
			(xy 168.95572 -303.974754) (xy 168.955166 -304.002372) (xy 168.945986 -304.05684) (xy 168.927874 -304.109022)
			(xy 168.91508 -304.133504) (xy 168.908476 -304.145442) (xy 168.908984 -304.172112) (xy 168.960546 -304.25898)
			(xy 168.965341 -304.266363) (xy 168.978892 -304.277582) (xy 168.995439 -304.283555) (xy 169.004234 -304.283872)
			(xy 169.19575 -304.283872) (xy 169.204545 -304.283511) (xy 169.2211 -304.27757) (xy 169.234665 -304.266374)
			(xy 169.239438 -304.25898) (xy 169.291 -304.172112) (xy 169.291508 -304.145442) (xy 169.284904 -304.133504)
			(xy 169.272127 -304.109014) (xy 169.254017 -304.056834) (xy 169.24483 -304.002371) (xy 169.244264 -303.974754)
			(xy 169.244774 -303.948767) (xy 169.252904 -303.897432) (xy 169.268965 -303.848002) (xy 169.292561 -303.801692)
			(xy 169.323111 -303.759644) (xy 169.359862 -303.722893) (xy 169.40191 -303.692343) (xy 169.44822 -303.668747)
			(xy 169.49765 -303.652686) (xy 169.548985 -303.644556) (xy 169.600959 -303.644556) (xy 169.652294 -303.652686)
			(xy 169.701724 -303.668747) (xy 169.748034 -303.692343) (xy 169.790082 -303.722893) (xy 169.826833 -303.759644)
			(xy 169.857383 -303.801692) (xy 169.880979 -303.848002) (xy 169.89704 -303.897432) (xy 169.90517 -303.948767)
			(xy 169.90568 -303.974754) (xy 169.905126 -304.002372) (xy 169.895945 -304.056839) (xy 169.877831 -304.109021)
			(xy 169.86504 -304.133504) (xy 169.858436 -304.145442) (xy 169.858944 -304.172112) (xy 169.910506 -304.25898)
			(xy 169.915304 -304.266356) (xy 169.928857 -304.277559) (xy 169.945402 -304.283513) (xy 169.954194 -304.283872)
			(xy 170.14571 -304.283872) (xy 170.154499 -304.283501) (xy 170.17104 -304.277548) (xy 170.184589 -304.266347)
			(xy 170.189398 -304.25898) (xy 170.24096 -304.172112) (xy 170.241468 -304.145442) (xy 170.234864 -304.133504)
			(xy 170.222085 -304.109015) (xy 170.203972 -304.056835) (xy 170.194783 -304.002371) (xy 170.194224 -303.974754)
			(xy 170.194734 -303.948767) (xy 170.202864 -303.897432) (xy 170.218925 -303.848002) (xy 170.242521 -303.801692)
			(xy 170.273071 -303.759644) (xy 170.309822 -303.722893) (xy 170.35187 -303.692343) (xy 170.39818 -303.668747)
			(xy 170.44761 -303.652686) (xy 170.498945 -303.644556) (xy 170.550919 -303.644556) (xy 170.602254 -303.652686)
			(xy 170.651684 -303.668747) (xy 170.697994 -303.692343) (xy 170.740042 -303.722893) (xy 170.776793 -303.759644)
			(xy 170.807343 -303.801692) (xy 170.830939 -303.848002) (xy 170.847 -303.897432) (xy 170.85513 -303.948767)
			(xy 170.85564 -303.974754) (xy 170.855086 -304.002372) (xy 170.845907 -304.05684) (xy 170.827795 -304.109023)
			(xy 170.815 -304.133504) (xy 170.808396 -304.145442) (xy 170.808904 -304.172112) (xy 170.860466 -304.25898)
			(xy 170.865262 -304.266361) (xy 170.878814 -304.277574) (xy 170.89536 -304.283541) (xy 170.904154 -304.283872)
			(xy 171.09567 -304.283872) (xy 171.104463 -304.283507) (xy 171.121013 -304.277563) (xy 171.134573 -304.266365)
			(xy 171.139358 -304.25898) (xy 171.19092 -304.172112) (xy 171.191428 -304.145442) (xy 171.184824 -304.133504)
			(xy 171.172046 -304.109015) (xy 171.153935 -304.056835) (xy 171.144748 -304.002371) (xy 171.144184 -303.974754)
			(xy 171.144694 -303.948767) (xy 171.152824 -303.897432) (xy 171.168885 -303.848002) (xy 171.192481 -303.801692)
			(xy 171.223031 -303.759644) (xy 171.259782 -303.722893) (xy 171.30183 -303.692343) (xy 171.34814 -303.668747)
			(xy 171.39757 -303.652686) (xy 171.448905 -303.644556) (xy 171.500879 -303.644556) (xy 171.552214 -303.652686)
			(xy 171.601644 -303.668747) (xy 171.647954 -303.692343) (xy 171.690002 -303.722893) (xy 171.726753 -303.759644)
			(xy 171.757303 -303.801692) (xy 171.780899 -303.848002) (xy 171.79696 -303.897432) (xy 171.80509 -303.948767)
			(xy 171.8056 -303.974754) (xy 171.805046 -304.002372) (xy 171.795866 -304.05684) (xy 171.777752 -304.109021)
			(xy 171.76496 -304.133504) (xy 171.758356 -304.145442) (xy 171.758864 -304.172112) (xy 171.810426 -304.25898)
			(xy 171.815225 -304.266354) (xy 171.828779 -304.277552) (xy 171.845323 -304.283499) (xy 171.854114 -304.283872)
			(xy 172.04563 -304.283872) (xy 172.054418 -304.283498) (xy 172.070953 -304.27754) (xy 172.084496 -304.266338)
			(xy 172.089318 -304.25898) (xy 172.14088 -304.172112) (xy 172.141388 -304.145442) (xy 172.134784 -304.133504)
			(xy 172.122004 -304.109015) (xy 172.10389 -304.056836) (xy 172.0947 -304.002371) (xy 172.094144 -303.974754)
			(xy 172.094654 -303.948767) (xy 172.102784 -303.897432) (xy 172.118845 -303.848002) (xy 172.142441 -303.801692)
			(xy 172.172991 -303.759644) (xy 172.209742 -303.722893) (xy 172.25179 -303.692343) (xy 172.2981 -303.668747)
			(xy 172.34753 -303.652686) (xy 172.398865 -303.644556) (xy 172.450839 -303.644556) (xy 172.502174 -303.652686)
			(xy 172.551604 -303.668747) (xy 172.597914 -303.692343) (xy 172.639962 -303.722893) (xy 172.676713 -303.759644)
			(xy 172.707263 -303.801692) (xy 172.730859 -303.848002) (xy 172.74692 -303.897432) (xy 172.75505 -303.948767)
			(xy 172.75556 -303.974754) (xy 172.755006 -304.002372) (xy 172.745824 -304.056839) (xy 172.727709 -304.10902)
			(xy 172.71492 -304.133504) (xy 172.708316 -304.145442) (xy 172.708824 -304.172112) (xy 172.760386 -304.25898)
			(xy 172.765183 -304.266359) (xy 172.778735 -304.277567) (xy 172.795281 -304.283527) (xy 172.804074 -304.283872)
			(xy 172.995844 -304.283872) (xy 173.004639 -304.283512) (xy 173.021196 -304.277573) (xy 173.034763 -304.266377)
			(xy 173.039532 -304.25898) (xy 173.091094 -304.172112) (xy 173.091602 -304.145442) (xy 173.084998 -304.133504)
			(xy 173.072218 -304.109015) (xy 173.054103 -304.056836) (xy 173.044913 -304.002371) (xy 173.044358 -303.974754)
			(xy 173.044868 -303.948767) (xy 173.052998 -303.897432) (xy 173.069059 -303.848002) (xy 173.092655 -303.801692)
			(xy 173.123205 -303.759644) (xy 173.159956 -303.722893) (xy 173.202004 -303.692343) (xy 173.248314 -303.668747)
			(xy 173.297744 -303.652686) (xy 173.349079 -303.644556) (xy 173.401053 -303.644556) (xy 173.452388 -303.652686)
			(xy 173.501818 -303.668747) (xy 173.548128 -303.692343) (xy 173.590176 -303.722893) (xy 173.626927 -303.759644)
			(xy 173.657477 -303.801692) (xy 173.681073 -303.848002) (xy 173.697134 -303.897432) (xy 173.705264 -303.948767)
			(xy 173.705774 -303.974754) (xy 173.70522 -304.002372) (xy 173.696039 -304.056839) (xy 173.677924 -304.10902)
			(xy 173.665134 -304.133504) (xy 173.65853 -304.145442) (xy 173.659038 -304.172112) (xy 173.7106 -304.25898)
			(xy 173.715398 -304.266357) (xy 173.728951 -304.277561) (xy 173.745496 -304.283517) (xy 173.754288 -304.283872)
			(xy 173.945804 -304.283872) (xy 173.954594 -304.283502) (xy 173.971136 -304.27755) (xy 173.984686 -304.26635)
			(xy 173.989492 -304.25898) (xy 174.041054 -304.172112) (xy 174.041562 -304.145442) (xy 174.034958 -304.133504)
			(xy 174.022179 -304.109015) (xy 174.004066 -304.056835) (xy 173.994878 -304.002371) (xy 173.994318 -303.974754)
			(xy 173.994828 -303.948767) (xy 174.002958 -303.897432) (xy 174.019019 -303.848002) (xy 174.042615 -303.801692)
			(xy 174.073165 -303.759644) (xy 174.109916 -303.722893) (xy 174.151964 -303.692343) (xy 174.198274 -303.668747)
			(xy 174.247704 -303.652686) (xy 174.299039 -303.644556) (xy 174.351013 -303.644556) (xy 174.402348 -303.652686)
			(xy 174.451778 -303.668747) (xy 174.498088 -303.692343) (xy 174.540136 -303.722893) (xy 174.576887 -303.759644)
			(xy 174.607437 -303.801692) (xy 174.631033 -303.848002) (xy 174.647094 -303.897432) (xy 174.655224 -303.948767)
			(xy 174.655734 -303.974754) (xy 174.65518 -304.002372) (xy 174.646001 -304.05684) (xy 174.627889 -304.109023)
			(xy 174.615094 -304.133504) (xy 174.60849 -304.145442) (xy 174.608998 -304.172112) (xy 174.66056 -304.25898)
			(xy 174.665356 -304.266361) (xy 174.678907 -304.277576) (xy 174.695453 -304.283545) (xy 174.704248 -304.283872)
			(xy 175.845724 -304.283872) (xy 175.854512 -304.283499) (xy 175.871049 -304.277542) (xy 175.884594 -304.266341)
			(xy 175.889412 -304.25898) (xy 175.940974 -304.172112) (xy 175.941482 -304.145442) (xy 175.934878 -304.133504)
			(xy 175.922098 -304.109015) (xy 175.903984 -304.056836) (xy 175.894795 -304.002371) (xy 175.894238 -303.974754)
			(xy 175.894748 -303.948767) (xy 175.902878 -303.897432) (xy 175.918939 -303.848002) (xy 175.942535 -303.801692)
			(xy 175.973085 -303.759644) (xy 176.009836 -303.722893) (xy 176.051884 -303.692343) (xy 176.098194 -303.668747)
			(xy 176.147624 -303.652686) (xy 176.198959 -303.644556) (xy 176.250933 -303.644556) (xy 176.302268 -303.652686)
			(xy 176.351698 -303.668747) (xy 176.398008 -303.692343) (xy 176.440056 -303.722893) (xy 176.476807 -303.759644)
			(xy 176.507357 -303.801692) (xy 176.530953 -303.848002) (xy 176.547014 -303.897432) (xy 176.555144 -303.948767)
			(xy 176.555654 -303.974754) (xy 176.5551 -304.002372) (xy 176.545918 -304.056839) (xy 176.527803 -304.109019)
			(xy 176.515014 -304.133504) (xy 176.50841 -304.145442) (xy 176.508918 -304.172112) (xy 176.56048 -304.25898)
			(xy 176.565277 -304.266359) (xy 176.578829 -304.277569) (xy 176.595375 -304.283531) (xy 176.604168 -304.283872)
			(xy 176.795684 -304.283872) (xy 176.804476 -304.283505) (xy 176.821023 -304.277557) (xy 176.834579 -304.266359)
			(xy 176.839372 -304.25898) (xy 176.890934 -304.172112) (xy 176.891442 -304.145442) (xy 176.884838 -304.133504)
			(xy 176.87206 -304.109015) (xy 176.853948 -304.056835) (xy 176.84476 -304.002371) (xy 176.844198 -303.974754)
			(xy 176.844708 -303.948767) (xy 176.852838 -303.897432) (xy 176.868899 -303.848002) (xy 176.892495 -303.801692)
			(xy 176.923045 -303.759644) (xy 176.959796 -303.722893) (xy 177.001844 -303.692343) (xy 177.048154 -303.668747)
			(xy 177.097584 -303.652686) (xy 177.148919 -303.644556) (xy 177.200893 -303.644556) (xy 177.252228 -303.652686)
			(xy 177.301658 -303.668747) (xy 177.347968 -303.692343) (xy 177.390016 -303.722893) (xy 177.426767 -303.759644)
			(xy 177.457317 -303.801692) (xy 177.480913 -303.848002) (xy 177.496974 -303.897432) (xy 177.505104 -303.948767)
			(xy 177.505614 -303.974754) (xy 177.50506 -304.002372) (xy 177.49588 -304.05684) (xy 177.477768 -304.109022)
			(xy 177.464974 -304.133504) (xy 177.45837 -304.145442) (xy 177.458878 -304.172112) (xy 177.51044 -304.25898)
			(xy 177.51524 -304.266353) (xy 177.528794 -304.277546) (xy 177.545338 -304.283489) (xy 177.554128 -304.283872)
			(xy 177.745644 -304.283872) (xy 177.754439 -304.283512) (xy 177.770996 -304.277573) (xy 177.784563 -304.266377)
			(xy 177.789332 -304.25898) (xy 177.840894 -304.172112) (xy 177.841402 -304.145442) (xy 177.834798 -304.133504)
			(xy 177.822018 -304.109015) (xy 177.803903 -304.056836) (xy 177.794713 -304.002371) (xy 177.794158 -303.974754)
			(xy 177.794668 -303.948767) (xy 177.802798 -303.897432) (xy 177.818859 -303.848002) (xy 177.842455 -303.801692)
			(xy 177.873005 -303.759644) (xy 177.909756 -303.722893) (xy 177.951804 -303.692343) (xy 177.998114 -303.668747)
			(xy 178.047544 -303.652686) (xy 178.098879 -303.644556) (xy 178.150853 -303.644556) (xy 178.202188 -303.652686)
			(xy 178.251618 -303.668747) (xy 178.297928 -303.692343) (xy 178.339976 -303.722893) (xy 178.376727 -303.759644)
			(xy 178.407277 -303.801692) (xy 178.430873 -303.848002) (xy 178.446934 -303.897432) (xy 178.455064 -303.948767)
			(xy 178.455574 -303.974754) (xy 178.45502 -304.002372) (xy 178.445839 -304.056839) (xy 178.427724 -304.10902)
			(xy 178.414934 -304.133504) (xy 178.40833 -304.145442) (xy 178.408838 -304.172112) (xy 178.4604 -304.25898)
			(xy 178.465198 -304.266357) (xy 178.478751 -304.277561) (xy 178.495296 -304.283517) (xy 178.504088 -304.283872)
			(xy 178.695858 -304.283872) (xy 178.704652 -304.283509) (xy 178.721205 -304.277567) (xy 178.734769 -304.266371)
			(xy 178.739546 -304.25898) (xy 178.791108 -304.172112) (xy 178.791616 -304.145442) (xy 178.785012 -304.133504)
			(xy 178.772235 -304.109015) (xy 178.754124 -304.056835) (xy 178.744937 -304.002371) (xy 178.744372 -303.974754)
			(xy 178.744882 -303.948767) (xy 178.753012 -303.897432) (xy 178.769073 -303.848002) (xy 178.792669 -303.801692)
			(xy 178.823219 -303.759644) (xy 178.85997 -303.722893) (xy 178.902018 -303.692343) (xy 178.948328 -303.668747)
			(xy 178.997758 -303.652686) (xy 179.049093 -303.644556) (xy 179.101067 -303.644556) (xy 179.152402 -303.652686)
			(xy 179.201832 -303.668747) (xy 179.248142 -303.692343) (xy 179.29019 -303.722893) (xy 179.326941 -303.759644)
			(xy 179.357491 -303.801692) (xy 179.381087 -303.848002) (xy 179.397148 -303.897432) (xy 179.405278 -303.948767)
			(xy 179.405788 -303.974754) (xy 179.405234 -304.002372) (xy 179.396053 -304.05684) (xy 179.37794 -304.109021)
			(xy 179.365148 -304.133504) (xy 179.358544 -304.145442) (xy 179.359052 -304.172112) (xy 179.410614 -304.25898)
			(xy 179.415413 -304.266355) (xy 179.428966 -304.277556) (xy 179.445511 -304.283507) (xy 179.454302 -304.283872)
			(xy 179.645818 -304.283872) (xy 179.654607 -304.2835) (xy 179.671145 -304.277545) (xy 179.684692 -304.266344)
			(xy 179.689506 -304.25898) (xy 179.741068 -304.172112) (xy 179.741576 -304.145442) (xy 179.734972 -304.133504)
			(xy 179.722193 -304.109015) (xy 179.704079 -304.056836) (xy 179.69489 -304.002371) (xy 179.694332 -303.974754)
			(xy 179.694842 -303.948767) (xy 179.702972 -303.897432) (xy 179.719033 -303.848002) (xy 179.742629 -303.801692)
			(xy 179.773179 -303.759644) (xy 179.80993 -303.722893) (xy 179.851978 -303.692343) (xy 179.898288 -303.668747)
			(xy 179.947718 -303.652686) (xy 179.999053 -303.644556) (xy 180.051027 -303.644556) (xy 180.102362 -303.652686)
			(xy 180.151792 -303.668747) (xy 180.198102 -303.692343) (xy 180.24015 -303.722893) (xy 180.276901 -303.759644)
			(xy 180.307451 -303.801692) (xy 180.331047 -303.848002) (xy 180.347108 -303.897432) (xy 180.355238 -303.948767)
			(xy 180.355748 -303.974754) (xy 180.355194 -304.002372) (xy 180.346015 -304.05684) (xy 180.327904 -304.109023)
			(xy 180.315108 -304.133504) (xy 180.308504 -304.145442) (xy 180.309012 -304.172112) (xy 180.360574 -304.25898)
			(xy 180.365371 -304.26636) (xy 180.378922 -304.277571) (xy 180.395468 -304.283535) (xy 180.404262 -304.283872)
			(xy 180.595778 -304.283872) (xy 180.60457 -304.283506) (xy 180.621119 -304.27756) (xy 180.634676 -304.266362)
			(xy 180.639466 -304.25898) (xy 180.691028 -304.172112) (xy 180.691536 -304.145442) (xy 180.684932 -304.133504)
			(xy 180.672154 -304.109015) (xy 180.654043 -304.056835) (xy 180.644855 -304.002371) (xy 180.644292 -303.974754)
			(xy 180.644802 -303.948767) (xy 180.652932 -303.897432) (xy 180.668993 -303.848002) (xy 180.692589 -303.801692)
			(xy 180.723139 -303.759644) (xy 180.75989 -303.722893) (xy 180.801938 -303.692343) (xy 180.848248 -303.668747)
			(xy 180.897678 -303.652686) (xy 180.949013 -303.644556) (xy 181.000987 -303.644556) (xy 181.052322 -303.652686)
			(xy 181.101752 -303.668747) (xy 181.148062 -303.692343) (xy 181.19011 -303.722893) (xy 181.226861 -303.759644)
			(xy 181.257411 -303.801692) (xy 181.281007 -303.848002) (xy 181.297068 -303.897432) (xy 181.305198 -303.948767)
			(xy 181.305708 -303.974754) (xy 181.305154 -304.002372) (xy 181.295974 -304.05684) (xy 181.277861 -304.109022)
			(xy 181.265068 -304.133504) (xy 181.258464 -304.145442) (xy 181.258972 -304.172112) (xy 181.310534 -304.25898)
			(xy 181.315333 -304.266353) (xy 181.328888 -304.277549) (xy 181.345432 -304.283494) (xy 181.354222 -304.283872)
			(xy 181.545738 -304.283872) (xy 181.554525 -304.283497) (xy 181.571058 -304.277537) (xy 181.5846 -304.266334)
			(xy 181.589426 -304.25898) (xy 181.640988 -304.172112) (xy 181.641496 -304.145442) (xy 181.634892 -304.133504)
			(xy 181.622112 -304.109015) (xy 181.603997 -304.056836) (xy 181.594808 -304.002371) (xy 181.594252 -303.974754)
			(xy 181.594762 -303.948767) (xy 181.602892 -303.897432) (xy 181.618953 -303.848002) (xy 181.642549 -303.801692)
			(xy 181.673099 -303.759644) (xy 181.70985 -303.722893) (xy 181.751898 -303.692343) (xy 181.798208 -303.668747)
			(xy 181.847638 -303.652686) (xy 181.898973 -303.644556) (xy 181.950947 -303.644556) (xy 182.002282 -303.652686)
			(xy 182.051712 -303.668747) (xy 182.098022 -303.692343) (xy 182.14007 -303.722893) (xy 182.176821 -303.759644)
			(xy 182.207371 -303.801692) (xy 182.230967 -303.848002) (xy 182.247028 -303.897432) (xy 182.255158 -303.948767)
			(xy 182.255668 -303.974754) (xy 182.255114 -304.002372) (xy 182.245933 -304.056839) (xy 182.227818 -304.10902)
			(xy 182.215028 -304.133504) (xy 182.208424 -304.145442) (xy 182.208932 -304.172112) (xy 182.260494 -304.25898)
			(xy 182.265291 -304.266358) (xy 182.278844 -304.277564) (xy 182.295389 -304.283522) (xy 182.304182 -304.283872)
			(xy 182.495698 -304.283872) (xy 182.504489 -304.283503) (xy 182.521032 -304.277552) (xy 182.534584 -304.266353)
			(xy 182.539386 -304.25898) (xy 182.590948 -304.172112) (xy 182.591456 -304.145442) (xy 182.584852 -304.133504)
			(xy 182.572073 -304.109015) (xy 182.553961 -304.056835) (xy 182.544772 -304.002371) (xy 182.544212 -303.974754)
			(xy 182.544722 -303.948767) (xy 182.552852 -303.897432) (xy 182.568913 -303.848002) (xy 182.592509 -303.801692)
			(xy 182.623059 -303.759644) (xy 182.65981 -303.722893) (xy 182.701858 -303.692343) (xy 182.748168 -303.668747)
			(xy 182.797598 -303.652686) (xy 182.848933 -303.644556) (xy 182.900907 -303.644556) (xy 182.952242 -303.652686)
			(xy 183.001672 -303.668747) (xy 183.047982 -303.692343) (xy 183.09003 -303.722893) (xy 183.126781 -303.759644)
			(xy 183.157331 -303.801692) (xy 183.180927 -303.848002) (xy 183.196988 -303.897432) (xy 183.205118 -303.948767)
			(xy 183.205628 -303.974754) (xy 183.205074 -304.002372) (xy 183.195894 -304.05684) (xy 183.177783 -304.109022)
			(xy 183.164988 -304.133504) (xy 183.158384 -304.145442) (xy 183.158892 -304.172112) (xy 183.210454 -304.25898)
			(xy 183.21525 -304.266362) (xy 183.2288 -304.277579) (xy 183.245347 -304.283549) (xy 183.254142 -304.283872)
			(xy 183.445658 -304.283872) (xy 183.454452 -304.283509) (xy 183.471005 -304.277567) (xy 183.484569 -304.266371)
			(xy 183.489346 -304.25898) (xy 183.540908 -304.172112) (xy 183.541416 -304.145442) (xy 183.534812 -304.133504)
			(xy 183.522035 -304.109015) (xy 183.503924 -304.056835) (xy 183.494737 -304.002371) (xy 183.494172 -303.974754)
			(xy 183.494682 -303.948767) (xy 183.502812 -303.897432) (xy 183.518873 -303.848002) (xy 183.542469 -303.801692)
			(xy 183.573019 -303.759644) (xy 183.60977 -303.722893) (xy 183.651818 -303.692343) (xy 183.698128 -303.668747)
			(xy 183.747558 -303.652686) (xy 183.798893 -303.644556) (xy 183.850867 -303.644556) (xy 183.902202 -303.652686)
			(xy 183.951632 -303.668747) (xy 183.997942 -303.692343) (xy 184.03999 -303.722893) (xy 184.076741 -303.759644)
			(xy 184.107291 -303.801692) (xy 184.130887 -303.848002) (xy 184.146948 -303.897432) (xy 184.155078 -303.948767)
			(xy 184.155588 -303.974754) (xy 184.155034 -304.002372) (xy 184.145853 -304.05684) (xy 184.12774 -304.109021)
			(xy 184.114948 -304.133504) (xy 184.108344 -304.145442) (xy 184.108852 -304.172112) (xy 184.160414 -304.25898)
			(xy 184.165213 -304.266355) (xy 184.178766 -304.277556) (xy 184.195311 -304.283507) (xy 184.204102 -304.283872)
			(xy 184.403492 -304.283872) (xy 184.412302 -304.283456) (xy 184.428859 -304.277415) (xy 184.442407 -304.266142)
			(xy 184.44718 -304.258726) (xy 184.498488 -304.171096) (xy 184.498488 -304.144172) (xy 184.491884 -304.132488)
			(xy 184.478469 -304.107516) (xy 184.459441 -304.054123) (xy 184.449784 -303.998269) (xy 184.449212 -303.969928)
			(xy 184.449722 -303.943941) (xy 184.457852 -303.892606) (xy 184.473913 -303.843176) (xy 184.497509 -303.796866)
			(xy 184.528059 -303.754818) (xy 184.56481 -303.718067) (xy 184.606858 -303.687517) (xy 184.653168 -303.663921)
			(xy 184.702598 -303.64786) (xy 184.753933 -303.63973) (xy 184.805907 -303.63973) (xy 184.857242 -303.64786)
			(xy 184.906672 -303.663921) (xy 184.952982 -303.687517) (xy 184.99503 -303.718067) (xy 185.031781 -303.754818)
			(xy 185.062331 -303.796866) (xy 185.085927 -303.843176) (xy 185.101988 -303.892606) (xy 185.110118 -303.943941)
			(xy 185.110628 -303.969928) (xy 185.110045 -303.998268) (xy 185.100389 -304.05412) (xy 185.081363 -304.107513)
			(xy 185.067956 -304.132488) (xy 185.061352 -304.144172) (xy 185.061352 -304.171096) (xy 185.11266 -304.258726)
			(xy 185.11742 -304.266161) (xy 185.130951 -304.277477) (xy 185.147529 -304.283505) (xy 185.156348 -304.283872)
			(xy 185.345832 -304.283872) (xy 185.35462 -304.283498) (xy 185.371154 -304.277539) (xy 185.384697 -304.266337)
			(xy 185.38952 -304.25898) (xy 185.441082 -304.172112) (xy 185.44159 -304.145442) (xy 185.434986 -304.133504)
			(xy 185.422206 -304.109015) (xy 185.404092 -304.056836) (xy 185.394902 -304.002371) (xy 185.394346 -303.974754)
			(xy 185.394859 -303.948768) (xy 185.402995 -303.897436) (xy 185.419059 -303.848009) (xy 185.442657 -303.801702)
			(xy 185.473207 -303.759657) (xy 185.509957 -303.722907) (xy 185.552002 -303.692357) (xy 185.598309 -303.668759)
			(xy 185.647736 -303.652695) (xy 185.699068 -303.644559) (xy 185.725054 -303.644046) (xy 185.748323 -303.64444)
			(xy 185.794403 -303.650961) (xy 185.839112 -303.663881) (xy 185.881567 -303.682944) (xy 185.920928 -303.707773)
			(xy 185.938922 -303.722532) (xy 185.950352 -303.732184) (xy 185.979562 -303.736248) (xy 186.076844 -303.69129)
			(xy 186.085483 -303.68686) (xy 186.098839 -303.672794) (xy 186.105987 -303.654762) (xy 186.106308 -303.645062)
			(xy 186.106308 -300.978062) (xy 186.105878 -300.967995) (xy 186.098155 -300.949399) (xy 186.091322 -300.941994)
			(xy 185.767726 -300.618398) (xy 185.760323 -300.611563) (xy 185.741725 -300.603856) (xy 185.731658 -300.603412)
			(xy 184.413144 -300.603412) (xy 184.403078 -300.602979) (xy 184.384487 -300.595252) (xy 184.377076 -300.588426)
			(xy 184.354978 -300.566328) (xy 184.348135 -300.558929) (xy 184.340414 -300.54033) (xy 184.339992 -300.53026)
			(xy 184.339992 -297.41114) (xy 184.340426 -297.401074) (xy 184.348154 -297.382485) (xy 184.354978 -297.375072)
			(xy 184.440576 -297.289474) (xy 184.447688 -297.275758) (xy 184.448958 -297.267884) (xy 184.453856 -297.242649)
			(xy 184.470424 -297.193988) (xy 184.494324 -297.148478) (xy 184.524981 -297.107217) (xy 184.561655 -297.071198)
			(xy 184.603463 -297.041291) (xy 184.649396 -297.018215) (xy 184.698348 -297.002529) (xy 184.749138 -296.994608)
			(xy 184.77484 -296.994072) (xy 184.80188 -296.994606) (xy 184.85524 -297.003397) (xy 184.906458 -297.020755)
			(xy 184.954168 -297.046217) (xy 184.997099 -297.079104) (xy 185.034105 -297.118539) (xy 185.0642 -297.16347)
			(xy 185.086582 -297.2127) (xy 185.094118 -297.238674) (xy 185.09869 -297.255438) (xy 185.125868 -297.276266)
			(xy 185.374026 -297.276266) (xy 185.401204 -297.255438) (xy 185.405776 -297.238674) (xy 185.412853 -297.214228)
			(xy 185.433475 -297.167703) (xy 185.460982 -297.124887) (xy 185.494724 -297.08679) (xy 185.533904 -297.054312)
			(xy 185.577597 -297.02822) (xy 185.624771 -297.00913) (xy 185.674314 -296.997493) (xy 185.725054 -296.993583)
			(xy 185.775794 -296.997493) (xy 185.825337 -297.00913) (xy 185.872511 -297.02822) (xy 185.916204 -297.054312)
			(xy 185.955384 -297.08679) (xy 185.989126 -297.124887) (xy 186.016633 -297.167703) (xy 186.037255 -297.214228)
			(xy 186.044332 -297.238674) (xy 186.048904 -297.255438) (xy 186.076082 -297.276266) (xy 186.323986 -297.276266)
			(xy 186.351164 -297.255438) (xy 186.355736 -297.238674) (xy 186.362548 -297.215121) (xy 186.382166 -297.170187)
			(xy 186.408207 -297.128646) (xy 186.440101 -297.091408) (xy 186.477147 -297.059291) (xy 186.518531 -297.033)
			(xy 186.563346 -297.013113) (xy 186.610607 -297.000065) (xy 186.634882 -296.996612) (xy 186.654186 -296.994072)
			(xy 186.679586 -296.96537) (xy 186.679586 -296.73423) (xy 186.654186 -296.705528) (xy 186.634882 -296.702988)
			(xy 186.609896 -296.699454) (xy 186.56132 -296.685791) (xy 186.515385 -296.664906) (xy 186.473156 -296.637284)
			(xy 186.435615 -296.603566) (xy 186.403634 -296.564534) (xy 186.377954 -296.521097) (xy 186.359174 -296.474261)
			(xy 186.347728 -296.425116) (xy 186.343883 -296.374802) (xy 186.347727 -296.324489) (xy 186.359172 -296.275343)
			(xy 186.377952 -296.228508) (xy 186.403631 -296.18507) (xy 186.435612 -296.146038) (xy 186.473152 -296.112319)
			(xy 186.515381 -296.084696) (xy 186.561316 -296.06381) (xy 186.609891 -296.050147) (xy 186.634882 -296.046652)
			(xy 186.654186 -296.044112) (xy 186.679586 -296.01541) (xy 186.679586 -294.83431) (xy 186.654186 -294.805608)
			(xy 186.634882 -294.803068) (xy 186.609897 -294.799534) (xy 186.561325 -294.785872) (xy 186.515392 -294.764988)
			(xy 186.473166 -294.737367) (xy 186.435628 -294.70365) (xy 186.403649 -294.664621) (xy 186.377971 -294.621186)
			(xy 186.359192 -294.574353) (xy 186.347747 -294.525211) (xy 186.343902 -294.4749) (xy 186.347747 -294.424589)
			(xy 186.359192 -294.375447) (xy 186.377971 -294.328614) (xy 186.403649 -294.285179) (xy 186.435628 -294.24615)
			(xy 186.473166 -294.212433) (xy 186.515392 -294.184812) (xy 186.561325 -294.163928) (xy 186.609897 -294.150266)
			(xy 186.634882 -294.146732) (xy 186.654186 -294.144192) (xy 186.679586 -294.11549) (xy 186.679586 -293.88435)
			(xy 186.654186 -293.855648) (xy 186.634882 -293.853108) (xy 186.609894 -293.849574) (xy 186.561316 -293.835911)
			(xy 186.515377 -293.815025) (xy 186.473146 -293.787401) (xy 186.435603 -293.753681) (xy 186.403619 -293.714648)
			(xy 186.377938 -293.671208) (xy 186.359156 -293.62437) (xy 186.347709 -293.575222) (xy 186.343863 -293.524905)
			(xy 186.347707 -293.474588) (xy 186.359153 -293.42544) (xy 186.377933 -293.378601) (xy 186.403613 -293.33516)
			(xy 186.435596 -293.296126) (xy 186.473138 -293.262405) (xy 186.515369 -293.23478) (xy 186.561307 -293.213892)
			(xy 186.609885 -293.200228) (xy 186.634882 -293.196772) (xy 186.654186 -293.194232) (xy 186.679586 -293.16553)
			(xy 186.679586 -292.93439) (xy 186.654186 -292.905688) (xy 186.634882 -292.903148) (xy 186.609899 -292.899614)
			(xy 186.561329 -292.885953) (xy 186.5154 -292.865069) (xy 186.473177 -292.83745) (xy 186.435641 -292.803735)
			(xy 186.403663 -292.764708) (xy 186.377988 -292.721275) (xy 186.35921 -292.674445) (xy 186.347766 -292.625305)
			(xy 186.343922 -292.574998) (xy 186.347767 -292.52469) (xy 186.359212 -292.475551) (xy 186.37799 -292.428721)
			(xy 186.403666 -292.385288) (xy 186.435644 -292.346262) (xy 186.47318 -292.312548) (xy 186.515404 -292.284928)
			(xy 186.561334 -292.264046) (xy 186.609904 -292.250385) (xy 186.634882 -292.246812) (xy 186.654186 -292.244272)
			(xy 186.679586 -292.21557) (xy 186.679586 -291.984176) (xy 186.654186 -291.955474) (xy 186.634882 -291.952934)
			(xy 186.6099 -291.9494) (xy 186.561333 -291.935739) (xy 186.515405 -291.914856) (xy 186.473184 -291.887237)
			(xy 186.435649 -291.853524) (xy 186.403674 -291.814498) (xy 186.378 -291.771067) (xy 186.359223 -291.724239)
			(xy 186.34778 -291.675102) (xy 186.343936 -291.624796) (xy 186.347781 -291.57449) (xy 186.359225 -291.525353)
			(xy 186.378003 -291.478526) (xy 186.403679 -291.435095) (xy 186.435655 -291.39607) (xy 186.47319 -291.362357)
			(xy 186.515412 -291.33474) (xy 186.56134 -291.313858) (xy 186.609908 -291.300198) (xy 186.634882 -291.296598)
			(xy 186.654186 -291.294058) (xy 186.679586 -291.265356) (xy 186.679586 -291.034216) (xy 186.654186 -291.005514)
			(xy 186.634882 -291.002974) (xy 186.609897 -290.99944) (xy 186.561324 -290.985778) (xy 186.51539 -290.964893)
			(xy 186.473163 -290.937272) (xy 186.435624 -290.903555) (xy 186.403644 -290.864525) (xy 186.377966 -290.821089)
			(xy 186.359187 -290.774256) (xy 186.347741 -290.725112) (xy 186.343896 -290.674801) (xy 186.347741 -290.624489)
			(xy 186.359186 -290.575346) (xy 186.377966 -290.528512) (xy 186.403643 -290.485076) (xy 186.435623 -290.446046)
			(xy 186.473162 -290.412329) (xy 186.515389 -290.384707) (xy 186.561322 -290.363823) (xy 186.609896 -290.35016)
			(xy 186.634882 -290.346638) (xy 186.654186 -290.344098) (xy 186.679586 -290.315396) (xy 186.679586 -290.084256)
			(xy 186.654186 -290.055554) (xy 186.634882 -290.053014) (xy 186.609894 -290.04948) (xy 186.561314 -290.035817)
			(xy 186.515375 -290.014931) (xy 186.473143 -289.987306) (xy 186.435599 -289.953586) (xy 186.403614 -289.914552)
			(xy 186.377933 -289.871111) (xy 186.35915 -289.824272) (xy 186.347703 -289.775123) (xy 186.343857 -289.724806)
			(xy 186.347701 -289.674488) (xy 186.359147 -289.625339) (xy 186.377928 -289.578499) (xy 186.403608 -289.535058)
			(xy 186.435591 -289.496022) (xy 186.473134 -289.4623) (xy 186.515365 -289.434675) (xy 186.561304 -289.413787)
			(xy 186.609883 -289.400122) (xy 186.634882 -289.396678) (xy 186.654186 -289.394138) (xy 186.679586 -289.365436)
			(xy 186.679586 -289.134296) (xy 186.654186 -289.105594) (xy 186.634882 -289.103054) (xy 186.608692 -289.099323)
			(xy 186.557878 -289.084618) (xy 186.510051 -289.062013) (xy 186.466431 -289.032086) (xy 186.42813 -288.995598)
			(xy 186.396124 -288.95348) (xy 186.371228 -288.906806) (xy 186.354077 -288.856764) (xy 186.345109 -288.804631)
			(xy 186.344306 -288.778188) (xy 186.344306 -288.774632) (xy 186.344726 -288.750731) (xy 186.351608 -288.703426)
			(xy 186.358022 -288.680398) (xy 186.360263 -288.671563) (xy 186.359025 -288.653392) (xy 186.351501 -288.636805)
			(xy 186.345322 -288.630106) (xy 186.12866 -288.413444) (xy 186.121548 -288.406078) (xy 186.102752 -288.398458)
			(xy 185.108596 -288.398458) (xy 185.099012 -288.398874) (xy 185.081178 -288.405901) (xy 185.067136 -288.41895)
			(xy 185.062622 -288.427414) (xy 185.023506 -288.510472) (xy 185.01974 -288.519336) (xy 185.018454 -288.538537)
			(xy 185.024343 -288.556858) (xy 185.03011 -288.564574) (xy 185.04777 -288.586962) (xy 185.075935 -288.636538)
			(xy 185.095194 -288.690205) (xy 185.104978 -288.746377) (xy 185.105548 -288.774886) (xy 185.105038 -288.800873)
			(xy 185.096908 -288.852208) (xy 185.080847 -288.901638) (xy 185.057251 -288.947948) (xy 185.026701 -288.989996)
			(xy 184.98995 -289.026747) (xy 184.947902 -289.057297) (xy 184.901592 -289.080893) (xy 184.852162 -289.096954)
			(xy 184.800827 -289.105084) (xy 184.748853 -289.105084) (xy 184.697518 -289.096954) (xy 184.648088 -289.080893)
			(xy 184.601778 -289.057297) (xy 184.55973 -289.026747) (xy 184.522979 -288.989996) (xy 184.492429 -288.947948)
			(xy 184.468833 -288.901638) (xy 184.452772 -288.852208) (xy 184.444642 -288.800873) (xy 184.444132 -288.774886)
			(xy 184.444223 -288.762136) (xy 184.446129 -288.736707) (xy 184.447942 -288.724086) (xy 184.4531 -288.694978)
			(xy 184.472367 -288.639097) (xy 184.501267 -288.587534) (xy 184.51957 -288.56432) (xy 184.525336 -288.556659)
			(xy 184.531194 -288.538417) (xy 184.529918 -288.5193) (xy 184.526174 -288.510472) (xy 184.487058 -288.427414)
			(xy 184.482587 -288.418908) (xy 184.468562 -288.405792) (xy 184.450686 -288.39878) (xy 184.441084 -288.398458)
			(xy 184.158636 -288.398458) (xy 184.149016 -288.398865) (xy 184.131127 -288.405948) (xy 184.117112 -288.41913)
			(xy 184.112662 -288.427668) (xy 184.066942 -288.524188) (xy 184.070752 -288.553144) (xy 184.08015 -288.564574)
			(xy 184.097808 -288.586963) (xy 184.12597 -288.63654) (xy 184.145226 -288.690206) (xy 184.155009 -288.746378)
			(xy 184.155588 -288.774886) (xy 184.155078 -288.800873) (xy 184.146948 -288.852208) (xy 184.130887 -288.901638)
			(xy 184.107291 -288.947948) (xy 184.076741 -288.989996) (xy 184.03999 -289.026747) (xy 183.997942 -289.057297)
			(xy 183.951632 -289.080893) (xy 183.902202 -289.096954) (xy 183.850867 -289.105084) (xy 183.798893 -289.105084)
			(xy 183.747558 -289.096954) (xy 183.698128 -289.080893) (xy 183.651818 -289.057297) (xy 183.60977 -289.026747)
			(xy 183.573019 -288.989996) (xy 183.542469 -288.947948) (xy 183.518873 -288.901638) (xy 183.502812 -288.852208)
			(xy 183.494682 -288.800873) (xy 183.494172 -288.774886) (xy 183.494769 -288.746379) (xy 183.504543 -288.690208)
			(xy 183.523797 -288.636543) (xy 183.551964 -288.586972) (xy 183.56961 -288.564574) (xy 183.579008 -288.553144)
			(xy 183.582818 -288.524188) (xy 183.537098 -288.427668) (xy 183.532634 -288.419141) (xy 183.518619 -288.405971)
			(xy 183.50074 -288.398885) (xy 183.491124 -288.398458) (xy 183.208676 -288.398458) (xy 183.199062 -288.398876)
			(xy 183.181191 -288.405972) (xy 183.167194 -288.419155) (xy 183.162702 -288.427668) (xy 183.116982 -288.524188)
			(xy 183.120792 -288.553144) (xy 183.13019 -288.564574) (xy 183.147846 -288.586964) (xy 183.176005 -288.636541)
			(xy 183.195259 -288.690208) (xy 183.20504 -288.746378) (xy 183.205628 -288.774886) (xy 183.205118 -288.800873)
			(xy 183.196988 -288.852208) (xy 183.180927 -288.901638) (xy 183.157331 -288.947948) (xy 183.126781 -288.989996)
			(xy 183.09003 -289.026747) (xy 183.047982 -289.057297) (xy 183.001672 -289.080893) (xy 182.952242 -289.096954)
			(xy 182.900907 -289.105084) (xy 182.848933 -289.105084) (xy 182.797598 -289.096954) (xy 182.748168 -289.080893)
			(xy 182.701858 -289.057297) (xy 182.65981 -289.026747) (xy 182.623059 -288.989996) (xy 182.592509 -288.947948)
			(xy 182.568913 -288.901638) (xy 182.552852 -288.852208) (xy 182.544722 -288.800873) (xy 182.544212 -288.774886)
			(xy 182.544809 -288.746379) (xy 182.554584 -288.690209) (xy 182.57384 -288.636545) (xy 182.602009 -288.586976)
			(xy 182.61965 -288.564574) (xy 182.629048 -288.553144) (xy 182.632858 -288.524188) (xy 182.587138 -288.427668)
			(xy 182.582676 -288.419137) (xy 182.568663 -288.405956) (xy 182.550783 -288.398855) (xy 182.541164 -288.398458)
			(xy 182.258716 -288.398458) (xy 182.249098 -288.398869) (xy 182.231215 -288.405956) (xy 182.217206 -288.419138)
			(xy 182.212742 -288.427668) (xy 182.167022 -288.524188) (xy 182.170832 -288.553144) (xy 182.18023 -288.564574)
			(xy 182.197889 -288.586963) (xy 182.226052 -288.636539) (xy 182.24531 -288.690206) (xy 182.255093 -288.746378)
			(xy 182.255668 -288.774886) (xy 182.255158 -288.800873) (xy 182.247028 -288.852208) (xy 182.230967 -288.901638)
			(xy 182.207371 -288.947948) (xy 182.176821 -288.989996) (xy 182.14007 -289.026747) (xy 182.098022 -289.057297)
			(xy 182.051712 -289.080893) (xy 182.002282 -289.096954) (xy 181.950947 -289.105084) (xy 181.898973 -289.105084)
			(xy 181.847638 -289.096954) (xy 181.798208 -289.080893) (xy 181.751898 -289.057297) (xy 181.70985 -289.026747)
			(xy 181.673099 -288.989996) (xy 181.642549 -288.947948) (xy 181.618953 -288.901638) (xy 181.602892 -288.852208)
			(xy 181.594762 -288.800873) (xy 181.594252 -288.774886) (xy 181.594849 -288.746379) (xy 181.604622 -288.690207)
			(xy 181.623876 -288.636542) (xy 181.652041 -288.58697) (xy 181.66969 -288.564574) (xy 181.679088 -288.553144)
			(xy 181.682898 -288.524188) (xy 181.637178 -288.427668) (xy 181.632713 -288.419143) (xy 181.618696 -288.405979)
			(xy 181.600818 -288.398899) (xy 181.591204 -288.398458) (xy 181.308756 -288.398458) (xy 181.299134 -288.398862)
			(xy 181.28124 -288.405941) (xy 181.267219 -288.419121) (xy 181.262782 -288.427668) (xy 181.217062 -288.524188)
			(xy 181.220872 -288.553144) (xy 181.23027 -288.564574) (xy 181.247927 -288.586963) (xy 181.276087 -288.636541)
			(xy 181.295342 -288.690207) (xy 181.305124 -288.746378) (xy 181.305708 -288.774886) (xy 181.305198 -288.800873)
			(xy 181.297068 -288.852208) (xy 181.281007 -288.901638) (xy 181.257411 -288.947948) (xy 181.226861 -288.989996)
			(xy 181.19011 -289.026747) (xy 181.148062 -289.057297) (xy 181.101752 -289.080893) (xy 181.052322 -289.096954)
			(xy 181.000987 -289.105084) (xy 180.949013 -289.105084) (xy 180.897678 -289.096954) (xy 180.848248 -289.080893)
			(xy 180.801938 -289.057297) (xy 180.75989 -289.026747) (xy 180.723139 -288.989996) (xy 180.692589 -288.947948)
			(xy 180.668993 -288.901638) (xy 180.652932 -288.852208) (xy 180.644802 -288.800873) (xy 180.644292 -288.774886)
			(xy 180.644889 -288.746379) (xy 180.654663 -288.690208) (xy 180.673919 -288.636544) (xy 180.702087 -288.586974)
			(xy 180.71973 -288.564574) (xy 180.729128 -288.553144) (xy 180.732938 -288.524188) (xy 180.687218 -288.427668)
			(xy 180.682755 -288.419139) (xy 180.66874 -288.405964) (xy 180.650861 -288.39887) (xy 180.641244 -288.398458)
			(xy 180.358796 -288.398458) (xy 180.34918 -288.398872) (xy 180.331303 -288.405964) (xy 180.3173 -288.419147)
			(xy 180.312822 -288.427668) (xy 180.267102 -288.524188) (xy 180.270912 -288.553144) (xy 180.28031 -288.564574)
			(xy 180.29797 -288.586962) (xy 180.326135 -288.636538) (xy 180.345394 -288.690205) (xy 180.355178 -288.746377)
			(xy 180.355748 -288.774886) (xy 180.355238 -288.800873) (xy 180.347108 -288.852208) (xy 180.331047 -288.901638)
			(xy 180.307451 -288.947948) (xy 180.276901 -288.989996) (xy 180.24015 -289.026747) (xy 180.198102 -289.057297)
			(xy 180.151792 -289.080893) (xy 180.102362 -289.096954) (xy 180.051027 -289.105084) (xy 179.999053 -289.105084)
			(xy 179.947718 -289.096954) (xy 179.898288 -289.080893) (xy 179.851978 -289.057297) (xy 179.80993 -289.026747)
			(xy 179.773179 -288.989996) (xy 179.742629 -288.947948) (xy 179.719033 -288.901638) (xy 179.702972 -288.852208)
			(xy 179.694842 -288.800873) (xy 179.694332 -288.774886) (xy 179.69493 -288.746379) (xy 179.704705 -288.69021)
			(xy 179.723962 -288.636547) (xy 179.752133 -288.586979) (xy 179.76977 -288.564574) (xy 179.779168 -288.553144)
			(xy 179.782978 -288.524188) (xy 179.737258 -288.427668) (xy 179.732792 -288.419146) (xy 179.718775 -288.405987)
			(xy 179.700897 -288.398914) (xy 179.691284 -288.398458) (xy 179.408836 -288.398458) (xy 179.399216 -288.398865)
			(xy 179.381327 -288.405948) (xy 179.367312 -288.41913) (xy 179.362862 -288.427668) (xy 179.317142 -288.524188)
			(xy 179.320952 -288.553144) (xy 179.33035 -288.564574) (xy 179.348008 -288.586963) (xy 179.37617 -288.63654)
			(xy 179.395426 -288.690206) (xy 179.405209 -288.746378) (xy 179.405788 -288.774886) (xy 179.405278 -288.800873)
			(xy 179.397148 -288.852208) (xy 179.381087 -288.901638) (xy 179.357491 -288.947948) (xy 179.326941 -288.989996)
			(xy 179.29019 -289.026747) (xy 179.248142 -289.057297) (xy 179.201832 -289.080893) (xy 179.152402 -289.096954)
			(xy 179.101067 -289.105084) (xy 179.049093 -289.105084) (xy 178.997758 -289.096954) (xy 178.948328 -289.080893)
			(xy 178.902018 -289.057297) (xy 178.85997 -289.026747) (xy 178.823219 -288.989996) (xy 178.792669 -288.947948)
			(xy 178.769073 -288.901638) (xy 178.753012 -288.852208) (xy 178.744882 -288.800873) (xy 178.744372 -288.774886)
			(xy 178.744969 -288.746379) (xy 178.754743 -288.690208) (xy 178.773997 -288.636543) (xy 178.802164 -288.586972)
			(xy 178.81981 -288.564574) (xy 178.829208 -288.553144) (xy 178.833018 -288.524188) (xy 178.787298 -288.427668)
			(xy 178.782834 -288.419141) (xy 178.768819 -288.405971) (xy 178.75094 -288.398885) (xy 178.741324 -288.398458)
			(xy 178.458622 -288.398458) (xy 178.449003 -288.398868) (xy 178.431119 -288.405954) (xy 178.417108 -288.419136)
			(xy 178.412648 -288.427668) (xy 178.366928 -288.524188) (xy 178.370738 -288.553144) (xy 178.380136 -288.564574)
			(xy 178.397795 -288.586963) (xy 178.425958 -288.636539) (xy 178.445215 -288.690206) (xy 178.454998 -288.746378)
			(xy 178.455574 -288.774886) (xy 178.455064 -288.800873) (xy 178.446934 -288.852208) (xy 178.430873 -288.901638)
			(xy 178.407277 -288.947948) (xy 178.376727 -288.989996) (xy 178.339976 -289.026747) (xy 178.297928 -289.057297)
			(xy 178.251618 -289.080893) (xy 178.202188 -289.096954) (xy 178.150853 -289.105084) (xy 178.098879 -289.105084)
			(xy 178.047544 -289.096954) (xy 177.998114 -289.080893) (xy 177.951804 -289.057297) (xy 177.909756 -289.026747)
			(xy 177.873005 -288.989996) (xy 177.842455 -288.947948) (xy 177.818859 -288.901638) (xy 177.802798 -288.852208)
			(xy 177.794668 -288.800873) (xy 177.794158 -288.774886) (xy 177.794755 -288.746379) (xy 177.804528 -288.690208)
			(xy 177.823782 -288.636542) (xy 177.851948 -288.58697) (xy 177.869596 -288.564574) (xy 177.878994 -288.553144)
			(xy 177.882804 -288.524188) (xy 177.837084 -288.427668) (xy 177.832619 -288.419143) (xy 177.818603 -288.405977)
			(xy 177.800725 -288.398895) (xy 177.79111 -288.398458) (xy 177.508662 -288.398458) (xy 177.499049 -288.398878)
			(xy 177.481183 -288.405977) (xy 177.46719 -288.419161) (xy 177.462688 -288.427668) (xy 177.416968 -288.524188)
			(xy 177.420778 -288.553144) (xy 177.430176 -288.564574) (xy 177.447833 -288.586964) (xy 177.475992 -288.636541)
			(xy 177.495247 -288.690207) (xy 177.505029 -288.746378) (xy 177.505614 -288.774886) (xy 177.505104 -288.800873)
			(xy 177.496974 -288.852208) (xy 177.480913 -288.901638) (xy 177.457317 -288.947948) (xy 177.426767 -288.989996)
			(xy 177.390016 -289.026747) (xy 177.347968 -289.057297) (xy 177.301658 -289.080893) (xy 177.252228 -289.096954)
			(xy 177.200893 -289.105084) (xy 177.148919 -289.105084) (xy 177.097584 -289.096954) (xy 177.048154 -289.080893)
			(xy 177.001844 -289.057297) (xy 176.959796 -289.026747) (xy 176.923045 -288.989996) (xy 176.892495 -288.947948)
			(xy 176.868899 -288.901638) (xy 176.852838 -288.852208) (xy 176.844708 -288.800873) (xy 176.844198 -288.774886)
			(xy 176.844795 -288.746379) (xy 176.854569 -288.690209) (xy 176.873825 -288.636545) (xy 176.901994 -288.586975)
			(xy 176.919636 -288.564574) (xy 176.929034 -288.553144) (xy 176.932844 -288.524188) (xy 176.887124 -288.427668)
			(xy 176.882661 -288.419138) (xy 176.868647 -288.405962) (xy 176.850768 -288.398866) (xy 176.84115 -288.398458)
			(xy 176.558702 -288.398458) (xy 176.549085 -288.398871) (xy 176.531207 -288.405962) (xy 176.517202 -288.419144)
			(xy 176.512728 -288.427668) (xy 176.467008 -288.524188) (xy 176.470818 -288.553144) (xy 176.480216 -288.564574)
			(xy 176.497876 -288.586962) (xy 176.52604 -288.636538) (xy 176.545299 -288.690205) (xy 176.555082 -288.746377)
			(xy 176.555654 -288.774886) (xy 176.555144 -288.800873) (xy 176.547014 -288.852208) (xy 176.530953 -288.901638)
			(xy 176.507357 -288.947948) (xy 176.476807 -288.989996) (xy 176.440056 -289.026747) (xy 176.398008 -289.057297)
			(xy 176.351698 -289.080893) (xy 176.302268 -289.096954) (xy 176.250933 -289.105084) (xy 176.198959 -289.105084)
			(xy 176.147624 -289.096954) (xy 176.098194 -289.080893) (xy 176.051884 -289.057297) (xy 176.009836 -289.026747)
			(xy 175.973085 -288.989996) (xy 175.942535 -288.947948) (xy 175.918939 -288.901638) (xy 175.902878 -288.852208)
			(xy 175.894748 -288.800873) (xy 175.894238 -288.774886) (xy 175.894836 -288.746379) (xy 175.904611 -288.69021)
			(xy 175.923869 -288.636547) (xy 175.95204 -288.586979) (xy 175.969676 -288.564574) (xy 175.979074 -288.553144)
			(xy 175.982884 -288.524188) (xy 175.937164 -288.427668) (xy 175.932698 -288.419145) (xy 175.918681 -288.405985)
			(xy 175.900803 -288.39891) (xy 175.89119 -288.398458) (xy 174.658782 -288.398458) (xy 174.649167 -288.398875)
			(xy 174.631295 -288.405969) (xy 174.617296 -288.419153) (xy 174.612808 -288.427668) (xy 174.567088 -288.524188)
			(xy 174.570898 -288.553144) (xy 174.580296 -288.564574) (xy 174.597952 -288.586964) (xy 174.62611 -288.636542)
			(xy 174.645363 -288.690208) (xy 174.655144 -288.746378) (xy 174.655734 -288.774886) (xy 174.655224 -288.800873)
			(xy 174.647094 -288.852208) (xy 174.631033 -288.901638) (xy 174.607437 -288.947948) (xy 174.576887 -288.989996)
			(xy 174.540136 -289.026747) (xy 174.498088 -289.057297) (xy 174.451778 -289.080893) (xy 174.402348 -289.096954)
			(xy 174.351013 -289.105084) (xy 174.299039 -289.105084) (xy 174.247704 -289.096954) (xy 174.198274 -289.080893)
			(xy 174.151964 -289.057297) (xy 174.109916 -289.026747) (xy 174.073165 -288.989996) (xy 174.042615 -288.947948)
			(xy 174.019019 -288.901638) (xy 174.002958 -288.852208) (xy 173.994828 -288.800873) (xy 173.994318 -288.774886)
			(xy 173.994916 -288.746379) (xy 174.00469 -288.690209) (xy 174.023947 -288.636546) (xy 174.052116 -288.586977)
			(xy 174.069756 -288.564574) (xy 174.079154 -288.553144) (xy 174.082964 -288.524188) (xy 174.037244 -288.427668)
			(xy 174.032782 -288.419136) (xy 174.018769 -288.405954) (xy 174.000889 -288.398851) (xy 173.99127 -288.398458)
			(xy 173.708822 -288.398458) (xy 173.699203 -288.398868) (xy 173.681319 -288.405954) (xy 173.667308 -288.419136)
			(xy 173.662848 -288.427668) (xy 173.617128 -288.524188) (xy 173.620938 -288.553144) (xy 173.630336 -288.564574)
			(xy 173.647995 -288.586963) (xy 173.676158 -288.636539) (xy 173.695415 -288.690206) (xy 173.705198 -288.746378)
			(xy 173.705774 -288.774886) (xy 173.705264 -288.800873) (xy 173.697134 -288.852208) (xy 173.681073 -288.901638)
			(xy 173.657477 -288.947948) (xy 173.626927 -288.989996) (xy 173.590176 -289.026747) (xy 173.548128 -289.057297)
			(xy 173.501818 -289.080893) (xy 173.452388 -289.096954) (xy 173.401053 -289.105084) (xy 173.349079 -289.105084)
			(xy 173.297744 -289.096954) (xy 173.248314 -289.080893) (xy 173.202004 -289.057297) (xy 173.159956 -289.026747)
			(xy 173.123205 -288.989996) (xy 173.092655 -288.947948) (xy 173.069059 -288.901638) (xy 173.052998 -288.852208)
			(xy 173.044868 -288.800873) (xy 173.044358 -288.774886) (xy 173.044955 -288.746379) (xy 173.054728 -288.690208)
			(xy 173.073982 -288.636542) (xy 173.102148 -288.58697) (xy 173.119796 -288.564574) (xy 173.129194 -288.553144)
			(xy 173.133004 -288.524188) (xy 173.087284 -288.427668) (xy 173.082819 -288.419143) (xy 173.068803 -288.405977)
			(xy 173.050925 -288.398895) (xy 173.04131 -288.398458) (xy 172.758608 -288.398458) (xy 172.748991 -288.39887)
			(xy 172.73111 -288.405959) (xy 172.717104 -288.419142) (xy 172.712634 -288.427668) (xy 172.666914 -288.524188)
			(xy 172.670724 -288.553144) (xy 172.680122 -288.564574) (xy 172.697782 -288.586962) (xy 172.725946 -288.636539)
			(xy 172.745204 -288.690205) (xy 172.754987 -288.746377) (xy 172.75556 -288.774886) (xy 172.75505 -288.800873)
			(xy 172.74692 -288.852208) (xy 172.730859 -288.901638) (xy 172.707263 -288.947948) (xy 172.676713 -288.989996)
			(xy 172.639962 -289.026747) (xy 172.597914 -289.057297) (xy 172.551604 -289.080893) (xy 172.502174 -289.096954)
			(xy 172.450839 -289.105084) (xy 172.398865 -289.105084) (xy 172.34753 -289.096954) (xy 172.2981 -289.080893)
			(xy 172.25179 -289.057297) (xy 172.209742 -289.026747) (xy 172.172991 -288.989996) (xy 172.142441 -288.947948)
			(xy 172.118845 -288.901638) (xy 172.102784 -288.852208) (xy 172.094654 -288.800873) (xy 172.094144 -288.774886)
			(xy 172.094742 -288.746379) (xy 172.104517 -288.69021) (xy 172.123775 -288.636547) (xy 172.151946 -288.58698)
			(xy 172.169582 -288.564574) (xy 172.17898 -288.553144) (xy 172.18279 -288.524188) (xy 172.13707 -288.427668)
			(xy 172.132604 -288.419144) (xy 172.118588 -288.405982) (xy 172.10071 -288.398905) (xy 172.091096 -288.398458)
			(xy 171.808648 -288.398458) (xy 171.799027 -288.398863) (xy 171.781135 -288.405944) (xy 171.767116 -288.419125)
			(xy 171.762674 -288.427668) (xy 171.716954 -288.524188) (xy 171.720764 -288.553144) (xy 171.730162 -288.564574)
			(xy 171.74782 -288.586963) (xy 171.77598 -288.63654) (xy 171.795236 -288.690207) (xy 171.805018 -288.746378)
			(xy 171.8056 -288.774886) (xy 171.80509 -288.800873) (xy 171.79696 -288.852208) (xy 171.780899 -288.901638)
			(xy 171.757303 -288.947948) (xy 171.726753 -288.989996) (xy 171.690002 -289.026747) (xy 171.647954 -289.057297)
			(xy 171.601644 -289.080893) (xy 171.552214 -289.096954) (xy 171.500879 -289.105084) (xy 171.448905 -289.105084)
			(xy 171.39757 -289.096954) (xy 171.34814 -289.080893) (xy 171.30183 -289.057297) (xy 171.259782 -289.026747)
			(xy 171.223031 -288.989996) (xy 171.192481 -288.947948) (xy 171.168885 -288.901638) (xy 171.152824 -288.852208)
			(xy 171.144694 -288.800873) (xy 171.144184 -288.774886) (xy 171.144781 -288.746379) (xy 171.154555 -288.690208)
			(xy 171.17381 -288.636544) (xy 171.201978 -288.586973) (xy 171.219622 -288.564574) (xy 171.22902 -288.553144)
			(xy 171.23283 -288.524188) (xy 171.18711 -288.427668) (xy 171.182646 -288.41914) (xy 171.168632 -288.405967)
			(xy 171.150753 -288.398876) (xy 171.141136 -288.398458) (xy 170.858688 -288.398458) (xy 170.849073 -288.398874)
			(xy 170.831198 -288.405967) (xy 170.817198 -288.41915) (xy 170.812714 -288.427668) (xy 170.766994 -288.524188)
			(xy 170.770804 -288.553144) (xy 170.780202 -288.564574) (xy 170.797858 -288.586964) (xy 170.826015 -288.636542)
			(xy 170.845268 -288.690208) (xy 170.855049 -288.746378) (xy 170.85564 -288.774886) (xy 170.85513 -288.800873)
			(xy 170.847 -288.852208) (xy 170.830939 -288.901638) (xy 170.807343 -288.947948) (xy 170.776793 -288.989996)
			(xy 170.740042 -289.026747) (xy 170.697994 -289.057297) (xy 170.651684 -289.080893) (xy 170.602254 -289.096954)
			(xy 170.550919 -289.105084) (xy 170.498945 -289.105084) (xy 170.44761 -289.096954) (xy 170.39818 -289.080893)
			(xy 170.35187 -289.057297) (xy 170.309822 -289.026747) (xy 170.273071 -288.989996) (xy 170.242521 -288.947948)
			(xy 170.218925 -288.901638) (xy 170.202864 -288.852208) (xy 170.194734 -288.800873) (xy 170.194224 -288.774886)
			(xy 170.194822 -288.746379) (xy 170.204596 -288.690209) (xy 170.223853 -288.636546) (xy 170.252023 -288.586977)
			(xy 170.269662 -288.564574) (xy 170.27906 -288.553144) (xy 170.28287 -288.524188) (xy 170.23715 -288.427668)
			(xy 170.232684 -288.419146) (xy 170.218666 -288.40599) (xy 170.200789 -288.39892) (xy 170.191176 -288.398458)
			(xy 169.908728 -288.398458) (xy 169.899109 -288.398867) (xy 169.881223 -288.405952) (xy 169.86721 -288.419133)
			(xy 169.862754 -288.427668) (xy 169.817034 -288.524188) (xy 169.820844 -288.553144) (xy 169.830242 -288.564574)
			(xy 169.847901 -288.586963) (xy 169.876063 -288.636539) (xy 169.89532 -288.690206) (xy 169.905103 -288.746378)
			(xy 169.90568 -288.774886) (xy 169.90517 -288.800873) (xy 169.89704 -288.852208) (xy 169.880979 -288.901638)
			(xy 169.857383 -288.947948) (xy 169.826833 -288.989996) (xy 169.790082 -289.026747) (xy 169.748034 -289.057297)
			(xy 169.701724 -289.080893) (xy 169.652294 -289.096954) (xy 169.600959 -289.105084) (xy 169.548985 -289.105084)
			(xy 169.49765 -289.096954) (xy 169.44822 -289.080893) (xy 169.40191 -289.057297) (xy 169.359862 -289.026747)
			(xy 169.323111 -288.989996) (xy 169.292561 -288.947948) (xy 169.268965 -288.901638) (xy 169.252904 -288.852208)
			(xy 169.244774 -288.800873) (xy 169.244264 -288.774886) (xy 169.244861 -288.746379) (xy 169.254634 -288.690208)
			(xy 169.273889 -288.636543) (xy 169.302055 -288.586971) (xy 169.319702 -288.564574) (xy 169.3291 -288.553144)
			(xy 169.33291 -288.524188) (xy 169.28719 -288.427668) (xy 169.282726 -288.419142) (xy 169.26871 -288.405974)
			(xy 169.250831 -288.39889) (xy 169.241216 -288.398458) (xy 168.958768 -288.398458) (xy 168.949155 -288.398877)
			(xy 168.931286 -288.405975) (xy 168.917291 -288.419159) (xy 168.912794 -288.427668) (xy 168.867074 -288.524188)
			(xy 168.870884 -288.553144) (xy 168.880282 -288.564574) (xy 168.897939 -288.586964) (xy 168.926098 -288.636541)
			(xy 168.945352 -288.690207) (xy 168.955134 -288.746378) (xy 168.95572 -288.774886) (xy 168.95521 -288.800873)
			(xy 168.94708 -288.852208) (xy 168.931019 -288.901638) (xy 168.907423 -288.947948) (xy 168.876873 -288.989996)
			(xy 168.840122 -289.026747) (xy 168.798074 -289.057297) (xy 168.751764 -289.080893) (xy 168.702334 -289.096954)
			(xy 168.650999 -289.105084) (xy 168.599025 -289.105084) (xy 168.54769 -289.096954) (xy 168.49826 -289.080893)
			(xy 168.45195 -289.057297) (xy 168.409902 -289.026747) (xy 168.373151 -288.989996) (xy 168.342601 -288.947948)
			(xy 168.319005 -288.901638) (xy 168.302944 -288.852208) (xy 168.294814 -288.800873) (xy 168.294304 -288.774886)
			(xy 168.294901 -288.746379) (xy 168.304675 -288.690209) (xy 168.323932 -288.636545) (xy 168.3521 -288.586975)
			(xy 168.369742 -288.564574) (xy 168.37914 -288.553144) (xy 168.38295 -288.524188) (xy 168.33723 -288.427668)
			(xy 168.332767 -288.419138) (xy 168.318754 -288.405959) (xy 168.300874 -288.398862) (xy 168.291256 -288.398458)
			(xy 168.008808 -288.398458) (xy 167.999191 -288.39887) (xy 167.98131 -288.405959) (xy 167.967304 -288.419142)
			(xy 167.962834 -288.427668) (xy 167.917114 -288.524188) (xy 167.920924 -288.553144) (xy 167.930322 -288.564574)
			(xy 167.947982 -288.586962) (xy 167.976146 -288.636539) (xy 167.995404 -288.690205) (xy 168.005187 -288.746377)
			(xy 168.00576 -288.774886) (xy 168.00525 -288.800873) (xy 167.99712 -288.852208) (xy 167.981059 -288.901638)
			(xy 167.957463 -288.947948) (xy 167.926913 -288.989996) (xy 167.890162 -289.026747) (xy 167.848114 -289.057297)
			(xy 167.801804 -289.080893) (xy 167.752374 -289.096954) (xy 167.701039 -289.105084) (xy 167.649065 -289.105084)
			(xy 167.59773 -289.096954) (xy 167.5483 -289.080893) (xy 167.50199 -289.057297) (xy 167.459942 -289.026747)
			(xy 167.423191 -288.989996) (xy 167.392641 -288.947948) (xy 167.369045 -288.901638) (xy 167.352984 -288.852208)
			(xy 167.344854 -288.800873) (xy 167.344344 -288.774886) (xy 167.344942 -288.746379) (xy 167.354717 -288.69021)
			(xy 167.373975 -288.636547) (xy 167.402146 -288.58698) (xy 167.419782 -288.564574) (xy 167.42918 -288.553144)
			(xy 167.43299 -288.524188) (xy 167.38727 -288.427668) (xy 167.382804 -288.419144) (xy 167.368788 -288.405982)
			(xy 167.35091 -288.398905) (xy 167.341296 -288.398458) (xy 167.058848 -288.398458) (xy 167.049227 -288.398863)
			(xy 167.031335 -288.405944) (xy 167.017316 -288.419125) (xy 167.012874 -288.427668) (xy 166.967154 -288.524188)
			(xy 166.970964 -288.553144) (xy 166.980362 -288.564574) (xy 166.99802 -288.586963) (xy 167.02618 -288.63654)
			(xy 167.045436 -288.690207) (xy 167.055218 -288.746378) (xy 167.0558 -288.774886) (xy 167.05529 -288.800873)
			(xy 167.04716 -288.852208) (xy 167.031099 -288.901638) (xy 167.007503 -288.947948) (xy 166.976953 -288.989996)
			(xy 166.940202 -289.026747) (xy 166.898154 -289.057297) (xy 166.851844 -289.080893) (xy 166.802414 -289.096954)
			(xy 166.751079 -289.105084) (xy 166.699105 -289.105084) (xy 166.64777 -289.096954) (xy 166.59834 -289.080893)
			(xy 166.55203 -289.057297) (xy 166.509982 -289.026747) (xy 166.473231 -288.989996) (xy 166.442681 -288.947948)
			(xy 166.419085 -288.901638) (xy 166.403024 -288.852208) (xy 166.394894 -288.800873) (xy 166.394384 -288.774886)
			(xy 166.394981 -288.746379) (xy 166.404755 -288.690208) (xy 166.42401 -288.636544) (xy 166.452178 -288.586973)
			(xy 166.469822 -288.564574) (xy 166.47922 -288.553144) (xy 166.48303 -288.524188) (xy 166.43731 -288.427668)
			(xy 166.432846 -288.41914) (xy 166.418832 -288.405967) (xy 166.400953 -288.398876) (xy 166.391336 -288.398458)
			(xy 166.182802 -288.398458) (xy 166.172733 -288.398882) (xy 166.154133 -288.406603) (xy 166.146734 -288.413444)
			(xy 166.033196 -288.526982) (xy 166.030402 -288.564066) (xy 166.041578 -288.579306) (xy 166.056658 -288.600705)
			(xy 166.080582 -288.647266) (xy 166.096867 -288.697017) (xy 166.105105 -288.748712) (xy 166.105586 -288.774886)
			(xy 166.105104 -288.800875) (xy 166.096974 -288.852214) (xy 166.080913 -288.901649) (xy 166.057316 -288.947963)
			(xy 166.026763 -288.990014) (xy 165.990008 -289.026768) (xy 165.947956 -289.05732) (xy 165.901642 -289.080916)
			(xy 165.852207 -289.096976) (xy 165.800867 -289.105105) (xy 165.774878 -289.105594) (xy 165.748705 -289.105095)
			(xy 165.697014 -289.09685) (xy 165.647265 -289.08057) (xy 165.6007 -289.05666) (xy 165.579298 -289.041586)
			(xy 165.564058 -289.03041) (xy 165.526974 -289.033204) (xy 165.216332 -289.343846) (xy 165.208933 -289.350688)
			(xy 165.190334 -289.358406) (xy 165.180264 -289.358832) (xy 165.166802 -289.358832) (xy 165.157364 -289.359317)
			(xy 165.139791 -289.366224) (xy 165.125887 -289.378998) (xy 165.121336 -289.38728) (xy 165.0746 -289.482276)
			(xy 165.077648 -289.510978) (xy 165.086538 -289.522662) (xy 165.10275 -289.544525) (xy 165.128548 -289.592446)
			(xy 165.146147 -289.643946) (xy 165.155072 -289.697634) (xy 165.155626 -289.724846) (xy 165.155116 -289.750833)
			(xy 165.44468 -289.750833) (xy 165.44468 -289.698859) (xy 165.45281 -289.647524) (xy 165.468871 -289.598094)
			(xy 165.492467 -289.551784) (xy 165.523017 -289.509736) (xy 165.559768 -289.472985) (xy 165.601816 -289.442435)
			(xy 165.648126 -289.418839) (xy 165.697556 -289.402778) (xy 165.748891 -289.394648) (xy 165.800865 -289.394648)
			(xy 165.8522 -289.402778) (xy 165.90163 -289.418839) (xy 165.94794 -289.442435) (xy 165.989988 -289.472985)
			(xy 166.026739 -289.509736) (xy 166.057289 -289.551784) (xy 166.080885 -289.598094) (xy 166.096946 -289.647524)
			(xy 166.105076 -289.698859) (xy 166.105586 -289.724846) (xy 166.105076 -289.750833) (xy 166.394894 -289.750833)
			(xy 166.394894 -289.698859) (xy 166.403024 -289.647524) (xy 166.419085 -289.598094) (xy 166.442681 -289.551784)
			(xy 166.473231 -289.509736) (xy 166.509982 -289.472985) (xy 166.55203 -289.442435) (xy 166.59834 -289.418839)
			(xy 166.64777 -289.402778) (xy 166.699105 -289.394648) (xy 166.751079 -289.394648) (xy 166.802414 -289.402778)
			(xy 166.851844 -289.418839) (xy 166.898154 -289.442435) (xy 166.940202 -289.472985) (xy 166.976953 -289.509736)
			(xy 167.007503 -289.551784) (xy 167.031099 -289.598094) (xy 167.04716 -289.647524) (xy 167.05529 -289.698859)
			(xy 167.0558 -289.724846) (xy 167.05529 -289.750833) (xy 167.344854 -289.750833) (xy 167.344854 -289.698859)
			(xy 167.352984 -289.647524) (xy 167.369045 -289.598094) (xy 167.392641 -289.551784) (xy 167.423191 -289.509736)
			(xy 167.459942 -289.472985) (xy 167.50199 -289.442435) (xy 167.5483 -289.418839) (xy 167.59773 -289.402778)
			(xy 167.649065 -289.394648) (xy 167.701039 -289.394648) (xy 167.752374 -289.402778) (xy 167.801804 -289.418839)
			(xy 167.848114 -289.442435) (xy 167.890162 -289.472985) (xy 167.926913 -289.509736) (xy 167.957463 -289.551784)
			(xy 167.981059 -289.598094) (xy 167.99712 -289.647524) (xy 168.00525 -289.698859) (xy 168.00576 -289.724846)
			(xy 168.00525 -289.750833) (xy 168.294814 -289.750833) (xy 168.294814 -289.698859) (xy 168.302944 -289.647524)
			(xy 168.319005 -289.598094) (xy 168.342601 -289.551784) (xy 168.373151 -289.509736) (xy 168.409902 -289.472985)
			(xy 168.45195 -289.442435) (xy 168.49826 -289.418839) (xy 168.54769 -289.402778) (xy 168.599025 -289.394648)
			(xy 168.650999 -289.394648) (xy 168.702334 -289.402778) (xy 168.751764 -289.418839) (xy 168.798074 -289.442435)
			(xy 168.840122 -289.472985) (xy 168.876873 -289.509736) (xy 168.907423 -289.551784) (xy 168.931019 -289.598094)
			(xy 168.94708 -289.647524) (xy 168.95521 -289.698859) (xy 168.95572 -289.724846) (xy 168.95521 -289.750833)
			(xy 169.244774 -289.750833) (xy 169.244774 -289.698859) (xy 169.252904 -289.647524) (xy 169.268965 -289.598094)
			(xy 169.292561 -289.551784) (xy 169.323111 -289.509736) (xy 169.359862 -289.472985) (xy 169.40191 -289.442435)
			(xy 169.44822 -289.418839) (xy 169.49765 -289.402778) (xy 169.548985 -289.394648) (xy 169.600959 -289.394648)
			(xy 169.652294 -289.402778) (xy 169.701724 -289.418839) (xy 169.748034 -289.442435) (xy 169.790082 -289.472985)
			(xy 169.826833 -289.509736) (xy 169.857383 -289.551784) (xy 169.880979 -289.598094) (xy 169.89704 -289.647524)
			(xy 169.90517 -289.698859) (xy 169.90568 -289.724846) (xy 169.90517 -289.750833) (xy 170.194734 -289.750833)
			(xy 170.194734 -289.698859) (xy 170.202864 -289.647524) (xy 170.218925 -289.598094) (xy 170.242521 -289.551784)
			(xy 170.273071 -289.509736) (xy 170.309822 -289.472985) (xy 170.35187 -289.442435) (xy 170.39818 -289.418839)
			(xy 170.44761 -289.402778) (xy 170.498945 -289.394648) (xy 170.550919 -289.394648) (xy 170.602254 -289.402778)
			(xy 170.651684 -289.418839) (xy 170.697994 -289.442435) (xy 170.740042 -289.472985) (xy 170.776793 -289.509736)
			(xy 170.807343 -289.551784) (xy 170.830939 -289.598094) (xy 170.847 -289.647524) (xy 170.85513 -289.698859)
			(xy 170.85564 -289.724846) (xy 170.85513 -289.750833) (xy 171.144694 -289.750833) (xy 171.144694 -289.698859)
			(xy 171.152824 -289.647524) (xy 171.168885 -289.598094) (xy 171.192481 -289.551784) (xy 171.223031 -289.509736)
			(xy 171.259782 -289.472985) (xy 171.30183 -289.442435) (xy 171.34814 -289.418839) (xy 171.39757 -289.402778)
			(xy 171.448905 -289.394648) (xy 171.500879 -289.394648) (xy 171.552214 -289.402778) (xy 171.601644 -289.418839)
			(xy 171.647954 -289.442435) (xy 171.690002 -289.472985) (xy 171.726753 -289.509736) (xy 171.757303 -289.551784)
			(xy 171.780899 -289.598094) (xy 171.79696 -289.647524) (xy 171.80509 -289.698859) (xy 171.8056 -289.724846)
			(xy 171.80509 -289.750833) (xy 172.094654 -289.750833) (xy 172.094654 -289.698859) (xy 172.102784 -289.647524)
			(xy 172.118845 -289.598094) (xy 172.142441 -289.551784) (xy 172.172991 -289.509736) (xy 172.209742 -289.472985)
			(xy 172.25179 -289.442435) (xy 172.2981 -289.418839) (xy 172.34753 -289.402778) (xy 172.398865 -289.394648)
			(xy 172.450839 -289.394648) (xy 172.502174 -289.402778) (xy 172.551604 -289.418839) (xy 172.597914 -289.442435)
			(xy 172.639962 -289.472985) (xy 172.676713 -289.509736) (xy 172.707263 -289.551784) (xy 172.730859 -289.598094)
			(xy 172.74692 -289.647524) (xy 172.75505 -289.698859) (xy 172.75556 -289.724846) (xy 172.75505 -289.750833)
			(xy 173.044868 -289.750833) (xy 173.044868 -289.698859) (xy 173.052998 -289.647524) (xy 173.069059 -289.598094)
			(xy 173.092655 -289.551784) (xy 173.123205 -289.509736) (xy 173.159956 -289.472985) (xy 173.202004 -289.442435)
			(xy 173.248314 -289.418839) (xy 173.297744 -289.402778) (xy 173.349079 -289.394648) (xy 173.401053 -289.394648)
			(xy 173.452388 -289.402778) (xy 173.501818 -289.418839) (xy 173.548128 -289.442435) (xy 173.590176 -289.472985)
			(xy 173.626927 -289.509736) (xy 173.657477 -289.551784) (xy 173.681073 -289.598094) (xy 173.697134 -289.647524)
			(xy 173.705264 -289.698859) (xy 173.705774 -289.724846) (xy 173.705264 -289.750833) (xy 173.994828 -289.750833)
			(xy 173.994828 -289.698859) (xy 174.002958 -289.647524) (xy 174.019019 -289.598094) (xy 174.042615 -289.551784)
			(xy 174.073165 -289.509736) (xy 174.109916 -289.472985) (xy 174.151964 -289.442435) (xy 174.198274 -289.418839)
			(xy 174.247704 -289.402778) (xy 174.299039 -289.394648) (xy 174.351013 -289.394648) (xy 174.402348 -289.402778)
			(xy 174.451778 -289.418839) (xy 174.498088 -289.442435) (xy 174.540136 -289.472985) (xy 174.576887 -289.509736)
			(xy 174.607437 -289.551784) (xy 174.631033 -289.598094) (xy 174.647094 -289.647524) (xy 174.655224 -289.698859)
			(xy 174.655734 -289.724846) (xy 174.655224 -289.750833) (xy 175.894748 -289.750833) (xy 175.894748 -289.698859)
			(xy 175.902878 -289.647524) (xy 175.918939 -289.598094) (xy 175.942535 -289.551784) (xy 175.973085 -289.509736)
			(xy 176.009836 -289.472985) (xy 176.051884 -289.442435) (xy 176.098194 -289.418839) (xy 176.147624 -289.402778)
			(xy 176.198959 -289.394648) (xy 176.250933 -289.394648) (xy 176.302268 -289.402778) (xy 176.351698 -289.418839)
			(xy 176.398008 -289.442435) (xy 176.440056 -289.472985) (xy 176.476807 -289.509736) (xy 176.507357 -289.551784)
			(xy 176.530953 -289.598094) (xy 176.547014 -289.647524) (xy 176.555144 -289.698859) (xy 176.555654 -289.724846)
			(xy 176.555144 -289.750833) (xy 176.844708 -289.750833) (xy 176.844708 -289.698859) (xy 176.852838 -289.647524)
			(xy 176.868899 -289.598094) (xy 176.892495 -289.551784) (xy 176.923045 -289.509736) (xy 176.959796 -289.472985)
			(xy 177.001844 -289.442435) (xy 177.048154 -289.418839) (xy 177.097584 -289.402778) (xy 177.148919 -289.394648)
			(xy 177.200893 -289.394648) (xy 177.252228 -289.402778) (xy 177.301658 -289.418839) (xy 177.347968 -289.442435)
			(xy 177.390016 -289.472985) (xy 177.426767 -289.509736) (xy 177.457317 -289.551784) (xy 177.480913 -289.598094)
			(xy 177.496974 -289.647524) (xy 177.505104 -289.698859) (xy 177.505614 -289.724846) (xy 177.505104 -289.750833)
			(xy 177.794668 -289.750833) (xy 177.794668 -289.698859) (xy 177.802798 -289.647524) (xy 177.818859 -289.598094)
			(xy 177.842455 -289.551784) (xy 177.873005 -289.509736) (xy 177.909756 -289.472985) (xy 177.951804 -289.442435)
			(xy 177.998114 -289.418839) (xy 178.047544 -289.402778) (xy 178.098879 -289.394648) (xy 178.150853 -289.394648)
			(xy 178.202188 -289.402778) (xy 178.251618 -289.418839) (xy 178.297928 -289.442435) (xy 178.339976 -289.472985)
			(xy 178.376727 -289.509736) (xy 178.407277 -289.551784) (xy 178.430873 -289.598094) (xy 178.446934 -289.647524)
			(xy 178.455064 -289.698859) (xy 178.455574 -289.724846) (xy 178.455064 -289.750833) (xy 178.744882 -289.750833)
			(xy 178.744882 -289.698859) (xy 178.753012 -289.647524) (xy 178.769073 -289.598094) (xy 178.792669 -289.551784)
			(xy 178.823219 -289.509736) (xy 178.85997 -289.472985) (xy 178.902018 -289.442435) (xy 178.948328 -289.418839)
			(xy 178.997758 -289.402778) (xy 179.049093 -289.394648) (xy 179.101067 -289.394648) (xy 179.152402 -289.402778)
			(xy 179.201832 -289.418839) (xy 179.248142 -289.442435) (xy 179.29019 -289.472985) (xy 179.326941 -289.509736)
			(xy 179.357491 -289.551784) (xy 179.381087 -289.598094) (xy 179.397148 -289.647524) (xy 179.405278 -289.698859)
			(xy 179.405788 -289.724846) (xy 179.405278 -289.750833) (xy 179.694842 -289.750833) (xy 179.694842 -289.698859)
			(xy 179.702972 -289.647524) (xy 179.719033 -289.598094) (xy 179.742629 -289.551784) (xy 179.773179 -289.509736)
			(xy 179.80993 -289.472985) (xy 179.851978 -289.442435) (xy 179.898288 -289.418839) (xy 179.947718 -289.402778)
			(xy 179.999053 -289.394648) (xy 180.051027 -289.394648) (xy 180.102362 -289.402778) (xy 180.151792 -289.418839)
			(xy 180.198102 -289.442435) (xy 180.24015 -289.472985) (xy 180.276901 -289.509736) (xy 180.307451 -289.551784)
			(xy 180.331047 -289.598094) (xy 180.347108 -289.647524) (xy 180.355238 -289.698859) (xy 180.355748 -289.724846)
			(xy 180.355238 -289.750833) (xy 180.644802 -289.750833) (xy 180.644802 -289.698859) (xy 180.652932 -289.647524)
			(xy 180.668993 -289.598094) (xy 180.692589 -289.551784) (xy 180.723139 -289.509736) (xy 180.75989 -289.472985)
			(xy 180.801938 -289.442435) (xy 180.848248 -289.418839) (xy 180.897678 -289.402778) (xy 180.949013 -289.394648)
			(xy 181.000987 -289.394648) (xy 181.052322 -289.402778) (xy 181.101752 -289.418839) (xy 181.148062 -289.442435)
			(xy 181.19011 -289.472985) (xy 181.226861 -289.509736) (xy 181.257411 -289.551784) (xy 181.281007 -289.598094)
			(xy 181.297068 -289.647524) (xy 181.305198 -289.698859) (xy 181.305708 -289.724846) (xy 181.305198 -289.750833)
			(xy 181.594762 -289.750833) (xy 181.594762 -289.698859) (xy 181.602892 -289.647524) (xy 181.618953 -289.598094)
			(xy 181.642549 -289.551784) (xy 181.673099 -289.509736) (xy 181.70985 -289.472985) (xy 181.751898 -289.442435)
			(xy 181.798208 -289.418839) (xy 181.847638 -289.402778) (xy 181.898973 -289.394648) (xy 181.950947 -289.394648)
			(xy 182.002282 -289.402778) (xy 182.051712 -289.418839) (xy 182.098022 -289.442435) (xy 182.14007 -289.472985)
			(xy 182.176821 -289.509736) (xy 182.207371 -289.551784) (xy 182.230967 -289.598094) (xy 182.247028 -289.647524)
			(xy 182.255158 -289.698859) (xy 182.255668 -289.724846) (xy 182.255158 -289.750833) (xy 182.544722 -289.750833)
			(xy 182.544722 -289.698859) (xy 182.552852 -289.647524) (xy 182.568913 -289.598094) (xy 182.592509 -289.551784)
			(xy 182.623059 -289.509736) (xy 182.65981 -289.472985) (xy 182.701858 -289.442435) (xy 182.748168 -289.418839)
			(xy 182.797598 -289.402778) (xy 182.848933 -289.394648) (xy 182.900907 -289.394648) (xy 182.952242 -289.402778)
			(xy 183.001672 -289.418839) (xy 183.047982 -289.442435) (xy 183.09003 -289.472985) (xy 183.126781 -289.509736)
			(xy 183.157331 -289.551784) (xy 183.180927 -289.598094) (xy 183.196988 -289.647524) (xy 183.205118 -289.698859)
			(xy 183.205628 -289.724846) (xy 183.205118 -289.750833) (xy 183.494682 -289.750833) (xy 183.494682 -289.698859)
			(xy 183.502812 -289.647524) (xy 183.518873 -289.598094) (xy 183.542469 -289.551784) (xy 183.573019 -289.509736)
			(xy 183.60977 -289.472985) (xy 183.651818 -289.442435) (xy 183.698128 -289.418839) (xy 183.747558 -289.402778)
			(xy 183.798893 -289.394648) (xy 183.850867 -289.394648) (xy 183.902202 -289.402778) (xy 183.951632 -289.418839)
			(xy 183.997942 -289.442435) (xy 184.03999 -289.472985) (xy 184.076741 -289.509736) (xy 184.107291 -289.551784)
			(xy 184.130887 -289.598094) (xy 184.146948 -289.647524) (xy 184.155078 -289.698859) (xy 184.155588 -289.724846)
			(xy 184.155078 -289.750833) (xy 184.444642 -289.750833) (xy 184.444642 -289.698859) (xy 184.452772 -289.647524)
			(xy 184.468833 -289.598094) (xy 184.492429 -289.551784) (xy 184.522979 -289.509736) (xy 184.55973 -289.472985)
			(xy 184.601778 -289.442435) (xy 184.648088 -289.418839) (xy 184.697518 -289.402778) (xy 184.748853 -289.394648)
			(xy 184.800827 -289.394648) (xy 184.852162 -289.402778) (xy 184.901592 -289.418839) (xy 184.947902 -289.442435)
			(xy 184.98995 -289.472985) (xy 185.026701 -289.509736) (xy 185.057251 -289.551784) (xy 185.080847 -289.598094)
			(xy 185.096908 -289.647524) (xy 185.105038 -289.698859) (xy 185.105548 -289.724846) (xy 185.105038 -289.750833)
			(xy 185.096908 -289.802168) (xy 185.080847 -289.851598) (xy 185.057251 -289.897908) (xy 185.026701 -289.939956)
			(xy 184.98995 -289.976707) (xy 184.947902 -290.007257) (xy 184.901592 -290.030853) (xy 184.852162 -290.046914)
			(xy 184.800827 -290.055044) (xy 184.748853 -290.055044) (xy 184.697518 -290.046914) (xy 184.648088 -290.030853)
			(xy 184.601778 -290.007257) (xy 184.55973 -289.976707) (xy 184.522979 -289.939956) (xy 184.492429 -289.897908)
			(xy 184.468833 -289.851598) (xy 184.452772 -289.802168) (xy 184.444642 -289.750833) (xy 184.155078 -289.750833)
			(xy 184.146948 -289.802168) (xy 184.130887 -289.851598) (xy 184.107291 -289.897908) (xy 184.076741 -289.939956)
			(xy 184.03999 -289.976707) (xy 183.997942 -290.007257) (xy 183.951632 -290.030853) (xy 183.902202 -290.046914)
			(xy 183.850867 -290.055044) (xy 183.798893 -290.055044) (xy 183.747558 -290.046914) (xy 183.698128 -290.030853)
			(xy 183.651818 -290.007257) (xy 183.60977 -289.976707) (xy 183.573019 -289.939956) (xy 183.542469 -289.897908)
			(xy 183.518873 -289.851598) (xy 183.502812 -289.802168) (xy 183.494682 -289.750833) (xy 183.205118 -289.750833)
			(xy 183.196988 -289.802168) (xy 183.180927 -289.851598) (xy 183.157331 -289.897908) (xy 183.126781 -289.939956)
			(xy 183.09003 -289.976707) (xy 183.047982 -290.007257) (xy 183.001672 -290.030853) (xy 182.952242 -290.046914)
			(xy 182.900907 -290.055044) (xy 182.848933 -290.055044) (xy 182.797598 -290.046914) (xy 182.748168 -290.030853)
			(xy 182.701858 -290.007257) (xy 182.65981 -289.976707) (xy 182.623059 -289.939956) (xy 182.592509 -289.897908)
			(xy 182.568913 -289.851598) (xy 182.552852 -289.802168) (xy 182.544722 -289.750833) (xy 182.255158 -289.750833)
			(xy 182.247028 -289.802168) (xy 182.230967 -289.851598) (xy 182.207371 -289.897908) (xy 182.176821 -289.939956)
			(xy 182.14007 -289.976707) (xy 182.098022 -290.007257) (xy 182.051712 -290.030853) (xy 182.002282 -290.046914)
			(xy 181.950947 -290.055044) (xy 181.898973 -290.055044) (xy 181.847638 -290.046914) (xy 181.798208 -290.030853)
			(xy 181.751898 -290.007257) (xy 181.70985 -289.976707) (xy 181.673099 -289.939956) (xy 181.642549 -289.897908)
			(xy 181.618953 -289.851598) (xy 181.602892 -289.802168) (xy 181.594762 -289.750833) (xy 181.305198 -289.750833)
			(xy 181.297068 -289.802168) (xy 181.281007 -289.851598) (xy 181.257411 -289.897908) (xy 181.226861 -289.939956)
			(xy 181.19011 -289.976707) (xy 181.148062 -290.007257) (xy 181.101752 -290.030853) (xy 181.052322 -290.046914)
			(xy 181.000987 -290.055044) (xy 180.949013 -290.055044) (xy 180.897678 -290.046914) (xy 180.848248 -290.030853)
			(xy 180.801938 -290.007257) (xy 180.75989 -289.976707) (xy 180.723139 -289.939956) (xy 180.692589 -289.897908)
			(xy 180.668993 -289.851598) (xy 180.652932 -289.802168) (xy 180.644802 -289.750833) (xy 180.355238 -289.750833)
			(xy 180.347108 -289.802168) (xy 180.331047 -289.851598) (xy 180.307451 -289.897908) (xy 180.276901 -289.939956)
			(xy 180.24015 -289.976707) (xy 180.198102 -290.007257) (xy 180.151792 -290.030853) (xy 180.102362 -290.046914)
			(xy 180.051027 -290.055044) (xy 179.999053 -290.055044) (xy 179.947718 -290.046914) (xy 179.898288 -290.030853)
			(xy 179.851978 -290.007257) (xy 179.80993 -289.976707) (xy 179.773179 -289.939956) (xy 179.742629 -289.897908)
			(xy 179.719033 -289.851598) (xy 179.702972 -289.802168) (xy 179.694842 -289.750833) (xy 179.405278 -289.750833)
			(xy 179.397148 -289.802168) (xy 179.381087 -289.851598) (xy 179.357491 -289.897908) (xy 179.326941 -289.939956)
			(xy 179.29019 -289.976707) (xy 179.248142 -290.007257) (xy 179.201832 -290.030853) (xy 179.152402 -290.046914)
			(xy 179.101067 -290.055044) (xy 179.049093 -290.055044) (xy 178.997758 -290.046914) (xy 178.948328 -290.030853)
			(xy 178.902018 -290.007257) (xy 178.85997 -289.976707) (xy 178.823219 -289.939956) (xy 178.792669 -289.897908)
			(xy 178.769073 -289.851598) (xy 178.753012 -289.802168) (xy 178.744882 -289.750833) (xy 178.455064 -289.750833)
			(xy 178.446934 -289.802168) (xy 178.430873 -289.851598) (xy 178.407277 -289.897908) (xy 178.376727 -289.939956)
			(xy 178.339976 -289.976707) (xy 178.297928 -290.007257) (xy 178.251618 -290.030853) (xy 178.202188 -290.046914)
			(xy 178.150853 -290.055044) (xy 178.098879 -290.055044) (xy 178.047544 -290.046914) (xy 177.998114 -290.030853)
			(xy 177.951804 -290.007257) (xy 177.909756 -289.976707) (xy 177.873005 -289.939956) (xy 177.842455 -289.897908)
			(xy 177.818859 -289.851598) (xy 177.802798 -289.802168) (xy 177.794668 -289.750833) (xy 177.505104 -289.750833)
			(xy 177.496974 -289.802168) (xy 177.480913 -289.851598) (xy 177.457317 -289.897908) (xy 177.426767 -289.939956)
			(xy 177.390016 -289.976707) (xy 177.347968 -290.007257) (xy 177.301658 -290.030853) (xy 177.252228 -290.046914)
			(xy 177.200893 -290.055044) (xy 177.148919 -290.055044) (xy 177.097584 -290.046914) (xy 177.048154 -290.030853)
			(xy 177.001844 -290.007257) (xy 176.959796 -289.976707) (xy 176.923045 -289.939956) (xy 176.892495 -289.897908)
			(xy 176.868899 -289.851598) (xy 176.852838 -289.802168) (xy 176.844708 -289.750833) (xy 176.555144 -289.750833)
			(xy 176.547014 -289.802168) (xy 176.530953 -289.851598) (xy 176.507357 -289.897908) (xy 176.476807 -289.939956)
			(xy 176.440056 -289.976707) (xy 176.398008 -290.007257) (xy 176.351698 -290.030853) (xy 176.302268 -290.046914)
			(xy 176.250933 -290.055044) (xy 176.198959 -290.055044) (xy 176.147624 -290.046914) (xy 176.098194 -290.030853)
			(xy 176.051884 -290.007257) (xy 176.009836 -289.976707) (xy 175.973085 -289.939956) (xy 175.942535 -289.897908)
			(xy 175.918939 -289.851598) (xy 175.902878 -289.802168) (xy 175.894748 -289.750833) (xy 174.655224 -289.750833)
			(xy 174.647094 -289.802168) (xy 174.631033 -289.851598) (xy 174.607437 -289.897908) (xy 174.576887 -289.939956)
			(xy 174.540136 -289.976707) (xy 174.498088 -290.007257) (xy 174.451778 -290.030853) (xy 174.402348 -290.046914)
			(xy 174.351013 -290.055044) (xy 174.299039 -290.055044) (xy 174.247704 -290.046914) (xy 174.198274 -290.030853)
			(xy 174.151964 -290.007257) (xy 174.109916 -289.976707) (xy 174.073165 -289.939956) (xy 174.042615 -289.897908)
			(xy 174.019019 -289.851598) (xy 174.002958 -289.802168) (xy 173.994828 -289.750833) (xy 173.705264 -289.750833)
			(xy 173.697134 -289.802168) (xy 173.681073 -289.851598) (xy 173.657477 -289.897908) (xy 173.626927 -289.939956)
			(xy 173.590176 -289.976707) (xy 173.548128 -290.007257) (xy 173.501818 -290.030853) (xy 173.452388 -290.046914)
			(xy 173.401053 -290.055044) (xy 173.349079 -290.055044) (xy 173.297744 -290.046914) (xy 173.248314 -290.030853)
			(xy 173.202004 -290.007257) (xy 173.159956 -289.976707) (xy 173.123205 -289.939956) (xy 173.092655 -289.897908)
			(xy 173.069059 -289.851598) (xy 173.052998 -289.802168) (xy 173.044868 -289.750833) (xy 172.75505 -289.750833)
			(xy 172.74692 -289.802168) (xy 172.730859 -289.851598) (xy 172.707263 -289.897908) (xy 172.676713 -289.939956)
			(xy 172.639962 -289.976707) (xy 172.597914 -290.007257) (xy 172.551604 -290.030853) (xy 172.502174 -290.046914)
			(xy 172.450839 -290.055044) (xy 172.398865 -290.055044) (xy 172.34753 -290.046914) (xy 172.2981 -290.030853)
			(xy 172.25179 -290.007257) (xy 172.209742 -289.976707) (xy 172.172991 -289.939956) (xy 172.142441 -289.897908)
			(xy 172.118845 -289.851598) (xy 172.102784 -289.802168) (xy 172.094654 -289.750833) (xy 171.80509 -289.750833)
			(xy 171.79696 -289.802168) (xy 171.780899 -289.851598) (xy 171.757303 -289.897908) (xy 171.726753 -289.939956)
			(xy 171.690002 -289.976707) (xy 171.647954 -290.007257) (xy 171.601644 -290.030853) (xy 171.552214 -290.046914)
			(xy 171.500879 -290.055044) (xy 171.448905 -290.055044) (xy 171.39757 -290.046914) (xy 171.34814 -290.030853)
			(xy 171.30183 -290.007257) (xy 171.259782 -289.976707) (xy 171.223031 -289.939956) (xy 171.192481 -289.897908)
			(xy 171.168885 -289.851598) (xy 171.152824 -289.802168) (xy 171.144694 -289.750833) (xy 170.85513 -289.750833)
			(xy 170.847 -289.802168) (xy 170.830939 -289.851598) (xy 170.807343 -289.897908) (xy 170.776793 -289.939956)
			(xy 170.740042 -289.976707) (xy 170.697994 -290.007257) (xy 170.651684 -290.030853) (xy 170.602254 -290.046914)
			(xy 170.550919 -290.055044) (xy 170.498945 -290.055044) (xy 170.44761 -290.046914) (xy 170.39818 -290.030853)
			(xy 170.35187 -290.007257) (xy 170.309822 -289.976707) (xy 170.273071 -289.939956) (xy 170.242521 -289.897908)
			(xy 170.218925 -289.851598) (xy 170.202864 -289.802168) (xy 170.194734 -289.750833) (xy 169.90517 -289.750833)
			(xy 169.89704 -289.802168) (xy 169.880979 -289.851598) (xy 169.857383 -289.897908) (xy 169.826833 -289.939956)
			(xy 169.790082 -289.976707) (xy 169.748034 -290.007257) (xy 169.701724 -290.030853) (xy 169.652294 -290.046914)
			(xy 169.600959 -290.055044) (xy 169.548985 -290.055044) (xy 169.49765 -290.046914) (xy 169.44822 -290.030853)
			(xy 169.40191 -290.007257) (xy 169.359862 -289.976707) (xy 169.323111 -289.939956) (xy 169.292561 -289.897908)
			(xy 169.268965 -289.851598) (xy 169.252904 -289.802168) (xy 169.244774 -289.750833) (xy 168.95521 -289.750833)
			(xy 168.94708 -289.802168) (xy 168.931019 -289.851598) (xy 168.907423 -289.897908) (xy 168.876873 -289.939956)
			(xy 168.840122 -289.976707) (xy 168.798074 -290.007257) (xy 168.751764 -290.030853) (xy 168.702334 -290.046914)
			(xy 168.650999 -290.055044) (xy 168.599025 -290.055044) (xy 168.54769 -290.046914) (xy 168.49826 -290.030853)
			(xy 168.45195 -290.007257) (xy 168.409902 -289.976707) (xy 168.373151 -289.939956) (xy 168.342601 -289.897908)
			(xy 168.319005 -289.851598) (xy 168.302944 -289.802168) (xy 168.294814 -289.750833) (xy 168.00525 -289.750833)
			(xy 167.99712 -289.802168) (xy 167.981059 -289.851598) (xy 167.957463 -289.897908) (xy 167.926913 -289.939956)
			(xy 167.890162 -289.976707) (xy 167.848114 -290.007257) (xy 167.801804 -290.030853) (xy 167.752374 -290.046914)
			(xy 167.701039 -290.055044) (xy 167.649065 -290.055044) (xy 167.59773 -290.046914) (xy 167.5483 -290.030853)
			(xy 167.50199 -290.007257) (xy 167.459942 -289.976707) (xy 167.423191 -289.939956) (xy 167.392641 -289.897908)
			(xy 167.369045 -289.851598) (xy 167.352984 -289.802168) (xy 167.344854 -289.750833) (xy 167.05529 -289.750833)
			(xy 167.04716 -289.802168) (xy 167.031099 -289.851598) (xy 167.007503 -289.897908) (xy 166.976953 -289.939956)
			(xy 166.940202 -289.976707) (xy 166.898154 -290.007257) (xy 166.851844 -290.030853) (xy 166.802414 -290.046914)
			(xy 166.751079 -290.055044) (xy 166.699105 -290.055044) (xy 166.64777 -290.046914) (xy 166.59834 -290.030853)
			(xy 166.55203 -290.007257) (xy 166.509982 -289.976707) (xy 166.473231 -289.939956) (xy 166.442681 -289.897908)
			(xy 166.419085 -289.851598) (xy 166.403024 -289.802168) (xy 166.394894 -289.750833) (xy 166.105076 -289.750833)
			(xy 166.096946 -289.802168) (xy 166.080885 -289.851598) (xy 166.057289 -289.897908) (xy 166.026739 -289.939956)
			(xy 165.989988 -289.976707) (xy 165.94794 -290.007257) (xy 165.90163 -290.030853) (xy 165.8522 -290.046914)
			(xy 165.800865 -290.055044) (xy 165.748891 -290.055044) (xy 165.697556 -290.046914) (xy 165.648126 -290.030853)
			(xy 165.601816 -290.007257) (xy 165.559768 -289.976707) (xy 165.523017 -289.939956) (xy 165.492467 -289.897908)
			(xy 165.468871 -289.851598) (xy 165.45281 -289.802168) (xy 165.44468 -289.750833) (xy 165.155116 -289.750833)
			(xy 165.146986 -289.802168) (xy 165.130925 -289.851598) (xy 165.107329 -289.897908) (xy 165.076779 -289.939956)
			(xy 165.040028 -289.976707) (xy 164.99798 -290.007257) (xy 164.95167 -290.030853) (xy 164.90224 -290.046914)
			(xy 164.850905 -290.055044) (xy 164.798931 -290.055044) (xy 164.747596 -290.046914) (xy 164.698166 -290.030853)
			(xy 164.651856 -290.007257) (xy 164.609808 -289.976707) (xy 164.573057 -289.939956) (xy 164.542507 -289.897908)
			(xy 164.518911 -289.851598) (xy 164.50285 -289.802168) (xy 164.49472 -289.750833) (xy 164.49421 -289.724846)
			(xy 164.494761 -289.697633) (xy 164.503677 -289.643942) (xy 164.521273 -289.592439) (xy 164.547076 -289.544518)
			(xy 164.563298 -289.522662) (xy 164.572188 -289.510978) (xy 164.575236 -289.482276) (xy 164.5285 -289.38728)
			(xy 164.524014 -289.378941) (xy 164.510114 -289.366102) (xy 164.492495 -289.359203) (xy 164.483034 -289.358832)
			(xy 164.216842 -289.358832) (xy 164.20741 -289.359327) (xy 164.189854 -289.366246) (xy 164.175967 -289.379024)
			(xy 164.171376 -289.38728) (xy 164.12464 -289.482276) (xy 164.127688 -289.510978) (xy 164.136578 -289.522662)
			(xy 164.152788 -289.544525) (xy 164.178583 -289.592447) (xy 164.19618 -289.643948) (xy 164.205104 -289.697634)
			(xy 164.205666 -289.724846) (xy 164.205156 -289.750833) (xy 164.197026 -289.802168) (xy 164.180965 -289.851598)
			(xy 164.157369 -289.897908) (xy 164.126819 -289.939956) (xy 164.090068 -289.976707) (xy 164.04802 -290.007257)
			(xy 164.00171 -290.030853) (xy 163.95228 -290.046914) (xy 163.900945 -290.055044) (xy 163.848971 -290.055044)
			(xy 163.797636 -290.046914) (xy 163.748206 -290.030853) (xy 163.701896 -290.007257) (xy 163.659848 -289.976707)
			(xy 163.623097 -289.939956) (xy 163.592547 -289.897908) (xy 163.568951 -289.851598) (xy 163.55289 -289.802168)
			(xy 163.54476 -289.750833) (xy 163.54425 -289.724846) (xy 163.544801 -289.697633) (xy 163.553715 -289.643941)
			(xy 163.571309 -289.592436) (xy 163.597108 -289.544512) (xy 163.613338 -289.522662) (xy 163.622228 -289.510978)
			(xy 163.625276 -289.482276) (xy 163.57854 -289.38728) (xy 163.574051 -289.378948) (xy 163.560149 -289.366125)
			(xy 163.542531 -289.359246) (xy 163.533074 -289.358832) (xy 163.266882 -289.358832) (xy 163.257446 -289.35932)
			(xy 163.239878 -289.366231) (xy 163.22598 -289.379007) (xy 163.221416 -289.38728) (xy 163.17468 -289.482276)
			(xy 163.177728 -289.510978) (xy 163.186618 -289.522662) (xy 163.202827 -289.544526) (xy 163.228618 -289.592449)
			(xy 163.246213 -289.643949) (xy 163.255135 -289.697635) (xy 163.255706 -289.724846) (xy 163.255196 -289.750833)
			(xy 163.247066 -289.802168) (xy 163.231005 -289.851598) (xy 163.207409 -289.897908) (xy 163.176859 -289.939956)
			(xy 163.140108 -289.976707) (xy 163.09806 -290.007257) (xy 163.05175 -290.030853) (xy 163.00232 -290.046914)
			(xy 162.950985 -290.055044) (xy 162.899011 -290.055044) (xy 162.847676 -290.046914) (xy 162.798246 -290.030853)
			(xy 162.751936 -290.007257) (xy 162.709888 -289.976707) (xy 162.673137 -289.939956) (xy 162.642587 -289.897908)
			(xy 162.618991 -289.851598) (xy 162.60293 -289.802168) (xy 162.5948 -289.750833) (xy 162.59429 -289.724846)
			(xy 162.594841 -289.697633) (xy 162.603756 -289.643942) (xy 162.621352 -289.592438) (xy 162.647153 -289.544516)
			(xy 162.663378 -289.522662) (xy 162.672268 -289.510978) (xy 162.675316 -289.482276) (xy 162.62858 -289.38728)
			(xy 162.624093 -289.378943) (xy 162.610193 -289.366109) (xy 162.592574 -289.359217) (xy 162.583114 -289.358832)
			(xy 162.316922 -289.358832) (xy 162.307492 -289.35933) (xy 162.289941 -289.366254) (xy 162.276061 -289.379033)
			(xy 162.271456 -289.38728) (xy 162.22472 -289.482276) (xy 162.227768 -289.510978) (xy 162.236658 -289.522662)
			(xy 162.252869 -289.544525) (xy 162.278666 -289.592447) (xy 162.296264 -289.643947) (xy 162.305188 -289.697634)
			(xy 162.305746 -289.724846) (xy 162.305236 -289.750833) (xy 162.297106 -289.802168) (xy 162.281045 -289.851598)
			(xy 162.257449 -289.897908) (xy 162.226899 -289.939956) (xy 162.190148 -289.976707) (xy 162.1481 -290.007257)
			(xy 162.10179 -290.030853) (xy 162.05236 -290.046914) (xy 162.001025 -290.055044) (xy 161.949051 -290.055044)
			(xy 161.897716 -290.046914) (xy 161.848286 -290.030853) (xy 161.801976 -290.007257) (xy 161.759928 -289.976707)
			(xy 161.723177 -289.939956) (xy 161.692627 -289.897908) (xy 161.669031 -289.851598) (xy 161.65297 -289.802168)
			(xy 161.64484 -289.750833) (xy 161.64433 -289.724846) (xy 161.644881 -289.697632) (xy 161.653794 -289.64394)
			(xy 161.671388 -289.592435) (xy 161.697185 -289.544511) (xy 161.713418 -289.522662) (xy 161.722308 -289.510978)
			(xy 161.725356 -289.482276) (xy 161.67862 -289.38728) (xy 161.674135 -289.378939) (xy 161.660236 -289.366094)
			(xy 161.642616 -289.359188) (xy 161.633154 -289.358832) (xy 161.366962 -289.358832) (xy 161.357528 -289.359324)
			(xy 161.339966 -289.366239) (xy 161.326074 -289.379016) (xy 161.321496 -289.38728) (xy 161.27476 -289.482276)
			(xy 161.277808 -289.510978) (xy 161.286698 -289.522662) (xy 161.302907 -289.544526) (xy 161.328701 -289.592448)
			(xy 161.346297 -289.643948) (xy 161.35522 -289.697635) (xy 161.355786 -289.724846) (xy 161.355276 -289.750833)
			(xy 161.347146 -289.802168) (xy 161.331085 -289.851598) (xy 161.307489 -289.897908) (xy 161.276939 -289.939956)
			(xy 161.240188 -289.976707) (xy 161.19814 -290.007257) (xy 161.15183 -290.030853) (xy 161.1024 -290.046914)
			(xy 161.051065 -290.055044) (xy 160.999091 -290.055044) (xy 160.947756 -290.046914) (xy 160.898326 -290.030853)
			(xy 160.852016 -290.007257) (xy 160.809968 -289.976707) (xy 160.773217 -289.939956) (xy 160.742667 -289.897908)
			(xy 160.719071 -289.851598) (xy 160.70301 -289.802168) (xy 160.69488 -289.750833) (xy 160.69437 -289.724846)
			(xy 160.694921 -289.697633) (xy 160.703836 -289.643941) (xy 160.721431 -289.592437) (xy 160.747231 -289.544514)
			(xy 160.763458 -289.522662) (xy 160.772348 -289.510978) (xy 160.775396 -289.482276) (xy 160.72866 -289.38728)
			(xy 160.724172 -289.378945) (xy 160.71027 -289.366117) (xy 160.692652 -289.359232) (xy 160.683194 -289.358832)
			(xy 160.416748 -289.358832) (xy 160.407315 -289.359326) (xy 160.389757 -289.366244) (xy 160.375869 -289.379022)
			(xy 160.371282 -289.38728) (xy 160.324546 -289.482276) (xy 160.327594 -289.510978) (xy 160.336484 -289.522662)
			(xy 160.352694 -289.544526) (xy 160.378489 -289.592448) (xy 160.396085 -289.643948) (xy 160.405008 -289.697634)
			(xy 160.405572 -289.724846) (xy 160.405062 -289.750833) (xy 160.396932 -289.802168) (xy 160.380871 -289.851598)
			(xy 160.357275 -289.897908) (xy 160.326725 -289.939956) (xy 160.289974 -289.976707) (xy 160.247926 -290.007257)
			(xy 160.201616 -290.030853) (xy 160.152186 -290.046914) (xy 160.100851 -290.055044) (xy 160.048877 -290.055044)
			(xy 159.997542 -290.046914) (xy 159.948112 -290.030853) (xy 159.901802 -290.007257) (xy 159.859754 -289.976707)
			(xy 159.823003 -289.939956) (xy 159.792453 -289.897908) (xy 159.768857 -289.851598) (xy 159.752796 -289.802168)
			(xy 159.744666 -289.750833) (xy 159.744156 -289.724846) (xy 159.744707 -289.697633) (xy 159.753621 -289.643941)
			(xy 159.771216 -289.592437) (xy 159.797015 -289.544513) (xy 159.813244 -289.522662) (xy 159.822134 -289.510978)
			(xy 159.825182 -289.482276) (xy 159.778446 -289.38728) (xy 159.773958 -289.378947) (xy 159.760055 -289.366123)
			(xy 159.742437 -289.359242) (xy 159.73298 -289.358832) (xy 159.352234 -289.358832) (xy 159.34217 -289.359268)
			(xy 159.323586 -289.367003) (xy 159.316166 -289.373818) (xy 159.311086 -289.378898) (xy 159.30441 -289.386312)
			(xy 159.296824 -289.404743) (xy 159.296827 -289.424674) (xy 159.304419 -289.443102) (xy 159.311086 -289.450526)
			(xy 159.314134 -289.453574) (xy 159.317436 -289.456114) (xy 159.338427 -289.471747) (xy 159.375657 -289.50853)
			(xy 159.406625 -289.55072) (xy 159.430557 -289.597264) (xy 159.446854 -289.646998) (xy 159.455111 -289.698678)
			(xy 159.455612 -289.724846) (xy 159.455079 -289.752242) (xy 159.446052 -289.806285) (xy 159.428236 -289.8581)
			(xy 159.402119 -289.906267) (xy 159.368416 -289.949468) (xy 159.32805 -289.986519) (xy 159.282127 -290.016406)
			(xy 159.257238 -290.027868) (xy 159.243268 -290.033964) (xy 159.226758 -290.059364) (xy 159.226758 -290.145724)
			(xy 159.226329 -290.155791) (xy 159.218604 -290.174385) (xy 159.211772 -290.181792) (xy 159.211772 -290.318952)
			(xy 159.212025 -290.326598) (xy 159.216541 -290.341209) (xy 159.220662 -290.347654) (xy 159.225234 -290.354258)
			(xy 159.236918 -290.363656) (xy 159.244284 -290.36645) (xy 159.268806 -290.376506) (xy 159.314542 -290.403278)
			(xy 159.355423 -290.437003) (xy 159.390401 -290.476816) (xy 159.418581 -290.521699) (xy 159.439241 -290.570502)
			(xy 159.451853 -290.621976) (xy 159.456092 -290.674802) (xy 159.454006 -290.700793) (xy 159.744666 -290.700793)
			(xy 159.744666 -290.648819) (xy 159.752796 -290.597484) (xy 159.768857 -290.548054) (xy 159.792453 -290.501744)
			(xy 159.823003 -290.459696) (xy 159.859754 -290.422945) (xy 159.901802 -290.392395) (xy 159.948112 -290.368799)
			(xy 159.997542 -290.352738) (xy 160.048877 -290.344608) (xy 160.100851 -290.344608) (xy 160.152186 -290.352738)
			(xy 160.201616 -290.368799) (xy 160.247926 -290.392395) (xy 160.289974 -290.422945) (xy 160.326725 -290.459696)
			(xy 160.357275 -290.501744) (xy 160.380871 -290.548054) (xy 160.396932 -290.597484) (xy 160.405062 -290.648819)
			(xy 160.405572 -290.674806) (xy 160.405062 -290.700793) (xy 161.64484 -290.700793) (xy 161.64484 -290.648819)
			(xy 161.65297 -290.597484) (xy 161.669031 -290.548054) (xy 161.692627 -290.501744) (xy 161.723177 -290.459696)
			(xy 161.759928 -290.422945) (xy 161.801976 -290.392395) (xy 161.848286 -290.368799) (xy 161.897716 -290.352738)
			(xy 161.949051 -290.344608) (xy 162.001025 -290.344608) (xy 162.05236 -290.352738) (xy 162.10179 -290.368799)
			(xy 162.1481 -290.392395) (xy 162.190148 -290.422945) (xy 162.226899 -290.459696) (xy 162.257449 -290.501744)
			(xy 162.281045 -290.548054) (xy 162.297106 -290.597484) (xy 162.305236 -290.648819) (xy 162.305746 -290.674806)
			(xy 162.305236 -290.700793) (xy 163.54476 -290.700793) (xy 163.54476 -290.648819) (xy 163.55289 -290.597484)
			(xy 163.568951 -290.548054) (xy 163.592547 -290.501744) (xy 163.623097 -290.459696) (xy 163.659848 -290.422945)
			(xy 163.701896 -290.392395) (xy 163.748206 -290.368799) (xy 163.797636 -290.352738) (xy 163.848971 -290.344608)
			(xy 163.900945 -290.344608) (xy 163.95228 -290.352738) (xy 164.00171 -290.368799) (xy 164.04802 -290.392395)
			(xy 164.090068 -290.422945) (xy 164.126819 -290.459696) (xy 164.157369 -290.501744) (xy 164.180965 -290.548054)
			(xy 164.197026 -290.597484) (xy 164.205156 -290.648819) (xy 164.205666 -290.674806) (xy 164.205156 -290.700793)
			(xy 164.49472 -290.700793) (xy 164.49472 -290.648819) (xy 164.50285 -290.597484) (xy 164.518911 -290.548054)
			(xy 164.542507 -290.501744) (xy 164.573057 -290.459696) (xy 164.609808 -290.422945) (xy 164.651856 -290.392395)
			(xy 164.698166 -290.368799) (xy 164.747596 -290.352738) (xy 164.798931 -290.344608) (xy 164.850905 -290.344608)
			(xy 164.90224 -290.352738) (xy 164.95167 -290.368799) (xy 164.99798 -290.392395) (xy 165.040028 -290.422945)
			(xy 165.076779 -290.459696) (xy 165.107329 -290.501744) (xy 165.130925 -290.548054) (xy 165.146986 -290.597484)
			(xy 165.155116 -290.648819) (xy 165.155626 -290.674806) (xy 165.155116 -290.700793) (xy 165.44468 -290.700793)
			(xy 165.44468 -290.648819) (xy 165.45281 -290.597484) (xy 165.468871 -290.548054) (xy 165.492467 -290.501744)
			(xy 165.523017 -290.459696) (xy 165.559768 -290.422945) (xy 165.601816 -290.392395) (xy 165.648126 -290.368799)
			(xy 165.697556 -290.352738) (xy 165.748891 -290.344608) (xy 165.800865 -290.344608) (xy 165.8522 -290.352738)
			(xy 165.90163 -290.368799) (xy 165.94794 -290.392395) (xy 165.989988 -290.422945) (xy 166.026739 -290.459696)
			(xy 166.057289 -290.501744) (xy 166.080885 -290.548054) (xy 166.096946 -290.597484) (xy 166.105076 -290.648819)
			(xy 166.105586 -290.674806) (xy 166.105076 -290.700793) (xy 166.394894 -290.700793) (xy 166.394894 -290.648819)
			(xy 166.403024 -290.597484) (xy 166.419085 -290.548054) (xy 166.442681 -290.501744) (xy 166.473231 -290.459696)
			(xy 166.509982 -290.422945) (xy 166.55203 -290.392395) (xy 166.59834 -290.368799) (xy 166.64777 -290.352738)
			(xy 166.699105 -290.344608) (xy 166.751079 -290.344608) (xy 166.802414 -290.352738) (xy 166.851844 -290.368799)
			(xy 166.898154 -290.392395) (xy 166.940202 -290.422945) (xy 166.976953 -290.459696) (xy 167.007503 -290.501744)
			(xy 167.031099 -290.548054) (xy 167.04716 -290.597484) (xy 167.05529 -290.648819) (xy 167.0558 -290.674806)
			(xy 167.05529 -290.700793) (xy 167.344854 -290.700793) (xy 167.344854 -290.648819) (xy 167.352984 -290.597484)
			(xy 167.369045 -290.548054) (xy 167.392641 -290.501744) (xy 167.423191 -290.459696) (xy 167.459942 -290.422945)
			(xy 167.50199 -290.392395) (xy 167.5483 -290.368799) (xy 167.59773 -290.352738) (xy 167.649065 -290.344608)
			(xy 167.701039 -290.344608) (xy 167.752374 -290.352738) (xy 167.801804 -290.368799) (xy 167.848114 -290.392395)
			(xy 167.890162 -290.422945) (xy 167.926913 -290.459696) (xy 167.957463 -290.501744) (xy 167.981059 -290.548054)
			(xy 167.99712 -290.597484) (xy 168.00525 -290.648819) (xy 168.00576 -290.674806) (xy 168.00525 -290.700793)
			(xy 168.294814 -290.700793) (xy 168.294814 -290.648819) (xy 168.302944 -290.597484) (xy 168.319005 -290.548054)
			(xy 168.342601 -290.501744) (xy 168.373151 -290.459696) (xy 168.409902 -290.422945) (xy 168.45195 -290.392395)
			(xy 168.49826 -290.368799) (xy 168.54769 -290.352738) (xy 168.599025 -290.344608) (xy 168.650999 -290.344608)
			(xy 168.702334 -290.352738) (xy 168.751764 -290.368799) (xy 168.798074 -290.392395) (xy 168.840122 -290.422945)
			(xy 168.876873 -290.459696) (xy 168.907423 -290.501744) (xy 168.931019 -290.548054) (xy 168.94708 -290.597484)
			(xy 168.95521 -290.648819) (xy 168.95572 -290.674806) (xy 168.95521 -290.700793) (xy 169.244774 -290.700793)
			(xy 169.244774 -290.648819) (xy 169.252904 -290.597484) (xy 169.268965 -290.548054) (xy 169.292561 -290.501744)
			(xy 169.323111 -290.459696) (xy 169.359862 -290.422945) (xy 169.40191 -290.392395) (xy 169.44822 -290.368799)
			(xy 169.49765 -290.352738) (xy 169.548985 -290.344608) (xy 169.600959 -290.344608) (xy 169.652294 -290.352738)
			(xy 169.701724 -290.368799) (xy 169.748034 -290.392395) (xy 169.790082 -290.422945) (xy 169.826833 -290.459696)
			(xy 169.857383 -290.501744) (xy 169.880979 -290.548054) (xy 169.89704 -290.597484) (xy 169.90517 -290.648819)
			(xy 169.90568 -290.674806) (xy 169.90517 -290.700793) (xy 170.194734 -290.700793) (xy 170.194734 -290.648819)
			(xy 170.202864 -290.597484) (xy 170.218925 -290.548054) (xy 170.242521 -290.501744) (xy 170.273071 -290.459696)
			(xy 170.309822 -290.422945) (xy 170.35187 -290.392395) (xy 170.39818 -290.368799) (xy 170.44761 -290.352738)
			(xy 170.498945 -290.344608) (xy 170.550919 -290.344608) (xy 170.602254 -290.352738) (xy 170.651684 -290.368799)
			(xy 170.697994 -290.392395) (xy 170.740042 -290.422945) (xy 170.776793 -290.459696) (xy 170.807343 -290.501744)
			(xy 170.830939 -290.548054) (xy 170.847 -290.597484) (xy 170.85513 -290.648819) (xy 170.85564 -290.674806)
			(xy 170.85513 -290.700793) (xy 171.144694 -290.700793) (xy 171.144694 -290.648819) (xy 171.152824 -290.597484)
			(xy 171.168885 -290.548054) (xy 171.192481 -290.501744) (xy 171.223031 -290.459696) (xy 171.259782 -290.422945)
			(xy 171.30183 -290.392395) (xy 171.34814 -290.368799) (xy 171.39757 -290.352738) (xy 171.448905 -290.344608)
			(xy 171.500879 -290.344608) (xy 171.552214 -290.352738) (xy 171.601644 -290.368799) (xy 171.647954 -290.392395)
			(xy 171.690002 -290.422945) (xy 171.726753 -290.459696) (xy 171.757303 -290.501744) (xy 171.780899 -290.548054)
			(xy 171.79696 -290.597484) (xy 171.80509 -290.648819) (xy 171.8056 -290.674806) (xy 171.80509 -290.700793)
			(xy 172.094654 -290.700793) (xy 172.094654 -290.648819) (xy 172.102784 -290.597484) (xy 172.118845 -290.548054)
			(xy 172.142441 -290.501744) (xy 172.172991 -290.459696) (xy 172.209742 -290.422945) (xy 172.25179 -290.392395)
			(xy 172.2981 -290.368799) (xy 172.34753 -290.352738) (xy 172.398865 -290.344608) (xy 172.450839 -290.344608)
			(xy 172.502174 -290.352738) (xy 172.551604 -290.368799) (xy 172.597914 -290.392395) (xy 172.639962 -290.422945)
			(xy 172.676713 -290.459696) (xy 172.707263 -290.501744) (xy 172.730859 -290.548054) (xy 172.74692 -290.597484)
			(xy 172.75505 -290.648819) (xy 172.75556 -290.674806) (xy 172.75505 -290.700793) (xy 173.044868 -290.700793)
			(xy 173.044868 -290.648819) (xy 173.052998 -290.597484) (xy 173.069059 -290.548054) (xy 173.092655 -290.501744)
			(xy 173.123205 -290.459696) (xy 173.159956 -290.422945) (xy 173.202004 -290.392395) (xy 173.248314 -290.368799)
			(xy 173.297744 -290.352738) (xy 173.349079 -290.344608) (xy 173.401053 -290.344608) (xy 173.452388 -290.352738)
			(xy 173.501818 -290.368799) (xy 173.548128 -290.392395) (xy 173.590176 -290.422945) (xy 173.626927 -290.459696)
			(xy 173.657477 -290.501744) (xy 173.681073 -290.548054) (xy 173.697134 -290.597484) (xy 173.705264 -290.648819)
			(xy 173.705774 -290.674806) (xy 173.705264 -290.700793) (xy 173.994828 -290.700793) (xy 173.994828 -290.648819)
			(xy 174.002958 -290.597484) (xy 174.019019 -290.548054) (xy 174.042615 -290.501744) (xy 174.073165 -290.459696)
			(xy 174.109916 -290.422945) (xy 174.151964 -290.392395) (xy 174.198274 -290.368799) (xy 174.247704 -290.352738)
			(xy 174.299039 -290.344608) (xy 174.351013 -290.344608) (xy 174.402348 -290.352738) (xy 174.451778 -290.368799)
			(xy 174.498088 -290.392395) (xy 174.540136 -290.422945) (xy 174.576887 -290.459696) (xy 174.607437 -290.501744)
			(xy 174.631033 -290.548054) (xy 174.647094 -290.597484) (xy 174.655224 -290.648819) (xy 174.655734 -290.674806)
			(xy 174.655224 -290.700793) (xy 175.894748 -290.700793) (xy 175.894748 -290.648819) (xy 175.902878 -290.597484)
			(xy 175.918939 -290.548054) (xy 175.942535 -290.501744) (xy 175.973085 -290.459696) (xy 176.009836 -290.422945)
			(xy 176.051884 -290.392395) (xy 176.098194 -290.368799) (xy 176.147624 -290.352738) (xy 176.198959 -290.344608)
			(xy 176.250933 -290.344608) (xy 176.302268 -290.352738) (xy 176.351698 -290.368799) (xy 176.398008 -290.392395)
			(xy 176.440056 -290.422945) (xy 176.476807 -290.459696) (xy 176.507357 -290.501744) (xy 176.530953 -290.548054)
			(xy 176.547014 -290.597484) (xy 176.555144 -290.648819) (xy 176.555654 -290.674806) (xy 176.555144 -290.700793)
			(xy 176.844708 -290.700793) (xy 176.844708 -290.648819) (xy 176.852838 -290.597484) (xy 176.868899 -290.548054)
			(xy 176.892495 -290.501744) (xy 176.923045 -290.459696) (xy 176.959796 -290.422945) (xy 177.001844 -290.392395)
			(xy 177.048154 -290.368799) (xy 177.097584 -290.352738) (xy 177.148919 -290.344608) (xy 177.200893 -290.344608)
			(xy 177.252228 -290.352738) (xy 177.301658 -290.368799) (xy 177.347968 -290.392395) (xy 177.390016 -290.422945)
			(xy 177.426767 -290.459696) (xy 177.457317 -290.501744) (xy 177.480913 -290.548054) (xy 177.496974 -290.597484)
			(xy 177.505104 -290.648819) (xy 177.505614 -290.674806) (xy 177.505104 -290.700793) (xy 177.794668 -290.700793)
			(xy 177.794668 -290.648819) (xy 177.802798 -290.597484) (xy 177.818859 -290.548054) (xy 177.842455 -290.501744)
			(xy 177.873005 -290.459696) (xy 177.909756 -290.422945) (xy 177.951804 -290.392395) (xy 177.998114 -290.368799)
			(xy 178.047544 -290.352738) (xy 178.098879 -290.344608) (xy 178.150853 -290.344608) (xy 178.202188 -290.352738)
			(xy 178.251618 -290.368799) (xy 178.297928 -290.392395) (xy 178.339976 -290.422945) (xy 178.376727 -290.459696)
			(xy 178.407277 -290.501744) (xy 178.430873 -290.548054) (xy 178.446934 -290.597484) (xy 178.455064 -290.648819)
			(xy 178.455574 -290.674806) (xy 178.455064 -290.700793) (xy 178.744882 -290.700793) (xy 178.744882 -290.648819)
			(xy 178.753012 -290.597484) (xy 178.769073 -290.548054) (xy 178.792669 -290.501744) (xy 178.823219 -290.459696)
			(xy 178.85997 -290.422945) (xy 178.902018 -290.392395) (xy 178.948328 -290.368799) (xy 178.997758 -290.352738)
			(xy 179.049093 -290.344608) (xy 179.101067 -290.344608) (xy 179.152402 -290.352738) (xy 179.201832 -290.368799)
			(xy 179.248142 -290.392395) (xy 179.29019 -290.422945) (xy 179.326941 -290.459696) (xy 179.357491 -290.501744)
			(xy 179.381087 -290.548054) (xy 179.397148 -290.597484) (xy 179.405278 -290.648819) (xy 179.405788 -290.674806)
			(xy 179.405278 -290.700793) (xy 179.694842 -290.700793) (xy 179.694842 -290.648819) (xy 179.702972 -290.597484)
			(xy 179.719033 -290.548054) (xy 179.742629 -290.501744) (xy 179.773179 -290.459696) (xy 179.80993 -290.422945)
			(xy 179.851978 -290.392395) (xy 179.898288 -290.368799) (xy 179.947718 -290.352738) (xy 179.999053 -290.344608)
			(xy 180.051027 -290.344608) (xy 180.102362 -290.352738) (xy 180.151792 -290.368799) (xy 180.198102 -290.392395)
			(xy 180.24015 -290.422945) (xy 180.276901 -290.459696) (xy 180.307451 -290.501744) (xy 180.331047 -290.548054)
			(xy 180.347108 -290.597484) (xy 180.355238 -290.648819) (xy 180.355748 -290.674806) (xy 180.355238 -290.700793)
			(xy 180.644802 -290.700793) (xy 180.644802 -290.648819) (xy 180.652932 -290.597484) (xy 180.668993 -290.548054)
			(xy 180.692589 -290.501744) (xy 180.723139 -290.459696) (xy 180.75989 -290.422945) (xy 180.801938 -290.392395)
			(xy 180.848248 -290.368799) (xy 180.897678 -290.352738) (xy 180.949013 -290.344608) (xy 181.000987 -290.344608)
			(xy 181.052322 -290.352738) (xy 181.101752 -290.368799) (xy 181.148062 -290.392395) (xy 181.19011 -290.422945)
			(xy 181.226861 -290.459696) (xy 181.257411 -290.501744) (xy 181.281007 -290.548054) (xy 181.297068 -290.597484)
			(xy 181.305198 -290.648819) (xy 181.305708 -290.674806) (xy 181.305198 -290.700793) (xy 181.594762 -290.700793)
			(xy 181.594762 -290.648819) (xy 181.602892 -290.597484) (xy 181.618953 -290.548054) (xy 181.642549 -290.501744)
			(xy 181.673099 -290.459696) (xy 181.70985 -290.422945) (xy 181.751898 -290.392395) (xy 181.798208 -290.368799)
			(xy 181.847638 -290.352738) (xy 181.898973 -290.344608) (xy 181.950947 -290.344608) (xy 182.002282 -290.352738)
			(xy 182.051712 -290.368799) (xy 182.098022 -290.392395) (xy 182.14007 -290.422945) (xy 182.176821 -290.459696)
			(xy 182.207371 -290.501744) (xy 182.230967 -290.548054) (xy 182.247028 -290.597484) (xy 182.255158 -290.648819)
			(xy 182.255668 -290.674806) (xy 182.255158 -290.700793) (xy 182.544722 -290.700793) (xy 182.544722 -290.648819)
			(xy 182.552852 -290.597484) (xy 182.568913 -290.548054) (xy 182.592509 -290.501744) (xy 182.623059 -290.459696)
			(xy 182.65981 -290.422945) (xy 182.701858 -290.392395) (xy 182.748168 -290.368799) (xy 182.797598 -290.352738)
			(xy 182.848933 -290.344608) (xy 182.900907 -290.344608) (xy 182.952242 -290.352738) (xy 183.001672 -290.368799)
			(xy 183.047982 -290.392395) (xy 183.09003 -290.422945) (xy 183.126781 -290.459696) (xy 183.157331 -290.501744)
			(xy 183.180927 -290.548054) (xy 183.196988 -290.597484) (xy 183.205118 -290.648819) (xy 183.205628 -290.674806)
			(xy 183.205118 -290.700793) (xy 183.494682 -290.700793) (xy 183.494682 -290.648819) (xy 183.502812 -290.597484)
			(xy 183.518873 -290.548054) (xy 183.542469 -290.501744) (xy 183.573019 -290.459696) (xy 183.60977 -290.422945)
			(xy 183.651818 -290.392395) (xy 183.698128 -290.368799) (xy 183.747558 -290.352738) (xy 183.798893 -290.344608)
			(xy 183.850867 -290.344608) (xy 183.902202 -290.352738) (xy 183.951632 -290.368799) (xy 183.997942 -290.392395)
			(xy 184.03999 -290.422945) (xy 184.076741 -290.459696) (xy 184.107291 -290.501744) (xy 184.130887 -290.548054)
			(xy 184.146948 -290.597484) (xy 184.155078 -290.648819) (xy 184.155588 -290.674806) (xy 184.155078 -290.700793)
			(xy 184.444642 -290.700793) (xy 184.444642 -290.648819) (xy 184.452772 -290.597484) (xy 184.468833 -290.548054)
			(xy 184.492429 -290.501744) (xy 184.522979 -290.459696) (xy 184.55973 -290.422945) (xy 184.601778 -290.392395)
			(xy 184.648088 -290.368799) (xy 184.697518 -290.352738) (xy 184.748853 -290.344608) (xy 184.800827 -290.344608)
			(xy 184.852162 -290.352738) (xy 184.901592 -290.368799) (xy 184.947902 -290.392395) (xy 184.98995 -290.422945)
			(xy 185.026701 -290.459696) (xy 185.057251 -290.501744) (xy 185.080847 -290.548054) (xy 185.096908 -290.597484)
			(xy 185.105038 -290.648819) (xy 185.105548 -290.674806) (xy 185.105038 -290.700793) (xy 185.096908 -290.752128)
			(xy 185.080847 -290.801558) (xy 185.057251 -290.847868) (xy 185.026701 -290.889916) (xy 184.98995 -290.926667)
			(xy 184.947902 -290.957217) (xy 184.901592 -290.980813) (xy 184.852162 -290.996874) (xy 184.800827 -291.005004)
			(xy 184.748853 -291.005004) (xy 184.697518 -290.996874) (xy 184.648088 -290.980813) (xy 184.601778 -290.957217)
			(xy 184.55973 -290.926667) (xy 184.522979 -290.889916) (xy 184.492429 -290.847868) (xy 184.468833 -290.801558)
			(xy 184.452772 -290.752128) (xy 184.444642 -290.700793) (xy 184.155078 -290.700793) (xy 184.146948 -290.752128)
			(xy 184.130887 -290.801558) (xy 184.107291 -290.847868) (xy 184.076741 -290.889916) (xy 184.03999 -290.926667)
			(xy 183.997942 -290.957217) (xy 183.951632 -290.980813) (xy 183.902202 -290.996874) (xy 183.850867 -291.005004)
			(xy 183.798893 -291.005004) (xy 183.747558 -290.996874) (xy 183.698128 -290.980813) (xy 183.651818 -290.957217)
			(xy 183.60977 -290.926667) (xy 183.573019 -290.889916) (xy 183.542469 -290.847868) (xy 183.518873 -290.801558)
			(xy 183.502812 -290.752128) (xy 183.494682 -290.700793) (xy 183.205118 -290.700793) (xy 183.196988 -290.752128)
			(xy 183.180927 -290.801558) (xy 183.157331 -290.847868) (xy 183.126781 -290.889916) (xy 183.09003 -290.926667)
			(xy 183.047982 -290.957217) (xy 183.001672 -290.980813) (xy 182.952242 -290.996874) (xy 182.900907 -291.005004)
			(xy 182.848933 -291.005004) (xy 182.797598 -290.996874) (xy 182.748168 -290.980813) (xy 182.701858 -290.957217)
			(xy 182.65981 -290.926667) (xy 182.623059 -290.889916) (xy 182.592509 -290.847868) (xy 182.568913 -290.801558)
			(xy 182.552852 -290.752128) (xy 182.544722 -290.700793) (xy 182.255158 -290.700793) (xy 182.247028 -290.752128)
			(xy 182.230967 -290.801558) (xy 182.207371 -290.847868) (xy 182.176821 -290.889916) (xy 182.14007 -290.926667)
			(xy 182.098022 -290.957217) (xy 182.051712 -290.980813) (xy 182.002282 -290.996874) (xy 181.950947 -291.005004)
			(xy 181.898973 -291.005004) (xy 181.847638 -290.996874) (xy 181.798208 -290.980813) (xy 181.751898 -290.957217)
			(xy 181.70985 -290.926667) (xy 181.673099 -290.889916) (xy 181.642549 -290.847868) (xy 181.618953 -290.801558)
			(xy 181.602892 -290.752128) (xy 181.594762 -290.700793) (xy 181.305198 -290.700793) (xy 181.297068 -290.752128)
			(xy 181.281007 -290.801558) (xy 181.257411 -290.847868) (xy 181.226861 -290.889916) (xy 181.19011 -290.926667)
			(xy 181.148062 -290.957217) (xy 181.101752 -290.980813) (xy 181.052322 -290.996874) (xy 181.000987 -291.005004)
			(xy 180.949013 -291.005004) (xy 180.897678 -290.996874) (xy 180.848248 -290.980813) (xy 180.801938 -290.957217)
			(xy 180.75989 -290.926667) (xy 180.723139 -290.889916) (xy 180.692589 -290.847868) (xy 180.668993 -290.801558)
			(xy 180.652932 -290.752128) (xy 180.644802 -290.700793) (xy 180.355238 -290.700793) (xy 180.347108 -290.752128)
			(xy 180.331047 -290.801558) (xy 180.307451 -290.847868) (xy 180.276901 -290.889916) (xy 180.24015 -290.926667)
			(xy 180.198102 -290.957217) (xy 180.151792 -290.980813) (xy 180.102362 -290.996874) (xy 180.051027 -291.005004)
			(xy 179.999053 -291.005004) (xy 179.947718 -290.996874) (xy 179.898288 -290.980813) (xy 179.851978 -290.957217)
			(xy 179.80993 -290.926667) (xy 179.773179 -290.889916) (xy 179.742629 -290.847868) (xy 179.719033 -290.801558)
			(xy 179.702972 -290.752128) (xy 179.694842 -290.700793) (xy 179.405278 -290.700793) (xy 179.397148 -290.752128)
			(xy 179.381087 -290.801558) (xy 179.357491 -290.847868) (xy 179.326941 -290.889916) (xy 179.29019 -290.926667)
			(xy 179.248142 -290.957217) (xy 179.201832 -290.980813) (xy 179.152402 -290.996874) (xy 179.101067 -291.005004)
			(xy 179.049093 -291.005004) (xy 178.997758 -290.996874) (xy 178.948328 -290.980813) (xy 178.902018 -290.957217)
			(xy 178.85997 -290.926667) (xy 178.823219 -290.889916) (xy 178.792669 -290.847868) (xy 178.769073 -290.801558)
			(xy 178.753012 -290.752128) (xy 178.744882 -290.700793) (xy 178.455064 -290.700793) (xy 178.446934 -290.752128)
			(xy 178.430873 -290.801558) (xy 178.407277 -290.847868) (xy 178.376727 -290.889916) (xy 178.339976 -290.926667)
			(xy 178.297928 -290.957217) (xy 178.251618 -290.980813) (xy 178.202188 -290.996874) (xy 178.150853 -291.005004)
			(xy 178.098879 -291.005004) (xy 178.047544 -290.996874) (xy 177.998114 -290.980813) (xy 177.951804 -290.957217)
			(xy 177.909756 -290.926667) (xy 177.873005 -290.889916) (xy 177.842455 -290.847868) (xy 177.818859 -290.801558)
			(xy 177.802798 -290.752128) (xy 177.794668 -290.700793) (xy 177.505104 -290.700793) (xy 177.496974 -290.752128)
			(xy 177.480913 -290.801558) (xy 177.457317 -290.847868) (xy 177.426767 -290.889916) (xy 177.390016 -290.926667)
			(xy 177.347968 -290.957217) (xy 177.301658 -290.980813) (xy 177.252228 -290.996874) (xy 177.200893 -291.005004)
			(xy 177.148919 -291.005004) (xy 177.097584 -290.996874) (xy 177.048154 -290.980813) (xy 177.001844 -290.957217)
			(xy 176.959796 -290.926667) (xy 176.923045 -290.889916) (xy 176.892495 -290.847868) (xy 176.868899 -290.801558)
			(xy 176.852838 -290.752128) (xy 176.844708 -290.700793) (xy 176.555144 -290.700793) (xy 176.547014 -290.752128)
			(xy 176.530953 -290.801558) (xy 176.507357 -290.847868) (xy 176.476807 -290.889916) (xy 176.440056 -290.926667)
			(xy 176.398008 -290.957217) (xy 176.351698 -290.980813) (xy 176.302268 -290.996874) (xy 176.250933 -291.005004)
			(xy 176.198959 -291.005004) (xy 176.147624 -290.996874) (xy 176.098194 -290.980813) (xy 176.051884 -290.957217)
			(xy 176.009836 -290.926667) (xy 175.973085 -290.889916) (xy 175.942535 -290.847868) (xy 175.918939 -290.801558)
			(xy 175.902878 -290.752128) (xy 175.894748 -290.700793) (xy 174.655224 -290.700793) (xy 174.647094 -290.752128)
			(xy 174.631033 -290.801558) (xy 174.607437 -290.847868) (xy 174.576887 -290.889916) (xy 174.540136 -290.926667)
			(xy 174.498088 -290.957217) (xy 174.451778 -290.980813) (xy 174.402348 -290.996874) (xy 174.351013 -291.005004)
			(xy 174.299039 -291.005004) (xy 174.247704 -290.996874) (xy 174.198274 -290.980813) (xy 174.151964 -290.957217)
			(xy 174.109916 -290.926667) (xy 174.073165 -290.889916) (xy 174.042615 -290.847868) (xy 174.019019 -290.801558)
			(xy 174.002958 -290.752128) (xy 173.994828 -290.700793) (xy 173.705264 -290.700793) (xy 173.697134 -290.752128)
			(xy 173.681073 -290.801558) (xy 173.657477 -290.847868) (xy 173.626927 -290.889916) (xy 173.590176 -290.926667)
			(xy 173.548128 -290.957217) (xy 173.501818 -290.980813) (xy 173.452388 -290.996874) (xy 173.401053 -291.005004)
			(xy 173.349079 -291.005004) (xy 173.297744 -290.996874) (xy 173.248314 -290.980813) (xy 173.202004 -290.957217)
			(xy 173.159956 -290.926667) (xy 173.123205 -290.889916) (xy 173.092655 -290.847868) (xy 173.069059 -290.801558)
			(xy 173.052998 -290.752128) (xy 173.044868 -290.700793) (xy 172.75505 -290.700793) (xy 172.74692 -290.752128)
			(xy 172.730859 -290.801558) (xy 172.707263 -290.847868) (xy 172.676713 -290.889916) (xy 172.639962 -290.926667)
			(xy 172.597914 -290.957217) (xy 172.551604 -290.980813) (xy 172.502174 -290.996874) (xy 172.450839 -291.005004)
			(xy 172.398865 -291.005004) (xy 172.34753 -290.996874) (xy 172.2981 -290.980813) (xy 172.25179 -290.957217)
			(xy 172.209742 -290.926667) (xy 172.172991 -290.889916) (xy 172.142441 -290.847868) (xy 172.118845 -290.801558)
			(xy 172.102784 -290.752128) (xy 172.094654 -290.700793) (xy 171.80509 -290.700793) (xy 171.79696 -290.752128)
			(xy 171.780899 -290.801558) (xy 171.757303 -290.847868) (xy 171.726753 -290.889916) (xy 171.690002 -290.926667)
			(xy 171.647954 -290.957217) (xy 171.601644 -290.980813) (xy 171.552214 -290.996874) (xy 171.500879 -291.005004)
			(xy 171.448905 -291.005004) (xy 171.39757 -290.996874) (xy 171.34814 -290.980813) (xy 171.30183 -290.957217)
			(xy 171.259782 -290.926667) (xy 171.223031 -290.889916) (xy 171.192481 -290.847868) (xy 171.168885 -290.801558)
			(xy 171.152824 -290.752128) (xy 171.144694 -290.700793) (xy 170.85513 -290.700793) (xy 170.847 -290.752128)
			(xy 170.830939 -290.801558) (xy 170.807343 -290.847868) (xy 170.776793 -290.889916) (xy 170.740042 -290.926667)
			(xy 170.697994 -290.957217) (xy 170.651684 -290.980813) (xy 170.602254 -290.996874) (xy 170.550919 -291.005004)
			(xy 170.498945 -291.005004) (xy 170.44761 -290.996874) (xy 170.39818 -290.980813) (xy 170.35187 -290.957217)
			(xy 170.309822 -290.926667) (xy 170.273071 -290.889916) (xy 170.242521 -290.847868) (xy 170.218925 -290.801558)
			(xy 170.202864 -290.752128) (xy 170.194734 -290.700793) (xy 169.90517 -290.700793) (xy 169.89704 -290.752128)
			(xy 169.880979 -290.801558) (xy 169.857383 -290.847868) (xy 169.826833 -290.889916) (xy 169.790082 -290.926667)
			(xy 169.748034 -290.957217) (xy 169.701724 -290.980813) (xy 169.652294 -290.996874) (xy 169.600959 -291.005004)
			(xy 169.548985 -291.005004) (xy 169.49765 -290.996874) (xy 169.44822 -290.980813) (xy 169.40191 -290.957217)
			(xy 169.359862 -290.926667) (xy 169.323111 -290.889916) (xy 169.292561 -290.847868) (xy 169.268965 -290.801558)
			(xy 169.252904 -290.752128) (xy 169.244774 -290.700793) (xy 168.95521 -290.700793) (xy 168.94708 -290.752128)
			(xy 168.931019 -290.801558) (xy 168.907423 -290.847868) (xy 168.876873 -290.889916) (xy 168.840122 -290.926667)
			(xy 168.798074 -290.957217) (xy 168.751764 -290.980813) (xy 168.702334 -290.996874) (xy 168.650999 -291.005004)
			(xy 168.599025 -291.005004) (xy 168.54769 -290.996874) (xy 168.49826 -290.980813) (xy 168.45195 -290.957217)
			(xy 168.409902 -290.926667) (xy 168.373151 -290.889916) (xy 168.342601 -290.847868) (xy 168.319005 -290.801558)
			(xy 168.302944 -290.752128) (xy 168.294814 -290.700793) (xy 168.00525 -290.700793) (xy 167.99712 -290.752128)
			(xy 167.981059 -290.801558) (xy 167.957463 -290.847868) (xy 167.926913 -290.889916) (xy 167.890162 -290.926667)
			(xy 167.848114 -290.957217) (xy 167.801804 -290.980813) (xy 167.752374 -290.996874) (xy 167.701039 -291.005004)
			(xy 167.649065 -291.005004) (xy 167.59773 -290.996874) (xy 167.5483 -290.980813) (xy 167.50199 -290.957217)
			(xy 167.459942 -290.926667) (xy 167.423191 -290.889916) (xy 167.392641 -290.847868) (xy 167.369045 -290.801558)
			(xy 167.352984 -290.752128) (xy 167.344854 -290.700793) (xy 167.05529 -290.700793) (xy 167.04716 -290.752128)
			(xy 167.031099 -290.801558) (xy 167.007503 -290.847868) (xy 166.976953 -290.889916) (xy 166.940202 -290.926667)
			(xy 166.898154 -290.957217) (xy 166.851844 -290.980813) (xy 166.802414 -290.996874) (xy 166.751079 -291.005004)
			(xy 166.699105 -291.005004) (xy 166.64777 -290.996874) (xy 166.59834 -290.980813) (xy 166.55203 -290.957217)
			(xy 166.509982 -290.926667) (xy 166.473231 -290.889916) (xy 166.442681 -290.847868) (xy 166.419085 -290.801558)
			(xy 166.403024 -290.752128) (xy 166.394894 -290.700793) (xy 166.105076 -290.700793) (xy 166.096946 -290.752128)
			(xy 166.080885 -290.801558) (xy 166.057289 -290.847868) (xy 166.026739 -290.889916) (xy 165.989988 -290.926667)
			(xy 165.94794 -290.957217) (xy 165.90163 -290.980813) (xy 165.8522 -290.996874) (xy 165.800865 -291.005004)
			(xy 165.748891 -291.005004) (xy 165.697556 -290.996874) (xy 165.648126 -290.980813) (xy 165.601816 -290.957217)
			(xy 165.559768 -290.926667) (xy 165.523017 -290.889916) (xy 165.492467 -290.847868) (xy 165.468871 -290.801558)
			(xy 165.45281 -290.752128) (xy 165.44468 -290.700793) (xy 165.155116 -290.700793) (xy 165.146986 -290.752128)
			(xy 165.130925 -290.801558) (xy 165.107329 -290.847868) (xy 165.076779 -290.889916) (xy 165.040028 -290.926667)
			(xy 164.99798 -290.957217) (xy 164.95167 -290.980813) (xy 164.90224 -290.996874) (xy 164.850905 -291.005004)
			(xy 164.798931 -291.005004) (xy 164.747596 -290.996874) (xy 164.698166 -290.980813) (xy 164.651856 -290.957217)
			(xy 164.609808 -290.926667) (xy 164.573057 -290.889916) (xy 164.542507 -290.847868) (xy 164.518911 -290.801558)
			(xy 164.50285 -290.752128) (xy 164.49472 -290.700793) (xy 164.205156 -290.700793) (xy 164.197026 -290.752128)
			(xy 164.180965 -290.801558) (xy 164.157369 -290.847868) (xy 164.126819 -290.889916) (xy 164.090068 -290.926667)
			(xy 164.04802 -290.957217) (xy 164.00171 -290.980813) (xy 163.95228 -290.996874) (xy 163.900945 -291.005004)
			(xy 163.848971 -291.005004) (xy 163.797636 -290.996874) (xy 163.748206 -290.980813) (xy 163.701896 -290.957217)
			(xy 163.659848 -290.926667) (xy 163.623097 -290.889916) (xy 163.592547 -290.847868) (xy 163.568951 -290.801558)
			(xy 163.55289 -290.752128) (xy 163.54476 -290.700793) (xy 162.305236 -290.700793) (xy 162.297106 -290.752128)
			(xy 162.281045 -290.801558) (xy 162.257449 -290.847868) (xy 162.226899 -290.889916) (xy 162.190148 -290.926667)
			(xy 162.1481 -290.957217) (xy 162.10179 -290.980813) (xy 162.05236 -290.996874) (xy 162.001025 -291.005004)
			(xy 161.949051 -291.005004) (xy 161.897716 -290.996874) (xy 161.848286 -290.980813) (xy 161.801976 -290.957217)
			(xy 161.759928 -290.926667) (xy 161.723177 -290.889916) (xy 161.692627 -290.847868) (xy 161.669031 -290.801558)
			(xy 161.65297 -290.752128) (xy 161.64484 -290.700793) (xy 160.405062 -290.700793) (xy 160.396932 -290.752128)
			(xy 160.380871 -290.801558) (xy 160.357275 -290.847868) (xy 160.326725 -290.889916) (xy 160.289974 -290.926667)
			(xy 160.247926 -290.957217) (xy 160.201616 -290.980813) (xy 160.152186 -290.996874) (xy 160.100851 -291.005004)
			(xy 160.048877 -291.005004) (xy 159.997542 -290.996874) (xy 159.948112 -290.980813) (xy 159.901802 -290.957217)
			(xy 159.859754 -290.926667) (xy 159.823003 -290.889916) (xy 159.792453 -290.847868) (xy 159.768857 -290.801558)
			(xy 159.752796 -290.752128) (xy 159.744666 -290.700793) (xy 159.454006 -290.700793) (xy 159.451852 -290.727628)
			(xy 159.43924 -290.779102) (xy 159.418579 -290.827905) (xy 159.390398 -290.872787) (xy 159.35542 -290.9126)
			(xy 159.314539 -290.946325) (xy 159.268802 -290.973096) (xy 159.244284 -290.983162) (xy 159.236918 -290.985956)
			(xy 159.225234 -290.995354) (xy 159.220662 -291.001958) (xy 159.216552 -291.00841) (xy 159.212022 -291.023015)
			(xy 159.211772 -291.03066) (xy 159.211772 -291.268912) (xy 159.212033 -291.276556) (xy 159.216564 -291.291156)
			(xy 159.220662 -291.297614) (xy 159.225234 -291.304218) (xy 159.236918 -291.313616) (xy 159.244284 -291.31641)
			(xy 159.268809 -291.326466) (xy 159.314552 -291.353239) (xy 159.355438 -291.386966) (xy 159.390422 -291.426782)
			(xy 159.418607 -291.471669) (xy 159.439272 -291.520477) (xy 159.451887 -291.571956) (xy 159.45613 -291.624788)
			(xy 159.454047 -291.650753) (xy 159.744666 -291.650753) (xy 159.744666 -291.598779) (xy 159.752796 -291.547444)
			(xy 159.768857 -291.498014) (xy 159.792453 -291.451704) (xy 159.823003 -291.409656) (xy 159.859754 -291.372905)
			(xy 159.901802 -291.342355) (xy 159.948112 -291.318759) (xy 159.997542 -291.302698) (xy 160.048877 -291.294568)
			(xy 160.100851 -291.294568) (xy 160.152186 -291.302698) (xy 160.201616 -291.318759) (xy 160.247926 -291.342355)
			(xy 160.289974 -291.372905) (xy 160.326725 -291.409656) (xy 160.357275 -291.451704) (xy 160.380871 -291.498014)
			(xy 160.396932 -291.547444) (xy 160.405062 -291.598779) (xy 160.405572 -291.624766) (xy 160.405062 -291.650753)
			(xy 161.64484 -291.650753) (xy 161.64484 -291.598779) (xy 161.65297 -291.547444) (xy 161.669031 -291.498014)
			(xy 161.692627 -291.451704) (xy 161.723177 -291.409656) (xy 161.759928 -291.372905) (xy 161.801976 -291.342355)
			(xy 161.848286 -291.318759) (xy 161.897716 -291.302698) (xy 161.949051 -291.294568) (xy 162.001025 -291.294568)
			(xy 162.05236 -291.302698) (xy 162.10179 -291.318759) (xy 162.1481 -291.342355) (xy 162.190148 -291.372905)
			(xy 162.226899 -291.409656) (xy 162.257449 -291.451704) (xy 162.281045 -291.498014) (xy 162.297106 -291.547444)
			(xy 162.305236 -291.598779) (xy 162.305746 -291.624766) (xy 162.305236 -291.650753) (xy 162.5948 -291.650753)
			(xy 162.5948 -291.598779) (xy 162.60293 -291.547444) (xy 162.618991 -291.498014) (xy 162.642587 -291.451704)
			(xy 162.673137 -291.409656) (xy 162.709888 -291.372905) (xy 162.751936 -291.342355) (xy 162.798246 -291.318759)
			(xy 162.847676 -291.302698) (xy 162.899011 -291.294568) (xy 162.950985 -291.294568) (xy 163.00232 -291.302698)
			(xy 163.05175 -291.318759) (xy 163.09806 -291.342355) (xy 163.140108 -291.372905) (xy 163.176859 -291.409656)
			(xy 163.207409 -291.451704) (xy 163.231005 -291.498014) (xy 163.247066 -291.547444) (xy 163.255196 -291.598779)
			(xy 163.255706 -291.624766) (xy 163.255196 -291.650753) (xy 163.54476 -291.650753) (xy 163.54476 -291.598779)
			(xy 163.55289 -291.547444) (xy 163.568951 -291.498014) (xy 163.592547 -291.451704) (xy 163.623097 -291.409656)
			(xy 163.659848 -291.372905) (xy 163.701896 -291.342355) (xy 163.748206 -291.318759) (xy 163.797636 -291.302698)
			(xy 163.848971 -291.294568) (xy 163.900945 -291.294568) (xy 163.95228 -291.302698) (xy 164.00171 -291.318759)
			(xy 164.04802 -291.342355) (xy 164.090068 -291.372905) (xy 164.126819 -291.409656) (xy 164.157369 -291.451704)
			(xy 164.180965 -291.498014) (xy 164.197026 -291.547444) (xy 164.205156 -291.598779) (xy 164.205666 -291.624766)
			(xy 164.205156 -291.650753) (xy 164.49472 -291.650753) (xy 164.49472 -291.598779) (xy 164.50285 -291.547444)
			(xy 164.518911 -291.498014) (xy 164.542507 -291.451704) (xy 164.573057 -291.409656) (xy 164.609808 -291.372905)
			(xy 164.651856 -291.342355) (xy 164.698166 -291.318759) (xy 164.747596 -291.302698) (xy 164.798931 -291.294568)
			(xy 164.850905 -291.294568) (xy 164.90224 -291.302698) (xy 164.95167 -291.318759) (xy 164.99798 -291.342355)
			(xy 165.040028 -291.372905) (xy 165.076779 -291.409656) (xy 165.107329 -291.451704) (xy 165.130925 -291.498014)
			(xy 165.146986 -291.547444) (xy 165.155116 -291.598779) (xy 165.155626 -291.624766) (xy 165.155116 -291.650753)
			(xy 165.44468 -291.650753) (xy 165.44468 -291.598779) (xy 165.45281 -291.547444) (xy 165.468871 -291.498014)
			(xy 165.492467 -291.451704) (xy 165.523017 -291.409656) (xy 165.559768 -291.372905) (xy 165.601816 -291.342355)
			(xy 165.648126 -291.318759) (xy 165.697556 -291.302698) (xy 165.748891 -291.294568) (xy 165.800865 -291.294568)
			(xy 165.8522 -291.302698) (xy 165.90163 -291.318759) (xy 165.94794 -291.342355) (xy 165.989988 -291.372905)
			(xy 166.026739 -291.409656) (xy 166.057289 -291.451704) (xy 166.080885 -291.498014) (xy 166.096946 -291.547444)
			(xy 166.105076 -291.598779) (xy 166.105586 -291.624766) (xy 166.105076 -291.650753) (xy 166.394894 -291.650753)
			(xy 166.394894 -291.598779) (xy 166.403024 -291.547444) (xy 166.419085 -291.498014) (xy 166.442681 -291.451704)
			(xy 166.473231 -291.409656) (xy 166.509982 -291.372905) (xy 166.55203 -291.342355) (xy 166.59834 -291.318759)
			(xy 166.64777 -291.302698) (xy 166.699105 -291.294568) (xy 166.751079 -291.294568) (xy 166.802414 -291.302698)
			(xy 166.851844 -291.318759) (xy 166.898154 -291.342355) (xy 166.940202 -291.372905) (xy 166.976953 -291.409656)
			(xy 167.007503 -291.451704) (xy 167.031099 -291.498014) (xy 167.04716 -291.547444) (xy 167.05529 -291.598779)
			(xy 167.0558 -291.624766) (xy 167.05529 -291.650753) (xy 167.344854 -291.650753) (xy 167.344854 -291.598779)
			(xy 167.352984 -291.547444) (xy 167.369045 -291.498014) (xy 167.392641 -291.451704) (xy 167.423191 -291.409656)
			(xy 167.459942 -291.372905) (xy 167.50199 -291.342355) (xy 167.5483 -291.318759) (xy 167.59773 -291.302698)
			(xy 167.649065 -291.294568) (xy 167.701039 -291.294568) (xy 167.752374 -291.302698) (xy 167.801804 -291.318759)
			(xy 167.848114 -291.342355) (xy 167.890162 -291.372905) (xy 167.926913 -291.409656) (xy 167.957463 -291.451704)
			(xy 167.981059 -291.498014) (xy 167.99712 -291.547444) (xy 168.00525 -291.598779) (xy 168.00576 -291.624766)
			(xy 168.00525 -291.650753) (xy 168.294814 -291.650753) (xy 168.294814 -291.598779) (xy 168.302944 -291.547444)
			(xy 168.319005 -291.498014) (xy 168.342601 -291.451704) (xy 168.373151 -291.409656) (xy 168.409902 -291.372905)
			(xy 168.45195 -291.342355) (xy 168.49826 -291.318759) (xy 168.54769 -291.302698) (xy 168.599025 -291.294568)
			(xy 168.650999 -291.294568) (xy 168.702334 -291.302698) (xy 168.751764 -291.318759) (xy 168.798074 -291.342355)
			(xy 168.840122 -291.372905) (xy 168.876873 -291.409656) (xy 168.907423 -291.451704) (xy 168.931019 -291.498014)
			(xy 168.94708 -291.547444) (xy 168.95521 -291.598779) (xy 168.95572 -291.624766) (xy 168.95521 -291.650753)
			(xy 169.244774 -291.650753) (xy 169.244774 -291.598779) (xy 169.252904 -291.547444) (xy 169.268965 -291.498014)
			(xy 169.292561 -291.451704) (xy 169.323111 -291.409656) (xy 169.359862 -291.372905) (xy 169.40191 -291.342355)
			(xy 169.44822 -291.318759) (xy 169.49765 -291.302698) (xy 169.548985 -291.294568) (xy 169.600959 -291.294568)
			(xy 169.652294 -291.302698) (xy 169.701724 -291.318759) (xy 169.748034 -291.342355) (xy 169.790082 -291.372905)
			(xy 169.826833 -291.409656) (xy 169.857383 -291.451704) (xy 169.880979 -291.498014) (xy 169.89704 -291.547444)
			(xy 169.90517 -291.598779) (xy 169.90568 -291.624766) (xy 169.90517 -291.650753) (xy 170.194734 -291.650753)
			(xy 170.194734 -291.598779) (xy 170.202864 -291.547444) (xy 170.218925 -291.498014) (xy 170.242521 -291.451704)
			(xy 170.273071 -291.409656) (xy 170.309822 -291.372905) (xy 170.35187 -291.342355) (xy 170.39818 -291.318759)
			(xy 170.44761 -291.302698) (xy 170.498945 -291.294568) (xy 170.550919 -291.294568) (xy 170.602254 -291.302698)
			(xy 170.651684 -291.318759) (xy 170.697994 -291.342355) (xy 170.740042 -291.372905) (xy 170.776793 -291.409656)
			(xy 170.807343 -291.451704) (xy 170.830939 -291.498014) (xy 170.847 -291.547444) (xy 170.85513 -291.598779)
			(xy 170.85564 -291.624766) (xy 170.85513 -291.650753) (xy 171.144694 -291.650753) (xy 171.144694 -291.598779)
			(xy 171.152824 -291.547444) (xy 171.168885 -291.498014) (xy 171.192481 -291.451704) (xy 171.223031 -291.409656)
			(xy 171.259782 -291.372905) (xy 171.30183 -291.342355) (xy 171.34814 -291.318759) (xy 171.39757 -291.302698)
			(xy 171.448905 -291.294568) (xy 171.500879 -291.294568) (xy 171.552214 -291.302698) (xy 171.601644 -291.318759)
			(xy 171.647954 -291.342355) (xy 171.690002 -291.372905) (xy 171.726753 -291.409656) (xy 171.757303 -291.451704)
			(xy 171.780899 -291.498014) (xy 171.79696 -291.547444) (xy 171.80509 -291.598779) (xy 171.8056 -291.624766)
			(xy 171.80509 -291.650753) (xy 172.094654 -291.650753) (xy 172.094654 -291.598779) (xy 172.102784 -291.547444)
			(xy 172.118845 -291.498014) (xy 172.142441 -291.451704) (xy 172.172991 -291.409656) (xy 172.209742 -291.372905)
			(xy 172.25179 -291.342355) (xy 172.2981 -291.318759) (xy 172.34753 -291.302698) (xy 172.398865 -291.294568)
			(xy 172.450839 -291.294568) (xy 172.502174 -291.302698) (xy 172.551604 -291.318759) (xy 172.597914 -291.342355)
			(xy 172.639962 -291.372905) (xy 172.676713 -291.409656) (xy 172.707263 -291.451704) (xy 172.730859 -291.498014)
			(xy 172.74692 -291.547444) (xy 172.75505 -291.598779) (xy 172.75556 -291.624766) (xy 172.75505 -291.650753)
			(xy 173.044868 -291.650753) (xy 173.044868 -291.598779) (xy 173.052998 -291.547444) (xy 173.069059 -291.498014)
			(xy 173.092655 -291.451704) (xy 173.123205 -291.409656) (xy 173.159956 -291.372905) (xy 173.202004 -291.342355)
			(xy 173.248314 -291.318759) (xy 173.297744 -291.302698) (xy 173.349079 -291.294568) (xy 173.401053 -291.294568)
			(xy 173.452388 -291.302698) (xy 173.501818 -291.318759) (xy 173.548128 -291.342355) (xy 173.590176 -291.372905)
			(xy 173.626927 -291.409656) (xy 173.657477 -291.451704) (xy 173.681073 -291.498014) (xy 173.697134 -291.547444)
			(xy 173.705264 -291.598779) (xy 173.705774 -291.624766) (xy 173.705264 -291.650753) (xy 173.994828 -291.650753)
			(xy 173.994828 -291.598779) (xy 174.002958 -291.547444) (xy 174.019019 -291.498014) (xy 174.042615 -291.451704)
			(xy 174.073165 -291.409656) (xy 174.109916 -291.372905) (xy 174.151964 -291.342355) (xy 174.198274 -291.318759)
			(xy 174.247704 -291.302698) (xy 174.299039 -291.294568) (xy 174.351013 -291.294568) (xy 174.402348 -291.302698)
			(xy 174.451778 -291.318759) (xy 174.498088 -291.342355) (xy 174.540136 -291.372905) (xy 174.576887 -291.409656)
			(xy 174.607437 -291.451704) (xy 174.631033 -291.498014) (xy 174.647094 -291.547444) (xy 174.655224 -291.598779)
			(xy 174.655734 -291.624766) (xy 174.655224 -291.650753) (xy 175.894748 -291.650753) (xy 175.894748 -291.598779)
			(xy 175.902878 -291.547444) (xy 175.918939 -291.498014) (xy 175.942535 -291.451704) (xy 175.973085 -291.409656)
			(xy 176.009836 -291.372905) (xy 176.051884 -291.342355) (xy 176.098194 -291.318759) (xy 176.147624 -291.302698)
			(xy 176.198959 -291.294568) (xy 176.250933 -291.294568) (xy 176.302268 -291.302698) (xy 176.351698 -291.318759)
			(xy 176.398008 -291.342355) (xy 176.440056 -291.372905) (xy 176.476807 -291.409656) (xy 176.507357 -291.451704)
			(xy 176.530953 -291.498014) (xy 176.547014 -291.547444) (xy 176.555144 -291.598779) (xy 176.555654 -291.624766)
			(xy 176.555144 -291.650753) (xy 176.844708 -291.650753) (xy 176.844708 -291.598779) (xy 176.852838 -291.547444)
			(xy 176.868899 -291.498014) (xy 176.892495 -291.451704) (xy 176.923045 -291.409656) (xy 176.959796 -291.372905)
			(xy 177.001844 -291.342355) (xy 177.048154 -291.318759) (xy 177.097584 -291.302698) (xy 177.148919 -291.294568)
			(xy 177.200893 -291.294568) (xy 177.252228 -291.302698) (xy 177.301658 -291.318759) (xy 177.347968 -291.342355)
			(xy 177.390016 -291.372905) (xy 177.426767 -291.409656) (xy 177.457317 -291.451704) (xy 177.480913 -291.498014)
			(xy 177.496974 -291.547444) (xy 177.505104 -291.598779) (xy 177.505614 -291.624766) (xy 177.505104 -291.650753)
			(xy 177.794668 -291.650753) (xy 177.794668 -291.598779) (xy 177.802798 -291.547444) (xy 177.818859 -291.498014)
			(xy 177.842455 -291.451704) (xy 177.873005 -291.409656) (xy 177.909756 -291.372905) (xy 177.951804 -291.342355)
			(xy 177.998114 -291.318759) (xy 178.047544 -291.302698) (xy 178.098879 -291.294568) (xy 178.150853 -291.294568)
			(xy 178.202188 -291.302698) (xy 178.251618 -291.318759) (xy 178.297928 -291.342355) (xy 178.339976 -291.372905)
			(xy 178.376727 -291.409656) (xy 178.407277 -291.451704) (xy 178.430873 -291.498014) (xy 178.446934 -291.547444)
			(xy 178.455064 -291.598779) (xy 178.455574 -291.624766) (xy 178.455064 -291.650753) (xy 178.744882 -291.650753)
			(xy 178.744882 -291.598779) (xy 178.753012 -291.547444) (xy 178.769073 -291.498014) (xy 178.792669 -291.451704)
			(xy 178.823219 -291.409656) (xy 178.85997 -291.372905) (xy 178.902018 -291.342355) (xy 178.948328 -291.318759)
			(xy 178.997758 -291.302698) (xy 179.049093 -291.294568) (xy 179.101067 -291.294568) (xy 179.152402 -291.302698)
			(xy 179.201832 -291.318759) (xy 179.248142 -291.342355) (xy 179.29019 -291.372905) (xy 179.326941 -291.409656)
			(xy 179.357491 -291.451704) (xy 179.381087 -291.498014) (xy 179.397148 -291.547444) (xy 179.405278 -291.598779)
			(xy 179.405788 -291.624766) (xy 179.405278 -291.650753) (xy 179.694842 -291.650753) (xy 179.694842 -291.598779)
			(xy 179.702972 -291.547444) (xy 179.719033 -291.498014) (xy 179.742629 -291.451704) (xy 179.773179 -291.409656)
			(xy 179.80993 -291.372905) (xy 179.851978 -291.342355) (xy 179.898288 -291.318759) (xy 179.947718 -291.302698)
			(xy 179.999053 -291.294568) (xy 180.051027 -291.294568) (xy 180.102362 -291.302698) (xy 180.151792 -291.318759)
			(xy 180.198102 -291.342355) (xy 180.24015 -291.372905) (xy 180.276901 -291.409656) (xy 180.307451 -291.451704)
			(xy 180.331047 -291.498014) (xy 180.347108 -291.547444) (xy 180.355238 -291.598779) (xy 180.355748 -291.624766)
			(xy 180.355238 -291.650753) (xy 180.644802 -291.650753) (xy 180.644802 -291.598779) (xy 180.652932 -291.547444)
			(xy 180.668993 -291.498014) (xy 180.692589 -291.451704) (xy 180.723139 -291.409656) (xy 180.75989 -291.372905)
			(xy 180.801938 -291.342355) (xy 180.848248 -291.318759) (xy 180.897678 -291.302698) (xy 180.949013 -291.294568)
			(xy 181.000987 -291.294568) (xy 181.052322 -291.302698) (xy 181.101752 -291.318759) (xy 181.148062 -291.342355)
			(xy 181.19011 -291.372905) (xy 181.226861 -291.409656) (xy 181.257411 -291.451704) (xy 181.281007 -291.498014)
			(xy 181.297068 -291.547444) (xy 181.305198 -291.598779) (xy 181.305708 -291.624766) (xy 181.305198 -291.650753)
			(xy 181.594762 -291.650753) (xy 181.594762 -291.598779) (xy 181.602892 -291.547444) (xy 181.618953 -291.498014)
			(xy 181.642549 -291.451704) (xy 181.673099 -291.409656) (xy 181.70985 -291.372905) (xy 181.751898 -291.342355)
			(xy 181.798208 -291.318759) (xy 181.847638 -291.302698) (xy 181.898973 -291.294568) (xy 181.950947 -291.294568)
			(xy 182.002282 -291.302698) (xy 182.051712 -291.318759) (xy 182.098022 -291.342355) (xy 182.14007 -291.372905)
			(xy 182.176821 -291.409656) (xy 182.207371 -291.451704) (xy 182.230967 -291.498014) (xy 182.247028 -291.547444)
			(xy 182.255158 -291.598779) (xy 182.255668 -291.624766) (xy 182.255158 -291.650753) (xy 182.544722 -291.650753)
			(xy 182.544722 -291.598779) (xy 182.552852 -291.547444) (xy 182.568913 -291.498014) (xy 182.592509 -291.451704)
			(xy 182.623059 -291.409656) (xy 182.65981 -291.372905) (xy 182.701858 -291.342355) (xy 182.748168 -291.318759)
			(xy 182.797598 -291.302698) (xy 182.848933 -291.294568) (xy 182.900907 -291.294568) (xy 182.952242 -291.302698)
			(xy 183.001672 -291.318759) (xy 183.047982 -291.342355) (xy 183.09003 -291.372905) (xy 183.126781 -291.409656)
			(xy 183.157331 -291.451704) (xy 183.180927 -291.498014) (xy 183.196988 -291.547444) (xy 183.205118 -291.598779)
			(xy 183.205628 -291.624766) (xy 183.205118 -291.650753) (xy 183.494682 -291.650753) (xy 183.494682 -291.598779)
			(xy 183.502812 -291.547444) (xy 183.518873 -291.498014) (xy 183.542469 -291.451704) (xy 183.573019 -291.409656)
			(xy 183.60977 -291.372905) (xy 183.651818 -291.342355) (xy 183.698128 -291.318759) (xy 183.747558 -291.302698)
			(xy 183.798893 -291.294568) (xy 183.850867 -291.294568) (xy 183.902202 -291.302698) (xy 183.951632 -291.318759)
			(xy 183.997942 -291.342355) (xy 184.03999 -291.372905) (xy 184.076741 -291.409656) (xy 184.107291 -291.451704)
			(xy 184.130887 -291.498014) (xy 184.146948 -291.547444) (xy 184.155078 -291.598779) (xy 184.155588 -291.624766)
			(xy 184.155078 -291.650753) (xy 184.444642 -291.650753) (xy 184.444642 -291.598779) (xy 184.452772 -291.547444)
			(xy 184.468833 -291.498014) (xy 184.492429 -291.451704) (xy 184.522979 -291.409656) (xy 184.55973 -291.372905)
			(xy 184.601778 -291.342355) (xy 184.648088 -291.318759) (xy 184.697518 -291.302698) (xy 184.748853 -291.294568)
			(xy 184.800827 -291.294568) (xy 184.852162 -291.302698) (xy 184.901592 -291.318759) (xy 184.947902 -291.342355)
			(xy 184.98995 -291.372905) (xy 185.026701 -291.409656) (xy 185.057251 -291.451704) (xy 185.080847 -291.498014)
			(xy 185.096908 -291.547444) (xy 185.105038 -291.598779) (xy 185.105548 -291.624766) (xy 185.105038 -291.650753)
			(xy 185.394856 -291.650753) (xy 185.394856 -291.598779) (xy 185.402986 -291.547444) (xy 185.419047 -291.498014)
			(xy 185.442643 -291.451704) (xy 185.473193 -291.409656) (xy 185.509944 -291.372905) (xy 185.551992 -291.342355)
			(xy 185.598302 -291.318759) (xy 185.647732 -291.302698) (xy 185.699067 -291.294568) (xy 185.751041 -291.294568)
			(xy 185.802376 -291.302698) (xy 185.851806 -291.318759) (xy 185.898116 -291.342355) (xy 185.940164 -291.372905)
			(xy 185.976915 -291.409656) (xy 186.007465 -291.451704) (xy 186.031061 -291.498014) (xy 186.047122 -291.547444)
			(xy 186.055252 -291.598779) (xy 186.055762 -291.624766) (xy 186.055252 -291.650753) (xy 186.047122 -291.702088)
			(xy 186.031061 -291.751518) (xy 186.007465 -291.797828) (xy 185.976915 -291.839876) (xy 185.940164 -291.876627)
			(xy 185.898116 -291.907177) (xy 185.851806 -291.930773) (xy 185.802376 -291.946834) (xy 185.751041 -291.954964)
			(xy 185.699067 -291.954964) (xy 185.647732 -291.946834) (xy 185.598302 -291.930773) (xy 185.551992 -291.907177)
			(xy 185.509944 -291.876627) (xy 185.473193 -291.839876) (xy 185.442643 -291.797828) (xy 185.419047 -291.751518)
			(xy 185.402986 -291.702088) (xy 185.394856 -291.650753) (xy 185.105038 -291.650753) (xy 185.096908 -291.702088)
			(xy 185.080847 -291.751518) (xy 185.057251 -291.797828) (xy 185.026701 -291.839876) (xy 184.98995 -291.876627)
			(xy 184.947902 -291.907177) (xy 184.901592 -291.930773) (xy 184.852162 -291.946834) (xy 184.800827 -291.954964)
			(xy 184.748853 -291.954964) (xy 184.697518 -291.946834) (xy 184.648088 -291.930773) (xy 184.601778 -291.907177)
			(xy 184.55973 -291.876627) (xy 184.522979 -291.839876) (xy 184.492429 -291.797828) (xy 184.468833 -291.751518)
			(xy 184.452772 -291.702088) (xy 184.444642 -291.650753) (xy 184.155078 -291.650753) (xy 184.146948 -291.702088)
			(xy 184.130887 -291.751518) (xy 184.107291 -291.797828) (xy 184.076741 -291.839876) (xy 184.03999 -291.876627)
			(xy 183.997942 -291.907177) (xy 183.951632 -291.930773) (xy 183.902202 -291.946834) (xy 183.850867 -291.954964)
			(xy 183.798893 -291.954964) (xy 183.747558 -291.946834) (xy 183.698128 -291.930773) (xy 183.651818 -291.907177)
			(xy 183.60977 -291.876627) (xy 183.573019 -291.839876) (xy 183.542469 -291.797828) (xy 183.518873 -291.751518)
			(xy 183.502812 -291.702088) (xy 183.494682 -291.650753) (xy 183.205118 -291.650753) (xy 183.196988 -291.702088)
			(xy 183.180927 -291.751518) (xy 183.157331 -291.797828) (xy 183.126781 -291.839876) (xy 183.09003 -291.876627)
			(xy 183.047982 -291.907177) (xy 183.001672 -291.930773) (xy 182.952242 -291.946834) (xy 182.900907 -291.954964)
			(xy 182.848933 -291.954964) (xy 182.797598 -291.946834) (xy 182.748168 -291.930773) (xy 182.701858 -291.907177)
			(xy 182.65981 -291.876627) (xy 182.623059 -291.839876) (xy 182.592509 -291.797828) (xy 182.568913 -291.751518)
			(xy 182.552852 -291.702088) (xy 182.544722 -291.650753) (xy 182.255158 -291.650753) (xy 182.247028 -291.702088)
			(xy 182.230967 -291.751518) (xy 182.207371 -291.797828) (xy 182.176821 -291.839876) (xy 182.14007 -291.876627)
			(xy 182.098022 -291.907177) (xy 182.051712 -291.930773) (xy 182.002282 -291.946834) (xy 181.950947 -291.954964)
			(xy 181.898973 -291.954964) (xy 181.847638 -291.946834) (xy 181.798208 -291.930773) (xy 181.751898 -291.907177)
			(xy 181.70985 -291.876627) (xy 181.673099 -291.839876) (xy 181.642549 -291.797828) (xy 181.618953 -291.751518)
			(xy 181.602892 -291.702088) (xy 181.594762 -291.650753) (xy 181.305198 -291.650753) (xy 181.297068 -291.702088)
			(xy 181.281007 -291.751518) (xy 181.257411 -291.797828) (xy 181.226861 -291.839876) (xy 181.19011 -291.876627)
			(xy 181.148062 -291.907177) (xy 181.101752 -291.930773) (xy 181.052322 -291.946834) (xy 181.000987 -291.954964)
			(xy 180.949013 -291.954964) (xy 180.897678 -291.946834) (xy 180.848248 -291.930773) (xy 180.801938 -291.907177)
			(xy 180.75989 -291.876627) (xy 180.723139 -291.839876) (xy 180.692589 -291.797828) (xy 180.668993 -291.751518)
			(xy 180.652932 -291.702088) (xy 180.644802 -291.650753) (xy 180.355238 -291.650753) (xy 180.347108 -291.702088)
			(xy 180.331047 -291.751518) (xy 180.307451 -291.797828) (xy 180.276901 -291.839876) (xy 180.24015 -291.876627)
			(xy 180.198102 -291.907177) (xy 180.151792 -291.930773) (xy 180.102362 -291.946834) (xy 180.051027 -291.954964)
			(xy 179.999053 -291.954964) (xy 179.947718 -291.946834) (xy 179.898288 -291.930773) (xy 179.851978 -291.907177)
			(xy 179.80993 -291.876627) (xy 179.773179 -291.839876) (xy 179.742629 -291.797828) (xy 179.719033 -291.751518)
			(xy 179.702972 -291.702088) (xy 179.694842 -291.650753) (xy 179.405278 -291.650753) (xy 179.397148 -291.702088)
			(xy 179.381087 -291.751518) (xy 179.357491 -291.797828) (xy 179.326941 -291.839876) (xy 179.29019 -291.876627)
			(xy 179.248142 -291.907177) (xy 179.201832 -291.930773) (xy 179.152402 -291.946834) (xy 179.101067 -291.954964)
			(xy 179.049093 -291.954964) (xy 178.997758 -291.946834) (xy 178.948328 -291.930773) (xy 178.902018 -291.907177)
			(xy 178.85997 -291.876627) (xy 178.823219 -291.839876) (xy 178.792669 -291.797828) (xy 178.769073 -291.751518)
			(xy 178.753012 -291.702088) (xy 178.744882 -291.650753) (xy 178.455064 -291.650753) (xy 178.446934 -291.702088)
			(xy 178.430873 -291.751518) (xy 178.407277 -291.797828) (xy 178.376727 -291.839876) (xy 178.339976 -291.876627)
			(xy 178.297928 -291.907177) (xy 178.251618 -291.930773) (xy 178.202188 -291.946834) (xy 178.150853 -291.954964)
			(xy 178.098879 -291.954964) (xy 178.047544 -291.946834) (xy 177.998114 -291.930773) (xy 177.951804 -291.907177)
			(xy 177.909756 -291.876627) (xy 177.873005 -291.839876) (xy 177.842455 -291.797828) (xy 177.818859 -291.751518)
			(xy 177.802798 -291.702088) (xy 177.794668 -291.650753) (xy 177.505104 -291.650753) (xy 177.496974 -291.702088)
			(xy 177.480913 -291.751518) (xy 177.457317 -291.797828) (xy 177.426767 -291.839876) (xy 177.390016 -291.876627)
			(xy 177.347968 -291.907177) (xy 177.301658 -291.930773) (xy 177.252228 -291.946834) (xy 177.200893 -291.954964)
			(xy 177.148919 -291.954964) (xy 177.097584 -291.946834) (xy 177.048154 -291.930773) (xy 177.001844 -291.907177)
			(xy 176.959796 -291.876627) (xy 176.923045 -291.839876) (xy 176.892495 -291.797828) (xy 176.868899 -291.751518)
			(xy 176.852838 -291.702088) (xy 176.844708 -291.650753) (xy 176.555144 -291.650753) (xy 176.547014 -291.702088)
			(xy 176.530953 -291.751518) (xy 176.507357 -291.797828) (xy 176.476807 -291.839876) (xy 176.440056 -291.876627)
			(xy 176.398008 -291.907177) (xy 176.351698 -291.930773) (xy 176.302268 -291.946834) (xy 176.250933 -291.954964)
			(xy 176.198959 -291.954964) (xy 176.147624 -291.946834) (xy 176.098194 -291.930773) (xy 176.051884 -291.907177)
			(xy 176.009836 -291.876627) (xy 175.973085 -291.839876) (xy 175.942535 -291.797828) (xy 175.918939 -291.751518)
			(xy 175.902878 -291.702088) (xy 175.894748 -291.650753) (xy 174.655224 -291.650753) (xy 174.647094 -291.702088)
			(xy 174.631033 -291.751518) (xy 174.607437 -291.797828) (xy 174.576887 -291.839876) (xy 174.540136 -291.876627)
			(xy 174.498088 -291.907177) (xy 174.451778 -291.930773) (xy 174.402348 -291.946834) (xy 174.351013 -291.954964)
			(xy 174.299039 -291.954964) (xy 174.247704 -291.946834) (xy 174.198274 -291.930773) (xy 174.151964 -291.907177)
			(xy 174.109916 -291.876627) (xy 174.073165 -291.839876) (xy 174.042615 -291.797828) (xy 174.019019 -291.751518)
			(xy 174.002958 -291.702088) (xy 173.994828 -291.650753) (xy 173.705264 -291.650753) (xy 173.697134 -291.702088)
			(xy 173.681073 -291.751518) (xy 173.657477 -291.797828) (xy 173.626927 -291.839876) (xy 173.590176 -291.876627)
			(xy 173.548128 -291.907177) (xy 173.501818 -291.930773) (xy 173.452388 -291.946834) (xy 173.401053 -291.954964)
			(xy 173.349079 -291.954964) (xy 173.297744 -291.946834) (xy 173.248314 -291.930773) (xy 173.202004 -291.907177)
			(xy 173.159956 -291.876627) (xy 173.123205 -291.839876) (xy 173.092655 -291.797828) (xy 173.069059 -291.751518)
			(xy 173.052998 -291.702088) (xy 173.044868 -291.650753) (xy 172.75505 -291.650753) (xy 172.74692 -291.702088)
			(xy 172.730859 -291.751518) (xy 172.707263 -291.797828) (xy 172.676713 -291.839876) (xy 172.639962 -291.876627)
			(xy 172.597914 -291.907177) (xy 172.551604 -291.930773) (xy 172.502174 -291.946834) (xy 172.450839 -291.954964)
			(xy 172.398865 -291.954964) (xy 172.34753 -291.946834) (xy 172.2981 -291.930773) (xy 172.25179 -291.907177)
			(xy 172.209742 -291.876627) (xy 172.172991 -291.839876) (xy 172.142441 -291.797828) (xy 172.118845 -291.751518)
			(xy 172.102784 -291.702088) (xy 172.094654 -291.650753) (xy 171.80509 -291.650753) (xy 171.79696 -291.702088)
			(xy 171.780899 -291.751518) (xy 171.757303 -291.797828) (xy 171.726753 -291.839876) (xy 171.690002 -291.876627)
			(xy 171.647954 -291.907177) (xy 171.601644 -291.930773) (xy 171.552214 -291.946834) (xy 171.500879 -291.954964)
			(xy 171.448905 -291.954964) (xy 171.39757 -291.946834) (xy 171.34814 -291.930773) (xy 171.30183 -291.907177)
			(xy 171.259782 -291.876627) (xy 171.223031 -291.839876) (xy 171.192481 -291.797828) (xy 171.168885 -291.751518)
			(xy 171.152824 -291.702088) (xy 171.144694 -291.650753) (xy 170.85513 -291.650753) (xy 170.847 -291.702088)
			(xy 170.830939 -291.751518) (xy 170.807343 -291.797828) (xy 170.776793 -291.839876) (xy 170.740042 -291.876627)
			(xy 170.697994 -291.907177) (xy 170.651684 -291.930773) (xy 170.602254 -291.946834) (xy 170.550919 -291.954964)
			(xy 170.498945 -291.954964) (xy 170.44761 -291.946834) (xy 170.39818 -291.930773) (xy 170.35187 -291.907177)
			(xy 170.309822 -291.876627) (xy 170.273071 -291.839876) (xy 170.242521 -291.797828) (xy 170.218925 -291.751518)
			(xy 170.202864 -291.702088) (xy 170.194734 -291.650753) (xy 169.90517 -291.650753) (xy 169.89704 -291.702088)
			(xy 169.880979 -291.751518) (xy 169.857383 -291.797828) (xy 169.826833 -291.839876) (xy 169.790082 -291.876627)
			(xy 169.748034 -291.907177) (xy 169.701724 -291.930773) (xy 169.652294 -291.946834) (xy 169.600959 -291.954964)
			(xy 169.548985 -291.954964) (xy 169.49765 -291.946834) (xy 169.44822 -291.930773) (xy 169.40191 -291.907177)
			(xy 169.359862 -291.876627) (xy 169.323111 -291.839876) (xy 169.292561 -291.797828) (xy 169.268965 -291.751518)
			(xy 169.252904 -291.702088) (xy 169.244774 -291.650753) (xy 168.95521 -291.650753) (xy 168.94708 -291.702088)
			(xy 168.931019 -291.751518) (xy 168.907423 -291.797828) (xy 168.876873 -291.839876) (xy 168.840122 -291.876627)
			(xy 168.798074 -291.907177) (xy 168.751764 -291.930773) (xy 168.702334 -291.946834) (xy 168.650999 -291.954964)
			(xy 168.599025 -291.954964) (xy 168.54769 -291.946834) (xy 168.49826 -291.930773) (xy 168.45195 -291.907177)
			(xy 168.409902 -291.876627) (xy 168.373151 -291.839876) (xy 168.342601 -291.797828) (xy 168.319005 -291.751518)
			(xy 168.302944 -291.702088) (xy 168.294814 -291.650753) (xy 168.00525 -291.650753) (xy 167.99712 -291.702088)
			(xy 167.981059 -291.751518) (xy 167.957463 -291.797828) (xy 167.926913 -291.839876) (xy 167.890162 -291.876627)
			(xy 167.848114 -291.907177) (xy 167.801804 -291.930773) (xy 167.752374 -291.946834) (xy 167.701039 -291.954964)
			(xy 167.649065 -291.954964) (xy 167.59773 -291.946834) (xy 167.5483 -291.930773) (xy 167.50199 -291.907177)
			(xy 167.459942 -291.876627) (xy 167.423191 -291.839876) (xy 167.392641 -291.797828) (xy 167.369045 -291.751518)
			(xy 167.352984 -291.702088) (xy 167.344854 -291.650753) (xy 167.05529 -291.650753) (xy 167.04716 -291.702088)
			(xy 167.031099 -291.751518) (xy 167.007503 -291.797828) (xy 166.976953 -291.839876) (xy 166.940202 -291.876627)
			(xy 166.898154 -291.907177) (xy 166.851844 -291.930773) (xy 166.802414 -291.946834) (xy 166.751079 -291.954964)
			(xy 166.699105 -291.954964) (xy 166.64777 -291.946834) (xy 166.59834 -291.930773) (xy 166.55203 -291.907177)
			(xy 166.509982 -291.876627) (xy 166.473231 -291.839876) (xy 166.442681 -291.797828) (xy 166.419085 -291.751518)
			(xy 166.403024 -291.702088) (xy 166.394894 -291.650753) (xy 166.105076 -291.650753) (xy 166.096946 -291.702088)
			(xy 166.080885 -291.751518) (xy 166.057289 -291.797828) (xy 166.026739 -291.839876) (xy 165.989988 -291.876627)
			(xy 165.94794 -291.907177) (xy 165.90163 -291.930773) (xy 165.8522 -291.946834) (xy 165.800865 -291.954964)
			(xy 165.748891 -291.954964) (xy 165.697556 -291.946834) (xy 165.648126 -291.930773) (xy 165.601816 -291.907177)
			(xy 165.559768 -291.876627) (xy 165.523017 -291.839876) (xy 165.492467 -291.797828) (xy 165.468871 -291.751518)
			(xy 165.45281 -291.702088) (xy 165.44468 -291.650753) (xy 165.155116 -291.650753) (xy 165.146986 -291.702088)
			(xy 165.130925 -291.751518) (xy 165.107329 -291.797828) (xy 165.076779 -291.839876) (xy 165.040028 -291.876627)
			(xy 164.99798 -291.907177) (xy 164.95167 -291.930773) (xy 164.90224 -291.946834) (xy 164.850905 -291.954964)
			(xy 164.798931 -291.954964) (xy 164.747596 -291.946834) (xy 164.698166 -291.930773) (xy 164.651856 -291.907177)
			(xy 164.609808 -291.876627) (xy 164.573057 -291.839876) (xy 164.542507 -291.797828) (xy 164.518911 -291.751518)
			(xy 164.50285 -291.702088) (xy 164.49472 -291.650753) (xy 164.205156 -291.650753) (xy 164.197026 -291.702088)
			(xy 164.180965 -291.751518) (xy 164.157369 -291.797828) (xy 164.126819 -291.839876) (xy 164.090068 -291.876627)
			(xy 164.04802 -291.907177) (xy 164.00171 -291.930773) (xy 163.95228 -291.946834) (xy 163.900945 -291.954964)
			(xy 163.848971 -291.954964) (xy 163.797636 -291.946834) (xy 163.748206 -291.930773) (xy 163.701896 -291.907177)
			(xy 163.659848 -291.876627) (xy 163.623097 -291.839876) (xy 163.592547 -291.797828) (xy 163.568951 -291.751518)
			(xy 163.55289 -291.702088) (xy 163.54476 -291.650753) (xy 163.255196 -291.650753) (xy 163.247066 -291.702088)
			(xy 163.231005 -291.751518) (xy 163.207409 -291.797828) (xy 163.176859 -291.839876) (xy 163.140108 -291.876627)
			(xy 163.09806 -291.907177) (xy 163.05175 -291.930773) (xy 163.00232 -291.946834) (xy 162.950985 -291.954964)
			(xy 162.899011 -291.954964) (xy 162.847676 -291.946834) (xy 162.798246 -291.930773) (xy 162.751936 -291.907177)
			(xy 162.709888 -291.876627) (xy 162.673137 -291.839876) (xy 162.642587 -291.797828) (xy 162.618991 -291.751518)
			(xy 162.60293 -291.702088) (xy 162.5948 -291.650753) (xy 162.305236 -291.650753) (xy 162.297106 -291.702088)
			(xy 162.281045 -291.751518) (xy 162.257449 -291.797828) (xy 162.226899 -291.839876) (xy 162.190148 -291.876627)
			(xy 162.1481 -291.907177) (xy 162.10179 -291.930773) (xy 162.05236 -291.946834) (xy 162.001025 -291.954964)
			(xy 161.949051 -291.954964) (xy 161.897716 -291.946834) (xy 161.848286 -291.930773) (xy 161.801976 -291.907177)
			(xy 161.759928 -291.876627) (xy 161.723177 -291.839876) (xy 161.692627 -291.797828) (xy 161.669031 -291.751518)
			(xy 161.65297 -291.702088) (xy 161.64484 -291.650753) (xy 160.405062 -291.650753) (xy 160.396932 -291.702088)
			(xy 160.380871 -291.751518) (xy 160.357275 -291.797828) (xy 160.326725 -291.839876) (xy 160.289974 -291.876627)
			(xy 160.247926 -291.907177) (xy 160.201616 -291.930773) (xy 160.152186 -291.946834) (xy 160.100851 -291.954964)
			(xy 160.048877 -291.954964) (xy 159.997542 -291.946834) (xy 159.948112 -291.930773) (xy 159.901802 -291.907177)
			(xy 159.859754 -291.876627) (xy 159.823003 -291.839876) (xy 159.792453 -291.797828) (xy 159.768857 -291.751518)
			(xy 159.752796 -291.702088) (xy 159.744666 -291.650753) (xy 159.454047 -291.650753) (xy 159.451891 -291.67762)
			(xy 159.43928 -291.7291) (xy 159.418619 -291.777909) (xy 159.390437 -291.822798) (xy 159.355456 -291.862617)
			(xy 159.314572 -291.896347) (xy 159.268831 -291.923124) (xy 159.244284 -291.933122) (xy 159.236918 -291.935916)
			(xy 159.225234 -291.945314) (xy 159.220662 -291.951918) (xy 159.21656 -291.958372) (xy 159.212047 -291.972977)
			(xy 159.211772 -291.98062) (xy 159.211772 -292.219126) (xy 159.212035 -292.226769) (xy 159.216569 -292.241367)
			(xy 159.220662 -292.247828) (xy 159.225234 -292.254432) (xy 159.236918 -292.26383) (xy 159.244284 -292.266624)
			(xy 159.268808 -292.27668) (xy 159.314548 -292.303453) (xy 159.355433 -292.337179) (xy 159.390415 -292.376994)
			(xy 159.418598 -292.42188) (xy 159.439261 -292.470686) (xy 159.451875 -292.522163) (xy 159.456117 -292.574993)
			(xy 159.454032 -292.600967) (xy 159.744666 -292.600967) (xy 159.744666 -292.548993) (xy 159.752796 -292.497658)
			(xy 159.768857 -292.448228) (xy 159.792453 -292.401918) (xy 159.823003 -292.35987) (xy 159.859754 -292.323119)
			(xy 159.901802 -292.292569) (xy 159.948112 -292.268973) (xy 159.997542 -292.252912) (xy 160.048877 -292.244782)
			(xy 160.100851 -292.244782) (xy 160.152186 -292.252912) (xy 160.201616 -292.268973) (xy 160.247926 -292.292569)
			(xy 160.289974 -292.323119) (xy 160.326725 -292.35987) (xy 160.357275 -292.401918) (xy 160.380871 -292.448228)
			(xy 160.396932 -292.497658) (xy 160.405062 -292.548993) (xy 160.405572 -292.57498) (xy 160.405062 -292.600967)
			(xy 161.64484 -292.600967) (xy 161.64484 -292.548993) (xy 161.65297 -292.497658) (xy 161.669031 -292.448228)
			(xy 161.692627 -292.401918) (xy 161.723177 -292.35987) (xy 161.759928 -292.323119) (xy 161.801976 -292.292569)
			(xy 161.848286 -292.268973) (xy 161.897716 -292.252912) (xy 161.949051 -292.244782) (xy 162.001025 -292.244782)
			(xy 162.05236 -292.252912) (xy 162.10179 -292.268973) (xy 162.1481 -292.292569) (xy 162.190148 -292.323119)
			(xy 162.226899 -292.35987) (xy 162.257449 -292.401918) (xy 162.281045 -292.448228) (xy 162.297106 -292.497658)
			(xy 162.305236 -292.548993) (xy 162.305746 -292.57498) (xy 162.305236 -292.600967) (xy 162.5948 -292.600967)
			(xy 162.5948 -292.548993) (xy 162.60293 -292.497658) (xy 162.618991 -292.448228) (xy 162.642587 -292.401918)
			(xy 162.673137 -292.35987) (xy 162.709888 -292.323119) (xy 162.751936 -292.292569) (xy 162.798246 -292.268973)
			(xy 162.847676 -292.252912) (xy 162.899011 -292.244782) (xy 162.950985 -292.244782) (xy 163.00232 -292.252912)
			(xy 163.05175 -292.268973) (xy 163.09806 -292.292569) (xy 163.140108 -292.323119) (xy 163.176859 -292.35987)
			(xy 163.207409 -292.401918) (xy 163.231005 -292.448228) (xy 163.247066 -292.497658) (xy 163.255196 -292.548993)
			(xy 163.255706 -292.57498) (xy 163.255196 -292.600967) (xy 163.54476 -292.600967) (xy 163.54476 -292.548993)
			(xy 163.55289 -292.497658) (xy 163.568951 -292.448228) (xy 163.592547 -292.401918) (xy 163.623097 -292.35987)
			(xy 163.659848 -292.323119) (xy 163.701896 -292.292569) (xy 163.748206 -292.268973) (xy 163.797636 -292.252912)
			(xy 163.848971 -292.244782) (xy 163.900945 -292.244782) (xy 163.95228 -292.252912) (xy 164.00171 -292.268973)
			(xy 164.04802 -292.292569) (xy 164.090068 -292.323119) (xy 164.126819 -292.35987) (xy 164.157369 -292.401918)
			(xy 164.180965 -292.448228) (xy 164.197026 -292.497658) (xy 164.205156 -292.548993) (xy 164.205666 -292.57498)
			(xy 164.205161 -292.600713) (xy 164.49472 -292.600713) (xy 164.49472 -292.548739) (xy 164.50285 -292.497404)
			(xy 164.518911 -292.447974) (xy 164.542507 -292.401664) (xy 164.573057 -292.359616) (xy 164.609808 -292.322865)
			(xy 164.651856 -292.292315) (xy 164.698166 -292.268719) (xy 164.747596 -292.252658) (xy 164.798931 -292.244528)
			(xy 164.850905 -292.244528) (xy 164.90224 -292.252658) (xy 164.95167 -292.268719) (xy 164.99798 -292.292315)
			(xy 165.040028 -292.322865) (xy 165.076779 -292.359616) (xy 165.107329 -292.401664) (xy 165.130925 -292.447974)
			(xy 165.146986 -292.497404) (xy 165.155116 -292.548739) (xy 165.155626 -292.574726) (xy 165.155116 -292.600713)
			(xy 165.44468 -292.600713) (xy 165.44468 -292.548739) (xy 165.45281 -292.497404) (xy 165.468871 -292.447974)
			(xy 165.492467 -292.401664) (xy 165.523017 -292.359616) (xy 165.559768 -292.322865) (xy 165.601816 -292.292315)
			(xy 165.648126 -292.268719) (xy 165.697556 -292.252658) (xy 165.748891 -292.244528) (xy 165.800865 -292.244528)
			(xy 165.8522 -292.252658) (xy 165.90163 -292.268719) (xy 165.94794 -292.292315) (xy 165.989988 -292.322865)
			(xy 166.026739 -292.359616) (xy 166.057289 -292.401664) (xy 166.080885 -292.447974) (xy 166.096946 -292.497404)
			(xy 166.105076 -292.548739) (xy 166.105586 -292.574726) (xy 166.105076 -292.600713) (xy 166.105036 -292.600967)
			(xy 166.394894 -292.600967) (xy 166.394894 -292.548993) (xy 166.403024 -292.497658) (xy 166.419085 -292.448228)
			(xy 166.442681 -292.401918) (xy 166.473231 -292.35987) (xy 166.509982 -292.323119) (xy 166.55203 -292.292569)
			(xy 166.59834 -292.268973) (xy 166.64777 -292.252912) (xy 166.699105 -292.244782) (xy 166.751079 -292.244782)
			(xy 166.802414 -292.252912) (xy 166.851844 -292.268973) (xy 166.898154 -292.292569) (xy 166.940202 -292.323119)
			(xy 166.976953 -292.35987) (xy 167.007503 -292.401918) (xy 167.031099 -292.448228) (xy 167.04716 -292.497658)
			(xy 167.05529 -292.548993) (xy 167.0558 -292.57498) (xy 167.05529 -292.600967) (xy 167.344854 -292.600967)
			(xy 167.344854 -292.548993) (xy 167.352984 -292.497658) (xy 167.369045 -292.448228) (xy 167.392641 -292.401918)
			(xy 167.423191 -292.35987) (xy 167.459942 -292.323119) (xy 167.50199 -292.292569) (xy 167.5483 -292.268973)
			(xy 167.59773 -292.252912) (xy 167.649065 -292.244782) (xy 167.701039 -292.244782) (xy 167.752374 -292.252912)
			(xy 167.801804 -292.268973) (xy 167.848114 -292.292569) (xy 167.890162 -292.323119) (xy 167.926913 -292.35987)
			(xy 167.957463 -292.401918) (xy 167.981059 -292.448228) (xy 167.99712 -292.497658) (xy 168.00525 -292.548993)
			(xy 168.00576 -292.57498) (xy 168.00525 -292.600967) (xy 168.294814 -292.600967) (xy 168.294814 -292.548993)
			(xy 168.302944 -292.497658) (xy 168.319005 -292.448228) (xy 168.342601 -292.401918) (xy 168.373151 -292.35987)
			(xy 168.409902 -292.323119) (xy 168.45195 -292.292569) (xy 168.49826 -292.268973) (xy 168.54769 -292.252912)
			(xy 168.599025 -292.244782) (xy 168.650999 -292.244782) (xy 168.702334 -292.252912) (xy 168.751764 -292.268973)
			(xy 168.798074 -292.292569) (xy 168.840122 -292.323119) (xy 168.876873 -292.35987) (xy 168.907423 -292.401918)
			(xy 168.931019 -292.448228) (xy 168.94708 -292.497658) (xy 168.95521 -292.548993) (xy 168.95572 -292.57498)
			(xy 168.95521 -292.600967) (xy 169.244774 -292.600967) (xy 169.244774 -292.548993) (xy 169.252904 -292.497658)
			(xy 169.268965 -292.448228) (xy 169.292561 -292.401918) (xy 169.323111 -292.35987) (xy 169.359862 -292.323119)
			(xy 169.40191 -292.292569) (xy 169.44822 -292.268973) (xy 169.49765 -292.252912) (xy 169.548985 -292.244782)
			(xy 169.600959 -292.244782) (xy 169.652294 -292.252912) (xy 169.701724 -292.268973) (xy 169.748034 -292.292569)
			(xy 169.790082 -292.323119) (xy 169.826833 -292.35987) (xy 169.857383 -292.401918) (xy 169.880979 -292.448228)
			(xy 169.89704 -292.497658) (xy 169.90517 -292.548993) (xy 169.90568 -292.57498) (xy 169.90517 -292.600967)
			(xy 170.194734 -292.600967) (xy 170.194734 -292.548993) (xy 170.202864 -292.497658) (xy 170.218925 -292.448228)
			(xy 170.242521 -292.401918) (xy 170.273071 -292.35987) (xy 170.309822 -292.323119) (xy 170.35187 -292.292569)
			(xy 170.39818 -292.268973) (xy 170.44761 -292.252912) (xy 170.498945 -292.244782) (xy 170.550919 -292.244782)
			(xy 170.602254 -292.252912) (xy 170.651684 -292.268973) (xy 170.697994 -292.292569) (xy 170.740042 -292.323119)
			(xy 170.776793 -292.35987) (xy 170.807343 -292.401918) (xy 170.830939 -292.448228) (xy 170.847 -292.497658)
			(xy 170.85513 -292.548993) (xy 170.85564 -292.57498) (xy 170.85513 -292.600967) (xy 171.144694 -292.600967)
			(xy 171.144694 -292.548993) (xy 171.152824 -292.497658) (xy 171.168885 -292.448228) (xy 171.192481 -292.401918)
			(xy 171.223031 -292.35987) (xy 171.259782 -292.323119) (xy 171.30183 -292.292569) (xy 171.34814 -292.268973)
			(xy 171.39757 -292.252912) (xy 171.448905 -292.244782) (xy 171.500879 -292.244782) (xy 171.552214 -292.252912)
			(xy 171.601644 -292.268973) (xy 171.647954 -292.292569) (xy 171.690002 -292.323119) (xy 171.726753 -292.35987)
			(xy 171.757303 -292.401918) (xy 171.780899 -292.448228) (xy 171.79696 -292.497658) (xy 171.80509 -292.548993)
			(xy 171.8056 -292.57498) (xy 171.80509 -292.600967) (xy 172.094908 -292.600967) (xy 172.094908 -292.548993)
			(xy 172.103038 -292.497658) (xy 172.119099 -292.448228) (xy 172.142695 -292.401918) (xy 172.173245 -292.35987)
			(xy 172.209996 -292.323119) (xy 172.252044 -292.292569) (xy 172.298354 -292.268973) (xy 172.347784 -292.252912)
			(xy 172.399119 -292.244782) (xy 172.451093 -292.244782) (xy 172.502428 -292.252912) (xy 172.551858 -292.268973)
			(xy 172.598168 -292.292569) (xy 172.640216 -292.323119) (xy 172.676967 -292.35987) (xy 172.707517 -292.401918)
			(xy 172.731113 -292.448228) (xy 172.747174 -292.497658) (xy 172.755304 -292.548993) (xy 172.755814 -292.57498)
			(xy 172.755304 -292.600967) (xy 173.044868 -292.600967) (xy 173.044868 -292.548993) (xy 173.052998 -292.497658)
			(xy 173.069059 -292.448228) (xy 173.092655 -292.401918) (xy 173.123205 -292.35987) (xy 173.159956 -292.323119)
			(xy 173.202004 -292.292569) (xy 173.248314 -292.268973) (xy 173.297744 -292.252912) (xy 173.349079 -292.244782)
			(xy 173.401053 -292.244782) (xy 173.452388 -292.252912) (xy 173.501818 -292.268973) (xy 173.548128 -292.292569)
			(xy 173.590176 -292.323119) (xy 173.626927 -292.35987) (xy 173.657477 -292.401918) (xy 173.681073 -292.448228)
			(xy 173.697134 -292.497658) (xy 173.705264 -292.548993) (xy 173.705774 -292.57498) (xy 173.705264 -292.600967)
			(xy 173.994828 -292.600967) (xy 173.994828 -292.548993) (xy 174.002958 -292.497658) (xy 174.019019 -292.448228)
			(xy 174.042615 -292.401918) (xy 174.073165 -292.35987) (xy 174.109916 -292.323119) (xy 174.151964 -292.292569)
			(xy 174.198274 -292.268973) (xy 174.247704 -292.252912) (xy 174.299039 -292.244782) (xy 174.351013 -292.244782)
			(xy 174.402348 -292.252912) (xy 174.451778 -292.268973) (xy 174.498088 -292.292569) (xy 174.540136 -292.323119)
			(xy 174.576887 -292.35987) (xy 174.607437 -292.401918) (xy 174.631033 -292.448228) (xy 174.647094 -292.497658)
			(xy 174.655224 -292.548993) (xy 174.655734 -292.57498) (xy 174.655229 -292.600713) (xy 175.894748 -292.600713)
			(xy 175.894748 -292.548739) (xy 175.902878 -292.497404) (xy 175.918939 -292.447974) (xy 175.942535 -292.401664)
			(xy 175.973085 -292.359616) (xy 176.009836 -292.322865) (xy 176.051884 -292.292315) (xy 176.098194 -292.268719)
			(xy 176.147624 -292.252658) (xy 176.198959 -292.244528) (xy 176.250933 -292.244528) (xy 176.302268 -292.252658)
			(xy 176.351698 -292.268719) (xy 176.398008 -292.292315) (xy 176.440056 -292.322865) (xy 176.476807 -292.359616)
			(xy 176.507357 -292.401664) (xy 176.530953 -292.447974) (xy 176.547014 -292.497404) (xy 176.555144 -292.548739)
			(xy 176.555654 -292.574726) (xy 176.555144 -292.600713) (xy 176.844708 -292.600713) (xy 176.844708 -292.548739)
			(xy 176.852838 -292.497404) (xy 176.868899 -292.447974) (xy 176.892495 -292.401664) (xy 176.923045 -292.359616)
			(xy 176.959796 -292.322865) (xy 177.001844 -292.292315) (xy 177.048154 -292.268719) (xy 177.097584 -292.252658)
			(xy 177.148919 -292.244528) (xy 177.200893 -292.244528) (xy 177.252228 -292.252658) (xy 177.301658 -292.268719)
			(xy 177.347968 -292.292315) (xy 177.390016 -292.322865) (xy 177.426767 -292.359616) (xy 177.457317 -292.401664)
			(xy 177.480913 -292.447974) (xy 177.496974 -292.497404) (xy 177.505104 -292.548739) (xy 177.505614 -292.574726)
			(xy 177.505104 -292.600713) (xy 177.794668 -292.600713) (xy 177.794668 -292.548739) (xy 177.802798 -292.497404)
			(xy 177.818859 -292.447974) (xy 177.842455 -292.401664) (xy 177.873005 -292.359616) (xy 177.909756 -292.322865)
			(xy 177.951804 -292.292315) (xy 177.998114 -292.268719) (xy 178.047544 -292.252658) (xy 178.098879 -292.244528)
			(xy 178.150853 -292.244528) (xy 178.202188 -292.252658) (xy 178.251618 -292.268719) (xy 178.297928 -292.292315)
			(xy 178.339976 -292.322865) (xy 178.376727 -292.359616) (xy 178.407277 -292.401664) (xy 178.430873 -292.447974)
			(xy 178.446934 -292.497404) (xy 178.455064 -292.548739) (xy 178.455574 -292.574726) (xy 178.455064 -292.600713)
			(xy 178.744882 -292.600713) (xy 178.744882 -292.548739) (xy 178.753012 -292.497404) (xy 178.769073 -292.447974)
			(xy 178.792669 -292.401664) (xy 178.823219 -292.359616) (xy 178.85997 -292.322865) (xy 178.902018 -292.292315)
			(xy 178.948328 -292.268719) (xy 178.997758 -292.252658) (xy 179.049093 -292.244528) (xy 179.101067 -292.244528)
			(xy 179.152402 -292.252658) (xy 179.201832 -292.268719) (xy 179.248142 -292.292315) (xy 179.29019 -292.322865)
			(xy 179.326941 -292.359616) (xy 179.357491 -292.401664) (xy 179.381087 -292.447974) (xy 179.397148 -292.497404)
			(xy 179.405278 -292.548739) (xy 179.405788 -292.574726) (xy 179.405278 -292.600713) (xy 179.694842 -292.600713)
			(xy 179.694842 -292.548739) (xy 179.702972 -292.497404) (xy 179.719033 -292.447974) (xy 179.742629 -292.401664)
			(xy 179.773179 -292.359616) (xy 179.80993 -292.322865) (xy 179.851978 -292.292315) (xy 179.898288 -292.268719)
			(xy 179.947718 -292.252658) (xy 179.999053 -292.244528) (xy 180.051027 -292.244528) (xy 180.102362 -292.252658)
			(xy 180.151792 -292.268719) (xy 180.198102 -292.292315) (xy 180.24015 -292.322865) (xy 180.276901 -292.359616)
			(xy 180.307451 -292.401664) (xy 180.331047 -292.447974) (xy 180.347108 -292.497404) (xy 180.355238 -292.548739)
			(xy 180.355748 -292.574726) (xy 180.355238 -292.600713) (xy 180.644802 -292.600713) (xy 180.644802 -292.548739)
			(xy 180.652932 -292.497404) (xy 180.668993 -292.447974) (xy 180.692589 -292.401664) (xy 180.723139 -292.359616)
			(xy 180.75989 -292.322865) (xy 180.801938 -292.292315) (xy 180.848248 -292.268719) (xy 180.897678 -292.252658)
			(xy 180.949013 -292.244528) (xy 181.000987 -292.244528) (xy 181.052322 -292.252658) (xy 181.101752 -292.268719)
			(xy 181.148062 -292.292315) (xy 181.19011 -292.322865) (xy 181.226861 -292.359616) (xy 181.257411 -292.401664)
			(xy 181.281007 -292.447974) (xy 181.297068 -292.497404) (xy 181.305198 -292.548739) (xy 181.305708 -292.574726)
			(xy 181.305198 -292.600713) (xy 181.594762 -292.600713) (xy 181.594762 -292.548739) (xy 181.602892 -292.497404)
			(xy 181.618953 -292.447974) (xy 181.642549 -292.401664) (xy 181.673099 -292.359616) (xy 181.70985 -292.322865)
			(xy 181.751898 -292.292315) (xy 181.798208 -292.268719) (xy 181.847638 -292.252658) (xy 181.898973 -292.244528)
			(xy 181.950947 -292.244528) (xy 182.002282 -292.252658) (xy 182.051712 -292.268719) (xy 182.098022 -292.292315)
			(xy 182.14007 -292.322865) (xy 182.176821 -292.359616) (xy 182.207371 -292.401664) (xy 182.230967 -292.447974)
			(xy 182.247028 -292.497404) (xy 182.255158 -292.548739) (xy 182.255668 -292.574726) (xy 182.255158 -292.600713)
			(xy 182.544722 -292.600713) (xy 182.544722 -292.548739) (xy 182.552852 -292.497404) (xy 182.568913 -292.447974)
			(xy 182.592509 -292.401664) (xy 182.623059 -292.359616) (xy 182.65981 -292.322865) (xy 182.701858 -292.292315)
			(xy 182.748168 -292.268719) (xy 182.797598 -292.252658) (xy 182.848933 -292.244528) (xy 182.900907 -292.244528)
			(xy 182.952242 -292.252658) (xy 183.001672 -292.268719) (xy 183.047982 -292.292315) (xy 183.09003 -292.322865)
			(xy 183.126781 -292.359616) (xy 183.157331 -292.401664) (xy 183.180927 -292.447974) (xy 183.196988 -292.497404)
			(xy 183.205118 -292.548739) (xy 183.205628 -292.574726) (xy 183.205118 -292.600713) (xy 183.494682 -292.600713)
			(xy 183.494682 -292.548739) (xy 183.502812 -292.497404) (xy 183.518873 -292.447974) (xy 183.542469 -292.401664)
			(xy 183.573019 -292.359616) (xy 183.60977 -292.322865) (xy 183.651818 -292.292315) (xy 183.698128 -292.268719)
			(xy 183.747558 -292.252658) (xy 183.798893 -292.244528) (xy 183.850867 -292.244528) (xy 183.902202 -292.252658)
			(xy 183.951632 -292.268719) (xy 183.997942 -292.292315) (xy 184.03999 -292.322865) (xy 184.076741 -292.359616)
			(xy 184.107291 -292.401664) (xy 184.130887 -292.447974) (xy 184.146948 -292.497404) (xy 184.155078 -292.548739)
			(xy 184.155588 -292.574726) (xy 184.155078 -292.600713) (xy 184.444642 -292.600713) (xy 184.444642 -292.548739)
			(xy 184.452772 -292.497404) (xy 184.468833 -292.447974) (xy 184.492429 -292.401664) (xy 184.522979 -292.359616)
			(xy 184.55973 -292.322865) (xy 184.601778 -292.292315) (xy 184.648088 -292.268719) (xy 184.697518 -292.252658)
			(xy 184.748853 -292.244528) (xy 184.800827 -292.244528) (xy 184.852162 -292.252658) (xy 184.901592 -292.268719)
			(xy 184.947902 -292.292315) (xy 184.98995 -292.322865) (xy 185.026701 -292.359616) (xy 185.057251 -292.401664)
			(xy 185.080847 -292.447974) (xy 185.096908 -292.497404) (xy 185.105038 -292.548739) (xy 185.105548 -292.574726)
			(xy 185.105038 -292.600713) (xy 185.394856 -292.600713) (xy 185.394856 -292.548739) (xy 185.402986 -292.497404)
			(xy 185.419047 -292.447974) (xy 185.442643 -292.401664) (xy 185.473193 -292.359616) (xy 185.509944 -292.322865)
			(xy 185.551992 -292.292315) (xy 185.598302 -292.268719) (xy 185.647732 -292.252658) (xy 185.699067 -292.244528)
			(xy 185.751041 -292.244528) (xy 185.802376 -292.252658) (xy 185.851806 -292.268719) (xy 185.898116 -292.292315)
			(xy 185.940164 -292.322865) (xy 185.976915 -292.359616) (xy 186.007465 -292.401664) (xy 186.031061 -292.447974)
			(xy 186.047122 -292.497404) (xy 186.055252 -292.548739) (xy 186.055762 -292.574726) (xy 186.055252 -292.600713)
			(xy 186.047122 -292.652048) (xy 186.031061 -292.701478) (xy 186.007465 -292.747788) (xy 185.976915 -292.789836)
			(xy 185.940164 -292.826587) (xy 185.898116 -292.857137) (xy 185.851806 -292.880733) (xy 185.802376 -292.896794)
			(xy 185.751041 -292.904924) (xy 185.699067 -292.904924) (xy 185.647732 -292.896794) (xy 185.598302 -292.880733)
			(xy 185.551992 -292.857137) (xy 185.509944 -292.826587) (xy 185.473193 -292.789836) (xy 185.442643 -292.747788)
			(xy 185.419047 -292.701478) (xy 185.402986 -292.652048) (xy 185.394856 -292.600713) (xy 185.105038 -292.600713)
			(xy 185.096908 -292.652048) (xy 185.080847 -292.701478) (xy 185.057251 -292.747788) (xy 185.026701 -292.789836)
			(xy 184.98995 -292.826587) (xy 184.947902 -292.857137) (xy 184.901592 -292.880733) (xy 184.852162 -292.896794)
			(xy 184.800827 -292.904924) (xy 184.748853 -292.904924) (xy 184.697518 -292.896794) (xy 184.648088 -292.880733)
			(xy 184.601778 -292.857137) (xy 184.55973 -292.826587) (xy 184.522979 -292.789836) (xy 184.492429 -292.747788)
			(xy 184.468833 -292.701478) (xy 184.452772 -292.652048) (xy 184.444642 -292.600713) (xy 184.155078 -292.600713)
			(xy 184.146948 -292.652048) (xy 184.130887 -292.701478) (xy 184.107291 -292.747788) (xy 184.076741 -292.789836)
			(xy 184.03999 -292.826587) (xy 183.997942 -292.857137) (xy 183.951632 -292.880733) (xy 183.902202 -292.896794)
			(xy 183.850867 -292.904924) (xy 183.798893 -292.904924) (xy 183.747558 -292.896794) (xy 183.698128 -292.880733)
			(xy 183.651818 -292.857137) (xy 183.60977 -292.826587) (xy 183.573019 -292.789836) (xy 183.542469 -292.747788)
			(xy 183.518873 -292.701478) (xy 183.502812 -292.652048) (xy 183.494682 -292.600713) (xy 183.205118 -292.600713)
			(xy 183.196988 -292.652048) (xy 183.180927 -292.701478) (xy 183.157331 -292.747788) (xy 183.126781 -292.789836)
			(xy 183.09003 -292.826587) (xy 183.047982 -292.857137) (xy 183.001672 -292.880733) (xy 182.952242 -292.896794)
			(xy 182.900907 -292.904924) (xy 182.848933 -292.904924) (xy 182.797598 -292.896794) (xy 182.748168 -292.880733)
			(xy 182.701858 -292.857137) (xy 182.65981 -292.826587) (xy 182.623059 -292.789836) (xy 182.592509 -292.747788)
			(xy 182.568913 -292.701478) (xy 182.552852 -292.652048) (xy 182.544722 -292.600713) (xy 182.255158 -292.600713)
			(xy 182.247028 -292.652048) (xy 182.230967 -292.701478) (xy 182.207371 -292.747788) (xy 182.176821 -292.789836)
			(xy 182.14007 -292.826587) (xy 182.098022 -292.857137) (xy 182.051712 -292.880733) (xy 182.002282 -292.896794)
			(xy 181.950947 -292.904924) (xy 181.898973 -292.904924) (xy 181.847638 -292.896794) (xy 181.798208 -292.880733)
			(xy 181.751898 -292.857137) (xy 181.70985 -292.826587) (xy 181.673099 -292.789836) (xy 181.642549 -292.747788)
			(xy 181.618953 -292.701478) (xy 181.602892 -292.652048) (xy 181.594762 -292.600713) (xy 181.305198 -292.600713)
			(xy 181.297068 -292.652048) (xy 181.281007 -292.701478) (xy 181.257411 -292.747788) (xy 181.226861 -292.789836)
			(xy 181.19011 -292.826587) (xy 181.148062 -292.857137) (xy 181.101752 -292.880733) (xy 181.052322 -292.896794)
			(xy 181.000987 -292.904924) (xy 180.949013 -292.904924) (xy 180.897678 -292.896794) (xy 180.848248 -292.880733)
			(xy 180.801938 -292.857137) (xy 180.75989 -292.826587) (xy 180.723139 -292.789836) (xy 180.692589 -292.747788)
			(xy 180.668993 -292.701478) (xy 180.652932 -292.652048) (xy 180.644802 -292.600713) (xy 180.355238 -292.600713)
			(xy 180.347108 -292.652048) (xy 180.331047 -292.701478) (xy 180.307451 -292.747788) (xy 180.276901 -292.789836)
			(xy 180.24015 -292.826587) (xy 180.198102 -292.857137) (xy 180.151792 -292.880733) (xy 180.102362 -292.896794)
			(xy 180.051027 -292.904924) (xy 179.999053 -292.904924) (xy 179.947718 -292.896794) (xy 179.898288 -292.880733)
			(xy 179.851978 -292.857137) (xy 179.80993 -292.826587) (xy 179.773179 -292.789836) (xy 179.742629 -292.747788)
			(xy 179.719033 -292.701478) (xy 179.702972 -292.652048) (xy 179.694842 -292.600713) (xy 179.405278 -292.600713)
			(xy 179.397148 -292.652048) (xy 179.381087 -292.701478) (xy 179.357491 -292.747788) (xy 179.326941 -292.789836)
			(xy 179.29019 -292.826587) (xy 179.248142 -292.857137) (xy 179.201832 -292.880733) (xy 179.152402 -292.896794)
			(xy 179.101067 -292.904924) (xy 179.049093 -292.904924) (xy 178.997758 -292.896794) (xy 178.948328 -292.880733)
			(xy 178.902018 -292.857137) (xy 178.85997 -292.826587) (xy 178.823219 -292.789836) (xy 178.792669 -292.747788)
			(xy 178.769073 -292.701478) (xy 178.753012 -292.652048) (xy 178.744882 -292.600713) (xy 178.455064 -292.600713)
			(xy 178.446934 -292.652048) (xy 178.430873 -292.701478) (xy 178.407277 -292.747788) (xy 178.376727 -292.789836)
			(xy 178.339976 -292.826587) (xy 178.297928 -292.857137) (xy 178.251618 -292.880733) (xy 178.202188 -292.896794)
			(xy 178.150853 -292.904924) (xy 178.098879 -292.904924) (xy 178.047544 -292.896794) (xy 177.998114 -292.880733)
			(xy 177.951804 -292.857137) (xy 177.909756 -292.826587) (xy 177.873005 -292.789836) (xy 177.842455 -292.747788)
			(xy 177.818859 -292.701478) (xy 177.802798 -292.652048) (xy 177.794668 -292.600713) (xy 177.505104 -292.600713)
			(xy 177.496974 -292.652048) (xy 177.480913 -292.701478) (xy 177.457317 -292.747788) (xy 177.426767 -292.789836)
			(xy 177.390016 -292.826587) (xy 177.347968 -292.857137) (xy 177.301658 -292.880733) (xy 177.252228 -292.896794)
			(xy 177.200893 -292.904924) (xy 177.148919 -292.904924) (xy 177.097584 -292.896794) (xy 177.048154 -292.880733)
			(xy 177.001844 -292.857137) (xy 176.959796 -292.826587) (xy 176.923045 -292.789836) (xy 176.892495 -292.747788)
			(xy 176.868899 -292.701478) (xy 176.852838 -292.652048) (xy 176.844708 -292.600713) (xy 176.555144 -292.600713)
			(xy 176.547014 -292.652048) (xy 176.530953 -292.701478) (xy 176.507357 -292.747788) (xy 176.476807 -292.789836)
			(xy 176.440056 -292.826587) (xy 176.398008 -292.857137) (xy 176.351698 -292.880733) (xy 176.302268 -292.896794)
			(xy 176.250933 -292.904924) (xy 176.198959 -292.904924) (xy 176.147624 -292.896794) (xy 176.098194 -292.880733)
			(xy 176.051884 -292.857137) (xy 176.009836 -292.826587) (xy 175.973085 -292.789836) (xy 175.942535 -292.747788)
			(xy 175.918939 -292.701478) (xy 175.902878 -292.652048) (xy 175.894748 -292.600713) (xy 174.655229 -292.600713)
			(xy 174.655224 -292.600967) (xy 174.647094 -292.652302) (xy 174.631033 -292.701732) (xy 174.607437 -292.748042)
			(xy 174.576887 -292.79009) (xy 174.540136 -292.826841) (xy 174.498088 -292.857391) (xy 174.451778 -292.880987)
			(xy 174.402348 -292.897048) (xy 174.351013 -292.905178) (xy 174.299039 -292.905178) (xy 174.247704 -292.897048)
			(xy 174.198274 -292.880987) (xy 174.151964 -292.857391) (xy 174.109916 -292.826841) (xy 174.073165 -292.79009)
			(xy 174.042615 -292.748042) (xy 174.019019 -292.701732) (xy 174.002958 -292.652302) (xy 173.994828 -292.600967)
			(xy 173.705264 -292.600967) (xy 173.697134 -292.652302) (xy 173.681073 -292.701732) (xy 173.657477 -292.748042)
			(xy 173.626927 -292.79009) (xy 173.590176 -292.826841) (xy 173.548128 -292.857391) (xy 173.501818 -292.880987)
			(xy 173.452388 -292.897048) (xy 173.401053 -292.905178) (xy 173.349079 -292.905178) (xy 173.297744 -292.897048)
			(xy 173.248314 -292.880987) (xy 173.202004 -292.857391) (xy 173.159956 -292.826841) (xy 173.123205 -292.79009)
			(xy 173.092655 -292.748042) (xy 173.069059 -292.701732) (xy 173.052998 -292.652302) (xy 173.044868 -292.600967)
			(xy 172.755304 -292.600967) (xy 172.747174 -292.652302) (xy 172.731113 -292.701732) (xy 172.707517 -292.748042)
			(xy 172.676967 -292.79009) (xy 172.640216 -292.826841) (xy 172.598168 -292.857391) (xy 172.551858 -292.880987)
			(xy 172.502428 -292.897048) (xy 172.451093 -292.905178) (xy 172.399119 -292.905178) (xy 172.347784 -292.897048)
			(xy 172.298354 -292.880987) (xy 172.252044 -292.857391) (xy 172.209996 -292.826841) (xy 172.173245 -292.79009)
			(xy 172.142695 -292.748042) (xy 172.119099 -292.701732) (xy 172.103038 -292.652302) (xy 172.094908 -292.600967)
			(xy 171.80509 -292.600967) (xy 171.79696 -292.652302) (xy 171.780899 -292.701732) (xy 171.757303 -292.748042)
			(xy 171.726753 -292.79009) (xy 171.690002 -292.826841) (xy 171.647954 -292.857391) (xy 171.601644 -292.880987)
			(xy 171.552214 -292.897048) (xy 171.500879 -292.905178) (xy 171.448905 -292.905178) (xy 171.39757 -292.897048)
			(xy 171.34814 -292.880987) (xy 171.30183 -292.857391) (xy 171.259782 -292.826841) (xy 171.223031 -292.79009)
			(xy 171.192481 -292.748042) (xy 171.168885 -292.701732) (xy 171.152824 -292.652302) (xy 171.144694 -292.600967)
			(xy 170.85513 -292.600967) (xy 170.847 -292.652302) (xy 170.830939 -292.701732) (xy 170.807343 -292.748042)
			(xy 170.776793 -292.79009) (xy 170.740042 -292.826841) (xy 170.697994 -292.857391) (xy 170.651684 -292.880987)
			(xy 170.602254 -292.897048) (xy 170.550919 -292.905178) (xy 170.498945 -292.905178) (xy 170.44761 -292.897048)
			(xy 170.39818 -292.880987) (xy 170.35187 -292.857391) (xy 170.309822 -292.826841) (xy 170.273071 -292.79009)
			(xy 170.242521 -292.748042) (xy 170.218925 -292.701732) (xy 170.202864 -292.652302) (xy 170.194734 -292.600967)
			(xy 169.90517 -292.600967) (xy 169.89704 -292.652302) (xy 169.880979 -292.701732) (xy 169.857383 -292.748042)
			(xy 169.826833 -292.79009) (xy 169.790082 -292.826841) (xy 169.748034 -292.857391) (xy 169.701724 -292.880987)
			(xy 169.652294 -292.897048) (xy 169.600959 -292.905178) (xy 169.548985 -292.905178) (xy 169.49765 -292.897048)
			(xy 169.44822 -292.880987) (xy 169.40191 -292.857391) (xy 169.359862 -292.826841) (xy 169.323111 -292.79009)
			(xy 169.292561 -292.748042) (xy 169.268965 -292.701732) (xy 169.252904 -292.652302) (xy 169.244774 -292.600967)
			(xy 168.95521 -292.600967) (xy 168.94708 -292.652302) (xy 168.931019 -292.701732) (xy 168.907423 -292.748042)
			(xy 168.876873 -292.79009) (xy 168.840122 -292.826841) (xy 168.798074 -292.857391) (xy 168.751764 -292.880987)
			(xy 168.702334 -292.897048) (xy 168.650999 -292.905178) (xy 168.599025 -292.905178) (xy 168.54769 -292.897048)
			(xy 168.49826 -292.880987) (xy 168.45195 -292.857391) (xy 168.409902 -292.826841) (xy 168.373151 -292.79009)
			(xy 168.342601 -292.748042) (xy 168.319005 -292.701732) (xy 168.302944 -292.652302) (xy 168.294814 -292.600967)
			(xy 168.00525 -292.600967) (xy 167.99712 -292.652302) (xy 167.981059 -292.701732) (xy 167.957463 -292.748042)
			(xy 167.926913 -292.79009) (xy 167.890162 -292.826841) (xy 167.848114 -292.857391) (xy 167.801804 -292.880987)
			(xy 167.752374 -292.897048) (xy 167.701039 -292.905178) (xy 167.649065 -292.905178) (xy 167.59773 -292.897048)
			(xy 167.5483 -292.880987) (xy 167.50199 -292.857391) (xy 167.459942 -292.826841) (xy 167.423191 -292.79009)
			(xy 167.392641 -292.748042) (xy 167.369045 -292.701732) (xy 167.352984 -292.652302) (xy 167.344854 -292.600967)
			(xy 167.05529 -292.600967) (xy 167.04716 -292.652302) (xy 167.031099 -292.701732) (xy 167.007503 -292.748042)
			(xy 166.976953 -292.79009) (xy 166.940202 -292.826841) (xy 166.898154 -292.857391) (xy 166.851844 -292.880987)
			(xy 166.802414 -292.897048) (xy 166.751079 -292.905178) (xy 166.699105 -292.905178) (xy 166.64777 -292.897048)
			(xy 166.59834 -292.880987) (xy 166.55203 -292.857391) (xy 166.509982 -292.826841) (xy 166.473231 -292.79009)
			(xy 166.442681 -292.748042) (xy 166.419085 -292.701732) (xy 166.403024 -292.652302) (xy 166.394894 -292.600967)
			(xy 166.105036 -292.600967) (xy 166.096946 -292.652048) (xy 166.080885 -292.701478) (xy 166.057289 -292.747788)
			(xy 166.026739 -292.789836) (xy 165.989988 -292.826587) (xy 165.94794 -292.857137) (xy 165.90163 -292.880733)
			(xy 165.8522 -292.896794) (xy 165.800865 -292.904924) (xy 165.748891 -292.904924) (xy 165.697556 -292.896794)
			(xy 165.648126 -292.880733) (xy 165.601816 -292.857137) (xy 165.559768 -292.826587) (xy 165.523017 -292.789836)
			(xy 165.492467 -292.747788) (xy 165.468871 -292.701478) (xy 165.45281 -292.652048) (xy 165.44468 -292.600713)
			(xy 165.155116 -292.600713) (xy 165.146986 -292.652048) (xy 165.130925 -292.701478) (xy 165.107329 -292.747788)
			(xy 165.076779 -292.789836) (xy 165.040028 -292.826587) (xy 164.99798 -292.857137) (xy 164.95167 -292.880733)
			(xy 164.90224 -292.896794) (xy 164.850905 -292.904924) (xy 164.798931 -292.904924) (xy 164.747596 -292.896794)
			(xy 164.698166 -292.880733) (xy 164.651856 -292.857137) (xy 164.609808 -292.826587) (xy 164.573057 -292.789836)
			(xy 164.542507 -292.747788) (xy 164.518911 -292.701478) (xy 164.50285 -292.652048) (xy 164.49472 -292.600713)
			(xy 164.205161 -292.600713) (xy 164.205156 -292.600967) (xy 164.197026 -292.652302) (xy 164.180965 -292.701732)
			(xy 164.157369 -292.748042) (xy 164.126819 -292.79009) (xy 164.090068 -292.826841) (xy 164.04802 -292.857391)
			(xy 164.00171 -292.880987) (xy 163.95228 -292.897048) (xy 163.900945 -292.905178) (xy 163.848971 -292.905178)
			(xy 163.797636 -292.897048) (xy 163.748206 -292.880987) (xy 163.701896 -292.857391) (xy 163.659848 -292.826841)
			(xy 163.623097 -292.79009) (xy 163.592547 -292.748042) (xy 163.568951 -292.701732) (xy 163.55289 -292.652302)
			(xy 163.54476 -292.600967) (xy 163.255196 -292.600967) (xy 163.247066 -292.652302) (xy 163.231005 -292.701732)
			(xy 163.207409 -292.748042) (xy 163.176859 -292.79009) (xy 163.140108 -292.826841) (xy 163.09806 -292.857391)
			(xy 163.05175 -292.880987) (xy 163.00232 -292.897048) (xy 162.950985 -292.905178) (xy 162.899011 -292.905178)
			(xy 162.847676 -292.897048) (xy 162.798246 -292.880987) (xy 162.751936 -292.857391) (xy 162.709888 -292.826841)
			(xy 162.673137 -292.79009) (xy 162.642587 -292.748042) (xy 162.618991 -292.701732) (xy 162.60293 -292.652302)
			(xy 162.5948 -292.600967) (xy 162.305236 -292.600967) (xy 162.297106 -292.652302) (xy 162.281045 -292.701732)
			(xy 162.257449 -292.748042) (xy 162.226899 -292.79009) (xy 162.190148 -292.826841) (xy 162.1481 -292.857391)
			(xy 162.10179 -292.880987) (xy 162.05236 -292.897048) (xy 162.001025 -292.905178) (xy 161.949051 -292.905178)
			(xy 161.897716 -292.897048) (xy 161.848286 -292.880987) (xy 161.801976 -292.857391) (xy 161.759928 -292.826841)
			(xy 161.723177 -292.79009) (xy 161.692627 -292.748042) (xy 161.669031 -292.701732) (xy 161.65297 -292.652302)
			(xy 161.64484 -292.600967) (xy 160.405062 -292.600967) (xy 160.396932 -292.652302) (xy 160.380871 -292.701732)
			(xy 160.357275 -292.748042) (xy 160.326725 -292.79009) (xy 160.289974 -292.826841) (xy 160.247926 -292.857391)
			(xy 160.201616 -292.880987) (xy 160.152186 -292.897048) (xy 160.100851 -292.905178) (xy 160.048877 -292.905178)
			(xy 159.997542 -292.897048) (xy 159.948112 -292.880987) (xy 159.901802 -292.857391) (xy 159.859754 -292.826841)
			(xy 159.823003 -292.79009) (xy 159.792453 -292.748042) (xy 159.768857 -292.701732) (xy 159.752796 -292.652302)
			(xy 159.744666 -292.600967) (xy 159.454032 -292.600967) (xy 159.451877 -292.627823) (xy 159.439266 -292.679301)
			(xy 159.418605 -292.728108) (xy 159.390423 -292.772994) (xy 159.355443 -292.812811) (xy 159.31456 -292.846539)
			(xy 159.268821 -292.873314) (xy 159.244284 -292.883336) (xy 159.236918 -292.88613) (xy 159.225234 -292.895528)
			(xy 159.220662 -292.902132) (xy 159.216549 -292.908583) (xy 159.212011 -292.923188) (xy 159.211772 -292.930834)
			(xy 159.211772 -293.131494) (xy 159.230822 -293.15791) (xy 159.246316 -293.163244) (xy 159.2727 -293.172621)
			(xy 159.322606 -293.198009) (xy 159.368265 -293.230419) (xy 159.408696 -293.269155) (xy 159.44303 -293.313385)
			(xy 159.470531 -293.362159) (xy 159.490607 -293.414428) (xy 159.502827 -293.469071) (xy 159.506928 -293.524913)
			(xy 159.505016 -293.550927) (xy 159.744666 -293.550927) (xy 159.744666 -293.498953) (xy 159.752796 -293.447618)
			(xy 159.768857 -293.398188) (xy 159.792453 -293.351878) (xy 159.823003 -293.30983) (xy 159.859754 -293.273079)
			(xy 159.901802 -293.242529) (xy 159.948112 -293.218933) (xy 159.997542 -293.202872) (xy 160.048877 -293.194742)
			(xy 160.100851 -293.194742) (xy 160.152186 -293.202872) (xy 160.201616 -293.218933) (xy 160.247926 -293.242529)
			(xy 160.289974 -293.273079) (xy 160.326725 -293.30983) (xy 160.357275 -293.351878) (xy 160.380871 -293.398188)
			(xy 160.396932 -293.447618) (xy 160.405062 -293.498953) (xy 160.405572 -293.52494) (xy 160.405062 -293.550927)
			(xy 161.64484 -293.550927) (xy 161.64484 -293.498953) (xy 161.65297 -293.447618) (xy 161.669031 -293.398188)
			(xy 161.692627 -293.351878) (xy 161.723177 -293.30983) (xy 161.759928 -293.273079) (xy 161.801976 -293.242529)
			(xy 161.848286 -293.218933) (xy 161.897716 -293.202872) (xy 161.949051 -293.194742) (xy 162.001025 -293.194742)
			(xy 162.05236 -293.202872) (xy 162.10179 -293.218933) (xy 162.1481 -293.242529) (xy 162.190148 -293.273079)
			(xy 162.226899 -293.30983) (xy 162.257449 -293.351878) (xy 162.281045 -293.398188) (xy 162.297106 -293.447618)
			(xy 162.305236 -293.498953) (xy 162.305746 -293.52494) (xy 162.305236 -293.550927) (xy 162.5948 -293.550927)
			(xy 162.5948 -293.498953) (xy 162.60293 -293.447618) (xy 162.618991 -293.398188) (xy 162.642587 -293.351878)
			(xy 162.673137 -293.30983) (xy 162.709888 -293.273079) (xy 162.751936 -293.242529) (xy 162.798246 -293.218933)
			(xy 162.847676 -293.202872) (xy 162.899011 -293.194742) (xy 162.950985 -293.194742) (xy 163.00232 -293.202872)
			(xy 163.05175 -293.218933) (xy 163.09806 -293.242529) (xy 163.140108 -293.273079) (xy 163.176859 -293.30983)
			(xy 163.207409 -293.351878) (xy 163.231005 -293.398188) (xy 163.247066 -293.447618) (xy 163.255196 -293.498953)
			(xy 163.255706 -293.52494) (xy 163.255196 -293.550927) (xy 163.54476 -293.550927) (xy 163.54476 -293.498953)
			(xy 163.55289 -293.447618) (xy 163.568951 -293.398188) (xy 163.592547 -293.351878) (xy 163.623097 -293.30983)
			(xy 163.659848 -293.273079) (xy 163.701896 -293.242529) (xy 163.748206 -293.218933) (xy 163.797636 -293.202872)
			(xy 163.848971 -293.194742) (xy 163.900945 -293.194742) (xy 163.95228 -293.202872) (xy 164.00171 -293.218933)
			(xy 164.04802 -293.242529) (xy 164.090068 -293.273079) (xy 164.126819 -293.30983) (xy 164.157369 -293.351878)
			(xy 164.180965 -293.398188) (xy 164.197026 -293.447618) (xy 164.205156 -293.498953) (xy 164.205666 -293.52494)
			(xy 164.205156 -293.550927) (xy 164.49472 -293.550927) (xy 164.49472 -293.498953) (xy 164.50285 -293.447618)
			(xy 164.518911 -293.398188) (xy 164.542507 -293.351878) (xy 164.573057 -293.30983) (xy 164.609808 -293.273079)
			(xy 164.651856 -293.242529) (xy 164.698166 -293.218933) (xy 164.747596 -293.202872) (xy 164.798931 -293.194742)
			(xy 164.850905 -293.194742) (xy 164.90224 -293.202872) (xy 164.95167 -293.218933) (xy 164.99798 -293.242529)
			(xy 165.040028 -293.273079) (xy 165.076779 -293.30983) (xy 165.107329 -293.351878) (xy 165.130925 -293.398188)
			(xy 165.146986 -293.447618) (xy 165.155116 -293.498953) (xy 165.155626 -293.52494) (xy 165.155116 -293.550927)
			(xy 165.44468 -293.550927) (xy 165.44468 -293.498953) (xy 165.45281 -293.447618) (xy 165.468871 -293.398188)
			(xy 165.492467 -293.351878) (xy 165.523017 -293.30983) (xy 165.559768 -293.273079) (xy 165.601816 -293.242529)
			(xy 165.648126 -293.218933) (xy 165.697556 -293.202872) (xy 165.748891 -293.194742) (xy 165.800865 -293.194742)
			(xy 165.8522 -293.202872) (xy 165.90163 -293.218933) (xy 165.94794 -293.242529) (xy 165.989988 -293.273079)
			(xy 166.026739 -293.30983) (xy 166.057289 -293.351878) (xy 166.080885 -293.398188) (xy 166.096946 -293.447618)
			(xy 166.105076 -293.498953) (xy 166.105586 -293.52494) (xy 166.105076 -293.550927) (xy 166.394894 -293.550927)
			(xy 166.394894 -293.498953) (xy 166.403024 -293.447618) (xy 166.419085 -293.398188) (xy 166.442681 -293.351878)
			(xy 166.473231 -293.30983) (xy 166.509982 -293.273079) (xy 166.55203 -293.242529) (xy 166.59834 -293.218933)
			(xy 166.64777 -293.202872) (xy 166.699105 -293.194742) (xy 166.751079 -293.194742) (xy 166.802414 -293.202872)
			(xy 166.851844 -293.218933) (xy 166.898154 -293.242529) (xy 166.940202 -293.273079) (xy 166.976953 -293.30983)
			(xy 167.007503 -293.351878) (xy 167.031099 -293.398188) (xy 167.04716 -293.447618) (xy 167.05529 -293.498953)
			(xy 167.0558 -293.52494) (xy 167.05529 -293.550927) (xy 167.344854 -293.550927) (xy 167.344854 -293.498953)
			(xy 167.352984 -293.447618) (xy 167.369045 -293.398188) (xy 167.392641 -293.351878) (xy 167.423191 -293.30983)
			(xy 167.459942 -293.273079) (xy 167.50199 -293.242529) (xy 167.5483 -293.218933) (xy 167.59773 -293.202872)
			(xy 167.649065 -293.194742) (xy 167.701039 -293.194742) (xy 167.752374 -293.202872) (xy 167.801804 -293.218933)
			(xy 167.848114 -293.242529) (xy 167.890162 -293.273079) (xy 167.926913 -293.30983) (xy 167.957463 -293.351878)
			(xy 167.981059 -293.398188) (xy 167.99712 -293.447618) (xy 168.00525 -293.498953) (xy 168.00576 -293.52494)
			(xy 168.00525 -293.550927) (xy 168.294814 -293.550927) (xy 168.294814 -293.498953) (xy 168.302944 -293.447618)
			(xy 168.319005 -293.398188) (xy 168.342601 -293.351878) (xy 168.373151 -293.30983) (xy 168.409902 -293.273079)
			(xy 168.45195 -293.242529) (xy 168.49826 -293.218933) (xy 168.54769 -293.202872) (xy 168.599025 -293.194742)
			(xy 168.650999 -293.194742) (xy 168.702334 -293.202872) (xy 168.751764 -293.218933) (xy 168.798074 -293.242529)
			(xy 168.840122 -293.273079) (xy 168.876873 -293.30983) (xy 168.907423 -293.351878) (xy 168.931019 -293.398188)
			(xy 168.94708 -293.447618) (xy 168.95521 -293.498953) (xy 168.95572 -293.52494) (xy 168.95521 -293.550927)
			(xy 169.244774 -293.550927) (xy 169.244774 -293.498953) (xy 169.252904 -293.447618) (xy 169.268965 -293.398188)
			(xy 169.292561 -293.351878) (xy 169.323111 -293.30983) (xy 169.359862 -293.273079) (xy 169.40191 -293.242529)
			(xy 169.44822 -293.218933) (xy 169.49765 -293.202872) (xy 169.548985 -293.194742) (xy 169.600959 -293.194742)
			(xy 169.652294 -293.202872) (xy 169.701724 -293.218933) (xy 169.748034 -293.242529) (xy 169.790082 -293.273079)
			(xy 169.826833 -293.30983) (xy 169.857383 -293.351878) (xy 169.880979 -293.398188) (xy 169.89704 -293.447618)
			(xy 169.90517 -293.498953) (xy 169.90568 -293.52494) (xy 169.90517 -293.550927) (xy 170.194734 -293.550927)
			(xy 170.194734 -293.498953) (xy 170.202864 -293.447618) (xy 170.218925 -293.398188) (xy 170.242521 -293.351878)
			(xy 170.273071 -293.30983) (xy 170.309822 -293.273079) (xy 170.35187 -293.242529) (xy 170.39818 -293.218933)
			(xy 170.44761 -293.202872) (xy 170.498945 -293.194742) (xy 170.550919 -293.194742) (xy 170.602254 -293.202872)
			(xy 170.651684 -293.218933) (xy 170.697994 -293.242529) (xy 170.740042 -293.273079) (xy 170.776793 -293.30983)
			(xy 170.807343 -293.351878) (xy 170.830939 -293.398188) (xy 170.847 -293.447618) (xy 170.85513 -293.498953)
			(xy 170.85564 -293.52494) (xy 170.85513 -293.550927) (xy 171.144694 -293.550927) (xy 171.144694 -293.498953)
			(xy 171.152824 -293.447618) (xy 171.168885 -293.398188) (xy 171.192481 -293.351878) (xy 171.223031 -293.30983)
			(xy 171.259782 -293.273079) (xy 171.30183 -293.242529) (xy 171.34814 -293.218933) (xy 171.39757 -293.202872)
			(xy 171.448905 -293.194742) (xy 171.500879 -293.194742) (xy 171.552214 -293.202872) (xy 171.601644 -293.218933)
			(xy 171.647954 -293.242529) (xy 171.690002 -293.273079) (xy 171.726753 -293.30983) (xy 171.757303 -293.351878)
			(xy 171.780899 -293.398188) (xy 171.79696 -293.447618) (xy 171.80509 -293.498953) (xy 171.8056 -293.52494)
			(xy 171.80509 -293.550927) (xy 172.094654 -293.550927) (xy 172.094654 -293.498953) (xy 172.102784 -293.447618)
			(xy 172.118845 -293.398188) (xy 172.142441 -293.351878) (xy 172.172991 -293.30983) (xy 172.209742 -293.273079)
			(xy 172.25179 -293.242529) (xy 172.2981 -293.218933) (xy 172.34753 -293.202872) (xy 172.398865 -293.194742)
			(xy 172.450839 -293.194742) (xy 172.502174 -293.202872) (xy 172.551604 -293.218933) (xy 172.597914 -293.242529)
			(xy 172.639962 -293.273079) (xy 172.676713 -293.30983) (xy 172.707263 -293.351878) (xy 172.730859 -293.398188)
			(xy 172.74692 -293.447618) (xy 172.75505 -293.498953) (xy 172.75556 -293.52494) (xy 172.75505 -293.550927)
			(xy 173.044868 -293.550927) (xy 173.044868 -293.498953) (xy 173.052998 -293.447618) (xy 173.069059 -293.398188)
			(xy 173.092655 -293.351878) (xy 173.123205 -293.30983) (xy 173.159956 -293.273079) (xy 173.202004 -293.242529)
			(xy 173.248314 -293.218933) (xy 173.297744 -293.202872) (xy 173.349079 -293.194742) (xy 173.401053 -293.194742)
			(xy 173.452388 -293.202872) (xy 173.501818 -293.218933) (xy 173.548128 -293.242529) (xy 173.590176 -293.273079)
			(xy 173.626927 -293.30983) (xy 173.657477 -293.351878) (xy 173.681073 -293.398188) (xy 173.697134 -293.447618)
			(xy 173.705264 -293.498953) (xy 173.705774 -293.52494) (xy 173.705264 -293.550927) (xy 173.994828 -293.550927)
			(xy 173.994828 -293.498953) (xy 174.002958 -293.447618) (xy 174.019019 -293.398188) (xy 174.042615 -293.351878)
			(xy 174.073165 -293.30983) (xy 174.109916 -293.273079) (xy 174.151964 -293.242529) (xy 174.198274 -293.218933)
			(xy 174.247704 -293.202872) (xy 174.299039 -293.194742) (xy 174.351013 -293.194742) (xy 174.402348 -293.202872)
			(xy 174.451778 -293.218933) (xy 174.498088 -293.242529) (xy 174.540136 -293.273079) (xy 174.576887 -293.30983)
			(xy 174.607437 -293.351878) (xy 174.631033 -293.398188) (xy 174.647094 -293.447618) (xy 174.655224 -293.498953)
			(xy 174.655734 -293.52494) (xy 174.655224 -293.550927) (xy 175.894748 -293.550927) (xy 175.894748 -293.498953)
			(xy 175.902878 -293.447618) (xy 175.918939 -293.398188) (xy 175.942535 -293.351878) (xy 175.973085 -293.30983)
			(xy 176.009836 -293.273079) (xy 176.051884 -293.242529) (xy 176.098194 -293.218933) (xy 176.147624 -293.202872)
			(xy 176.198959 -293.194742) (xy 176.250933 -293.194742) (xy 176.302268 -293.202872) (xy 176.351698 -293.218933)
			(xy 176.398008 -293.242529) (xy 176.440056 -293.273079) (xy 176.476807 -293.30983) (xy 176.507357 -293.351878)
			(xy 176.530953 -293.398188) (xy 176.547014 -293.447618) (xy 176.555144 -293.498953) (xy 176.555654 -293.52494)
			(xy 176.555144 -293.550927) (xy 176.844708 -293.550927) (xy 176.844708 -293.498953) (xy 176.852838 -293.447618)
			(xy 176.868899 -293.398188) (xy 176.892495 -293.351878) (xy 176.923045 -293.30983) (xy 176.959796 -293.273079)
			(xy 177.001844 -293.242529) (xy 177.048154 -293.218933) (xy 177.097584 -293.202872) (xy 177.148919 -293.194742)
			(xy 177.200893 -293.194742) (xy 177.252228 -293.202872) (xy 177.301658 -293.218933) (xy 177.347968 -293.242529)
			(xy 177.390016 -293.273079) (xy 177.426767 -293.30983) (xy 177.457317 -293.351878) (xy 177.480913 -293.398188)
			(xy 177.496974 -293.447618) (xy 177.505104 -293.498953) (xy 177.505614 -293.52494) (xy 177.505104 -293.550927)
			(xy 177.794668 -293.550927) (xy 177.794668 -293.498953) (xy 177.802798 -293.447618) (xy 177.818859 -293.398188)
			(xy 177.842455 -293.351878) (xy 177.873005 -293.30983) (xy 177.909756 -293.273079) (xy 177.951804 -293.242529)
			(xy 177.998114 -293.218933) (xy 178.047544 -293.202872) (xy 178.098879 -293.194742) (xy 178.150853 -293.194742)
			(xy 178.202188 -293.202872) (xy 178.251618 -293.218933) (xy 178.297928 -293.242529) (xy 178.339976 -293.273079)
			(xy 178.376727 -293.30983) (xy 178.407277 -293.351878) (xy 178.430873 -293.398188) (xy 178.446934 -293.447618)
			(xy 178.455064 -293.498953) (xy 178.455574 -293.52494) (xy 178.455064 -293.550927) (xy 178.744882 -293.550927)
			(xy 178.744882 -293.498953) (xy 178.753012 -293.447618) (xy 178.769073 -293.398188) (xy 178.792669 -293.351878)
			(xy 178.823219 -293.30983) (xy 178.85997 -293.273079) (xy 178.902018 -293.242529) (xy 178.948328 -293.218933)
			(xy 178.997758 -293.202872) (xy 179.049093 -293.194742) (xy 179.101067 -293.194742) (xy 179.152402 -293.202872)
			(xy 179.201832 -293.218933) (xy 179.248142 -293.242529) (xy 179.29019 -293.273079) (xy 179.326941 -293.30983)
			(xy 179.357491 -293.351878) (xy 179.381087 -293.398188) (xy 179.397148 -293.447618) (xy 179.405278 -293.498953)
			(xy 179.405788 -293.52494) (xy 179.405278 -293.550927) (xy 179.694842 -293.550927) (xy 179.694842 -293.498953)
			(xy 179.702972 -293.447618) (xy 179.719033 -293.398188) (xy 179.742629 -293.351878) (xy 179.773179 -293.30983)
			(xy 179.80993 -293.273079) (xy 179.851978 -293.242529) (xy 179.898288 -293.218933) (xy 179.947718 -293.202872)
			(xy 179.999053 -293.194742) (xy 180.051027 -293.194742) (xy 180.102362 -293.202872) (xy 180.151792 -293.218933)
			(xy 180.198102 -293.242529) (xy 180.24015 -293.273079) (xy 180.276901 -293.30983) (xy 180.307451 -293.351878)
			(xy 180.331047 -293.398188) (xy 180.347108 -293.447618) (xy 180.355238 -293.498953) (xy 180.355748 -293.52494)
			(xy 180.355238 -293.550927) (xy 180.644802 -293.550927) (xy 180.644802 -293.498953) (xy 180.652932 -293.447618)
			(xy 180.668993 -293.398188) (xy 180.692589 -293.351878) (xy 180.723139 -293.30983) (xy 180.75989 -293.273079)
			(xy 180.801938 -293.242529) (xy 180.848248 -293.218933) (xy 180.897678 -293.202872) (xy 180.949013 -293.194742)
			(xy 181.000987 -293.194742) (xy 181.052322 -293.202872) (xy 181.101752 -293.218933) (xy 181.148062 -293.242529)
			(xy 181.19011 -293.273079) (xy 181.226861 -293.30983) (xy 181.257411 -293.351878) (xy 181.281007 -293.398188)
			(xy 181.297068 -293.447618) (xy 181.305198 -293.498953) (xy 181.305708 -293.52494) (xy 181.305198 -293.550927)
			(xy 181.594762 -293.550927) (xy 181.594762 -293.498953) (xy 181.602892 -293.447618) (xy 181.618953 -293.398188)
			(xy 181.642549 -293.351878) (xy 181.673099 -293.30983) (xy 181.70985 -293.273079) (xy 181.751898 -293.242529)
			(xy 181.798208 -293.218933) (xy 181.847638 -293.202872) (xy 181.898973 -293.194742) (xy 181.950947 -293.194742)
			(xy 182.002282 -293.202872) (xy 182.051712 -293.218933) (xy 182.098022 -293.242529) (xy 182.14007 -293.273079)
			(xy 182.176821 -293.30983) (xy 182.207371 -293.351878) (xy 182.230967 -293.398188) (xy 182.247028 -293.447618)
			(xy 182.255158 -293.498953) (xy 182.255668 -293.52494) (xy 182.255158 -293.550927) (xy 182.544722 -293.550927)
			(xy 182.544722 -293.498953) (xy 182.552852 -293.447618) (xy 182.568913 -293.398188) (xy 182.592509 -293.351878)
			(xy 182.623059 -293.30983) (xy 182.65981 -293.273079) (xy 182.701858 -293.242529) (xy 182.748168 -293.218933)
			(xy 182.797598 -293.202872) (xy 182.848933 -293.194742) (xy 182.900907 -293.194742) (xy 182.952242 -293.202872)
			(xy 183.001672 -293.218933) (xy 183.047982 -293.242529) (xy 183.09003 -293.273079) (xy 183.126781 -293.30983)
			(xy 183.157331 -293.351878) (xy 183.180927 -293.398188) (xy 183.196988 -293.447618) (xy 183.205118 -293.498953)
			(xy 183.205628 -293.52494) (xy 183.205118 -293.550927) (xy 183.494682 -293.550927) (xy 183.494682 -293.498953)
			(xy 183.502812 -293.447618) (xy 183.518873 -293.398188) (xy 183.542469 -293.351878) (xy 183.573019 -293.30983)
			(xy 183.60977 -293.273079) (xy 183.651818 -293.242529) (xy 183.698128 -293.218933) (xy 183.747558 -293.202872)
			(xy 183.798893 -293.194742) (xy 183.850867 -293.194742) (xy 183.902202 -293.202872) (xy 183.951632 -293.218933)
			(xy 183.997942 -293.242529) (xy 184.03999 -293.273079) (xy 184.076741 -293.30983) (xy 184.107291 -293.351878)
			(xy 184.130887 -293.398188) (xy 184.146948 -293.447618) (xy 184.155078 -293.498953) (xy 184.155588 -293.52494)
			(xy 184.155078 -293.550927) (xy 184.444642 -293.550927) (xy 184.444642 -293.498953) (xy 184.452772 -293.447618)
			(xy 184.468833 -293.398188) (xy 184.492429 -293.351878) (xy 184.522979 -293.30983) (xy 184.55973 -293.273079)
			(xy 184.601778 -293.242529) (xy 184.648088 -293.218933) (xy 184.697518 -293.202872) (xy 184.748853 -293.194742)
			(xy 184.800827 -293.194742) (xy 184.852162 -293.202872) (xy 184.901592 -293.218933) (xy 184.947902 -293.242529)
			(xy 184.98995 -293.273079) (xy 185.026701 -293.30983) (xy 185.057251 -293.351878) (xy 185.080847 -293.398188)
			(xy 185.096908 -293.447618) (xy 185.105038 -293.498953) (xy 185.105548 -293.52494) (xy 185.105038 -293.550927)
			(xy 185.394856 -293.550927) (xy 185.394856 -293.498953) (xy 185.402986 -293.447618) (xy 185.419047 -293.398188)
			(xy 185.442643 -293.351878) (xy 185.473193 -293.30983) (xy 185.509944 -293.273079) (xy 185.551992 -293.242529)
			(xy 185.598302 -293.218933) (xy 185.647732 -293.202872) (xy 185.699067 -293.194742) (xy 185.751041 -293.194742)
			(xy 185.802376 -293.202872) (xy 185.851806 -293.218933) (xy 185.898116 -293.242529) (xy 185.940164 -293.273079)
			(xy 185.976915 -293.30983) (xy 186.007465 -293.351878) (xy 186.031061 -293.398188) (xy 186.047122 -293.447618)
			(xy 186.055252 -293.498953) (xy 186.055762 -293.52494) (xy 186.055252 -293.550927) (xy 186.047122 -293.602262)
			(xy 186.031061 -293.651692) (xy 186.007465 -293.698002) (xy 185.976915 -293.74005) (xy 185.940164 -293.776801)
			(xy 185.898116 -293.807351) (xy 185.851806 -293.830947) (xy 185.802376 -293.847008) (xy 185.751041 -293.855138)
			(xy 185.699067 -293.855138) (xy 185.647732 -293.847008) (xy 185.598302 -293.830947) (xy 185.551992 -293.807351)
			(xy 185.509944 -293.776801) (xy 185.473193 -293.74005) (xy 185.442643 -293.698002) (xy 185.419047 -293.651692)
			(xy 185.402986 -293.602262) (xy 185.394856 -293.550927) (xy 185.105038 -293.550927) (xy 185.096908 -293.602262)
			(xy 185.080847 -293.651692) (xy 185.057251 -293.698002) (xy 185.026701 -293.74005) (xy 184.98995 -293.776801)
			(xy 184.947902 -293.807351) (xy 184.901592 -293.830947) (xy 184.852162 -293.847008) (xy 184.800827 -293.855138)
			(xy 184.748853 -293.855138) (xy 184.697518 -293.847008) (xy 184.648088 -293.830947) (xy 184.601778 -293.807351)
			(xy 184.55973 -293.776801) (xy 184.522979 -293.74005) (xy 184.492429 -293.698002) (xy 184.468833 -293.651692)
			(xy 184.452772 -293.602262) (xy 184.444642 -293.550927) (xy 184.155078 -293.550927) (xy 184.146948 -293.602262)
			(xy 184.130887 -293.651692) (xy 184.107291 -293.698002) (xy 184.076741 -293.74005) (xy 184.03999 -293.776801)
			(xy 183.997942 -293.807351) (xy 183.951632 -293.830947) (xy 183.902202 -293.847008) (xy 183.850867 -293.855138)
			(xy 183.798893 -293.855138) (xy 183.747558 -293.847008) (xy 183.698128 -293.830947) (xy 183.651818 -293.807351)
			(xy 183.60977 -293.776801) (xy 183.573019 -293.74005) (xy 183.542469 -293.698002) (xy 183.518873 -293.651692)
			(xy 183.502812 -293.602262) (xy 183.494682 -293.550927) (xy 183.205118 -293.550927) (xy 183.196988 -293.602262)
			(xy 183.180927 -293.651692) (xy 183.157331 -293.698002) (xy 183.126781 -293.74005) (xy 183.09003 -293.776801)
			(xy 183.047982 -293.807351) (xy 183.001672 -293.830947) (xy 182.952242 -293.847008) (xy 182.900907 -293.855138)
			(xy 182.848933 -293.855138) (xy 182.797598 -293.847008) (xy 182.748168 -293.830947) (xy 182.701858 -293.807351)
			(xy 182.65981 -293.776801) (xy 182.623059 -293.74005) (xy 182.592509 -293.698002) (xy 182.568913 -293.651692)
			(xy 182.552852 -293.602262) (xy 182.544722 -293.550927) (xy 182.255158 -293.550927) (xy 182.247028 -293.602262)
			(xy 182.230967 -293.651692) (xy 182.207371 -293.698002) (xy 182.176821 -293.74005) (xy 182.14007 -293.776801)
			(xy 182.098022 -293.807351) (xy 182.051712 -293.830947) (xy 182.002282 -293.847008) (xy 181.950947 -293.855138)
			(xy 181.898973 -293.855138) (xy 181.847638 -293.847008) (xy 181.798208 -293.830947) (xy 181.751898 -293.807351)
			(xy 181.70985 -293.776801) (xy 181.673099 -293.74005) (xy 181.642549 -293.698002) (xy 181.618953 -293.651692)
			(xy 181.602892 -293.602262) (xy 181.594762 -293.550927) (xy 181.305198 -293.550927) (xy 181.297068 -293.602262)
			(xy 181.281007 -293.651692) (xy 181.257411 -293.698002) (xy 181.226861 -293.74005) (xy 181.19011 -293.776801)
			(xy 181.148062 -293.807351) (xy 181.101752 -293.830947) (xy 181.052322 -293.847008) (xy 181.000987 -293.855138)
			(xy 180.949013 -293.855138) (xy 180.897678 -293.847008) (xy 180.848248 -293.830947) (xy 180.801938 -293.807351)
			(xy 180.75989 -293.776801) (xy 180.723139 -293.74005) (xy 180.692589 -293.698002) (xy 180.668993 -293.651692)
			(xy 180.652932 -293.602262) (xy 180.644802 -293.550927) (xy 180.355238 -293.550927) (xy 180.347108 -293.602262)
			(xy 180.331047 -293.651692) (xy 180.307451 -293.698002) (xy 180.276901 -293.74005) (xy 180.24015 -293.776801)
			(xy 180.198102 -293.807351) (xy 180.151792 -293.830947) (xy 180.102362 -293.847008) (xy 180.051027 -293.855138)
			(xy 179.999053 -293.855138) (xy 179.947718 -293.847008) (xy 179.898288 -293.830947) (xy 179.851978 -293.807351)
			(xy 179.80993 -293.776801) (xy 179.773179 -293.74005) (xy 179.742629 -293.698002) (xy 179.719033 -293.651692)
			(xy 179.702972 -293.602262) (xy 179.694842 -293.550927) (xy 179.405278 -293.550927) (xy 179.397148 -293.602262)
			(xy 179.381087 -293.651692) (xy 179.357491 -293.698002) (xy 179.326941 -293.74005) (xy 179.29019 -293.776801)
			(xy 179.248142 -293.807351) (xy 179.201832 -293.830947) (xy 179.152402 -293.847008) (xy 179.101067 -293.855138)
			(xy 179.049093 -293.855138) (xy 178.997758 -293.847008) (xy 178.948328 -293.830947) (xy 178.902018 -293.807351)
			(xy 178.85997 -293.776801) (xy 178.823219 -293.74005) (xy 178.792669 -293.698002) (xy 178.769073 -293.651692)
			(xy 178.753012 -293.602262) (xy 178.744882 -293.550927) (xy 178.455064 -293.550927) (xy 178.446934 -293.602262)
			(xy 178.430873 -293.651692) (xy 178.407277 -293.698002) (xy 178.376727 -293.74005) (xy 178.339976 -293.776801)
			(xy 178.297928 -293.807351) (xy 178.251618 -293.830947) (xy 178.202188 -293.847008) (xy 178.150853 -293.855138)
			(xy 178.098879 -293.855138) (xy 178.047544 -293.847008) (xy 177.998114 -293.830947) (xy 177.951804 -293.807351)
			(xy 177.909756 -293.776801) (xy 177.873005 -293.74005) (xy 177.842455 -293.698002) (xy 177.818859 -293.651692)
			(xy 177.802798 -293.602262) (xy 177.794668 -293.550927) (xy 177.505104 -293.550927) (xy 177.496974 -293.602262)
			(xy 177.480913 -293.651692) (xy 177.457317 -293.698002) (xy 177.426767 -293.74005) (xy 177.390016 -293.776801)
			(xy 177.347968 -293.807351) (xy 177.301658 -293.830947) (xy 177.252228 -293.847008) (xy 177.200893 -293.855138)
			(xy 177.148919 -293.855138) (xy 177.097584 -293.847008) (xy 177.048154 -293.830947) (xy 177.001844 -293.807351)
			(xy 176.959796 -293.776801) (xy 176.923045 -293.74005) (xy 176.892495 -293.698002) (xy 176.868899 -293.651692)
			(xy 176.852838 -293.602262) (xy 176.844708 -293.550927) (xy 176.555144 -293.550927) (xy 176.547014 -293.602262)
			(xy 176.530953 -293.651692) (xy 176.507357 -293.698002) (xy 176.476807 -293.74005) (xy 176.440056 -293.776801)
			(xy 176.398008 -293.807351) (xy 176.351698 -293.830947) (xy 176.302268 -293.847008) (xy 176.250933 -293.855138)
			(xy 176.198959 -293.855138) (xy 176.147624 -293.847008) (xy 176.098194 -293.830947) (xy 176.051884 -293.807351)
			(xy 176.009836 -293.776801) (xy 175.973085 -293.74005) (xy 175.942535 -293.698002) (xy 175.918939 -293.651692)
			(xy 175.902878 -293.602262) (xy 175.894748 -293.550927) (xy 174.655224 -293.550927) (xy 174.647094 -293.602262)
			(xy 174.631033 -293.651692) (xy 174.607437 -293.698002) (xy 174.576887 -293.74005) (xy 174.540136 -293.776801)
			(xy 174.498088 -293.807351) (xy 174.451778 -293.830947) (xy 174.402348 -293.847008) (xy 174.351013 -293.855138)
			(xy 174.299039 -293.855138) (xy 174.247704 -293.847008) (xy 174.198274 -293.830947) (xy 174.151964 -293.807351)
			(xy 174.109916 -293.776801) (xy 174.073165 -293.74005) (xy 174.042615 -293.698002) (xy 174.019019 -293.651692)
			(xy 174.002958 -293.602262) (xy 173.994828 -293.550927) (xy 173.705264 -293.550927) (xy 173.697134 -293.602262)
			(xy 173.681073 -293.651692) (xy 173.657477 -293.698002) (xy 173.626927 -293.74005) (xy 173.590176 -293.776801)
			(xy 173.548128 -293.807351) (xy 173.501818 -293.830947) (xy 173.452388 -293.847008) (xy 173.401053 -293.855138)
			(xy 173.349079 -293.855138) (xy 173.297744 -293.847008) (xy 173.248314 -293.830947) (xy 173.202004 -293.807351)
			(xy 173.159956 -293.776801) (xy 173.123205 -293.74005) (xy 173.092655 -293.698002) (xy 173.069059 -293.651692)
			(xy 173.052998 -293.602262) (xy 173.044868 -293.550927) (xy 172.75505 -293.550927) (xy 172.74692 -293.602262)
			(xy 172.730859 -293.651692) (xy 172.707263 -293.698002) (xy 172.676713 -293.74005) (xy 172.639962 -293.776801)
			(xy 172.597914 -293.807351) (xy 172.551604 -293.830947) (xy 172.502174 -293.847008) (xy 172.450839 -293.855138)
			(xy 172.398865 -293.855138) (xy 172.34753 -293.847008) (xy 172.2981 -293.830947) (xy 172.25179 -293.807351)
			(xy 172.209742 -293.776801) (xy 172.172991 -293.74005) (xy 172.142441 -293.698002) (xy 172.118845 -293.651692)
			(xy 172.102784 -293.602262) (xy 172.094654 -293.550927) (xy 171.80509 -293.550927) (xy 171.79696 -293.602262)
			(xy 171.780899 -293.651692) (xy 171.757303 -293.698002) (xy 171.726753 -293.74005) (xy 171.690002 -293.776801)
			(xy 171.647954 -293.807351) (xy 171.601644 -293.830947) (xy 171.552214 -293.847008) (xy 171.500879 -293.855138)
			(xy 171.448905 -293.855138) (xy 171.39757 -293.847008) (xy 171.34814 -293.830947) (xy 171.30183 -293.807351)
			(xy 171.259782 -293.776801) (xy 171.223031 -293.74005) (xy 171.192481 -293.698002) (xy 171.168885 -293.651692)
			(xy 171.152824 -293.602262) (xy 171.144694 -293.550927) (xy 170.85513 -293.550927) (xy 170.847 -293.602262)
			(xy 170.830939 -293.651692) (xy 170.807343 -293.698002) (xy 170.776793 -293.74005) (xy 170.740042 -293.776801)
			(xy 170.697994 -293.807351) (xy 170.651684 -293.830947) (xy 170.602254 -293.847008) (xy 170.550919 -293.855138)
			(xy 170.498945 -293.855138) (xy 170.44761 -293.847008) (xy 170.39818 -293.830947) (xy 170.35187 -293.807351)
			(xy 170.309822 -293.776801) (xy 170.273071 -293.74005) (xy 170.242521 -293.698002) (xy 170.218925 -293.651692)
			(xy 170.202864 -293.602262) (xy 170.194734 -293.550927) (xy 169.90517 -293.550927) (xy 169.89704 -293.602262)
			(xy 169.880979 -293.651692) (xy 169.857383 -293.698002) (xy 169.826833 -293.74005) (xy 169.790082 -293.776801)
			(xy 169.748034 -293.807351) (xy 169.701724 -293.830947) (xy 169.652294 -293.847008) (xy 169.600959 -293.855138)
			(xy 169.548985 -293.855138) (xy 169.49765 -293.847008) (xy 169.44822 -293.830947) (xy 169.40191 -293.807351)
			(xy 169.359862 -293.776801) (xy 169.323111 -293.74005) (xy 169.292561 -293.698002) (xy 169.268965 -293.651692)
			(xy 169.252904 -293.602262) (xy 169.244774 -293.550927) (xy 168.95521 -293.550927) (xy 168.94708 -293.602262)
			(xy 168.931019 -293.651692) (xy 168.907423 -293.698002) (xy 168.876873 -293.74005) (xy 168.840122 -293.776801)
			(xy 168.798074 -293.807351) (xy 168.751764 -293.830947) (xy 168.702334 -293.847008) (xy 168.650999 -293.855138)
			(xy 168.599025 -293.855138) (xy 168.54769 -293.847008) (xy 168.49826 -293.830947) (xy 168.45195 -293.807351)
			(xy 168.409902 -293.776801) (xy 168.373151 -293.74005) (xy 168.342601 -293.698002) (xy 168.319005 -293.651692)
			(xy 168.302944 -293.602262) (xy 168.294814 -293.550927) (xy 168.00525 -293.550927) (xy 167.99712 -293.602262)
			(xy 167.981059 -293.651692) (xy 167.957463 -293.698002) (xy 167.926913 -293.74005) (xy 167.890162 -293.776801)
			(xy 167.848114 -293.807351) (xy 167.801804 -293.830947) (xy 167.752374 -293.847008) (xy 167.701039 -293.855138)
			(xy 167.649065 -293.855138) (xy 167.59773 -293.847008) (xy 167.5483 -293.830947) (xy 167.50199 -293.807351)
			(xy 167.459942 -293.776801) (xy 167.423191 -293.74005) (xy 167.392641 -293.698002) (xy 167.369045 -293.651692)
			(xy 167.352984 -293.602262) (xy 167.344854 -293.550927) (xy 167.05529 -293.550927) (xy 167.04716 -293.602262)
			(xy 167.031099 -293.651692) (xy 167.007503 -293.698002) (xy 166.976953 -293.74005) (xy 166.940202 -293.776801)
			(xy 166.898154 -293.807351) (xy 166.851844 -293.830947) (xy 166.802414 -293.847008) (xy 166.751079 -293.855138)
			(xy 166.699105 -293.855138) (xy 166.64777 -293.847008) (xy 166.59834 -293.830947) (xy 166.55203 -293.807351)
			(xy 166.509982 -293.776801) (xy 166.473231 -293.74005) (xy 166.442681 -293.698002) (xy 166.419085 -293.651692)
			(xy 166.403024 -293.602262) (xy 166.394894 -293.550927) (xy 166.105076 -293.550927) (xy 166.096946 -293.602262)
			(xy 166.080885 -293.651692) (xy 166.057289 -293.698002) (xy 166.026739 -293.74005) (xy 165.989988 -293.776801)
			(xy 165.94794 -293.807351) (xy 165.90163 -293.830947) (xy 165.8522 -293.847008) (xy 165.800865 -293.855138)
			(xy 165.748891 -293.855138) (xy 165.697556 -293.847008) (xy 165.648126 -293.830947) (xy 165.601816 -293.807351)
			(xy 165.559768 -293.776801) (xy 165.523017 -293.74005) (xy 165.492467 -293.698002) (xy 165.468871 -293.651692)
			(xy 165.45281 -293.602262) (xy 165.44468 -293.550927) (xy 165.155116 -293.550927) (xy 165.146986 -293.602262)
			(xy 165.130925 -293.651692) (xy 165.107329 -293.698002) (xy 165.076779 -293.74005) (xy 165.040028 -293.776801)
			(xy 164.99798 -293.807351) (xy 164.95167 -293.830947) (xy 164.90224 -293.847008) (xy 164.850905 -293.855138)
			(xy 164.798931 -293.855138) (xy 164.747596 -293.847008) (xy 164.698166 -293.830947) (xy 164.651856 -293.807351)
			(xy 164.609808 -293.776801) (xy 164.573057 -293.74005) (xy 164.542507 -293.698002) (xy 164.518911 -293.651692)
			(xy 164.50285 -293.602262) (xy 164.49472 -293.550927) (xy 164.205156 -293.550927) (xy 164.197026 -293.602262)
			(xy 164.180965 -293.651692) (xy 164.157369 -293.698002) (xy 164.126819 -293.74005) (xy 164.090068 -293.776801)
			(xy 164.04802 -293.807351) (xy 164.00171 -293.830947) (xy 163.95228 -293.847008) (xy 163.900945 -293.855138)
			(xy 163.848971 -293.855138) (xy 163.797636 -293.847008) (xy 163.748206 -293.830947) (xy 163.701896 -293.807351)
			(xy 163.659848 -293.776801) (xy 163.623097 -293.74005) (xy 163.592547 -293.698002) (xy 163.568951 -293.651692)
			(xy 163.55289 -293.602262) (xy 163.54476 -293.550927) (xy 163.255196 -293.550927) (xy 163.247066 -293.602262)
			(xy 163.231005 -293.651692) (xy 163.207409 -293.698002) (xy 163.176859 -293.74005) (xy 163.140108 -293.776801)
			(xy 163.09806 -293.807351) (xy 163.05175 -293.830947) (xy 163.00232 -293.847008) (xy 162.950985 -293.855138)
			(xy 162.899011 -293.855138) (xy 162.847676 -293.847008) (xy 162.798246 -293.830947) (xy 162.751936 -293.807351)
			(xy 162.709888 -293.776801) (xy 162.673137 -293.74005) (xy 162.642587 -293.698002) (xy 162.618991 -293.651692)
			(xy 162.60293 -293.602262) (xy 162.5948 -293.550927) (xy 162.305236 -293.550927) (xy 162.297106 -293.602262)
			(xy 162.281045 -293.651692) (xy 162.257449 -293.698002) (xy 162.226899 -293.74005) (xy 162.190148 -293.776801)
			(xy 162.1481 -293.807351) (xy 162.10179 -293.830947) (xy 162.05236 -293.847008) (xy 162.001025 -293.855138)
			(xy 161.949051 -293.855138) (xy 161.897716 -293.847008) (xy 161.848286 -293.830947) (xy 161.801976 -293.807351)
			(xy 161.759928 -293.776801) (xy 161.723177 -293.74005) (xy 161.692627 -293.698002) (xy 161.669031 -293.651692)
			(xy 161.65297 -293.602262) (xy 161.64484 -293.550927) (xy 160.405062 -293.550927) (xy 160.396932 -293.602262)
			(xy 160.380871 -293.651692) (xy 160.357275 -293.698002) (xy 160.326725 -293.74005) (xy 160.289974 -293.776801)
			(xy 160.247926 -293.807351) (xy 160.201616 -293.830947) (xy 160.152186 -293.847008) (xy 160.100851 -293.855138)
			(xy 160.048877 -293.855138) (xy 159.997542 -293.847008) (xy 159.948112 -293.830947) (xy 159.901802 -293.807351)
			(xy 159.859754 -293.776801) (xy 159.823003 -293.74005) (xy 159.792453 -293.698002) (xy 159.768857 -293.651692)
			(xy 159.752796 -293.602262) (xy 159.744666 -293.550927) (xy 159.505016 -293.550927) (xy 159.502823 -293.580754)
			(xy 159.490599 -293.635396) (xy 159.47052 -293.687665) (xy 159.443016 -293.736436) (xy 159.408678 -293.780664)
			(xy 159.368245 -293.819397) (xy 159.322584 -293.851804) (xy 159.272676 -293.877189) (xy 159.246316 -293.886636)
			(xy 159.230822 -293.89197) (xy 159.211772 -293.918386) (xy 159.211772 -294.119046) (xy 159.212038 -294.126688)
			(xy 159.216577 -294.141283) (xy 159.220662 -294.147748) (xy 159.225234 -294.154352) (xy 159.236918 -294.16375)
			(xy 159.244284 -294.166544) (xy 159.268806 -294.1766) (xy 159.314543 -294.203372) (xy 159.355425 -294.237097)
			(xy 159.390404 -294.276911) (xy 159.418585 -294.321795) (xy 159.439246 -294.370598) (xy 159.451858 -294.422073)
			(xy 159.456098 -294.4749) (xy 159.454012 -294.500887) (xy 159.744666 -294.500887) (xy 159.744666 -294.448913)
			(xy 159.752796 -294.397578) (xy 159.768857 -294.348148) (xy 159.792453 -294.301838) (xy 159.823003 -294.25979)
			(xy 159.859754 -294.223039) (xy 159.901802 -294.192489) (xy 159.948112 -294.168893) (xy 159.997542 -294.152832)
			(xy 160.048877 -294.144702) (xy 160.100851 -294.144702) (xy 160.152186 -294.152832) (xy 160.201616 -294.168893)
			(xy 160.247926 -294.192489) (xy 160.289974 -294.223039) (xy 160.326725 -294.25979) (xy 160.357275 -294.301838)
			(xy 160.380871 -294.348148) (xy 160.396932 -294.397578) (xy 160.405062 -294.448913) (xy 160.405572 -294.4749)
			(xy 160.405062 -294.500887) (xy 161.64484 -294.500887) (xy 161.64484 -294.448913) (xy 161.65297 -294.397578)
			(xy 161.669031 -294.348148) (xy 161.692627 -294.301838) (xy 161.723177 -294.25979) (xy 161.759928 -294.223039)
			(xy 161.801976 -294.192489) (xy 161.848286 -294.168893) (xy 161.897716 -294.152832) (xy 161.949051 -294.144702)
			(xy 162.001025 -294.144702) (xy 162.05236 -294.152832) (xy 162.10179 -294.168893) (xy 162.1481 -294.192489)
			(xy 162.190148 -294.223039) (xy 162.226899 -294.25979) (xy 162.257449 -294.301838) (xy 162.281045 -294.348148)
			(xy 162.297106 -294.397578) (xy 162.305236 -294.448913) (xy 162.305746 -294.4749) (xy 162.305236 -294.500887)
			(xy 162.5948 -294.500887) (xy 162.5948 -294.448913) (xy 162.60293 -294.397578) (xy 162.618991 -294.348148)
			(xy 162.642587 -294.301838) (xy 162.673137 -294.25979) (xy 162.709888 -294.223039) (xy 162.751936 -294.192489)
			(xy 162.798246 -294.168893) (xy 162.847676 -294.152832) (xy 162.899011 -294.144702) (xy 162.950985 -294.144702)
			(xy 163.00232 -294.152832) (xy 163.05175 -294.168893) (xy 163.09806 -294.192489) (xy 163.140108 -294.223039)
			(xy 163.176859 -294.25979) (xy 163.207409 -294.301838) (xy 163.231005 -294.348148) (xy 163.247066 -294.397578)
			(xy 163.255196 -294.448913) (xy 163.255706 -294.4749) (xy 163.255196 -294.500887) (xy 163.54476 -294.500887)
			(xy 163.54476 -294.448913) (xy 163.55289 -294.397578) (xy 163.568951 -294.348148) (xy 163.592547 -294.301838)
			(xy 163.623097 -294.25979) (xy 163.659848 -294.223039) (xy 163.701896 -294.192489) (xy 163.748206 -294.168893)
			(xy 163.797636 -294.152832) (xy 163.848971 -294.144702) (xy 163.900945 -294.144702) (xy 163.95228 -294.152832)
			(xy 164.00171 -294.168893) (xy 164.04802 -294.192489) (xy 164.090068 -294.223039) (xy 164.126819 -294.25979)
			(xy 164.157369 -294.301838) (xy 164.180965 -294.348148) (xy 164.197026 -294.397578) (xy 164.205156 -294.448913)
			(xy 164.205666 -294.4749) (xy 164.205156 -294.500887) (xy 164.49472 -294.500887) (xy 164.49472 -294.448913)
			(xy 164.50285 -294.397578) (xy 164.518911 -294.348148) (xy 164.542507 -294.301838) (xy 164.573057 -294.25979)
			(xy 164.609808 -294.223039) (xy 164.651856 -294.192489) (xy 164.698166 -294.168893) (xy 164.747596 -294.152832)
			(xy 164.798931 -294.144702) (xy 164.850905 -294.144702) (xy 164.90224 -294.152832) (xy 164.95167 -294.168893)
			(xy 164.99798 -294.192489) (xy 165.040028 -294.223039) (xy 165.076779 -294.25979) (xy 165.107329 -294.301838)
			(xy 165.130925 -294.348148) (xy 165.146986 -294.397578) (xy 165.155116 -294.448913) (xy 165.155626 -294.4749)
			(xy 165.155116 -294.500887) (xy 165.44468 -294.500887) (xy 165.44468 -294.448913) (xy 165.45281 -294.397578)
			(xy 165.468871 -294.348148) (xy 165.492467 -294.301838) (xy 165.523017 -294.25979) (xy 165.559768 -294.223039)
			(xy 165.601816 -294.192489) (xy 165.648126 -294.168893) (xy 165.697556 -294.152832) (xy 165.748891 -294.144702)
			(xy 165.800865 -294.144702) (xy 165.8522 -294.152832) (xy 165.90163 -294.168893) (xy 165.94794 -294.192489)
			(xy 165.989988 -294.223039) (xy 166.026739 -294.25979) (xy 166.057289 -294.301838) (xy 166.080885 -294.348148)
			(xy 166.096946 -294.397578) (xy 166.105076 -294.448913) (xy 166.105586 -294.4749) (xy 166.105076 -294.500887)
			(xy 166.394894 -294.500887) (xy 166.394894 -294.448913) (xy 166.403024 -294.397578) (xy 166.419085 -294.348148)
			(xy 166.442681 -294.301838) (xy 166.473231 -294.25979) (xy 166.509982 -294.223039) (xy 166.55203 -294.192489)
			(xy 166.59834 -294.168893) (xy 166.64777 -294.152832) (xy 166.699105 -294.144702) (xy 166.751079 -294.144702)
			(xy 166.802414 -294.152832) (xy 166.851844 -294.168893) (xy 166.898154 -294.192489) (xy 166.940202 -294.223039)
			(xy 166.976953 -294.25979) (xy 167.007503 -294.301838) (xy 167.031099 -294.348148) (xy 167.04716 -294.397578)
			(xy 167.05529 -294.448913) (xy 167.0558 -294.4749) (xy 167.05529 -294.500887) (xy 167.344854 -294.500887)
			(xy 167.344854 -294.448913) (xy 167.352984 -294.397578) (xy 167.369045 -294.348148) (xy 167.392641 -294.301838)
			(xy 167.423191 -294.25979) (xy 167.459942 -294.223039) (xy 167.50199 -294.192489) (xy 167.5483 -294.168893)
			(xy 167.59773 -294.152832) (xy 167.649065 -294.144702) (xy 167.701039 -294.144702) (xy 167.752374 -294.152832)
			(xy 167.801804 -294.168893) (xy 167.848114 -294.192489) (xy 167.890162 -294.223039) (xy 167.926913 -294.25979)
			(xy 167.957463 -294.301838) (xy 167.981059 -294.348148) (xy 167.99712 -294.397578) (xy 168.00525 -294.448913)
			(xy 168.00576 -294.4749) (xy 168.00525 -294.500887) (xy 168.294814 -294.500887) (xy 168.294814 -294.448913)
			(xy 168.302944 -294.397578) (xy 168.319005 -294.348148) (xy 168.342601 -294.301838) (xy 168.373151 -294.25979)
			(xy 168.409902 -294.223039) (xy 168.45195 -294.192489) (xy 168.49826 -294.168893) (xy 168.54769 -294.152832)
			(xy 168.599025 -294.144702) (xy 168.650999 -294.144702) (xy 168.702334 -294.152832) (xy 168.751764 -294.168893)
			(xy 168.798074 -294.192489) (xy 168.840122 -294.223039) (xy 168.876873 -294.25979) (xy 168.907423 -294.301838)
			(xy 168.931019 -294.348148) (xy 168.94708 -294.397578) (xy 168.95521 -294.448913) (xy 168.95572 -294.4749)
			(xy 168.95521 -294.500887) (xy 169.244774 -294.500887) (xy 169.244774 -294.448913) (xy 169.252904 -294.397578)
			(xy 169.268965 -294.348148) (xy 169.292561 -294.301838) (xy 169.323111 -294.25979) (xy 169.359862 -294.223039)
			(xy 169.40191 -294.192489) (xy 169.44822 -294.168893) (xy 169.49765 -294.152832) (xy 169.548985 -294.144702)
			(xy 169.600959 -294.144702) (xy 169.652294 -294.152832) (xy 169.701724 -294.168893) (xy 169.748034 -294.192489)
			(xy 169.790082 -294.223039) (xy 169.826833 -294.25979) (xy 169.857383 -294.301838) (xy 169.880979 -294.348148)
			(xy 169.89704 -294.397578) (xy 169.90517 -294.448913) (xy 169.90568 -294.4749) (xy 169.90517 -294.500887)
			(xy 170.194734 -294.500887) (xy 170.194734 -294.448913) (xy 170.202864 -294.397578) (xy 170.218925 -294.348148)
			(xy 170.242521 -294.301838) (xy 170.273071 -294.25979) (xy 170.309822 -294.223039) (xy 170.35187 -294.192489)
			(xy 170.39818 -294.168893) (xy 170.44761 -294.152832) (xy 170.498945 -294.144702) (xy 170.550919 -294.144702)
			(xy 170.602254 -294.152832) (xy 170.651684 -294.168893) (xy 170.697994 -294.192489) (xy 170.740042 -294.223039)
			(xy 170.776793 -294.25979) (xy 170.807343 -294.301838) (xy 170.830939 -294.348148) (xy 170.847 -294.397578)
			(xy 170.85513 -294.448913) (xy 170.85564 -294.4749) (xy 170.85513 -294.500887) (xy 171.144694 -294.500887)
			(xy 171.144694 -294.448913) (xy 171.152824 -294.397578) (xy 171.168885 -294.348148) (xy 171.192481 -294.301838)
			(xy 171.223031 -294.25979) (xy 171.259782 -294.223039) (xy 171.30183 -294.192489) (xy 171.34814 -294.168893)
			(xy 171.39757 -294.152832) (xy 171.448905 -294.144702) (xy 171.500879 -294.144702) (xy 171.552214 -294.152832)
			(xy 171.601644 -294.168893) (xy 171.647954 -294.192489) (xy 171.690002 -294.223039) (xy 171.726753 -294.25979)
			(xy 171.757303 -294.301838) (xy 171.780899 -294.348148) (xy 171.79696 -294.397578) (xy 171.80509 -294.448913)
			(xy 171.8056 -294.4749) (xy 171.80509 -294.500887) (xy 172.094654 -294.500887) (xy 172.094654 -294.448913)
			(xy 172.102784 -294.397578) (xy 172.118845 -294.348148) (xy 172.142441 -294.301838) (xy 172.172991 -294.25979)
			(xy 172.209742 -294.223039) (xy 172.25179 -294.192489) (xy 172.2981 -294.168893) (xy 172.34753 -294.152832)
			(xy 172.398865 -294.144702) (xy 172.450839 -294.144702) (xy 172.502174 -294.152832) (xy 172.551604 -294.168893)
			(xy 172.597914 -294.192489) (xy 172.639962 -294.223039) (xy 172.676713 -294.25979) (xy 172.707263 -294.301838)
			(xy 172.730859 -294.348148) (xy 172.74692 -294.397578) (xy 172.75505 -294.448913) (xy 172.75556 -294.4749)
			(xy 172.75505 -294.500887) (xy 173.044868 -294.500887) (xy 173.044868 -294.448913) (xy 173.052998 -294.397578)
			(xy 173.069059 -294.348148) (xy 173.092655 -294.301838) (xy 173.123205 -294.25979) (xy 173.159956 -294.223039)
			(xy 173.202004 -294.192489) (xy 173.248314 -294.168893) (xy 173.297744 -294.152832) (xy 173.349079 -294.144702)
			(xy 173.401053 -294.144702) (xy 173.452388 -294.152832) (xy 173.501818 -294.168893) (xy 173.548128 -294.192489)
			(xy 173.590176 -294.223039) (xy 173.626927 -294.25979) (xy 173.657477 -294.301838) (xy 173.681073 -294.348148)
			(xy 173.697134 -294.397578) (xy 173.705264 -294.448913) (xy 173.705774 -294.4749) (xy 173.705264 -294.500887)
			(xy 173.994828 -294.500887) (xy 173.994828 -294.448913) (xy 174.002958 -294.397578) (xy 174.019019 -294.348148)
			(xy 174.042615 -294.301838) (xy 174.073165 -294.25979) (xy 174.109916 -294.223039) (xy 174.151964 -294.192489)
			(xy 174.198274 -294.168893) (xy 174.247704 -294.152832) (xy 174.299039 -294.144702) (xy 174.351013 -294.144702)
			(xy 174.402348 -294.152832) (xy 174.451778 -294.168893) (xy 174.498088 -294.192489) (xy 174.540136 -294.223039)
			(xy 174.576887 -294.25979) (xy 174.607437 -294.301838) (xy 174.631033 -294.348148) (xy 174.647094 -294.397578)
			(xy 174.655224 -294.448913) (xy 174.655734 -294.4749) (xy 174.655224 -294.500887) (xy 175.894748 -294.500887)
			(xy 175.894748 -294.448913) (xy 175.902878 -294.397578) (xy 175.918939 -294.348148) (xy 175.942535 -294.301838)
			(xy 175.973085 -294.25979) (xy 176.009836 -294.223039) (xy 176.051884 -294.192489) (xy 176.098194 -294.168893)
			(xy 176.147624 -294.152832) (xy 176.198959 -294.144702) (xy 176.250933 -294.144702) (xy 176.302268 -294.152832)
			(xy 176.351698 -294.168893) (xy 176.398008 -294.192489) (xy 176.440056 -294.223039) (xy 176.476807 -294.25979)
			(xy 176.507357 -294.301838) (xy 176.530953 -294.348148) (xy 176.547014 -294.397578) (xy 176.555144 -294.448913)
			(xy 176.555654 -294.4749) (xy 176.555144 -294.500887) (xy 176.844708 -294.500887) (xy 176.844708 -294.448913)
			(xy 176.852838 -294.397578) (xy 176.868899 -294.348148) (xy 176.892495 -294.301838) (xy 176.923045 -294.25979)
			(xy 176.959796 -294.223039) (xy 177.001844 -294.192489) (xy 177.048154 -294.168893) (xy 177.097584 -294.152832)
			(xy 177.148919 -294.144702) (xy 177.200893 -294.144702) (xy 177.252228 -294.152832) (xy 177.301658 -294.168893)
			(xy 177.347968 -294.192489) (xy 177.390016 -294.223039) (xy 177.426767 -294.25979) (xy 177.457317 -294.301838)
			(xy 177.480913 -294.348148) (xy 177.496974 -294.397578) (xy 177.505104 -294.448913) (xy 177.505614 -294.4749)
			(xy 177.505104 -294.500887) (xy 177.794668 -294.500887) (xy 177.794668 -294.448913) (xy 177.802798 -294.397578)
			(xy 177.818859 -294.348148) (xy 177.842455 -294.301838) (xy 177.873005 -294.25979) (xy 177.909756 -294.223039)
			(xy 177.951804 -294.192489) (xy 177.998114 -294.168893) (xy 178.047544 -294.152832) (xy 178.098879 -294.144702)
			(xy 178.150853 -294.144702) (xy 178.202188 -294.152832) (xy 178.251618 -294.168893) (xy 178.297928 -294.192489)
			(xy 178.339976 -294.223039) (xy 178.376727 -294.25979) (xy 178.407277 -294.301838) (xy 178.430873 -294.348148)
			(xy 178.446934 -294.397578) (xy 178.455064 -294.448913) (xy 178.455574 -294.4749) (xy 178.455064 -294.500887)
			(xy 178.744882 -294.500887) (xy 178.744882 -294.448913) (xy 178.753012 -294.397578) (xy 178.769073 -294.348148)
			(xy 178.792669 -294.301838) (xy 178.823219 -294.25979) (xy 178.85997 -294.223039) (xy 178.902018 -294.192489)
			(xy 178.948328 -294.168893) (xy 178.997758 -294.152832) (xy 179.049093 -294.144702) (xy 179.101067 -294.144702)
			(xy 179.152402 -294.152832) (xy 179.201832 -294.168893) (xy 179.248142 -294.192489) (xy 179.29019 -294.223039)
			(xy 179.326941 -294.25979) (xy 179.357491 -294.301838) (xy 179.381087 -294.348148) (xy 179.397148 -294.397578)
			(xy 179.405278 -294.448913) (xy 179.405788 -294.4749) (xy 179.405278 -294.500887) (xy 179.694842 -294.500887)
			(xy 179.694842 -294.448913) (xy 179.702972 -294.397578) (xy 179.719033 -294.348148) (xy 179.742629 -294.301838)
			(xy 179.773179 -294.25979) (xy 179.80993 -294.223039) (xy 179.851978 -294.192489) (xy 179.898288 -294.168893)
			(xy 179.947718 -294.152832) (xy 179.999053 -294.144702) (xy 180.051027 -294.144702) (xy 180.102362 -294.152832)
			(xy 180.151792 -294.168893) (xy 180.198102 -294.192489) (xy 180.24015 -294.223039) (xy 180.276901 -294.25979)
			(xy 180.307451 -294.301838) (xy 180.331047 -294.348148) (xy 180.347108 -294.397578) (xy 180.355238 -294.448913)
			(xy 180.355748 -294.4749) (xy 180.355238 -294.500887) (xy 180.644802 -294.500887) (xy 180.644802 -294.448913)
			(xy 180.652932 -294.397578) (xy 180.668993 -294.348148) (xy 180.692589 -294.301838) (xy 180.723139 -294.25979)
			(xy 180.75989 -294.223039) (xy 180.801938 -294.192489) (xy 180.848248 -294.168893) (xy 180.897678 -294.152832)
			(xy 180.949013 -294.144702) (xy 181.000987 -294.144702) (xy 181.052322 -294.152832) (xy 181.101752 -294.168893)
			(xy 181.148062 -294.192489) (xy 181.19011 -294.223039) (xy 181.226861 -294.25979) (xy 181.257411 -294.301838)
			(xy 181.281007 -294.348148) (xy 181.297068 -294.397578) (xy 181.305198 -294.448913) (xy 181.305708 -294.4749)
			(xy 181.305198 -294.500887) (xy 181.594762 -294.500887) (xy 181.594762 -294.448913) (xy 181.602892 -294.397578)
			(xy 181.618953 -294.348148) (xy 181.642549 -294.301838) (xy 181.673099 -294.25979) (xy 181.70985 -294.223039)
			(xy 181.751898 -294.192489) (xy 181.798208 -294.168893) (xy 181.847638 -294.152832) (xy 181.898973 -294.144702)
			(xy 181.950947 -294.144702) (xy 182.002282 -294.152832) (xy 182.051712 -294.168893) (xy 182.098022 -294.192489)
			(xy 182.14007 -294.223039) (xy 182.176821 -294.25979) (xy 182.207371 -294.301838) (xy 182.230967 -294.348148)
			(xy 182.247028 -294.397578) (xy 182.255158 -294.448913) (xy 182.255668 -294.4749) (xy 182.255158 -294.500887)
			(xy 182.544722 -294.500887) (xy 182.544722 -294.448913) (xy 182.552852 -294.397578) (xy 182.568913 -294.348148)
			(xy 182.592509 -294.301838) (xy 182.623059 -294.25979) (xy 182.65981 -294.223039) (xy 182.701858 -294.192489)
			(xy 182.748168 -294.168893) (xy 182.797598 -294.152832) (xy 182.848933 -294.144702) (xy 182.900907 -294.144702)
			(xy 182.952242 -294.152832) (xy 183.001672 -294.168893) (xy 183.047982 -294.192489) (xy 183.09003 -294.223039)
			(xy 183.126781 -294.25979) (xy 183.157331 -294.301838) (xy 183.180927 -294.348148) (xy 183.196988 -294.397578)
			(xy 183.205118 -294.448913) (xy 183.205628 -294.4749) (xy 183.205118 -294.500887) (xy 183.494682 -294.500887)
			(xy 183.494682 -294.448913) (xy 183.502812 -294.397578) (xy 183.518873 -294.348148) (xy 183.542469 -294.301838)
			(xy 183.573019 -294.25979) (xy 183.60977 -294.223039) (xy 183.651818 -294.192489) (xy 183.698128 -294.168893)
			(xy 183.747558 -294.152832) (xy 183.798893 -294.144702) (xy 183.850867 -294.144702) (xy 183.902202 -294.152832)
			(xy 183.951632 -294.168893) (xy 183.997942 -294.192489) (xy 184.03999 -294.223039) (xy 184.076741 -294.25979)
			(xy 184.107291 -294.301838) (xy 184.130887 -294.348148) (xy 184.146948 -294.397578) (xy 184.155078 -294.448913)
			(xy 184.155588 -294.4749) (xy 184.155078 -294.500887) (xy 184.444642 -294.500887) (xy 184.444642 -294.448913)
			(xy 184.452772 -294.397578) (xy 184.468833 -294.348148) (xy 184.492429 -294.301838) (xy 184.522979 -294.25979)
			(xy 184.55973 -294.223039) (xy 184.601778 -294.192489) (xy 184.648088 -294.168893) (xy 184.697518 -294.152832)
			(xy 184.748853 -294.144702) (xy 184.800827 -294.144702) (xy 184.852162 -294.152832) (xy 184.901592 -294.168893)
			(xy 184.947902 -294.192489) (xy 184.98995 -294.223039) (xy 185.026701 -294.25979) (xy 185.057251 -294.301838)
			(xy 185.080847 -294.348148) (xy 185.096908 -294.397578) (xy 185.105038 -294.448913) (xy 185.105548 -294.4749)
			(xy 185.105038 -294.500887) (xy 185.394856 -294.500887) (xy 185.394856 -294.448913) (xy 185.402986 -294.397578)
			(xy 185.419047 -294.348148) (xy 185.442643 -294.301838) (xy 185.473193 -294.25979) (xy 185.509944 -294.223039)
			(xy 185.551992 -294.192489) (xy 185.598302 -294.168893) (xy 185.647732 -294.152832) (xy 185.699067 -294.144702)
			(xy 185.751041 -294.144702) (xy 185.802376 -294.152832) (xy 185.851806 -294.168893) (xy 185.898116 -294.192489)
			(xy 185.940164 -294.223039) (xy 185.976915 -294.25979) (xy 186.007465 -294.301838) (xy 186.031061 -294.348148)
			(xy 186.047122 -294.397578) (xy 186.055252 -294.448913) (xy 186.055762 -294.4749) (xy 186.055252 -294.500887)
			(xy 186.047122 -294.552222) (xy 186.031061 -294.601652) (xy 186.007465 -294.647962) (xy 185.976915 -294.69001)
			(xy 185.940164 -294.726761) (xy 185.898116 -294.757311) (xy 185.851806 -294.780907) (xy 185.802376 -294.796968)
			(xy 185.751041 -294.805098) (xy 185.699067 -294.805098) (xy 185.647732 -294.796968) (xy 185.598302 -294.780907)
			(xy 185.551992 -294.757311) (xy 185.509944 -294.726761) (xy 185.473193 -294.69001) (xy 185.442643 -294.647962)
			(xy 185.419047 -294.601652) (xy 185.402986 -294.552222) (xy 185.394856 -294.500887) (xy 185.105038 -294.500887)
			(xy 185.096908 -294.552222) (xy 185.080847 -294.601652) (xy 185.057251 -294.647962) (xy 185.026701 -294.69001)
			(xy 184.98995 -294.726761) (xy 184.947902 -294.757311) (xy 184.901592 -294.780907) (xy 184.852162 -294.796968)
			(xy 184.800827 -294.805098) (xy 184.748853 -294.805098) (xy 184.697518 -294.796968) (xy 184.648088 -294.780907)
			(xy 184.601778 -294.757311) (xy 184.55973 -294.726761) (xy 184.522979 -294.69001) (xy 184.492429 -294.647962)
			(xy 184.468833 -294.601652) (xy 184.452772 -294.552222) (xy 184.444642 -294.500887) (xy 184.155078 -294.500887)
			(xy 184.146948 -294.552222) (xy 184.130887 -294.601652) (xy 184.107291 -294.647962) (xy 184.076741 -294.69001)
			(xy 184.03999 -294.726761) (xy 183.997942 -294.757311) (xy 183.951632 -294.780907) (xy 183.902202 -294.796968)
			(xy 183.850867 -294.805098) (xy 183.798893 -294.805098) (xy 183.747558 -294.796968) (xy 183.698128 -294.780907)
			(xy 183.651818 -294.757311) (xy 183.60977 -294.726761) (xy 183.573019 -294.69001) (xy 183.542469 -294.647962)
			(xy 183.518873 -294.601652) (xy 183.502812 -294.552222) (xy 183.494682 -294.500887) (xy 183.205118 -294.500887)
			(xy 183.196988 -294.552222) (xy 183.180927 -294.601652) (xy 183.157331 -294.647962) (xy 183.126781 -294.69001)
			(xy 183.09003 -294.726761) (xy 183.047982 -294.757311) (xy 183.001672 -294.780907) (xy 182.952242 -294.796968)
			(xy 182.900907 -294.805098) (xy 182.848933 -294.805098) (xy 182.797598 -294.796968) (xy 182.748168 -294.780907)
			(xy 182.701858 -294.757311) (xy 182.65981 -294.726761) (xy 182.623059 -294.69001) (xy 182.592509 -294.647962)
			(xy 182.568913 -294.601652) (xy 182.552852 -294.552222) (xy 182.544722 -294.500887) (xy 182.255158 -294.500887)
			(xy 182.247028 -294.552222) (xy 182.230967 -294.601652) (xy 182.207371 -294.647962) (xy 182.176821 -294.69001)
			(xy 182.14007 -294.726761) (xy 182.098022 -294.757311) (xy 182.051712 -294.780907) (xy 182.002282 -294.796968)
			(xy 181.950947 -294.805098) (xy 181.898973 -294.805098) (xy 181.847638 -294.796968) (xy 181.798208 -294.780907)
			(xy 181.751898 -294.757311) (xy 181.70985 -294.726761) (xy 181.673099 -294.69001) (xy 181.642549 -294.647962)
			(xy 181.618953 -294.601652) (xy 181.602892 -294.552222) (xy 181.594762 -294.500887) (xy 181.305198 -294.500887)
			(xy 181.297068 -294.552222) (xy 181.281007 -294.601652) (xy 181.257411 -294.647962) (xy 181.226861 -294.69001)
			(xy 181.19011 -294.726761) (xy 181.148062 -294.757311) (xy 181.101752 -294.780907) (xy 181.052322 -294.796968)
			(xy 181.000987 -294.805098) (xy 180.949013 -294.805098) (xy 180.897678 -294.796968) (xy 180.848248 -294.780907)
			(xy 180.801938 -294.757311) (xy 180.75989 -294.726761) (xy 180.723139 -294.69001) (xy 180.692589 -294.647962)
			(xy 180.668993 -294.601652) (xy 180.652932 -294.552222) (xy 180.644802 -294.500887) (xy 180.355238 -294.500887)
			(xy 180.347108 -294.552222) (xy 180.331047 -294.601652) (xy 180.307451 -294.647962) (xy 180.276901 -294.69001)
			(xy 180.24015 -294.726761) (xy 180.198102 -294.757311) (xy 180.151792 -294.780907) (xy 180.102362 -294.796968)
			(xy 180.051027 -294.805098) (xy 179.999053 -294.805098) (xy 179.947718 -294.796968) (xy 179.898288 -294.780907)
			(xy 179.851978 -294.757311) (xy 179.80993 -294.726761) (xy 179.773179 -294.69001) (xy 179.742629 -294.647962)
			(xy 179.719033 -294.601652) (xy 179.702972 -294.552222) (xy 179.694842 -294.500887) (xy 179.405278 -294.500887)
			(xy 179.397148 -294.552222) (xy 179.381087 -294.601652) (xy 179.357491 -294.647962) (xy 179.326941 -294.69001)
			(xy 179.29019 -294.726761) (xy 179.248142 -294.757311) (xy 179.201832 -294.780907) (xy 179.152402 -294.796968)
			(xy 179.101067 -294.805098) (xy 179.049093 -294.805098) (xy 178.997758 -294.796968) (xy 178.948328 -294.780907)
			(xy 178.902018 -294.757311) (xy 178.85997 -294.726761) (xy 178.823219 -294.69001) (xy 178.792669 -294.647962)
			(xy 178.769073 -294.601652) (xy 178.753012 -294.552222) (xy 178.744882 -294.500887) (xy 178.455064 -294.500887)
			(xy 178.446934 -294.552222) (xy 178.430873 -294.601652) (xy 178.407277 -294.647962) (xy 178.376727 -294.69001)
			(xy 178.339976 -294.726761) (xy 178.297928 -294.757311) (xy 178.251618 -294.780907) (xy 178.202188 -294.796968)
			(xy 178.150853 -294.805098) (xy 178.098879 -294.805098) (xy 178.047544 -294.796968) (xy 177.998114 -294.780907)
			(xy 177.951804 -294.757311) (xy 177.909756 -294.726761) (xy 177.873005 -294.69001) (xy 177.842455 -294.647962)
			(xy 177.818859 -294.601652) (xy 177.802798 -294.552222) (xy 177.794668 -294.500887) (xy 177.505104 -294.500887)
			(xy 177.496974 -294.552222) (xy 177.480913 -294.601652) (xy 177.457317 -294.647962) (xy 177.426767 -294.69001)
			(xy 177.390016 -294.726761) (xy 177.347968 -294.757311) (xy 177.301658 -294.780907) (xy 177.252228 -294.796968)
			(xy 177.200893 -294.805098) (xy 177.148919 -294.805098) (xy 177.097584 -294.796968) (xy 177.048154 -294.780907)
			(xy 177.001844 -294.757311) (xy 176.959796 -294.726761) (xy 176.923045 -294.69001) (xy 176.892495 -294.647962)
			(xy 176.868899 -294.601652) (xy 176.852838 -294.552222) (xy 176.844708 -294.500887) (xy 176.555144 -294.500887)
			(xy 176.547014 -294.552222) (xy 176.530953 -294.601652) (xy 176.507357 -294.647962) (xy 176.476807 -294.69001)
			(xy 176.440056 -294.726761) (xy 176.398008 -294.757311) (xy 176.351698 -294.780907) (xy 176.302268 -294.796968)
			(xy 176.250933 -294.805098) (xy 176.198959 -294.805098) (xy 176.147624 -294.796968) (xy 176.098194 -294.780907)
			(xy 176.051884 -294.757311) (xy 176.009836 -294.726761) (xy 175.973085 -294.69001) (xy 175.942535 -294.647962)
			(xy 175.918939 -294.601652) (xy 175.902878 -294.552222) (xy 175.894748 -294.500887) (xy 174.655224 -294.500887)
			(xy 174.647094 -294.552222) (xy 174.631033 -294.601652) (xy 174.607437 -294.647962) (xy 174.576887 -294.69001)
			(xy 174.540136 -294.726761) (xy 174.498088 -294.757311) (xy 174.451778 -294.780907) (xy 174.402348 -294.796968)
			(xy 174.351013 -294.805098) (xy 174.299039 -294.805098) (xy 174.247704 -294.796968) (xy 174.198274 -294.780907)
			(xy 174.151964 -294.757311) (xy 174.109916 -294.726761) (xy 174.073165 -294.69001) (xy 174.042615 -294.647962)
			(xy 174.019019 -294.601652) (xy 174.002958 -294.552222) (xy 173.994828 -294.500887) (xy 173.705264 -294.500887)
			(xy 173.697134 -294.552222) (xy 173.681073 -294.601652) (xy 173.657477 -294.647962) (xy 173.626927 -294.69001)
			(xy 173.590176 -294.726761) (xy 173.548128 -294.757311) (xy 173.501818 -294.780907) (xy 173.452388 -294.796968)
			(xy 173.401053 -294.805098) (xy 173.349079 -294.805098) (xy 173.297744 -294.796968) (xy 173.248314 -294.780907)
			(xy 173.202004 -294.757311) (xy 173.159956 -294.726761) (xy 173.123205 -294.69001) (xy 173.092655 -294.647962)
			(xy 173.069059 -294.601652) (xy 173.052998 -294.552222) (xy 173.044868 -294.500887) (xy 172.75505 -294.500887)
			(xy 172.74692 -294.552222) (xy 172.730859 -294.601652) (xy 172.707263 -294.647962) (xy 172.676713 -294.69001)
			(xy 172.639962 -294.726761) (xy 172.597914 -294.757311) (xy 172.551604 -294.780907) (xy 172.502174 -294.796968)
			(xy 172.450839 -294.805098) (xy 172.398865 -294.805098) (xy 172.34753 -294.796968) (xy 172.2981 -294.780907)
			(xy 172.25179 -294.757311) (xy 172.209742 -294.726761) (xy 172.172991 -294.69001) (xy 172.142441 -294.647962)
			(xy 172.118845 -294.601652) (xy 172.102784 -294.552222) (xy 172.094654 -294.500887) (xy 171.80509 -294.500887)
			(xy 171.79696 -294.552222) (xy 171.780899 -294.601652) (xy 171.757303 -294.647962) (xy 171.726753 -294.69001)
			(xy 171.690002 -294.726761) (xy 171.647954 -294.757311) (xy 171.601644 -294.780907) (xy 171.552214 -294.796968)
			(xy 171.500879 -294.805098) (xy 171.448905 -294.805098) (xy 171.39757 -294.796968) (xy 171.34814 -294.780907)
			(xy 171.30183 -294.757311) (xy 171.259782 -294.726761) (xy 171.223031 -294.69001) (xy 171.192481 -294.647962)
			(xy 171.168885 -294.601652) (xy 171.152824 -294.552222) (xy 171.144694 -294.500887) (xy 170.85513 -294.500887)
			(xy 170.847 -294.552222) (xy 170.830939 -294.601652) (xy 170.807343 -294.647962) (xy 170.776793 -294.69001)
			(xy 170.740042 -294.726761) (xy 170.697994 -294.757311) (xy 170.651684 -294.780907) (xy 170.602254 -294.796968)
			(xy 170.550919 -294.805098) (xy 170.498945 -294.805098) (xy 170.44761 -294.796968) (xy 170.39818 -294.780907)
			(xy 170.35187 -294.757311) (xy 170.309822 -294.726761) (xy 170.273071 -294.69001) (xy 170.242521 -294.647962)
			(xy 170.218925 -294.601652) (xy 170.202864 -294.552222) (xy 170.194734 -294.500887) (xy 169.90517 -294.500887)
			(xy 169.89704 -294.552222) (xy 169.880979 -294.601652) (xy 169.857383 -294.647962) (xy 169.826833 -294.69001)
			(xy 169.790082 -294.726761) (xy 169.748034 -294.757311) (xy 169.701724 -294.780907) (xy 169.652294 -294.796968)
			(xy 169.600959 -294.805098) (xy 169.548985 -294.805098) (xy 169.49765 -294.796968) (xy 169.44822 -294.780907)
			(xy 169.40191 -294.757311) (xy 169.359862 -294.726761) (xy 169.323111 -294.69001) (xy 169.292561 -294.647962)
			(xy 169.268965 -294.601652) (xy 169.252904 -294.552222) (xy 169.244774 -294.500887) (xy 168.95521 -294.500887)
			(xy 168.94708 -294.552222) (xy 168.931019 -294.601652) (xy 168.907423 -294.647962) (xy 168.876873 -294.69001)
			(xy 168.840122 -294.726761) (xy 168.798074 -294.757311) (xy 168.751764 -294.780907) (xy 168.702334 -294.796968)
			(xy 168.650999 -294.805098) (xy 168.599025 -294.805098) (xy 168.54769 -294.796968) (xy 168.49826 -294.780907)
			(xy 168.45195 -294.757311) (xy 168.409902 -294.726761) (xy 168.373151 -294.69001) (xy 168.342601 -294.647962)
			(xy 168.319005 -294.601652) (xy 168.302944 -294.552222) (xy 168.294814 -294.500887) (xy 168.00525 -294.500887)
			(xy 167.99712 -294.552222) (xy 167.981059 -294.601652) (xy 167.957463 -294.647962) (xy 167.926913 -294.69001)
			(xy 167.890162 -294.726761) (xy 167.848114 -294.757311) (xy 167.801804 -294.780907) (xy 167.752374 -294.796968)
			(xy 167.701039 -294.805098) (xy 167.649065 -294.805098) (xy 167.59773 -294.796968) (xy 167.5483 -294.780907)
			(xy 167.50199 -294.757311) (xy 167.459942 -294.726761) (xy 167.423191 -294.69001) (xy 167.392641 -294.647962)
			(xy 167.369045 -294.601652) (xy 167.352984 -294.552222) (xy 167.344854 -294.500887) (xy 167.05529 -294.500887)
			(xy 167.04716 -294.552222) (xy 167.031099 -294.601652) (xy 167.007503 -294.647962) (xy 166.976953 -294.69001)
			(xy 166.940202 -294.726761) (xy 166.898154 -294.757311) (xy 166.851844 -294.780907) (xy 166.802414 -294.796968)
			(xy 166.751079 -294.805098) (xy 166.699105 -294.805098) (xy 166.64777 -294.796968) (xy 166.59834 -294.780907)
			(xy 166.55203 -294.757311) (xy 166.509982 -294.726761) (xy 166.473231 -294.69001) (xy 166.442681 -294.647962)
			(xy 166.419085 -294.601652) (xy 166.403024 -294.552222) (xy 166.394894 -294.500887) (xy 166.105076 -294.500887)
			(xy 166.096946 -294.552222) (xy 166.080885 -294.601652) (xy 166.057289 -294.647962) (xy 166.026739 -294.69001)
			(xy 165.989988 -294.726761) (xy 165.94794 -294.757311) (xy 165.90163 -294.780907) (xy 165.8522 -294.796968)
			(xy 165.800865 -294.805098) (xy 165.748891 -294.805098) (xy 165.697556 -294.796968) (xy 165.648126 -294.780907)
			(xy 165.601816 -294.757311) (xy 165.559768 -294.726761) (xy 165.523017 -294.69001) (xy 165.492467 -294.647962)
			(xy 165.468871 -294.601652) (xy 165.45281 -294.552222) (xy 165.44468 -294.500887) (xy 165.155116 -294.500887)
			(xy 165.146986 -294.552222) (xy 165.130925 -294.601652) (xy 165.107329 -294.647962) (xy 165.076779 -294.69001)
			(xy 165.040028 -294.726761) (xy 164.99798 -294.757311) (xy 164.95167 -294.780907) (xy 164.90224 -294.796968)
			(xy 164.850905 -294.805098) (xy 164.798931 -294.805098) (xy 164.747596 -294.796968) (xy 164.698166 -294.780907)
			(xy 164.651856 -294.757311) (xy 164.609808 -294.726761) (xy 164.573057 -294.69001) (xy 164.542507 -294.647962)
			(xy 164.518911 -294.601652) (xy 164.50285 -294.552222) (xy 164.49472 -294.500887) (xy 164.205156 -294.500887)
			(xy 164.197026 -294.552222) (xy 164.180965 -294.601652) (xy 164.157369 -294.647962) (xy 164.126819 -294.69001)
			(xy 164.090068 -294.726761) (xy 164.04802 -294.757311) (xy 164.00171 -294.780907) (xy 163.95228 -294.796968)
			(xy 163.900945 -294.805098) (xy 163.848971 -294.805098) (xy 163.797636 -294.796968) (xy 163.748206 -294.780907)
			(xy 163.701896 -294.757311) (xy 163.659848 -294.726761) (xy 163.623097 -294.69001) (xy 163.592547 -294.647962)
			(xy 163.568951 -294.601652) (xy 163.55289 -294.552222) (xy 163.54476 -294.500887) (xy 163.255196 -294.500887)
			(xy 163.247066 -294.552222) (xy 163.231005 -294.601652) (xy 163.207409 -294.647962) (xy 163.176859 -294.69001)
			(xy 163.140108 -294.726761) (xy 163.09806 -294.757311) (xy 163.05175 -294.780907) (xy 163.00232 -294.796968)
			(xy 162.950985 -294.805098) (xy 162.899011 -294.805098) (xy 162.847676 -294.796968) (xy 162.798246 -294.780907)
			(xy 162.751936 -294.757311) (xy 162.709888 -294.726761) (xy 162.673137 -294.69001) (xy 162.642587 -294.647962)
			(xy 162.618991 -294.601652) (xy 162.60293 -294.552222) (xy 162.5948 -294.500887) (xy 162.305236 -294.500887)
			(xy 162.297106 -294.552222) (xy 162.281045 -294.601652) (xy 162.257449 -294.647962) (xy 162.226899 -294.69001)
			(xy 162.190148 -294.726761) (xy 162.1481 -294.757311) (xy 162.10179 -294.780907) (xy 162.05236 -294.796968)
			(xy 162.001025 -294.805098) (xy 161.949051 -294.805098) (xy 161.897716 -294.796968) (xy 161.848286 -294.780907)
			(xy 161.801976 -294.757311) (xy 161.759928 -294.726761) (xy 161.723177 -294.69001) (xy 161.692627 -294.647962)
			(xy 161.669031 -294.601652) (xy 161.65297 -294.552222) (xy 161.64484 -294.500887) (xy 160.405062 -294.500887)
			(xy 160.396932 -294.552222) (xy 160.380871 -294.601652) (xy 160.357275 -294.647962) (xy 160.326725 -294.69001)
			(xy 160.289974 -294.726761) (xy 160.247926 -294.757311) (xy 160.201616 -294.780907) (xy 160.152186 -294.796968)
			(xy 160.100851 -294.805098) (xy 160.048877 -294.805098) (xy 159.997542 -294.796968) (xy 159.948112 -294.780907)
			(xy 159.901802 -294.757311) (xy 159.859754 -294.726761) (xy 159.823003 -294.69001) (xy 159.792453 -294.647962)
			(xy 159.768857 -294.601652) (xy 159.752796 -294.552222) (xy 159.744666 -294.500887) (xy 159.454012 -294.500887)
			(xy 159.451858 -294.527727) (xy 159.439246 -294.579202) (xy 159.418585 -294.628005) (xy 159.390404 -294.672889)
			(xy 159.355425 -294.712703) (xy 159.314543 -294.746428) (xy 159.268806 -294.7732) (xy 159.244284 -294.783256)
			(xy 159.236918 -294.78605) (xy 159.225234 -294.795448) (xy 159.220662 -294.802052) (xy 159.216551 -294.808504)
			(xy 159.212019 -294.823108) (xy 159.211772 -294.830754) (xy 159.211772 -296.400807) (xy 159.744666 -296.400807)
			(xy 159.744666 -296.348833) (xy 159.752796 -296.297498) (xy 159.768857 -296.248068) (xy 159.792453 -296.201758)
			(xy 159.823003 -296.15971) (xy 159.859754 -296.122959) (xy 159.901802 -296.092409) (xy 159.948112 -296.068813)
			(xy 159.997542 -296.052752) (xy 160.048877 -296.044622) (xy 160.100851 -296.044622) (xy 160.152186 -296.052752)
			(xy 160.201616 -296.068813) (xy 160.247926 -296.092409) (xy 160.289974 -296.122959) (xy 160.326725 -296.15971)
			(xy 160.357275 -296.201758) (xy 160.380871 -296.248068) (xy 160.396932 -296.297498) (xy 160.405062 -296.348833)
			(xy 160.405572 -296.37482) (xy 160.405062 -296.400807) (xy 161.64484 -296.400807) (xy 161.64484 -296.348833)
			(xy 161.65297 -296.297498) (xy 161.669031 -296.248068) (xy 161.692627 -296.201758) (xy 161.723177 -296.15971)
			(xy 161.759928 -296.122959) (xy 161.801976 -296.092409) (xy 161.848286 -296.068813) (xy 161.897716 -296.052752)
			(xy 161.949051 -296.044622) (xy 162.001025 -296.044622) (xy 162.05236 -296.052752) (xy 162.10179 -296.068813)
			(xy 162.1481 -296.092409) (xy 162.190148 -296.122959) (xy 162.226899 -296.15971) (xy 162.257449 -296.201758)
			(xy 162.281045 -296.248068) (xy 162.297106 -296.297498) (xy 162.305236 -296.348833) (xy 162.305746 -296.37482)
			(xy 162.305236 -296.400807) (xy 162.5948 -296.400807) (xy 162.5948 -296.348833) (xy 162.60293 -296.297498)
			(xy 162.618991 -296.248068) (xy 162.642587 -296.201758) (xy 162.673137 -296.15971) (xy 162.709888 -296.122959)
			(xy 162.751936 -296.092409) (xy 162.798246 -296.068813) (xy 162.847676 -296.052752) (xy 162.899011 -296.044622)
			(xy 162.950985 -296.044622) (xy 163.00232 -296.052752) (xy 163.05175 -296.068813) (xy 163.09806 -296.092409)
			(xy 163.140108 -296.122959) (xy 163.176859 -296.15971) (xy 163.207409 -296.201758) (xy 163.231005 -296.248068)
			(xy 163.247066 -296.297498) (xy 163.255196 -296.348833) (xy 163.255706 -296.37482) (xy 163.255196 -296.400807)
			(xy 163.54476 -296.400807) (xy 163.54476 -296.348833) (xy 163.55289 -296.297498) (xy 163.568951 -296.248068)
			(xy 163.592547 -296.201758) (xy 163.623097 -296.15971) (xy 163.659848 -296.122959) (xy 163.701896 -296.092409)
			(xy 163.748206 -296.068813) (xy 163.797636 -296.052752) (xy 163.848971 -296.044622) (xy 163.900945 -296.044622)
			(xy 163.95228 -296.052752) (xy 164.00171 -296.068813) (xy 164.04802 -296.092409) (xy 164.090068 -296.122959)
			(xy 164.126819 -296.15971) (xy 164.157369 -296.201758) (xy 164.180965 -296.248068) (xy 164.197026 -296.297498)
			(xy 164.205156 -296.348833) (xy 164.205666 -296.37482) (xy 164.205156 -296.400807) (xy 164.49472 -296.400807)
			(xy 164.49472 -296.348833) (xy 164.50285 -296.297498) (xy 164.518911 -296.248068) (xy 164.542507 -296.201758)
			(xy 164.573057 -296.15971) (xy 164.609808 -296.122959) (xy 164.651856 -296.092409) (xy 164.698166 -296.068813)
			(xy 164.747596 -296.052752) (xy 164.798931 -296.044622) (xy 164.850905 -296.044622) (xy 164.90224 -296.052752)
			(xy 164.95167 -296.068813) (xy 164.99798 -296.092409) (xy 165.040028 -296.122959) (xy 165.076779 -296.15971)
			(xy 165.107329 -296.201758) (xy 165.130925 -296.248068) (xy 165.146986 -296.297498) (xy 165.155116 -296.348833)
			(xy 165.155626 -296.37482) (xy 165.155116 -296.400807) (xy 165.44468 -296.400807) (xy 165.44468 -296.348833)
			(xy 165.45281 -296.297498) (xy 165.468871 -296.248068) (xy 165.492467 -296.201758) (xy 165.523017 -296.15971)
			(xy 165.559768 -296.122959) (xy 165.601816 -296.092409) (xy 165.648126 -296.068813) (xy 165.697556 -296.052752)
			(xy 165.748891 -296.044622) (xy 165.800865 -296.044622) (xy 165.8522 -296.052752) (xy 165.90163 -296.068813)
			(xy 165.94794 -296.092409) (xy 165.989988 -296.122959) (xy 166.026739 -296.15971) (xy 166.057289 -296.201758)
			(xy 166.080885 -296.248068) (xy 166.096946 -296.297498) (xy 166.105076 -296.348833) (xy 166.105586 -296.37482)
			(xy 166.105076 -296.400807) (xy 166.394894 -296.400807) (xy 166.394894 -296.348833) (xy 166.403024 -296.297498)
			(xy 166.419085 -296.248068) (xy 166.442681 -296.201758) (xy 166.473231 -296.15971) (xy 166.509982 -296.122959)
			(xy 166.55203 -296.092409) (xy 166.59834 -296.068813) (xy 166.64777 -296.052752) (xy 166.699105 -296.044622)
			(xy 166.751079 -296.044622) (xy 166.802414 -296.052752) (xy 166.851844 -296.068813) (xy 166.898154 -296.092409)
			(xy 166.940202 -296.122959) (xy 166.976953 -296.15971) (xy 167.007503 -296.201758) (xy 167.031099 -296.248068)
			(xy 167.04716 -296.297498) (xy 167.05529 -296.348833) (xy 167.0558 -296.37482) (xy 167.05529 -296.400807)
			(xy 167.344854 -296.400807) (xy 167.344854 -296.348833) (xy 167.352984 -296.297498) (xy 167.369045 -296.248068)
			(xy 167.392641 -296.201758) (xy 167.423191 -296.15971) (xy 167.459942 -296.122959) (xy 167.50199 -296.092409)
			(xy 167.5483 -296.068813) (xy 167.59773 -296.052752) (xy 167.649065 -296.044622) (xy 167.701039 -296.044622)
			(xy 167.752374 -296.052752) (xy 167.801804 -296.068813) (xy 167.848114 -296.092409) (xy 167.890162 -296.122959)
			(xy 167.926913 -296.15971) (xy 167.957463 -296.201758) (xy 167.981059 -296.248068) (xy 167.99712 -296.297498)
			(xy 168.00525 -296.348833) (xy 168.00576 -296.37482) (xy 168.00525 -296.400807) (xy 168.294814 -296.400807)
			(xy 168.294814 -296.348833) (xy 168.302944 -296.297498) (xy 168.319005 -296.248068) (xy 168.342601 -296.201758)
			(xy 168.373151 -296.15971) (xy 168.409902 -296.122959) (xy 168.45195 -296.092409) (xy 168.49826 -296.068813)
			(xy 168.54769 -296.052752) (xy 168.599025 -296.044622) (xy 168.650999 -296.044622) (xy 168.702334 -296.052752)
			(xy 168.751764 -296.068813) (xy 168.798074 -296.092409) (xy 168.840122 -296.122959) (xy 168.876873 -296.15971)
			(xy 168.907423 -296.201758) (xy 168.931019 -296.248068) (xy 168.94708 -296.297498) (xy 168.95521 -296.348833)
			(xy 168.95572 -296.37482) (xy 168.95521 -296.400807) (xy 169.244774 -296.400807) (xy 169.244774 -296.348833)
			(xy 169.252904 -296.297498) (xy 169.268965 -296.248068) (xy 169.292561 -296.201758) (xy 169.323111 -296.15971)
			(xy 169.359862 -296.122959) (xy 169.40191 -296.092409) (xy 169.44822 -296.068813) (xy 169.49765 -296.052752)
			(xy 169.548985 -296.044622) (xy 169.600959 -296.044622) (xy 169.652294 -296.052752) (xy 169.701724 -296.068813)
			(xy 169.748034 -296.092409) (xy 169.790082 -296.122959) (xy 169.826833 -296.15971) (xy 169.857383 -296.201758)
			(xy 169.880979 -296.248068) (xy 169.89704 -296.297498) (xy 169.90517 -296.348833) (xy 169.90568 -296.37482)
			(xy 169.90517 -296.400807) (xy 170.194734 -296.400807) (xy 170.194734 -296.348833) (xy 170.202864 -296.297498)
			(xy 170.218925 -296.248068) (xy 170.242521 -296.201758) (xy 170.273071 -296.15971) (xy 170.309822 -296.122959)
			(xy 170.35187 -296.092409) (xy 170.39818 -296.068813) (xy 170.44761 -296.052752) (xy 170.498945 -296.044622)
			(xy 170.550919 -296.044622) (xy 170.602254 -296.052752) (xy 170.651684 -296.068813) (xy 170.697994 -296.092409)
			(xy 170.740042 -296.122959) (xy 170.776793 -296.15971) (xy 170.807343 -296.201758) (xy 170.830939 -296.248068)
			(xy 170.847 -296.297498) (xy 170.85513 -296.348833) (xy 170.85564 -296.37482) (xy 170.85513 -296.400807)
			(xy 171.144694 -296.400807) (xy 171.144694 -296.348833) (xy 171.152824 -296.297498) (xy 171.168885 -296.248068)
			(xy 171.192481 -296.201758) (xy 171.223031 -296.15971) (xy 171.259782 -296.122959) (xy 171.30183 -296.092409)
			(xy 171.34814 -296.068813) (xy 171.39757 -296.052752) (xy 171.448905 -296.044622) (xy 171.500879 -296.044622)
			(xy 171.552214 -296.052752) (xy 171.601644 -296.068813) (xy 171.647954 -296.092409) (xy 171.690002 -296.122959)
			(xy 171.726753 -296.15971) (xy 171.757303 -296.201758) (xy 171.780899 -296.248068) (xy 171.79696 -296.297498)
			(xy 171.80509 -296.348833) (xy 171.8056 -296.37482) (xy 171.80509 -296.400807) (xy 172.094908 -296.400807)
			(xy 172.094908 -296.348833) (xy 172.103038 -296.297498) (xy 172.119099 -296.248068) (xy 172.142695 -296.201758)
			(xy 172.173245 -296.15971) (xy 172.209996 -296.122959) (xy 172.252044 -296.092409) (xy 172.298354 -296.068813)
			(xy 172.347784 -296.052752) (xy 172.399119 -296.044622) (xy 172.451093 -296.044622) (xy 172.502428 -296.052752)
			(xy 172.551858 -296.068813) (xy 172.598168 -296.092409) (xy 172.640216 -296.122959) (xy 172.676967 -296.15971)
			(xy 172.707517 -296.201758) (xy 172.731113 -296.248068) (xy 172.747174 -296.297498) (xy 172.755304 -296.348833)
			(xy 172.755814 -296.37482) (xy 172.755304 -296.400807) (xy 173.044868 -296.400807) (xy 173.044868 -296.348833)
			(xy 173.052998 -296.297498) (xy 173.069059 -296.248068) (xy 173.092655 -296.201758) (xy 173.123205 -296.15971)
			(xy 173.159956 -296.122959) (xy 173.202004 -296.092409) (xy 173.248314 -296.068813) (xy 173.297744 -296.052752)
			(xy 173.349079 -296.044622) (xy 173.401053 -296.044622) (xy 173.452388 -296.052752) (xy 173.501818 -296.068813)
			(xy 173.548128 -296.092409) (xy 173.590176 -296.122959) (xy 173.626927 -296.15971) (xy 173.657477 -296.201758)
			(xy 173.681073 -296.248068) (xy 173.697134 -296.297498) (xy 173.705264 -296.348833) (xy 173.705774 -296.37482)
			(xy 173.705264 -296.400807) (xy 173.994828 -296.400807) (xy 173.994828 -296.348833) (xy 174.002958 -296.297498)
			(xy 174.019019 -296.248068) (xy 174.042615 -296.201758) (xy 174.073165 -296.15971) (xy 174.109916 -296.122959)
			(xy 174.151964 -296.092409) (xy 174.198274 -296.068813) (xy 174.247704 -296.052752) (xy 174.299039 -296.044622)
			(xy 174.351013 -296.044622) (xy 174.402348 -296.052752) (xy 174.451778 -296.068813) (xy 174.498088 -296.092409)
			(xy 174.540136 -296.122959) (xy 174.576887 -296.15971) (xy 174.607437 -296.201758) (xy 174.631033 -296.248068)
			(xy 174.647094 -296.297498) (xy 174.655224 -296.348833) (xy 174.655734 -296.37482) (xy 174.655224 -296.400807)
			(xy 175.894748 -296.400807) (xy 175.894748 -296.348833) (xy 175.902878 -296.297498) (xy 175.918939 -296.248068)
			(xy 175.942535 -296.201758) (xy 175.973085 -296.15971) (xy 176.009836 -296.122959) (xy 176.051884 -296.092409)
			(xy 176.098194 -296.068813) (xy 176.147624 -296.052752) (xy 176.198959 -296.044622) (xy 176.250933 -296.044622)
			(xy 176.302268 -296.052752) (xy 176.351698 -296.068813) (xy 176.398008 -296.092409) (xy 176.440056 -296.122959)
			(xy 176.476807 -296.15971) (xy 176.507357 -296.201758) (xy 176.530953 -296.248068) (xy 176.547014 -296.297498)
			(xy 176.555144 -296.348833) (xy 176.555654 -296.37482) (xy 176.555144 -296.400807) (xy 176.844708 -296.400807)
			(xy 176.844708 -296.348833) (xy 176.852838 -296.297498) (xy 176.868899 -296.248068) (xy 176.892495 -296.201758)
			(xy 176.923045 -296.15971) (xy 176.959796 -296.122959) (xy 177.001844 -296.092409) (xy 177.048154 -296.068813)
			(xy 177.097584 -296.052752) (xy 177.148919 -296.044622) (xy 177.200893 -296.044622) (xy 177.252228 -296.052752)
			(xy 177.301658 -296.068813) (xy 177.347968 -296.092409) (xy 177.390016 -296.122959) (xy 177.426767 -296.15971)
			(xy 177.457317 -296.201758) (xy 177.480913 -296.248068) (xy 177.496974 -296.297498) (xy 177.505104 -296.348833)
			(xy 177.505614 -296.37482) (xy 177.505104 -296.400807) (xy 177.794668 -296.400807) (xy 177.794668 -296.348833)
			(xy 177.802798 -296.297498) (xy 177.818859 -296.248068) (xy 177.842455 -296.201758) (xy 177.873005 -296.15971)
			(xy 177.909756 -296.122959) (xy 177.951804 -296.092409) (xy 177.998114 -296.068813) (xy 178.047544 -296.052752)
			(xy 178.098879 -296.044622) (xy 178.150853 -296.044622) (xy 178.202188 -296.052752) (xy 178.251618 -296.068813)
			(xy 178.297928 -296.092409) (xy 178.339976 -296.122959) (xy 178.376727 -296.15971) (xy 178.407277 -296.201758)
			(xy 178.430873 -296.248068) (xy 178.446934 -296.297498) (xy 178.455064 -296.348833) (xy 178.455574 -296.37482)
			(xy 178.455064 -296.400807) (xy 178.744882 -296.400807) (xy 178.744882 -296.348833) (xy 178.753012 -296.297498)
			(xy 178.769073 -296.248068) (xy 178.792669 -296.201758) (xy 178.823219 -296.15971) (xy 178.85997 -296.122959)
			(xy 178.902018 -296.092409) (xy 178.948328 -296.068813) (xy 178.997758 -296.052752) (xy 179.049093 -296.044622)
			(xy 179.101067 -296.044622) (xy 179.152402 -296.052752) (xy 179.201832 -296.068813) (xy 179.248142 -296.092409)
			(xy 179.29019 -296.122959) (xy 179.326941 -296.15971) (xy 179.357491 -296.201758) (xy 179.381087 -296.248068)
			(xy 179.397148 -296.297498) (xy 179.405278 -296.348833) (xy 179.405788 -296.37482) (xy 179.405278 -296.400807)
			(xy 179.694842 -296.400807) (xy 179.694842 -296.348833) (xy 179.702972 -296.297498) (xy 179.719033 -296.248068)
			(xy 179.742629 -296.201758) (xy 179.773179 -296.15971) (xy 179.80993 -296.122959) (xy 179.851978 -296.092409)
			(xy 179.898288 -296.068813) (xy 179.947718 -296.052752) (xy 179.999053 -296.044622) (xy 180.051027 -296.044622)
			(xy 180.102362 -296.052752) (xy 180.151792 -296.068813) (xy 180.198102 -296.092409) (xy 180.24015 -296.122959)
			(xy 180.276901 -296.15971) (xy 180.307451 -296.201758) (xy 180.331047 -296.248068) (xy 180.347108 -296.297498)
			(xy 180.355238 -296.348833) (xy 180.355748 -296.37482) (xy 180.355238 -296.400807) (xy 180.644802 -296.400807)
			(xy 180.644802 -296.348833) (xy 180.652932 -296.297498) (xy 180.668993 -296.248068) (xy 180.692589 -296.201758)
			(xy 180.723139 -296.15971) (xy 180.75989 -296.122959) (xy 180.801938 -296.092409) (xy 180.848248 -296.068813)
			(xy 180.897678 -296.052752) (xy 180.949013 -296.044622) (xy 181.000987 -296.044622) (xy 181.052322 -296.052752)
			(xy 181.101752 -296.068813) (xy 181.148062 -296.092409) (xy 181.19011 -296.122959) (xy 181.226861 -296.15971)
			(xy 181.257411 -296.201758) (xy 181.281007 -296.248068) (xy 181.297068 -296.297498) (xy 181.305198 -296.348833)
			(xy 181.305708 -296.37482) (xy 181.305198 -296.400807) (xy 181.594762 -296.400807) (xy 181.594762 -296.348833)
			(xy 181.602892 -296.297498) (xy 181.618953 -296.248068) (xy 181.642549 -296.201758) (xy 181.673099 -296.15971)
			(xy 181.70985 -296.122959) (xy 181.751898 -296.092409) (xy 181.798208 -296.068813) (xy 181.847638 -296.052752)
			(xy 181.898973 -296.044622) (xy 181.950947 -296.044622) (xy 182.002282 -296.052752) (xy 182.051712 -296.068813)
			(xy 182.098022 -296.092409) (xy 182.14007 -296.122959) (xy 182.176821 -296.15971) (xy 182.207371 -296.201758)
			(xy 182.230967 -296.248068) (xy 182.247028 -296.297498) (xy 182.255158 -296.348833) (xy 182.255668 -296.37482)
			(xy 182.255158 -296.400807) (xy 182.544722 -296.400807) (xy 182.544722 -296.348833) (xy 182.552852 -296.297498)
			(xy 182.568913 -296.248068) (xy 182.592509 -296.201758) (xy 182.623059 -296.15971) (xy 182.65981 -296.122959)
			(xy 182.701858 -296.092409) (xy 182.748168 -296.068813) (xy 182.797598 -296.052752) (xy 182.848933 -296.044622)
			(xy 182.900907 -296.044622) (xy 182.952242 -296.052752) (xy 183.001672 -296.068813) (xy 183.047982 -296.092409)
			(xy 183.09003 -296.122959) (xy 183.126781 -296.15971) (xy 183.157331 -296.201758) (xy 183.180927 -296.248068)
			(xy 183.196988 -296.297498) (xy 183.205118 -296.348833) (xy 183.205628 -296.37482) (xy 183.205118 -296.400807)
			(xy 183.494682 -296.400807) (xy 183.494682 -296.348833) (xy 183.502812 -296.297498) (xy 183.518873 -296.248068)
			(xy 183.542469 -296.201758) (xy 183.573019 -296.15971) (xy 183.60977 -296.122959) (xy 183.651818 -296.092409)
			(xy 183.698128 -296.068813) (xy 183.747558 -296.052752) (xy 183.798893 -296.044622) (xy 183.850867 -296.044622)
			(xy 183.902202 -296.052752) (xy 183.951632 -296.068813) (xy 183.997942 -296.092409) (xy 184.03999 -296.122959)
			(xy 184.076741 -296.15971) (xy 184.107291 -296.201758) (xy 184.130887 -296.248068) (xy 184.146948 -296.297498)
			(xy 184.155078 -296.348833) (xy 184.155588 -296.37482) (xy 184.155078 -296.400807) (xy 184.444642 -296.400807)
			(xy 184.444642 -296.348833) (xy 184.452772 -296.297498) (xy 184.468833 -296.248068) (xy 184.492429 -296.201758)
			(xy 184.522979 -296.15971) (xy 184.55973 -296.122959) (xy 184.601778 -296.092409) (xy 184.648088 -296.068813)
			(xy 184.697518 -296.052752) (xy 184.748853 -296.044622) (xy 184.800827 -296.044622) (xy 184.852162 -296.052752)
			(xy 184.901592 -296.068813) (xy 184.947902 -296.092409) (xy 184.98995 -296.122959) (xy 185.026701 -296.15971)
			(xy 185.057251 -296.201758) (xy 185.080847 -296.248068) (xy 185.096908 -296.297498) (xy 185.105038 -296.348833)
			(xy 185.105548 -296.37482) (xy 185.105038 -296.400807) (xy 185.394856 -296.400807) (xy 185.394856 -296.348833)
			(xy 185.402986 -296.297498) (xy 185.419047 -296.248068) (xy 185.442643 -296.201758) (xy 185.473193 -296.15971)
			(xy 185.509944 -296.122959) (xy 185.551992 -296.092409) (xy 185.598302 -296.068813) (xy 185.647732 -296.052752)
			(xy 185.699067 -296.044622) (xy 185.751041 -296.044622) (xy 185.802376 -296.052752) (xy 185.851806 -296.068813)
			(xy 185.898116 -296.092409) (xy 185.940164 -296.122959) (xy 185.976915 -296.15971) (xy 186.007465 -296.201758)
			(xy 186.031061 -296.248068) (xy 186.047122 -296.297498) (xy 186.055252 -296.348833) (xy 186.055762 -296.37482)
			(xy 186.055252 -296.400807) (xy 186.047122 -296.452142) (xy 186.031061 -296.501572) (xy 186.007465 -296.547882)
			(xy 185.976915 -296.58993) (xy 185.940164 -296.626681) (xy 185.898116 -296.657231) (xy 185.851806 -296.680827)
			(xy 185.802376 -296.696888) (xy 185.751041 -296.705018) (xy 185.699067 -296.705018) (xy 185.647732 -296.696888)
			(xy 185.598302 -296.680827) (xy 185.551992 -296.657231) (xy 185.509944 -296.626681) (xy 185.473193 -296.58993)
			(xy 185.442643 -296.547882) (xy 185.419047 -296.501572) (xy 185.402986 -296.452142) (xy 185.394856 -296.400807)
			(xy 185.105038 -296.400807) (xy 185.096908 -296.452142) (xy 185.080847 -296.501572) (xy 185.057251 -296.547882)
			(xy 185.026701 -296.58993) (xy 184.98995 -296.626681) (xy 184.947902 -296.657231) (xy 184.901592 -296.680827)
			(xy 184.852162 -296.696888) (xy 184.800827 -296.705018) (xy 184.748853 -296.705018) (xy 184.697518 -296.696888)
			(xy 184.648088 -296.680827) (xy 184.601778 -296.657231) (xy 184.55973 -296.626681) (xy 184.522979 -296.58993)
			(xy 184.492429 -296.547882) (xy 184.468833 -296.501572) (xy 184.452772 -296.452142) (xy 184.444642 -296.400807)
			(xy 184.155078 -296.400807) (xy 184.146948 -296.452142) (xy 184.130887 -296.501572) (xy 184.107291 -296.547882)
			(xy 184.076741 -296.58993) (xy 184.03999 -296.626681) (xy 183.997942 -296.657231) (xy 183.951632 -296.680827)
			(xy 183.902202 -296.696888) (xy 183.850867 -296.705018) (xy 183.798893 -296.705018) (xy 183.747558 -296.696888)
			(xy 183.698128 -296.680827) (xy 183.651818 -296.657231) (xy 183.60977 -296.626681) (xy 183.573019 -296.58993)
			(xy 183.542469 -296.547882) (xy 183.518873 -296.501572) (xy 183.502812 -296.452142) (xy 183.494682 -296.400807)
			(xy 183.205118 -296.400807) (xy 183.196988 -296.452142) (xy 183.180927 -296.501572) (xy 183.157331 -296.547882)
			(xy 183.126781 -296.58993) (xy 183.09003 -296.626681) (xy 183.047982 -296.657231) (xy 183.001672 -296.680827)
			(xy 182.952242 -296.696888) (xy 182.900907 -296.705018) (xy 182.848933 -296.705018) (xy 182.797598 -296.696888)
			(xy 182.748168 -296.680827) (xy 182.701858 -296.657231) (xy 182.65981 -296.626681) (xy 182.623059 -296.58993)
			(xy 182.592509 -296.547882) (xy 182.568913 -296.501572) (xy 182.552852 -296.452142) (xy 182.544722 -296.400807)
			(xy 182.255158 -296.400807) (xy 182.247028 -296.452142) (xy 182.230967 -296.501572) (xy 182.207371 -296.547882)
			(xy 182.176821 -296.58993) (xy 182.14007 -296.626681) (xy 182.098022 -296.657231) (xy 182.051712 -296.680827)
			(xy 182.002282 -296.696888) (xy 181.950947 -296.705018) (xy 181.898973 -296.705018) (xy 181.847638 -296.696888)
			(xy 181.798208 -296.680827) (xy 181.751898 -296.657231) (xy 181.70985 -296.626681) (xy 181.673099 -296.58993)
			(xy 181.642549 -296.547882) (xy 181.618953 -296.501572) (xy 181.602892 -296.452142) (xy 181.594762 -296.400807)
			(xy 181.305198 -296.400807) (xy 181.297068 -296.452142) (xy 181.281007 -296.501572) (xy 181.257411 -296.547882)
			(xy 181.226861 -296.58993) (xy 181.19011 -296.626681) (xy 181.148062 -296.657231) (xy 181.101752 -296.680827)
			(xy 181.052322 -296.696888) (xy 181.000987 -296.705018) (xy 180.949013 -296.705018) (xy 180.897678 -296.696888)
			(xy 180.848248 -296.680827) (xy 180.801938 -296.657231) (xy 180.75989 -296.626681) (xy 180.723139 -296.58993)
			(xy 180.692589 -296.547882) (xy 180.668993 -296.501572) (xy 180.652932 -296.452142) (xy 180.644802 -296.400807)
			(xy 180.355238 -296.400807) (xy 180.347108 -296.452142) (xy 180.331047 -296.501572) (xy 180.307451 -296.547882)
			(xy 180.276901 -296.58993) (xy 180.24015 -296.626681) (xy 180.198102 -296.657231) (xy 180.151792 -296.680827)
			(xy 180.102362 -296.696888) (xy 180.051027 -296.705018) (xy 179.999053 -296.705018) (xy 179.947718 -296.696888)
			(xy 179.898288 -296.680827) (xy 179.851978 -296.657231) (xy 179.80993 -296.626681) (xy 179.773179 -296.58993)
			(xy 179.742629 -296.547882) (xy 179.719033 -296.501572) (xy 179.702972 -296.452142) (xy 179.694842 -296.400807)
			(xy 179.405278 -296.400807) (xy 179.397148 -296.452142) (xy 179.381087 -296.501572) (xy 179.357491 -296.547882)
			(xy 179.326941 -296.58993) (xy 179.29019 -296.626681) (xy 179.248142 -296.657231) (xy 179.201832 -296.680827)
			(xy 179.152402 -296.696888) (xy 179.101067 -296.705018) (xy 179.049093 -296.705018) (xy 178.997758 -296.696888)
			(xy 178.948328 -296.680827) (xy 178.902018 -296.657231) (xy 178.85997 -296.626681) (xy 178.823219 -296.58993)
			(xy 178.792669 -296.547882) (xy 178.769073 -296.501572) (xy 178.753012 -296.452142) (xy 178.744882 -296.400807)
			(xy 178.455064 -296.400807) (xy 178.446934 -296.452142) (xy 178.430873 -296.501572) (xy 178.407277 -296.547882)
			(xy 178.376727 -296.58993) (xy 178.339976 -296.626681) (xy 178.297928 -296.657231) (xy 178.251618 -296.680827)
			(xy 178.202188 -296.696888) (xy 178.150853 -296.705018) (xy 178.098879 -296.705018) (xy 178.047544 -296.696888)
			(xy 177.998114 -296.680827) (xy 177.951804 -296.657231) (xy 177.909756 -296.626681) (xy 177.873005 -296.58993)
			(xy 177.842455 -296.547882) (xy 177.818859 -296.501572) (xy 177.802798 -296.452142) (xy 177.794668 -296.400807)
			(xy 177.505104 -296.400807) (xy 177.496974 -296.452142) (xy 177.480913 -296.501572) (xy 177.457317 -296.547882)
			(xy 177.426767 -296.58993) (xy 177.390016 -296.626681) (xy 177.347968 -296.657231) (xy 177.301658 -296.680827)
			(xy 177.252228 -296.696888) (xy 177.200893 -296.705018) (xy 177.148919 -296.705018) (xy 177.097584 -296.696888)
			(xy 177.048154 -296.680827) (xy 177.001844 -296.657231) (xy 176.959796 -296.626681) (xy 176.923045 -296.58993)
			(xy 176.892495 -296.547882) (xy 176.868899 -296.501572) (xy 176.852838 -296.452142) (xy 176.844708 -296.400807)
			(xy 176.555144 -296.400807) (xy 176.547014 -296.452142) (xy 176.530953 -296.501572) (xy 176.507357 -296.547882)
			(xy 176.476807 -296.58993) (xy 176.440056 -296.626681) (xy 176.398008 -296.657231) (xy 176.351698 -296.680827)
			(xy 176.302268 -296.696888) (xy 176.250933 -296.705018) (xy 176.198959 -296.705018) (xy 176.147624 -296.696888)
			(xy 176.098194 -296.680827) (xy 176.051884 -296.657231) (xy 176.009836 -296.626681) (xy 175.973085 -296.58993)
			(xy 175.942535 -296.547882) (xy 175.918939 -296.501572) (xy 175.902878 -296.452142) (xy 175.894748 -296.400807)
			(xy 174.655224 -296.400807) (xy 174.647094 -296.452142) (xy 174.631033 -296.501572) (xy 174.607437 -296.547882)
			(xy 174.576887 -296.58993) (xy 174.540136 -296.626681) (xy 174.498088 -296.657231) (xy 174.451778 -296.680827)
			(xy 174.402348 -296.696888) (xy 174.351013 -296.705018) (xy 174.299039 -296.705018) (xy 174.247704 -296.696888)
			(xy 174.198274 -296.680827) (xy 174.151964 -296.657231) (xy 174.109916 -296.626681) (xy 174.073165 -296.58993)
			(xy 174.042615 -296.547882) (xy 174.019019 -296.501572) (xy 174.002958 -296.452142) (xy 173.994828 -296.400807)
			(xy 173.705264 -296.400807) (xy 173.697134 -296.452142) (xy 173.681073 -296.501572) (xy 173.657477 -296.547882)
			(xy 173.626927 -296.58993) (xy 173.590176 -296.626681) (xy 173.548128 -296.657231) (xy 173.501818 -296.680827)
			(xy 173.452388 -296.696888) (xy 173.401053 -296.705018) (xy 173.349079 -296.705018) (xy 173.297744 -296.696888)
			(xy 173.248314 -296.680827) (xy 173.202004 -296.657231) (xy 173.159956 -296.626681) (xy 173.123205 -296.58993)
			(xy 173.092655 -296.547882) (xy 173.069059 -296.501572) (xy 173.052998 -296.452142) (xy 173.044868 -296.400807)
			(xy 172.755304 -296.400807) (xy 172.747174 -296.452142) (xy 172.731113 -296.501572) (xy 172.707517 -296.547882)
			(xy 172.676967 -296.58993) (xy 172.640216 -296.626681) (xy 172.598168 -296.657231) (xy 172.551858 -296.680827)
			(xy 172.502428 -296.696888) (xy 172.451093 -296.705018) (xy 172.399119 -296.705018) (xy 172.347784 -296.696888)
			(xy 172.298354 -296.680827) (xy 172.252044 -296.657231) (xy 172.209996 -296.626681) (xy 172.173245 -296.58993)
			(xy 172.142695 -296.547882) (xy 172.119099 -296.501572) (xy 172.103038 -296.452142) (xy 172.094908 -296.400807)
			(xy 171.80509 -296.400807) (xy 171.79696 -296.452142) (xy 171.780899 -296.501572) (xy 171.757303 -296.547882)
			(xy 171.726753 -296.58993) (xy 171.690002 -296.626681) (xy 171.647954 -296.657231) (xy 171.601644 -296.680827)
			(xy 171.552214 -296.696888) (xy 171.500879 -296.705018) (xy 171.448905 -296.705018) (xy 171.39757 -296.696888)
			(xy 171.34814 -296.680827) (xy 171.30183 -296.657231) (xy 171.259782 -296.626681) (xy 171.223031 -296.58993)
			(xy 171.192481 -296.547882) (xy 171.168885 -296.501572) (xy 171.152824 -296.452142) (xy 171.144694 -296.400807)
			(xy 170.85513 -296.400807) (xy 170.847 -296.452142) (xy 170.830939 -296.501572) (xy 170.807343 -296.547882)
			(xy 170.776793 -296.58993) (xy 170.740042 -296.626681) (xy 170.697994 -296.657231) (xy 170.651684 -296.680827)
			(xy 170.602254 -296.696888) (xy 170.550919 -296.705018) (xy 170.498945 -296.705018) (xy 170.44761 -296.696888)
			(xy 170.39818 -296.680827) (xy 170.35187 -296.657231) (xy 170.309822 -296.626681) (xy 170.273071 -296.58993)
			(xy 170.242521 -296.547882) (xy 170.218925 -296.501572) (xy 170.202864 -296.452142) (xy 170.194734 -296.400807)
			(xy 169.90517 -296.400807) (xy 169.89704 -296.452142) (xy 169.880979 -296.501572) (xy 169.857383 -296.547882)
			(xy 169.826833 -296.58993) (xy 169.790082 -296.626681) (xy 169.748034 -296.657231) (xy 169.701724 -296.680827)
			(xy 169.652294 -296.696888) (xy 169.600959 -296.705018) (xy 169.548985 -296.705018) (xy 169.49765 -296.696888)
			(xy 169.44822 -296.680827) (xy 169.40191 -296.657231) (xy 169.359862 -296.626681) (xy 169.323111 -296.58993)
			(xy 169.292561 -296.547882) (xy 169.268965 -296.501572) (xy 169.252904 -296.452142) (xy 169.244774 -296.400807)
			(xy 168.95521 -296.400807) (xy 168.94708 -296.452142) (xy 168.931019 -296.501572) (xy 168.907423 -296.547882)
			(xy 168.876873 -296.58993) (xy 168.840122 -296.626681) (xy 168.798074 -296.657231) (xy 168.751764 -296.680827)
			(xy 168.702334 -296.696888) (xy 168.650999 -296.705018) (xy 168.599025 -296.705018) (xy 168.54769 -296.696888)
			(xy 168.49826 -296.680827) (xy 168.45195 -296.657231) (xy 168.409902 -296.626681) (xy 168.373151 -296.58993)
			(xy 168.342601 -296.547882) (xy 168.319005 -296.501572) (xy 168.302944 -296.452142) (xy 168.294814 -296.400807)
			(xy 168.00525 -296.400807) (xy 167.99712 -296.452142) (xy 167.981059 -296.501572) (xy 167.957463 -296.547882)
			(xy 167.926913 -296.58993) (xy 167.890162 -296.626681) (xy 167.848114 -296.657231) (xy 167.801804 -296.680827)
			(xy 167.752374 -296.696888) (xy 167.701039 -296.705018) (xy 167.649065 -296.705018) (xy 167.59773 -296.696888)
			(xy 167.5483 -296.680827) (xy 167.50199 -296.657231) (xy 167.459942 -296.626681) (xy 167.423191 -296.58993)
			(xy 167.392641 -296.547882) (xy 167.369045 -296.501572) (xy 167.352984 -296.452142) (xy 167.344854 -296.400807)
			(xy 167.05529 -296.400807) (xy 167.04716 -296.452142) (xy 167.031099 -296.501572) (xy 167.007503 -296.547882)
			(xy 166.976953 -296.58993) (xy 166.940202 -296.626681) (xy 166.898154 -296.657231) (xy 166.851844 -296.680827)
			(xy 166.802414 -296.696888) (xy 166.751079 -296.705018) (xy 166.699105 -296.705018) (xy 166.64777 -296.696888)
			(xy 166.59834 -296.680827) (xy 166.55203 -296.657231) (xy 166.509982 -296.626681) (xy 166.473231 -296.58993)
			(xy 166.442681 -296.547882) (xy 166.419085 -296.501572) (xy 166.403024 -296.452142) (xy 166.394894 -296.400807)
			(xy 166.105076 -296.400807) (xy 166.096946 -296.452142) (xy 166.080885 -296.501572) (xy 166.057289 -296.547882)
			(xy 166.026739 -296.58993) (xy 165.989988 -296.626681) (xy 165.94794 -296.657231) (xy 165.90163 -296.680827)
			(xy 165.8522 -296.696888) (xy 165.800865 -296.705018) (xy 165.748891 -296.705018) (xy 165.697556 -296.696888)
			(xy 165.648126 -296.680827) (xy 165.601816 -296.657231) (xy 165.559768 -296.626681) (xy 165.523017 -296.58993)
			(xy 165.492467 -296.547882) (xy 165.468871 -296.501572) (xy 165.45281 -296.452142) (xy 165.44468 -296.400807)
			(xy 165.155116 -296.400807) (xy 165.146986 -296.452142) (xy 165.130925 -296.501572) (xy 165.107329 -296.547882)
			(xy 165.076779 -296.58993) (xy 165.040028 -296.626681) (xy 164.99798 -296.657231) (xy 164.95167 -296.680827)
			(xy 164.90224 -296.696888) (xy 164.850905 -296.705018) (xy 164.798931 -296.705018) (xy 164.747596 -296.696888)
			(xy 164.698166 -296.680827) (xy 164.651856 -296.657231) (xy 164.609808 -296.626681) (xy 164.573057 -296.58993)
			(xy 164.542507 -296.547882) (xy 164.518911 -296.501572) (xy 164.50285 -296.452142) (xy 164.49472 -296.400807)
			(xy 164.205156 -296.400807) (xy 164.197026 -296.452142) (xy 164.180965 -296.501572) (xy 164.157369 -296.547882)
			(xy 164.126819 -296.58993) (xy 164.090068 -296.626681) (xy 164.04802 -296.657231) (xy 164.00171 -296.680827)
			(xy 163.95228 -296.696888) (xy 163.900945 -296.705018) (xy 163.848971 -296.705018) (xy 163.797636 -296.696888)
			(xy 163.748206 -296.680827) (xy 163.701896 -296.657231) (xy 163.659848 -296.626681) (xy 163.623097 -296.58993)
			(xy 163.592547 -296.547882) (xy 163.568951 -296.501572) (xy 163.55289 -296.452142) (xy 163.54476 -296.400807)
			(xy 163.255196 -296.400807) (xy 163.247066 -296.452142) (xy 163.231005 -296.501572) (xy 163.207409 -296.547882)
			(xy 163.176859 -296.58993) (xy 163.140108 -296.626681) (xy 163.09806 -296.657231) (xy 163.05175 -296.680827)
			(xy 163.00232 -296.696888) (xy 162.950985 -296.705018) (xy 162.899011 -296.705018) (xy 162.847676 -296.696888)
			(xy 162.798246 -296.680827) (xy 162.751936 -296.657231) (xy 162.709888 -296.626681) (xy 162.673137 -296.58993)
			(xy 162.642587 -296.547882) (xy 162.618991 -296.501572) (xy 162.60293 -296.452142) (xy 162.5948 -296.400807)
			(xy 162.305236 -296.400807) (xy 162.297106 -296.452142) (xy 162.281045 -296.501572) (xy 162.257449 -296.547882)
			(xy 162.226899 -296.58993) (xy 162.190148 -296.626681) (xy 162.1481 -296.657231) (xy 162.10179 -296.680827)
			(xy 162.05236 -296.696888) (xy 162.001025 -296.705018) (xy 161.949051 -296.705018) (xy 161.897716 -296.696888)
			(xy 161.848286 -296.680827) (xy 161.801976 -296.657231) (xy 161.759928 -296.626681) (xy 161.723177 -296.58993)
			(xy 161.692627 -296.547882) (xy 161.669031 -296.501572) (xy 161.65297 -296.452142) (xy 161.64484 -296.400807)
			(xy 160.405062 -296.400807) (xy 160.396932 -296.452142) (xy 160.380871 -296.501572) (xy 160.357275 -296.547882)
			(xy 160.326725 -296.58993) (xy 160.289974 -296.626681) (xy 160.247926 -296.657231) (xy 160.201616 -296.680827)
			(xy 160.152186 -296.696888) (xy 160.100851 -296.705018) (xy 160.048877 -296.705018) (xy 159.997542 -296.696888)
			(xy 159.948112 -296.680827) (xy 159.901802 -296.657231) (xy 159.859754 -296.626681) (xy 159.823003 -296.58993)
			(xy 159.792453 -296.547882) (xy 159.768857 -296.501572) (xy 159.752796 -296.452142) (xy 159.744666 -296.400807)
			(xy 159.211772 -296.400807) (xy 159.211772 -296.950384) (xy 159.212243 -296.960256) (xy 159.2197 -296.978541)
			(xy 159.22625 -296.985944) (xy 159.226504 -296.986198) (xy 159.60852 -297.368214) (xy 159.613538 -297.372943)
			(xy 159.625516 -297.379764) (xy 159.632142 -297.381676) (xy 159.645096 -297.384724) (xy 159.669226 -297.378628)
			(xy 159.678878 -297.369992) (xy 159.736536 -297.317922) (xy 159.744918 -297.301412) (xy 159.74568 -297.29176)
			(xy 159.748733 -297.266325) (xy 159.761679 -297.216761) (xy 159.782109 -297.169785) (xy 159.809535 -297.126519)
			(xy 159.843301 -297.087996) (xy 159.882602 -297.055139) (xy 159.926497 -297.028731) (xy 159.973938 -297.009405)
			(xy 160.023791 -296.997621) (xy 160.074864 -296.993661) (xy 160.125937 -296.997621) (xy 160.17579 -297.009405)
			(xy 160.223231 -297.028731) (xy 160.267126 -297.055139) (xy 160.306427 -297.087996) (xy 160.340193 -297.126519)
			(xy 160.367619 -297.169785) (xy 160.388049 -297.216761) (xy 160.400995 -297.266325) (xy 160.404048 -297.29176)
			(xy 160.40481 -297.301412) (xy 160.413192 -297.317922) (xy 160.47085 -297.369992) (xy 160.478078 -297.376076)
			(xy 160.495698 -297.382853) (xy 160.50514 -297.3832) (xy 160.604454 -297.3832) (xy 160.62198 -297.376342)
			(xy 160.629092 -297.369992) (xy 160.68675 -297.317922) (xy 160.695132 -297.301412) (xy 160.695894 -297.29176)
			(xy 160.698947 -297.266325) (xy 160.711893 -297.216761) (xy 160.732323 -297.169785) (xy 160.759749 -297.126519)
			(xy 160.793515 -297.087996) (xy 160.832816 -297.055139) (xy 160.876711 -297.028731) (xy 160.924152 -297.009405)
			(xy 160.974005 -296.997621) (xy 161.025078 -296.993661) (xy 161.076151 -296.997621) (xy 161.126004 -297.009405)
			(xy 161.173445 -297.028731) (xy 161.21734 -297.055139) (xy 161.256641 -297.087996) (xy 161.290407 -297.126519)
			(xy 161.317833 -297.169785) (xy 161.338263 -297.216761) (xy 161.351209 -297.266325) (xy 161.354262 -297.29176)
			(xy 161.355024 -297.301412) (xy 161.363406 -297.317922) (xy 161.421064 -297.369992) (xy 161.428293 -297.376074)
			(xy 161.445913 -297.382847) (xy 161.455354 -297.3832) (xy 161.554414 -297.3832) (xy 161.57194 -297.376342)
			(xy 161.579052 -297.369992) (xy 161.63671 -297.317922) (xy 161.645092 -297.301412) (xy 161.645854 -297.29176)
			(xy 161.649111 -297.264912) (xy 161.663231 -297.212708) (xy 161.685649 -297.163494) (xy 161.715767 -297.118579)
			(xy 161.752786 -297.079156) (xy 161.795721 -297.046274) (xy 161.84343 -297.020809) (xy 161.894643 -297.003437)
			(xy 161.947999 -296.994621) (xy 161.975038 -296.994072) (xy 162.001024 -296.994584) (xy 162.052355 -297.00272)
			(xy 162.101782 -297.018784) (xy 162.148087 -297.042381) (xy 162.190132 -297.072931) (xy 162.22688 -297.109682)
			(xy 162.257428 -297.151728) (xy 162.281023 -297.198035) (xy 162.297085 -297.247463) (xy 162.305217 -297.298794)
			(xy 162.305746 -297.32478) (xy 162.305299 -297.349641) (xy 162.305129 -297.350767) (xy 162.5948 -297.350767)
			(xy 162.5948 -297.298793) (xy 162.60293 -297.247458) (xy 162.618991 -297.198028) (xy 162.642587 -297.151718)
			(xy 162.673137 -297.10967) (xy 162.709888 -297.072919) (xy 162.751936 -297.042369) (xy 162.798246 -297.018773)
			(xy 162.847676 -297.002712) (xy 162.899011 -296.994582) (xy 162.950985 -296.994582) (xy 163.00232 -297.002712)
			(xy 163.05175 -297.018773) (xy 163.09806 -297.042369) (xy 163.140108 -297.072919) (xy 163.176859 -297.10967)
			(xy 163.207409 -297.151718) (xy 163.231005 -297.198028) (xy 163.247066 -297.247458) (xy 163.255196 -297.298793)
			(xy 163.255706 -297.32478) (xy 163.255196 -297.350767) (xy 163.54476 -297.350767) (xy 163.54476 -297.298793)
			(xy 163.55289 -297.247458) (xy 163.568951 -297.198028) (xy 163.592547 -297.151718) (xy 163.623097 -297.10967)
			(xy 163.659848 -297.072919) (xy 163.701896 -297.042369) (xy 163.748206 -297.018773) (xy 163.797636 -297.002712)
			(xy 163.848971 -296.994582) (xy 163.900945 -296.994582) (xy 163.95228 -297.002712) (xy 164.00171 -297.018773)
			(xy 164.04802 -297.042369) (xy 164.090068 -297.072919) (xy 164.126819 -297.10967) (xy 164.157369 -297.151718)
			(xy 164.180965 -297.198028) (xy 164.197026 -297.247458) (xy 164.205156 -297.298793) (xy 164.205666 -297.32478)
			(xy 164.205156 -297.350767) (xy 164.49472 -297.350767) (xy 164.49472 -297.298793) (xy 164.50285 -297.247458)
			(xy 164.518911 -297.198028) (xy 164.542507 -297.151718) (xy 164.573057 -297.10967) (xy 164.609808 -297.072919)
			(xy 164.651856 -297.042369) (xy 164.698166 -297.018773) (xy 164.747596 -297.002712) (xy 164.798931 -296.994582)
			(xy 164.850905 -296.994582) (xy 164.90224 -297.002712) (xy 164.95167 -297.018773) (xy 164.99798 -297.042369)
			(xy 165.040028 -297.072919) (xy 165.076779 -297.10967) (xy 165.107329 -297.151718) (xy 165.130925 -297.198028)
			(xy 165.146986 -297.247458) (xy 165.155116 -297.298793) (xy 165.155626 -297.32478) (xy 165.155116 -297.350767)
			(xy 165.44468 -297.350767) (xy 165.44468 -297.298793) (xy 165.45281 -297.247458) (xy 165.468871 -297.198028)
			(xy 165.492467 -297.151718) (xy 165.523017 -297.10967) (xy 165.559768 -297.072919) (xy 165.601816 -297.042369)
			(xy 165.648126 -297.018773) (xy 165.697556 -297.002712) (xy 165.748891 -296.994582) (xy 165.800865 -296.994582)
			(xy 165.8522 -297.002712) (xy 165.90163 -297.018773) (xy 165.94794 -297.042369) (xy 165.989988 -297.072919)
			(xy 166.026739 -297.10967) (xy 166.057289 -297.151718) (xy 166.080885 -297.198028) (xy 166.096946 -297.247458)
			(xy 166.105076 -297.298793) (xy 166.105586 -297.32478) (xy 166.105076 -297.350767) (xy 166.394894 -297.350767)
			(xy 166.394894 -297.298793) (xy 166.403024 -297.247458) (xy 166.419085 -297.198028) (xy 166.442681 -297.151718)
			(xy 166.473231 -297.10967) (xy 166.509982 -297.072919) (xy 166.55203 -297.042369) (xy 166.59834 -297.018773)
			(xy 166.64777 -297.002712) (xy 166.699105 -296.994582) (xy 166.751079 -296.994582) (xy 166.802414 -297.002712)
			(xy 166.851844 -297.018773) (xy 166.898154 -297.042369) (xy 166.940202 -297.072919) (xy 166.976953 -297.10967)
			(xy 167.007503 -297.151718) (xy 167.031099 -297.198028) (xy 167.04716 -297.247458) (xy 167.05529 -297.298793)
			(xy 167.0558 -297.32478) (xy 167.05529 -297.350767) (xy 167.344854 -297.350767) (xy 167.344854 -297.298793)
			(xy 167.352984 -297.247458) (xy 167.369045 -297.198028) (xy 167.392641 -297.151718) (xy 167.423191 -297.10967)
			(xy 167.459942 -297.072919) (xy 167.50199 -297.042369) (xy 167.5483 -297.018773) (xy 167.59773 -297.002712)
			(xy 167.649065 -296.994582) (xy 167.701039 -296.994582) (xy 167.752374 -297.002712) (xy 167.801804 -297.018773)
			(xy 167.848114 -297.042369) (xy 167.890162 -297.072919) (xy 167.926913 -297.10967) (xy 167.957463 -297.151718)
			(xy 167.981059 -297.198028) (xy 167.99712 -297.247458) (xy 168.00525 -297.298793) (xy 168.00576 -297.32478)
			(xy 168.00525 -297.350767) (xy 168.294814 -297.350767) (xy 168.294814 -297.298793) (xy 168.302944 -297.247458)
			(xy 168.319005 -297.198028) (xy 168.342601 -297.151718) (xy 168.373151 -297.10967) (xy 168.409902 -297.072919)
			(xy 168.45195 -297.042369) (xy 168.49826 -297.018773) (xy 168.54769 -297.002712) (xy 168.599025 -296.994582)
			(xy 168.650999 -296.994582) (xy 168.702334 -297.002712) (xy 168.751764 -297.018773) (xy 168.798074 -297.042369)
			(xy 168.840122 -297.072919) (xy 168.876873 -297.10967) (xy 168.907423 -297.151718) (xy 168.931019 -297.198028)
			(xy 168.94708 -297.247458) (xy 168.95521 -297.298793) (xy 168.95572 -297.32478) (xy 168.95521 -297.350767)
			(xy 169.244774 -297.350767) (xy 169.244774 -297.298793) (xy 169.252904 -297.247458) (xy 169.268965 -297.198028)
			(xy 169.292561 -297.151718) (xy 169.323111 -297.10967) (xy 169.359862 -297.072919) (xy 169.40191 -297.042369)
			(xy 169.44822 -297.018773) (xy 169.49765 -297.002712) (xy 169.548985 -296.994582) (xy 169.600959 -296.994582)
			(xy 169.652294 -297.002712) (xy 169.701724 -297.018773) (xy 169.748034 -297.042369) (xy 169.790082 -297.072919)
			(xy 169.826833 -297.10967) (xy 169.857383 -297.151718) (xy 169.880979 -297.198028) (xy 169.89704 -297.247458)
			(xy 169.90517 -297.298793) (xy 169.90568 -297.32478) (xy 169.90517 -297.350767) (xy 170.194734 -297.350767)
			(xy 170.194734 -297.298793) (xy 170.202864 -297.247458) (xy 170.218925 -297.198028) (xy 170.242521 -297.151718)
			(xy 170.273071 -297.10967) (xy 170.309822 -297.072919) (xy 170.35187 -297.042369) (xy 170.39818 -297.018773)
			(xy 170.44761 -297.002712) (xy 170.498945 -296.994582) (xy 170.550919 -296.994582) (xy 170.602254 -297.002712)
			(xy 170.651684 -297.018773) (xy 170.697994 -297.042369) (xy 170.740042 -297.072919) (xy 170.776793 -297.10967)
			(xy 170.807343 -297.151718) (xy 170.830939 -297.198028) (xy 170.847 -297.247458) (xy 170.85513 -297.298793)
			(xy 170.85564 -297.32478) (xy 170.85513 -297.350767) (xy 171.144694 -297.350767) (xy 171.144694 -297.298793)
			(xy 171.152824 -297.247458) (xy 171.168885 -297.198028) (xy 171.192481 -297.151718) (xy 171.223031 -297.10967)
			(xy 171.259782 -297.072919) (xy 171.30183 -297.042369) (xy 171.34814 -297.018773) (xy 171.39757 -297.002712)
			(xy 171.448905 -296.994582) (xy 171.500879 -296.994582) (xy 171.552214 -297.002712) (xy 171.601644 -297.018773)
			(xy 171.647954 -297.042369) (xy 171.690002 -297.072919) (xy 171.726753 -297.10967) (xy 171.757303 -297.151718)
			(xy 171.780899 -297.198028) (xy 171.79696 -297.247458) (xy 171.80509 -297.298793) (xy 171.8056 -297.32478)
			(xy 171.80509 -297.350767) (xy 172.094654 -297.350767) (xy 172.094654 -297.298793) (xy 172.102784 -297.247458)
			(xy 172.118845 -297.198028) (xy 172.142441 -297.151718) (xy 172.172991 -297.10967) (xy 172.209742 -297.072919)
			(xy 172.25179 -297.042369) (xy 172.2981 -297.018773) (xy 172.34753 -297.002712) (xy 172.398865 -296.994582)
			(xy 172.450839 -296.994582) (xy 172.502174 -297.002712) (xy 172.551604 -297.018773) (xy 172.597914 -297.042369)
			(xy 172.639962 -297.072919) (xy 172.676713 -297.10967) (xy 172.707263 -297.151718) (xy 172.730859 -297.198028)
			(xy 172.74692 -297.247458) (xy 172.75505 -297.298793) (xy 172.75556 -297.32478) (xy 172.75505 -297.350767)
			(xy 173.044868 -297.350767) (xy 173.044868 -297.298793) (xy 173.052998 -297.247458) (xy 173.069059 -297.198028)
			(xy 173.092655 -297.151718) (xy 173.123205 -297.10967) (xy 173.159956 -297.072919) (xy 173.202004 -297.042369)
			(xy 173.248314 -297.018773) (xy 173.297744 -297.002712) (xy 173.349079 -296.994582) (xy 173.401053 -296.994582)
			(xy 173.452388 -297.002712) (xy 173.501818 -297.018773) (xy 173.548128 -297.042369) (xy 173.590176 -297.072919)
			(xy 173.626927 -297.10967) (xy 173.657477 -297.151718) (xy 173.681073 -297.198028) (xy 173.697134 -297.247458)
			(xy 173.705264 -297.298793) (xy 173.705774 -297.32478) (xy 173.705264 -297.350767) (xy 173.994828 -297.350767)
			(xy 173.994828 -297.298793) (xy 174.002958 -297.247458) (xy 174.019019 -297.198028) (xy 174.042615 -297.151718)
			(xy 174.073165 -297.10967) (xy 174.109916 -297.072919) (xy 174.151964 -297.042369) (xy 174.198274 -297.018773)
			(xy 174.247704 -297.002712) (xy 174.299039 -296.994582) (xy 174.351013 -296.994582) (xy 174.402348 -297.002712)
			(xy 174.451778 -297.018773) (xy 174.498088 -297.042369) (xy 174.540136 -297.072919) (xy 174.576887 -297.10967)
			(xy 174.607437 -297.151718) (xy 174.631033 -297.198028) (xy 174.647094 -297.247458) (xy 174.655224 -297.298793)
			(xy 174.655734 -297.32478) (xy 174.655224 -297.350767) (xy 175.894748 -297.350767) (xy 175.894748 -297.298793)
			(xy 175.902878 -297.247458) (xy 175.918939 -297.198028) (xy 175.942535 -297.151718) (xy 175.973085 -297.10967)
			(xy 176.009836 -297.072919) (xy 176.051884 -297.042369) (xy 176.098194 -297.018773) (xy 176.147624 -297.002712)
			(xy 176.198959 -296.994582) (xy 176.250933 -296.994582) (xy 176.302268 -297.002712) (xy 176.351698 -297.018773)
			(xy 176.398008 -297.042369) (xy 176.440056 -297.072919) (xy 176.476807 -297.10967) (xy 176.507357 -297.151718)
			(xy 176.530953 -297.198028) (xy 176.547014 -297.247458) (xy 176.555144 -297.298793) (xy 176.555654 -297.32478)
			(xy 176.555144 -297.350767) (xy 176.844708 -297.350767) (xy 176.844708 -297.298793) (xy 176.852838 -297.247458)
			(xy 176.868899 -297.198028) (xy 176.892495 -297.151718) (xy 176.923045 -297.10967) (xy 176.959796 -297.072919)
			(xy 177.001844 -297.042369) (xy 177.048154 -297.018773) (xy 177.097584 -297.002712) (xy 177.148919 -296.994582)
			(xy 177.200893 -296.994582) (xy 177.252228 -297.002712) (xy 177.301658 -297.018773) (xy 177.347968 -297.042369)
			(xy 177.390016 -297.072919) (xy 177.426767 -297.10967) (xy 177.457317 -297.151718) (xy 177.480913 -297.198028)
			(xy 177.496974 -297.247458) (xy 177.505104 -297.298793) (xy 177.505614 -297.32478) (xy 177.505104 -297.350767)
			(xy 177.794668 -297.350767) (xy 177.794668 -297.298793) (xy 177.802798 -297.247458) (xy 177.818859 -297.198028)
			(xy 177.842455 -297.151718) (xy 177.873005 -297.10967) (xy 177.909756 -297.072919) (xy 177.951804 -297.042369)
			(xy 177.998114 -297.018773) (xy 178.047544 -297.002712) (xy 178.098879 -296.994582) (xy 178.150853 -296.994582)
			(xy 178.202188 -297.002712) (xy 178.251618 -297.018773) (xy 178.297928 -297.042369) (xy 178.339976 -297.072919)
			(xy 178.376727 -297.10967) (xy 178.407277 -297.151718) (xy 178.430873 -297.198028) (xy 178.446934 -297.247458)
			(xy 178.455064 -297.298793) (xy 178.455574 -297.32478) (xy 178.455064 -297.350767) (xy 178.744882 -297.350767)
			(xy 178.744882 -297.298793) (xy 178.753012 -297.247458) (xy 178.769073 -297.198028) (xy 178.792669 -297.151718)
			(xy 178.823219 -297.10967) (xy 178.85997 -297.072919) (xy 178.902018 -297.042369) (xy 178.948328 -297.018773)
			(xy 178.997758 -297.002712) (xy 179.049093 -296.994582) (xy 179.101067 -296.994582) (xy 179.152402 -297.002712)
			(xy 179.201832 -297.018773) (xy 179.248142 -297.042369) (xy 179.29019 -297.072919) (xy 179.326941 -297.10967)
			(xy 179.357491 -297.151718) (xy 179.381087 -297.198028) (xy 179.397148 -297.247458) (xy 179.405278 -297.298793)
			(xy 179.405788 -297.32478) (xy 179.405278 -297.350767) (xy 179.694842 -297.350767) (xy 179.694842 -297.298793)
			(xy 179.702972 -297.247458) (xy 179.719033 -297.198028) (xy 179.742629 -297.151718) (xy 179.773179 -297.10967)
			(xy 179.80993 -297.072919) (xy 179.851978 -297.042369) (xy 179.898288 -297.018773) (xy 179.947718 -297.002712)
			(xy 179.999053 -296.994582) (xy 180.051027 -296.994582) (xy 180.102362 -297.002712) (xy 180.151792 -297.018773)
			(xy 180.198102 -297.042369) (xy 180.24015 -297.072919) (xy 180.276901 -297.10967) (xy 180.307451 -297.151718)
			(xy 180.331047 -297.198028) (xy 180.347108 -297.247458) (xy 180.355238 -297.298793) (xy 180.355748 -297.32478)
			(xy 180.355238 -297.350767) (xy 180.644802 -297.350767) (xy 180.644802 -297.298793) (xy 180.652932 -297.247458)
			(xy 180.668993 -297.198028) (xy 180.692589 -297.151718) (xy 180.723139 -297.10967) (xy 180.75989 -297.072919)
			(xy 180.801938 -297.042369) (xy 180.848248 -297.018773) (xy 180.897678 -297.002712) (xy 180.949013 -296.994582)
			(xy 181.000987 -296.994582) (xy 181.052322 -297.002712) (xy 181.101752 -297.018773) (xy 181.148062 -297.042369)
			(xy 181.19011 -297.072919) (xy 181.226861 -297.10967) (xy 181.257411 -297.151718) (xy 181.281007 -297.198028)
			(xy 181.297068 -297.247458) (xy 181.305198 -297.298793) (xy 181.305708 -297.32478) (xy 181.305198 -297.350767)
			(xy 181.594762 -297.350767) (xy 181.594762 -297.298793) (xy 181.602892 -297.247458) (xy 181.618953 -297.198028)
			(xy 181.642549 -297.151718) (xy 181.673099 -297.10967) (xy 181.70985 -297.072919) (xy 181.751898 -297.042369)
			(xy 181.798208 -297.018773) (xy 181.847638 -297.002712) (xy 181.898973 -296.994582) (xy 181.950947 -296.994582)
			(xy 182.002282 -297.002712) (xy 182.051712 -297.018773) (xy 182.098022 -297.042369) (xy 182.14007 -297.072919)
			(xy 182.176821 -297.10967) (xy 182.207371 -297.151718) (xy 182.230967 -297.198028) (xy 182.247028 -297.247458)
			(xy 182.255158 -297.298793) (xy 182.255668 -297.32478) (xy 182.255158 -297.350767) (xy 182.544722 -297.350767)
			(xy 182.544722 -297.298793) (xy 182.552852 -297.247458) (xy 182.568913 -297.198028) (xy 182.592509 -297.151718)
			(xy 182.623059 -297.10967) (xy 182.65981 -297.072919) (xy 182.701858 -297.042369) (xy 182.748168 -297.018773)
			(xy 182.797598 -297.002712) (xy 182.848933 -296.994582) (xy 182.900907 -296.994582) (xy 182.952242 -297.002712)
			(xy 183.001672 -297.018773) (xy 183.047982 -297.042369) (xy 183.09003 -297.072919) (xy 183.126781 -297.10967)
			(xy 183.157331 -297.151718) (xy 183.180927 -297.198028) (xy 183.196988 -297.247458) (xy 183.205118 -297.298793)
			(xy 183.205628 -297.32478) (xy 183.205118 -297.350767) (xy 183.494682 -297.350767) (xy 183.494682 -297.298793)
			(xy 183.502812 -297.247458) (xy 183.518873 -297.198028) (xy 183.542469 -297.151718) (xy 183.573019 -297.10967)
			(xy 183.60977 -297.072919) (xy 183.651818 -297.042369) (xy 183.698128 -297.018773) (xy 183.747558 -297.002712)
			(xy 183.798893 -296.994582) (xy 183.850867 -296.994582) (xy 183.902202 -297.002712) (xy 183.951632 -297.018773)
			(xy 183.997942 -297.042369) (xy 184.03999 -297.072919) (xy 184.076741 -297.10967) (xy 184.107291 -297.151718)
			(xy 184.130887 -297.198028) (xy 184.146948 -297.247458) (xy 184.155078 -297.298793) (xy 184.155588 -297.32478)
			(xy 184.155078 -297.350767) (xy 184.146948 -297.402102) (xy 184.130887 -297.451532) (xy 184.107291 -297.497842)
			(xy 184.076741 -297.53989) (xy 184.03999 -297.576641) (xy 183.997942 -297.607191) (xy 183.951632 -297.630787)
			(xy 183.902202 -297.646848) (xy 183.850867 -297.654978) (xy 183.798893 -297.654978) (xy 183.747558 -297.646848)
			(xy 183.698128 -297.630787) (xy 183.651818 -297.607191) (xy 183.60977 -297.576641) (xy 183.573019 -297.53989)
			(xy 183.542469 -297.497842) (xy 183.518873 -297.451532) (xy 183.502812 -297.402102) (xy 183.494682 -297.350767)
			(xy 183.205118 -297.350767) (xy 183.196988 -297.402102) (xy 183.180927 -297.451532) (xy 183.157331 -297.497842)
			(xy 183.126781 -297.53989) (xy 183.09003 -297.576641) (xy 183.047982 -297.607191) (xy 183.001672 -297.630787)
			(xy 182.952242 -297.646848) (xy 182.900907 -297.654978) (xy 182.848933 -297.654978) (xy 182.797598 -297.646848)
			(xy 182.748168 -297.630787) (xy 182.701858 -297.607191) (xy 182.65981 -297.576641) (xy 182.623059 -297.53989)
			(xy 182.592509 -297.497842) (xy 182.568913 -297.451532) (xy 182.552852 -297.402102) (xy 182.544722 -297.350767)
			(xy 182.255158 -297.350767) (xy 182.247028 -297.402102) (xy 182.230967 -297.451532) (xy 182.207371 -297.497842)
			(xy 182.176821 -297.53989) (xy 182.14007 -297.576641) (xy 182.098022 -297.607191) (xy 182.051712 -297.630787)
			(xy 182.002282 -297.646848) (xy 181.950947 -297.654978) (xy 181.898973 -297.654978) (xy 181.847638 -297.646848)
			(xy 181.798208 -297.630787) (xy 181.751898 -297.607191) (xy 181.70985 -297.576641) (xy 181.673099 -297.53989)
			(xy 181.642549 -297.497842) (xy 181.618953 -297.451532) (xy 181.602892 -297.402102) (xy 181.594762 -297.350767)
			(xy 181.305198 -297.350767) (xy 181.297068 -297.402102) (xy 181.281007 -297.451532) (xy 181.257411 -297.497842)
			(xy 181.226861 -297.53989) (xy 181.19011 -297.576641) (xy 181.148062 -297.607191) (xy 181.101752 -297.630787)
			(xy 181.052322 -297.646848) (xy 181.000987 -297.654978) (xy 180.949013 -297.654978) (xy 180.897678 -297.646848)
			(xy 180.848248 -297.630787) (xy 180.801938 -297.607191) (xy 180.75989 -297.576641) (xy 180.723139 -297.53989)
			(xy 180.692589 -297.497842) (xy 180.668993 -297.451532) (xy 180.652932 -297.402102) (xy 180.644802 -297.350767)
			(xy 180.355238 -297.350767) (xy 180.347108 -297.402102) (xy 180.331047 -297.451532) (xy 180.307451 -297.497842)
			(xy 180.276901 -297.53989) (xy 180.24015 -297.576641) (xy 180.198102 -297.607191) (xy 180.151792 -297.630787)
			(xy 180.102362 -297.646848) (xy 180.051027 -297.654978) (xy 179.999053 -297.654978) (xy 179.947718 -297.646848)
			(xy 179.898288 -297.630787) (xy 179.851978 -297.607191) (xy 179.80993 -297.576641) (xy 179.773179 -297.53989)
			(xy 179.742629 -297.497842) (xy 179.719033 -297.451532) (xy 179.702972 -297.402102) (xy 179.694842 -297.350767)
			(xy 179.405278 -297.350767) (xy 179.397148 -297.402102) (xy 179.381087 -297.451532) (xy 179.357491 -297.497842)
			(xy 179.326941 -297.53989) (xy 179.29019 -297.576641) (xy 179.248142 -297.607191) (xy 179.201832 -297.630787)
			(xy 179.152402 -297.646848) (xy 179.101067 -297.654978) (xy 179.049093 -297.654978) (xy 178.997758 -297.646848)
			(xy 178.948328 -297.630787) (xy 178.902018 -297.607191) (xy 178.85997 -297.576641) (xy 178.823219 -297.53989)
			(xy 178.792669 -297.497842) (xy 178.769073 -297.451532) (xy 178.753012 -297.402102) (xy 178.744882 -297.350767)
			(xy 178.455064 -297.350767) (xy 178.446934 -297.402102) (xy 178.430873 -297.451532) (xy 178.407277 -297.497842)
			(xy 178.376727 -297.53989) (xy 178.339976 -297.576641) (xy 178.297928 -297.607191) (xy 178.251618 -297.630787)
			(xy 178.202188 -297.646848) (xy 178.150853 -297.654978) (xy 178.098879 -297.654978) (xy 178.047544 -297.646848)
			(xy 177.998114 -297.630787) (xy 177.951804 -297.607191) (xy 177.909756 -297.576641) (xy 177.873005 -297.53989)
			(xy 177.842455 -297.497842) (xy 177.818859 -297.451532) (xy 177.802798 -297.402102) (xy 177.794668 -297.350767)
			(xy 177.505104 -297.350767) (xy 177.496974 -297.402102) (xy 177.480913 -297.451532) (xy 177.457317 -297.497842)
			(xy 177.426767 -297.53989) (xy 177.390016 -297.576641) (xy 177.347968 -297.607191) (xy 177.301658 -297.630787)
			(xy 177.252228 -297.646848) (xy 177.200893 -297.654978) (xy 177.148919 -297.654978) (xy 177.097584 -297.646848)
			(xy 177.048154 -297.630787) (xy 177.001844 -297.607191) (xy 176.959796 -297.576641) (xy 176.923045 -297.53989)
			(xy 176.892495 -297.497842) (xy 176.868899 -297.451532) (xy 176.852838 -297.402102) (xy 176.844708 -297.350767)
			(xy 176.555144 -297.350767) (xy 176.547014 -297.402102) (xy 176.530953 -297.451532) (xy 176.507357 -297.497842)
			(xy 176.476807 -297.53989) (xy 176.440056 -297.576641) (xy 176.398008 -297.607191) (xy 176.351698 -297.630787)
			(xy 176.302268 -297.646848) (xy 176.250933 -297.654978) (xy 176.198959 -297.654978) (xy 176.147624 -297.646848)
			(xy 176.098194 -297.630787) (xy 176.051884 -297.607191) (xy 176.009836 -297.576641) (xy 175.973085 -297.53989)
			(xy 175.942535 -297.497842) (xy 175.918939 -297.451532) (xy 175.902878 -297.402102) (xy 175.894748 -297.350767)
			(xy 174.655224 -297.350767) (xy 174.647094 -297.402102) (xy 174.631033 -297.451532) (xy 174.607437 -297.497842)
			(xy 174.576887 -297.53989) (xy 174.540136 -297.576641) (xy 174.498088 -297.607191) (xy 174.451778 -297.630787)
			(xy 174.402348 -297.646848) (xy 174.351013 -297.654978) (xy 174.299039 -297.654978) (xy 174.247704 -297.646848)
			(xy 174.198274 -297.630787) (xy 174.151964 -297.607191) (xy 174.109916 -297.576641) (xy 174.073165 -297.53989)
			(xy 174.042615 -297.497842) (xy 174.019019 -297.451532) (xy 174.002958 -297.402102) (xy 173.994828 -297.350767)
			(xy 173.705264 -297.350767) (xy 173.697134 -297.402102) (xy 173.681073 -297.451532) (xy 173.657477 -297.497842)
			(xy 173.626927 -297.53989) (xy 173.590176 -297.576641) (xy 173.548128 -297.607191) (xy 173.501818 -297.630787)
			(xy 173.452388 -297.646848) (xy 173.401053 -297.654978) (xy 173.349079 -297.654978) (xy 173.297744 -297.646848)
			(xy 173.248314 -297.630787) (xy 173.202004 -297.607191) (xy 173.159956 -297.576641) (xy 173.123205 -297.53989)
			(xy 173.092655 -297.497842) (xy 173.069059 -297.451532) (xy 173.052998 -297.402102) (xy 173.044868 -297.350767)
			(xy 172.75505 -297.350767) (xy 172.74692 -297.402102) (xy 172.730859 -297.451532) (xy 172.707263 -297.497842)
			(xy 172.676713 -297.53989) (xy 172.639962 -297.576641) (xy 172.597914 -297.607191) (xy 172.551604 -297.630787)
			(xy 172.502174 -297.646848) (xy 172.450839 -297.654978) (xy 172.398865 -297.654978) (xy 172.34753 -297.646848)
			(xy 172.2981 -297.630787) (xy 172.25179 -297.607191) (xy 172.209742 -297.576641) (xy 172.172991 -297.53989)
			(xy 172.142441 -297.497842) (xy 172.118845 -297.451532) (xy 172.102784 -297.402102) (xy 172.094654 -297.350767)
			(xy 171.80509 -297.350767) (xy 171.79696 -297.402102) (xy 171.780899 -297.451532) (xy 171.757303 -297.497842)
			(xy 171.726753 -297.53989) (xy 171.690002 -297.576641) (xy 171.647954 -297.607191) (xy 171.601644 -297.630787)
			(xy 171.552214 -297.646848) (xy 171.500879 -297.654978) (xy 171.448905 -297.654978) (xy 171.39757 -297.646848)
			(xy 171.34814 -297.630787) (xy 171.30183 -297.607191) (xy 171.259782 -297.576641) (xy 171.223031 -297.53989)
			(xy 171.192481 -297.497842) (xy 171.168885 -297.451532) (xy 171.152824 -297.402102) (xy 171.144694 -297.350767)
			(xy 170.85513 -297.350767) (xy 170.847 -297.402102) (xy 170.830939 -297.451532) (xy 170.807343 -297.497842)
			(xy 170.776793 -297.53989) (xy 170.740042 -297.576641) (xy 170.697994 -297.607191) (xy 170.651684 -297.630787)
			(xy 170.602254 -297.646848) (xy 170.550919 -297.654978) (xy 170.498945 -297.654978) (xy 170.44761 -297.646848)
			(xy 170.39818 -297.630787) (xy 170.35187 -297.607191) (xy 170.309822 -297.576641) (xy 170.273071 -297.53989)
			(xy 170.242521 -297.497842) (xy 170.218925 -297.451532) (xy 170.202864 -297.402102) (xy 170.194734 -297.350767)
			(xy 169.90517 -297.350767) (xy 169.89704 -297.402102) (xy 169.880979 -297.451532) (xy 169.857383 -297.497842)
			(xy 169.826833 -297.53989) (xy 169.790082 -297.576641) (xy 169.748034 -297.607191) (xy 169.701724 -297.630787)
			(xy 169.652294 -297.646848) (xy 169.600959 -297.654978) (xy 169.548985 -297.654978) (xy 169.49765 -297.646848)
			(xy 169.44822 -297.630787) (xy 169.40191 -297.607191) (xy 169.359862 -297.576641) (xy 169.323111 -297.53989)
			(xy 169.292561 -297.497842) (xy 169.268965 -297.451532) (xy 169.252904 -297.402102) (xy 169.244774 -297.350767)
			(xy 168.95521 -297.350767) (xy 168.94708 -297.402102) (xy 168.931019 -297.451532) (xy 168.907423 -297.497842)
			(xy 168.876873 -297.53989) (xy 168.840122 -297.576641) (xy 168.798074 -297.607191) (xy 168.751764 -297.630787)
			(xy 168.702334 -297.646848) (xy 168.650999 -297.654978) (xy 168.599025 -297.654978) (xy 168.54769 -297.646848)
			(xy 168.49826 -297.630787) (xy 168.45195 -297.607191) (xy 168.409902 -297.576641) (xy 168.373151 -297.53989)
			(xy 168.342601 -297.497842) (xy 168.319005 -297.451532) (xy 168.302944 -297.402102) (xy 168.294814 -297.350767)
			(xy 168.00525 -297.350767) (xy 167.99712 -297.402102) (xy 167.981059 -297.451532) (xy 167.957463 -297.497842)
			(xy 167.926913 -297.53989) (xy 167.890162 -297.576641) (xy 167.848114 -297.607191) (xy 167.801804 -297.630787)
			(xy 167.752374 -297.646848) (xy 167.701039 -297.654978) (xy 167.649065 -297.654978) (xy 167.59773 -297.646848)
			(xy 167.5483 -297.630787) (xy 167.50199 -297.607191) (xy 167.459942 -297.576641) (xy 167.423191 -297.53989)
			(xy 167.392641 -297.497842) (xy 167.369045 -297.451532) (xy 167.352984 -297.402102) (xy 167.344854 -297.350767)
			(xy 167.05529 -297.350767) (xy 167.04716 -297.402102) (xy 167.031099 -297.451532) (xy 167.007503 -297.497842)
			(xy 166.976953 -297.53989) (xy 166.940202 -297.576641) (xy 166.898154 -297.607191) (xy 166.851844 -297.630787)
			(xy 166.802414 -297.646848) (xy 166.751079 -297.654978) (xy 166.699105 -297.654978) (xy 166.64777 -297.646848)
			(xy 166.59834 -297.630787) (xy 166.55203 -297.607191) (xy 166.509982 -297.576641) (xy 166.473231 -297.53989)
			(xy 166.442681 -297.497842) (xy 166.419085 -297.451532) (xy 166.403024 -297.402102) (xy 166.394894 -297.350767)
			(xy 166.105076 -297.350767) (xy 166.096946 -297.402102) (xy 166.080885 -297.451532) (xy 166.057289 -297.497842)
			(xy 166.026739 -297.53989) (xy 165.989988 -297.576641) (xy 165.94794 -297.607191) (xy 165.90163 -297.630787)
			(xy 165.8522 -297.646848) (xy 165.800865 -297.654978) (xy 165.748891 -297.654978) (xy 165.697556 -297.646848)
			(xy 165.648126 -297.630787) (xy 165.601816 -297.607191) (xy 165.559768 -297.576641) (xy 165.523017 -297.53989)
			(xy 165.492467 -297.497842) (xy 165.468871 -297.451532) (xy 165.45281 -297.402102) (xy 165.44468 -297.350767)
			(xy 165.155116 -297.350767) (xy 165.146986 -297.402102) (xy 165.130925 -297.451532) (xy 165.107329 -297.497842)
			(xy 165.076779 -297.53989) (xy 165.040028 -297.576641) (xy 164.99798 -297.607191) (xy 164.95167 -297.630787)
			(xy 164.90224 -297.646848) (xy 164.850905 -297.654978) (xy 164.798931 -297.654978) (xy 164.747596 -297.646848)
			(xy 164.698166 -297.630787) (xy 164.651856 -297.607191) (xy 164.609808 -297.576641) (xy 164.573057 -297.53989)
			(xy 164.542507 -297.497842) (xy 164.518911 -297.451532) (xy 164.50285 -297.402102) (xy 164.49472 -297.350767)
			(xy 164.205156 -297.350767) (xy 164.197026 -297.402102) (xy 164.180965 -297.451532) (xy 164.157369 -297.497842)
			(xy 164.126819 -297.53989) (xy 164.090068 -297.576641) (xy 164.04802 -297.607191) (xy 164.00171 -297.630787)
			(xy 163.95228 -297.646848) (xy 163.900945 -297.654978) (xy 163.848971 -297.654978) (xy 163.797636 -297.646848)
			(xy 163.748206 -297.630787) (xy 163.701896 -297.607191) (xy 163.659848 -297.576641) (xy 163.623097 -297.53989)
			(xy 163.592547 -297.497842) (xy 163.568951 -297.451532) (xy 163.55289 -297.402102) (xy 163.54476 -297.350767)
			(xy 163.255196 -297.350767) (xy 163.247066 -297.402102) (xy 163.231005 -297.451532) (xy 163.207409 -297.497842)
			(xy 163.176859 -297.53989) (xy 163.140108 -297.576641) (xy 163.09806 -297.607191) (xy 163.05175 -297.630787)
			(xy 163.00232 -297.646848) (xy 162.950985 -297.654978) (xy 162.899011 -297.654978) (xy 162.847676 -297.646848)
			(xy 162.798246 -297.630787) (xy 162.751936 -297.607191) (xy 162.709888 -297.576641) (xy 162.673137 -297.53989)
			(xy 162.642587 -297.497842) (xy 162.618991 -297.451532) (xy 162.60293 -297.402102) (xy 162.5948 -297.350767)
			(xy 162.305129 -297.350767) (xy 162.297857 -297.398803) (xy 162.283138 -297.446296) (xy 162.261473 -297.49105)
			(xy 162.233351 -297.532056) (xy 162.199407 -297.568388) (xy 162.160405 -297.599228) (xy 162.117224 -297.623881)
			(xy 162.070839 -297.64179) (xy 162.046666 -297.647614) (xy 162.02914 -297.651424) (xy 162.006788 -297.679364)
			(xy 162.006788 -297.920156) (xy 162.02914 -297.948096) (xy 162.046666 -297.951906) (xy 162.072248 -297.958108)
			(xy 162.121178 -297.977513) (xy 162.166415 -298.004425) (xy 162.206817 -298.038165) (xy 162.241363 -298.077879)
			(xy 162.269181 -298.122564) (xy 162.289569 -298.171093) (xy 162.30201 -298.222238) (xy 162.306192 -298.274709)
			(xy 162.304117 -298.300727) (xy 162.5948 -298.300727) (xy 162.5948 -298.248753) (xy 162.60293 -298.197418)
			(xy 162.618991 -298.147988) (xy 162.642587 -298.101678) (xy 162.673137 -298.05963) (xy 162.709888 -298.022879)
			(xy 162.751936 -297.992329) (xy 162.798246 -297.968733) (xy 162.847676 -297.952672) (xy 162.899011 -297.944542)
			(xy 162.950985 -297.944542) (xy 163.00232 -297.952672) (xy 163.05175 -297.968733) (xy 163.09806 -297.992329)
			(xy 163.140108 -298.022879) (xy 163.176859 -298.05963) (xy 163.207409 -298.101678) (xy 163.231005 -298.147988)
			(xy 163.247066 -298.197418) (xy 163.255196 -298.248753) (xy 163.255706 -298.27474) (xy 163.255196 -298.300727)
			(xy 163.54476 -298.300727) (xy 163.54476 -298.248753) (xy 163.55289 -298.197418) (xy 163.568951 -298.147988)
			(xy 163.592547 -298.101678) (xy 163.623097 -298.05963) (xy 163.659848 -298.022879) (xy 163.701896 -297.992329)
			(xy 163.748206 -297.968733) (xy 163.797636 -297.952672) (xy 163.848971 -297.944542) (xy 163.900945 -297.944542)
			(xy 163.95228 -297.952672) (xy 164.00171 -297.968733) (xy 164.04802 -297.992329) (xy 164.090068 -298.022879)
			(xy 164.126819 -298.05963) (xy 164.157369 -298.101678) (xy 164.180965 -298.147988) (xy 164.197026 -298.197418)
			(xy 164.205156 -298.248753) (xy 164.205666 -298.27474) (xy 164.205156 -298.300727) (xy 164.49472 -298.300727)
			(xy 164.49472 -298.248753) (xy 164.50285 -298.197418) (xy 164.518911 -298.147988) (xy 164.542507 -298.101678)
			(xy 164.573057 -298.05963) (xy 164.609808 -298.022879) (xy 164.651856 -297.992329) (xy 164.698166 -297.968733)
			(xy 164.747596 -297.952672) (xy 164.798931 -297.944542) (xy 164.850905 -297.944542) (xy 164.90224 -297.952672)
			(xy 164.95167 -297.968733) (xy 164.99798 -297.992329) (xy 165.040028 -298.022879) (xy 165.076779 -298.05963)
			(xy 165.107329 -298.101678) (xy 165.130925 -298.147988) (xy 165.146986 -298.197418) (xy 165.155116 -298.248753)
			(xy 165.155626 -298.27474) (xy 165.155116 -298.300727) (xy 165.44468 -298.300727) (xy 165.44468 -298.248753)
			(xy 165.45281 -298.197418) (xy 165.468871 -298.147988) (xy 165.492467 -298.101678) (xy 165.523017 -298.05963)
			(xy 165.559768 -298.022879) (xy 165.601816 -297.992329) (xy 165.648126 -297.968733) (xy 165.697556 -297.952672)
			(xy 165.748891 -297.944542) (xy 165.800865 -297.944542) (xy 165.8522 -297.952672) (xy 165.90163 -297.968733)
			(xy 165.94794 -297.992329) (xy 165.989988 -298.022879) (xy 166.026739 -298.05963) (xy 166.057289 -298.101678)
			(xy 166.080885 -298.147988) (xy 166.096946 -298.197418) (xy 166.105076 -298.248753) (xy 166.105586 -298.27474)
			(xy 166.105076 -298.300727) (xy 166.394894 -298.300727) (xy 166.394894 -298.248753) (xy 166.403024 -298.197418)
			(xy 166.419085 -298.147988) (xy 166.442681 -298.101678) (xy 166.473231 -298.05963) (xy 166.509982 -298.022879)
			(xy 166.55203 -297.992329) (xy 166.59834 -297.968733) (xy 166.64777 -297.952672) (xy 166.699105 -297.944542)
			(xy 166.751079 -297.944542) (xy 166.802414 -297.952672) (xy 166.851844 -297.968733) (xy 166.898154 -297.992329)
			(xy 166.940202 -298.022879) (xy 166.976953 -298.05963) (xy 167.007503 -298.101678) (xy 167.031099 -298.147988)
			(xy 167.04716 -298.197418) (xy 167.05529 -298.248753) (xy 167.0558 -298.27474) (xy 167.05529 -298.300727)
			(xy 167.344854 -298.300727) (xy 167.344854 -298.248753) (xy 167.352984 -298.197418) (xy 167.369045 -298.147988)
			(xy 167.392641 -298.101678) (xy 167.423191 -298.05963) (xy 167.459942 -298.022879) (xy 167.50199 -297.992329)
			(xy 167.5483 -297.968733) (xy 167.59773 -297.952672) (xy 167.649065 -297.944542) (xy 167.701039 -297.944542)
			(xy 167.752374 -297.952672) (xy 167.801804 -297.968733) (xy 167.848114 -297.992329) (xy 167.890162 -298.022879)
			(xy 167.926913 -298.05963) (xy 167.957463 -298.101678) (xy 167.981059 -298.147988) (xy 167.99712 -298.197418)
			(xy 168.00525 -298.248753) (xy 168.00576 -298.27474) (xy 168.00525 -298.300727) (xy 168.294814 -298.300727)
			(xy 168.294814 -298.248753) (xy 168.302944 -298.197418) (xy 168.319005 -298.147988) (xy 168.342601 -298.101678)
			(xy 168.373151 -298.05963) (xy 168.409902 -298.022879) (xy 168.45195 -297.992329) (xy 168.49826 -297.968733)
			(xy 168.54769 -297.952672) (xy 168.599025 -297.944542) (xy 168.650999 -297.944542) (xy 168.702334 -297.952672)
			(xy 168.751764 -297.968733) (xy 168.798074 -297.992329) (xy 168.840122 -298.022879) (xy 168.876873 -298.05963)
			(xy 168.907423 -298.101678) (xy 168.931019 -298.147988) (xy 168.94708 -298.197418) (xy 168.95521 -298.248753)
			(xy 168.95572 -298.27474) (xy 168.95521 -298.300727) (xy 169.244774 -298.300727) (xy 169.244774 -298.248753)
			(xy 169.252904 -298.197418) (xy 169.268965 -298.147988) (xy 169.292561 -298.101678) (xy 169.323111 -298.05963)
			(xy 169.359862 -298.022879) (xy 169.40191 -297.992329) (xy 169.44822 -297.968733) (xy 169.49765 -297.952672)
			(xy 169.548985 -297.944542) (xy 169.600959 -297.944542) (xy 169.652294 -297.952672) (xy 169.701724 -297.968733)
			(xy 169.748034 -297.992329) (xy 169.790082 -298.022879) (xy 169.826833 -298.05963) (xy 169.857383 -298.101678)
			(xy 169.880979 -298.147988) (xy 169.89704 -298.197418) (xy 169.90517 -298.248753) (xy 169.90568 -298.27474)
			(xy 169.90517 -298.300727) (xy 170.194734 -298.300727) (xy 170.194734 -298.248753) (xy 170.202864 -298.197418)
			(xy 170.218925 -298.147988) (xy 170.242521 -298.101678) (xy 170.273071 -298.05963) (xy 170.309822 -298.022879)
			(xy 170.35187 -297.992329) (xy 170.39818 -297.968733) (xy 170.44761 -297.952672) (xy 170.498945 -297.944542)
			(xy 170.550919 -297.944542) (xy 170.602254 -297.952672) (xy 170.651684 -297.968733) (xy 170.697994 -297.992329)
			(xy 170.740042 -298.022879) (xy 170.776793 -298.05963) (xy 170.807343 -298.101678) (xy 170.830939 -298.147988)
			(xy 170.847 -298.197418) (xy 170.85513 -298.248753) (xy 170.85564 -298.27474) (xy 170.85513 -298.300727)
			(xy 171.144694 -298.300727) (xy 171.144694 -298.248753) (xy 171.152824 -298.197418) (xy 171.168885 -298.147988)
			(xy 171.192481 -298.101678) (xy 171.223031 -298.05963) (xy 171.259782 -298.022879) (xy 171.30183 -297.992329)
			(xy 171.34814 -297.968733) (xy 171.39757 -297.952672) (xy 171.448905 -297.944542) (xy 171.500879 -297.944542)
			(xy 171.552214 -297.952672) (xy 171.601644 -297.968733) (xy 171.647954 -297.992329) (xy 171.690002 -298.022879)
			(xy 171.726753 -298.05963) (xy 171.757303 -298.101678) (xy 171.780899 -298.147988) (xy 171.79696 -298.197418)
			(xy 171.80509 -298.248753) (xy 171.8056 -298.27474) (xy 171.80509 -298.300727) (xy 172.094654 -298.300727)
			(xy 172.094654 -298.248753) (xy 172.102784 -298.197418) (xy 172.118845 -298.147988) (xy 172.142441 -298.101678)
			(xy 172.172991 -298.05963) (xy 172.209742 -298.022879) (xy 172.25179 -297.992329) (xy 172.2981 -297.968733)
			(xy 172.34753 -297.952672) (xy 172.398865 -297.944542) (xy 172.450839 -297.944542) (xy 172.502174 -297.952672)
			(xy 172.551604 -297.968733) (xy 172.597914 -297.992329) (xy 172.639962 -298.022879) (xy 172.676713 -298.05963)
			(xy 172.707263 -298.101678) (xy 172.730859 -298.147988) (xy 172.74692 -298.197418) (xy 172.75505 -298.248753)
			(xy 172.75556 -298.27474) (xy 172.75505 -298.300727) (xy 173.044868 -298.300727) (xy 173.044868 -298.248753)
			(xy 173.052998 -298.197418) (xy 173.069059 -298.147988) (xy 173.092655 -298.101678) (xy 173.123205 -298.05963)
			(xy 173.159956 -298.022879) (xy 173.202004 -297.992329) (xy 173.248314 -297.968733) (xy 173.297744 -297.952672)
			(xy 173.349079 -297.944542) (xy 173.401053 -297.944542) (xy 173.452388 -297.952672) (xy 173.501818 -297.968733)
			(xy 173.548128 -297.992329) (xy 173.590176 -298.022879) (xy 173.626927 -298.05963) (xy 173.657477 -298.101678)
			(xy 173.681073 -298.147988) (xy 173.697134 -298.197418) (xy 173.705264 -298.248753) (xy 173.705774 -298.27474)
			(xy 173.705264 -298.300727) (xy 173.994828 -298.300727) (xy 173.994828 -298.248753) (xy 174.002958 -298.197418)
			(xy 174.019019 -298.147988) (xy 174.042615 -298.101678) (xy 174.073165 -298.05963) (xy 174.109916 -298.022879)
			(xy 174.151964 -297.992329) (xy 174.198274 -297.968733) (xy 174.247704 -297.952672) (xy 174.299039 -297.944542)
			(xy 174.351013 -297.944542) (xy 174.402348 -297.952672) (xy 174.451778 -297.968733) (xy 174.498088 -297.992329)
			(xy 174.540136 -298.022879) (xy 174.576887 -298.05963) (xy 174.607437 -298.101678) (xy 174.631033 -298.147988)
			(xy 174.647094 -298.197418) (xy 174.655224 -298.248753) (xy 174.655734 -298.27474) (xy 174.655224 -298.300727)
			(xy 175.894748 -298.300727) (xy 175.894748 -298.248753) (xy 175.902878 -298.197418) (xy 175.918939 -298.147988)
			(xy 175.942535 -298.101678) (xy 175.973085 -298.05963) (xy 176.009836 -298.022879) (xy 176.051884 -297.992329)
			(xy 176.098194 -297.968733) (xy 176.147624 -297.952672) (xy 176.198959 -297.944542) (xy 176.250933 -297.944542)
			(xy 176.302268 -297.952672) (xy 176.351698 -297.968733) (xy 176.398008 -297.992329) (xy 176.440056 -298.022879)
			(xy 176.476807 -298.05963) (xy 176.507357 -298.101678) (xy 176.530953 -298.147988) (xy 176.547014 -298.197418)
			(xy 176.555144 -298.248753) (xy 176.555654 -298.27474) (xy 176.555144 -298.300727) (xy 176.844708 -298.300727)
			(xy 176.844708 -298.248753) (xy 176.852838 -298.197418) (xy 176.868899 -298.147988) (xy 176.892495 -298.101678)
			(xy 176.923045 -298.05963) (xy 176.959796 -298.022879) (xy 177.001844 -297.992329) (xy 177.048154 -297.968733)
			(xy 177.097584 -297.952672) (xy 177.148919 -297.944542) (xy 177.200893 -297.944542) (xy 177.252228 -297.952672)
			(xy 177.301658 -297.968733) (xy 177.347968 -297.992329) (xy 177.390016 -298.022879) (xy 177.426767 -298.05963)
			(xy 177.457317 -298.101678) (xy 177.480913 -298.147988) (xy 177.496974 -298.197418) (xy 177.505104 -298.248753)
			(xy 177.505614 -298.27474) (xy 177.505104 -298.300727) (xy 177.794668 -298.300727) (xy 177.794668 -298.248753)
			(xy 177.802798 -298.197418) (xy 177.818859 -298.147988) (xy 177.842455 -298.101678) (xy 177.873005 -298.05963)
			(xy 177.909756 -298.022879) (xy 177.951804 -297.992329) (xy 177.998114 -297.968733) (xy 178.047544 -297.952672)
			(xy 178.098879 -297.944542) (xy 178.150853 -297.944542) (xy 178.202188 -297.952672) (xy 178.251618 -297.968733)
			(xy 178.297928 -297.992329) (xy 178.339976 -298.022879) (xy 178.376727 -298.05963) (xy 178.407277 -298.101678)
			(xy 178.430873 -298.147988) (xy 178.446934 -298.197418) (xy 178.455064 -298.248753) (xy 178.455574 -298.27474)
			(xy 178.455064 -298.300727) (xy 178.744882 -298.300727) (xy 178.744882 -298.248753) (xy 178.753012 -298.197418)
			(xy 178.769073 -298.147988) (xy 178.792669 -298.101678) (xy 178.823219 -298.05963) (xy 178.85997 -298.022879)
			(xy 178.902018 -297.992329) (xy 178.948328 -297.968733) (xy 178.997758 -297.952672) (xy 179.049093 -297.944542)
			(xy 179.101067 -297.944542) (xy 179.152402 -297.952672) (xy 179.201832 -297.968733) (xy 179.248142 -297.992329)
			(xy 179.29019 -298.022879) (xy 179.326941 -298.05963) (xy 179.357491 -298.101678) (xy 179.381087 -298.147988)
			(xy 179.397148 -298.197418) (xy 179.405278 -298.248753) (xy 179.405788 -298.27474) (xy 179.405278 -298.300727)
			(xy 179.694842 -298.300727) (xy 179.694842 -298.248753) (xy 179.702972 -298.197418) (xy 179.719033 -298.147988)
			(xy 179.742629 -298.101678) (xy 179.773179 -298.05963) (xy 179.80993 -298.022879) (xy 179.851978 -297.992329)
			(xy 179.898288 -297.968733) (xy 179.947718 -297.952672) (xy 179.999053 -297.944542) (xy 180.051027 -297.944542)
			(xy 180.102362 -297.952672) (xy 180.151792 -297.968733) (xy 180.198102 -297.992329) (xy 180.24015 -298.022879)
			(xy 180.276901 -298.05963) (xy 180.307451 -298.101678) (xy 180.331047 -298.147988) (xy 180.347108 -298.197418)
			(xy 180.355238 -298.248753) (xy 180.355748 -298.27474) (xy 180.355238 -298.300727) (xy 180.644802 -298.300727)
			(xy 180.644802 -298.248753) (xy 180.652932 -298.197418) (xy 180.668993 -298.147988) (xy 180.692589 -298.101678)
			(xy 180.723139 -298.05963) (xy 180.75989 -298.022879) (xy 180.801938 -297.992329) (xy 180.848248 -297.968733)
			(xy 180.897678 -297.952672) (xy 180.949013 -297.944542) (xy 181.000987 -297.944542) (xy 181.052322 -297.952672)
			(xy 181.101752 -297.968733) (xy 181.148062 -297.992329) (xy 181.19011 -298.022879) (xy 181.226861 -298.05963)
			(xy 181.257411 -298.101678) (xy 181.281007 -298.147988) (xy 181.297068 -298.197418) (xy 181.305198 -298.248753)
			(xy 181.305708 -298.27474) (xy 181.305198 -298.300727) (xy 181.594762 -298.300727) (xy 181.594762 -298.248753)
			(xy 181.602892 -298.197418) (xy 181.618953 -298.147988) (xy 181.642549 -298.101678) (xy 181.673099 -298.05963)
			(xy 181.70985 -298.022879) (xy 181.751898 -297.992329) (xy 181.798208 -297.968733) (xy 181.847638 -297.952672)
			(xy 181.898973 -297.944542) (xy 181.950947 -297.944542) (xy 182.002282 -297.952672) (xy 182.051712 -297.968733)
			(xy 182.098022 -297.992329) (xy 182.14007 -298.022879) (xy 182.176821 -298.05963) (xy 182.207371 -298.101678)
			(xy 182.230967 -298.147988) (xy 182.247028 -298.197418) (xy 182.255158 -298.248753) (xy 182.255668 -298.27474)
			(xy 182.255158 -298.300727) (xy 182.544722 -298.300727) (xy 182.544722 -298.248753) (xy 182.552852 -298.197418)
			(xy 182.568913 -298.147988) (xy 182.592509 -298.101678) (xy 182.623059 -298.05963) (xy 182.65981 -298.022879)
			(xy 182.701858 -297.992329) (xy 182.748168 -297.968733) (xy 182.797598 -297.952672) (xy 182.848933 -297.944542)
			(xy 182.900907 -297.944542) (xy 182.952242 -297.952672) (xy 183.001672 -297.968733) (xy 183.047982 -297.992329)
			(xy 183.09003 -298.022879) (xy 183.126781 -298.05963) (xy 183.157331 -298.101678) (xy 183.180927 -298.147988)
			(xy 183.196988 -298.197418) (xy 183.205118 -298.248753) (xy 183.205628 -298.27474) (xy 183.205118 -298.300727)
			(xy 183.494682 -298.300727) (xy 183.494682 -298.248753) (xy 183.502812 -298.197418) (xy 183.518873 -298.147988)
			(xy 183.542469 -298.101678) (xy 183.573019 -298.05963) (xy 183.60977 -298.022879) (xy 183.651818 -297.992329)
			(xy 183.698128 -297.968733) (xy 183.747558 -297.952672) (xy 183.798893 -297.944542) (xy 183.850867 -297.944542)
			(xy 183.902202 -297.952672) (xy 183.951632 -297.968733) (xy 183.997942 -297.992329) (xy 184.03999 -298.022879)
			(xy 184.076741 -298.05963) (xy 184.107291 -298.101678) (xy 184.130887 -298.147988) (xy 184.146948 -298.197418)
			(xy 184.155078 -298.248753) (xy 184.155588 -298.27474) (xy 184.155078 -298.300727) (xy 184.146948 -298.352062)
			(xy 184.130887 -298.401492) (xy 184.107291 -298.447802) (xy 184.076741 -298.48985) (xy 184.03999 -298.526601)
			(xy 183.997942 -298.557151) (xy 183.951632 -298.580747) (xy 183.902202 -298.596808) (xy 183.850867 -298.604938)
			(xy 183.798893 -298.604938) (xy 183.747558 -298.596808) (xy 183.698128 -298.580747) (xy 183.651818 -298.557151)
			(xy 183.60977 -298.526601) (xy 183.573019 -298.48985) (xy 183.542469 -298.447802) (xy 183.518873 -298.401492)
			(xy 183.502812 -298.352062) (xy 183.494682 -298.300727) (xy 183.205118 -298.300727) (xy 183.196988 -298.352062)
			(xy 183.180927 -298.401492) (xy 183.157331 -298.447802) (xy 183.126781 -298.48985) (xy 183.09003 -298.526601)
			(xy 183.047982 -298.557151) (xy 183.001672 -298.580747) (xy 182.952242 -298.596808) (xy 182.900907 -298.604938)
			(xy 182.848933 -298.604938) (xy 182.797598 -298.596808) (xy 182.748168 -298.580747) (xy 182.701858 -298.557151)
			(xy 182.65981 -298.526601) (xy 182.623059 -298.48985) (xy 182.592509 -298.447802) (xy 182.568913 -298.401492)
			(xy 182.552852 -298.352062) (xy 182.544722 -298.300727) (xy 182.255158 -298.300727) (xy 182.247028 -298.352062)
			(xy 182.230967 -298.401492) (xy 182.207371 -298.447802) (xy 182.176821 -298.48985) (xy 182.14007 -298.526601)
			(xy 182.098022 -298.557151) (xy 182.051712 -298.580747) (xy 182.002282 -298.596808) (xy 181.950947 -298.604938)
			(xy 181.898973 -298.604938) (xy 181.847638 -298.596808) (xy 181.798208 -298.580747) (xy 181.751898 -298.557151)
			(xy 181.70985 -298.526601) (xy 181.673099 -298.48985) (xy 181.642549 -298.447802) (xy 181.618953 -298.401492)
			(xy 181.602892 -298.352062) (xy 181.594762 -298.300727) (xy 181.305198 -298.300727) (xy 181.297068 -298.352062)
			(xy 181.281007 -298.401492) (xy 181.257411 -298.447802) (xy 181.226861 -298.48985) (xy 181.19011 -298.526601)
			(xy 181.148062 -298.557151) (xy 181.101752 -298.580747) (xy 181.052322 -298.596808) (xy 181.000987 -298.604938)
			(xy 180.949013 -298.604938) (xy 180.897678 -298.596808) (xy 180.848248 -298.580747) (xy 180.801938 -298.557151)
			(xy 180.75989 -298.526601) (xy 180.723139 -298.48985) (xy 180.692589 -298.447802) (xy 180.668993 -298.401492)
			(xy 180.652932 -298.352062) (xy 180.644802 -298.300727) (xy 180.355238 -298.300727) (xy 180.347108 -298.352062)
			(xy 180.331047 -298.401492) (xy 180.307451 -298.447802) (xy 180.276901 -298.48985) (xy 180.24015 -298.526601)
			(xy 180.198102 -298.557151) (xy 180.151792 -298.580747) (xy 180.102362 -298.596808) (xy 180.051027 -298.604938)
			(xy 179.999053 -298.604938) (xy 179.947718 -298.596808) (xy 179.898288 -298.580747) (xy 179.851978 -298.557151)
			(xy 179.80993 -298.526601) (xy 179.773179 -298.48985) (xy 179.742629 -298.447802) (xy 179.719033 -298.401492)
			(xy 179.702972 -298.352062) (xy 179.694842 -298.300727) (xy 179.405278 -298.300727) (xy 179.397148 -298.352062)
			(xy 179.381087 -298.401492) (xy 179.357491 -298.447802) (xy 179.326941 -298.48985) (xy 179.29019 -298.526601)
			(xy 179.248142 -298.557151) (xy 179.201832 -298.580747) (xy 179.152402 -298.596808) (xy 179.101067 -298.604938)
			(xy 179.049093 -298.604938) (xy 178.997758 -298.596808) (xy 178.948328 -298.580747) (xy 178.902018 -298.557151)
			(xy 178.85997 -298.526601) (xy 178.823219 -298.48985) (xy 178.792669 -298.447802) (xy 178.769073 -298.401492)
			(xy 178.753012 -298.352062) (xy 178.744882 -298.300727) (xy 178.455064 -298.300727) (xy 178.446934 -298.352062)
			(xy 178.430873 -298.401492) (xy 178.407277 -298.447802) (xy 178.376727 -298.48985) (xy 178.339976 -298.526601)
			(xy 178.297928 -298.557151) (xy 178.251618 -298.580747) (xy 178.202188 -298.596808) (xy 178.150853 -298.604938)
			(xy 178.098879 -298.604938) (xy 178.047544 -298.596808) (xy 177.998114 -298.580747) (xy 177.951804 -298.557151)
			(xy 177.909756 -298.526601) (xy 177.873005 -298.48985) (xy 177.842455 -298.447802) (xy 177.818859 -298.401492)
			(xy 177.802798 -298.352062) (xy 177.794668 -298.300727) (xy 177.505104 -298.300727) (xy 177.496974 -298.352062)
			(xy 177.480913 -298.401492) (xy 177.457317 -298.447802) (xy 177.426767 -298.48985) (xy 177.390016 -298.526601)
			(xy 177.347968 -298.557151) (xy 177.301658 -298.580747) (xy 177.252228 -298.596808) (xy 177.200893 -298.604938)
			(xy 177.148919 -298.604938) (xy 177.097584 -298.596808) (xy 177.048154 -298.580747) (xy 177.001844 -298.557151)
			(xy 176.959796 -298.526601) (xy 176.923045 -298.48985) (xy 176.892495 -298.447802) (xy 176.868899 -298.401492)
			(xy 176.852838 -298.352062) (xy 176.844708 -298.300727) (xy 176.555144 -298.300727) (xy 176.547014 -298.352062)
			(xy 176.530953 -298.401492) (xy 176.507357 -298.447802) (xy 176.476807 -298.48985) (xy 176.440056 -298.526601)
			(xy 176.398008 -298.557151) (xy 176.351698 -298.580747) (xy 176.302268 -298.596808) (xy 176.250933 -298.604938)
			(xy 176.198959 -298.604938) (xy 176.147624 -298.596808) (xy 176.098194 -298.580747) (xy 176.051884 -298.557151)
			(xy 176.009836 -298.526601) (xy 175.973085 -298.48985) (xy 175.942535 -298.447802) (xy 175.918939 -298.401492)
			(xy 175.902878 -298.352062) (xy 175.894748 -298.300727) (xy 174.655224 -298.300727) (xy 174.647094 -298.352062)
			(xy 174.631033 -298.401492) (xy 174.607437 -298.447802) (xy 174.576887 -298.48985) (xy 174.540136 -298.526601)
			(xy 174.498088 -298.557151) (xy 174.451778 -298.580747) (xy 174.402348 -298.596808) (xy 174.351013 -298.604938)
			(xy 174.299039 -298.604938) (xy 174.247704 -298.596808) (xy 174.198274 -298.580747) (xy 174.151964 -298.557151)
			(xy 174.109916 -298.526601) (xy 174.073165 -298.48985) (xy 174.042615 -298.447802) (xy 174.019019 -298.401492)
			(xy 174.002958 -298.352062) (xy 173.994828 -298.300727) (xy 173.705264 -298.300727) (xy 173.697134 -298.352062)
			(xy 173.681073 -298.401492) (xy 173.657477 -298.447802) (xy 173.626927 -298.48985) (xy 173.590176 -298.526601)
			(xy 173.548128 -298.557151) (xy 173.501818 -298.580747) (xy 173.452388 -298.596808) (xy 173.401053 -298.604938)
			(xy 173.349079 -298.604938) (xy 173.297744 -298.596808) (xy 173.248314 -298.580747) (xy 173.202004 -298.557151)
			(xy 173.159956 -298.526601) (xy 173.123205 -298.48985) (xy 173.092655 -298.447802) (xy 173.069059 -298.401492)
			(xy 173.052998 -298.352062) (xy 173.044868 -298.300727) (xy 172.75505 -298.300727) (xy 172.74692 -298.352062)
			(xy 172.730859 -298.401492) (xy 172.707263 -298.447802) (xy 172.676713 -298.48985) (xy 172.639962 -298.526601)
			(xy 172.597914 -298.557151) (xy 172.551604 -298.580747) (xy 172.502174 -298.596808) (xy 172.450839 -298.604938)
			(xy 172.398865 -298.604938) (xy 172.34753 -298.596808) (xy 172.2981 -298.580747) (xy 172.25179 -298.557151)
			(xy 172.209742 -298.526601) (xy 172.172991 -298.48985) (xy 172.142441 -298.447802) (xy 172.118845 -298.401492)
			(xy 172.102784 -298.352062) (xy 172.094654 -298.300727) (xy 171.80509 -298.300727) (xy 171.79696 -298.352062)
			(xy 171.780899 -298.401492) (xy 171.757303 -298.447802) (xy 171.726753 -298.48985) (xy 171.690002 -298.526601)
			(xy 171.647954 -298.557151) (xy 171.601644 -298.580747) (xy 171.552214 -298.596808) (xy 171.500879 -298.604938)
			(xy 171.448905 -298.604938) (xy 171.39757 -298.596808) (xy 171.34814 -298.580747) (xy 171.30183 -298.557151)
			(xy 171.259782 -298.526601) (xy 171.223031 -298.48985) (xy 171.192481 -298.447802) (xy 171.168885 -298.401492)
			(xy 171.152824 -298.352062) (xy 171.144694 -298.300727) (xy 170.85513 -298.300727) (xy 170.847 -298.352062)
			(xy 170.830939 -298.401492) (xy 170.807343 -298.447802) (xy 170.776793 -298.48985) (xy 170.740042 -298.526601)
			(xy 170.697994 -298.557151) (xy 170.651684 -298.580747) (xy 170.602254 -298.596808) (xy 170.550919 -298.604938)
			(xy 170.498945 -298.604938) (xy 170.44761 -298.596808) (xy 170.39818 -298.580747) (xy 170.35187 -298.557151)
			(xy 170.309822 -298.526601) (xy 170.273071 -298.48985) (xy 170.242521 -298.447802) (xy 170.218925 -298.401492)
			(xy 170.202864 -298.352062) (xy 170.194734 -298.300727) (xy 169.90517 -298.300727) (xy 169.89704 -298.352062)
			(xy 169.880979 -298.401492) (xy 169.857383 -298.447802) (xy 169.826833 -298.48985) (xy 169.790082 -298.526601)
			(xy 169.748034 -298.557151) (xy 169.701724 -298.580747) (xy 169.652294 -298.596808) (xy 169.600959 -298.604938)
			(xy 169.548985 -298.604938) (xy 169.49765 -298.596808) (xy 169.44822 -298.580747) (xy 169.40191 -298.557151)
			(xy 169.359862 -298.526601) (xy 169.323111 -298.48985) (xy 169.292561 -298.447802) (xy 169.268965 -298.401492)
			(xy 169.252904 -298.352062) (xy 169.244774 -298.300727) (xy 168.95521 -298.300727) (xy 168.94708 -298.352062)
			(xy 168.931019 -298.401492) (xy 168.907423 -298.447802) (xy 168.876873 -298.48985) (xy 168.840122 -298.526601)
			(xy 168.798074 -298.557151) (xy 168.751764 -298.580747) (xy 168.702334 -298.596808) (xy 168.650999 -298.604938)
			(xy 168.599025 -298.604938) (xy 168.54769 -298.596808) (xy 168.49826 -298.580747) (xy 168.45195 -298.557151)
			(xy 168.409902 -298.526601) (xy 168.373151 -298.48985) (xy 168.342601 -298.447802) (xy 168.319005 -298.401492)
			(xy 168.302944 -298.352062) (xy 168.294814 -298.300727) (xy 168.00525 -298.300727) (xy 167.99712 -298.352062)
			(xy 167.981059 -298.401492) (xy 167.957463 -298.447802) (xy 167.926913 -298.48985) (xy 167.890162 -298.526601)
			(xy 167.848114 -298.557151) (xy 167.801804 -298.580747) (xy 167.752374 -298.596808) (xy 167.701039 -298.604938)
			(xy 167.649065 -298.604938) (xy 167.59773 -298.596808) (xy 167.5483 -298.580747) (xy 167.50199 -298.557151)
			(xy 167.459942 -298.526601) (xy 167.423191 -298.48985) (xy 167.392641 -298.447802) (xy 167.369045 -298.401492)
			(xy 167.352984 -298.352062) (xy 167.344854 -298.300727) (xy 167.05529 -298.300727) (xy 167.04716 -298.352062)
			(xy 167.031099 -298.401492) (xy 167.007503 -298.447802) (xy 166.976953 -298.48985) (xy 166.940202 -298.526601)
			(xy 166.898154 -298.557151) (xy 166.851844 -298.580747) (xy 166.802414 -298.596808) (xy 166.751079 -298.604938)
			(xy 166.699105 -298.604938) (xy 166.64777 -298.596808) (xy 166.59834 -298.580747) (xy 166.55203 -298.557151)
			(xy 166.509982 -298.526601) (xy 166.473231 -298.48985) (xy 166.442681 -298.447802) (xy 166.419085 -298.401492)
			(xy 166.403024 -298.352062) (xy 166.394894 -298.300727) (xy 166.105076 -298.300727) (xy 166.096946 -298.352062)
			(xy 166.080885 -298.401492) (xy 166.057289 -298.447802) (xy 166.026739 -298.48985) (xy 165.989988 -298.526601)
			(xy 165.94794 -298.557151) (xy 165.90163 -298.580747) (xy 165.8522 -298.596808) (xy 165.800865 -298.604938)
			(xy 165.748891 -298.604938) (xy 165.697556 -298.596808) (xy 165.648126 -298.580747) (xy 165.601816 -298.557151)
			(xy 165.559768 -298.526601) (xy 165.523017 -298.48985) (xy 165.492467 -298.447802) (xy 165.468871 -298.401492)
			(xy 165.45281 -298.352062) (xy 165.44468 -298.300727) (xy 165.155116 -298.300727) (xy 165.146986 -298.352062)
			(xy 165.130925 -298.401492) (xy 165.107329 -298.447802) (xy 165.076779 -298.48985) (xy 165.040028 -298.526601)
			(xy 164.99798 -298.557151) (xy 164.95167 -298.580747) (xy 164.90224 -298.596808) (xy 164.850905 -298.604938)
			(xy 164.798931 -298.604938) (xy 164.747596 -298.596808) (xy 164.698166 -298.580747) (xy 164.651856 -298.557151)
			(xy 164.609808 -298.526601) (xy 164.573057 -298.48985) (xy 164.542507 -298.447802) (xy 164.518911 -298.401492)
			(xy 164.50285 -298.352062) (xy 164.49472 -298.300727) (xy 164.205156 -298.300727) (xy 164.197026 -298.352062)
			(xy 164.180965 -298.401492) (xy 164.157369 -298.447802) (xy 164.126819 -298.48985) (xy 164.090068 -298.526601)
			(xy 164.04802 -298.557151) (xy 164.00171 -298.580747) (xy 163.95228 -298.596808) (xy 163.900945 -298.604938)
			(xy 163.848971 -298.604938) (xy 163.797636 -298.596808) (xy 163.748206 -298.580747) (xy 163.701896 -298.557151)
			(xy 163.659848 -298.526601) (xy 163.623097 -298.48985) (xy 163.592547 -298.447802) (xy 163.568951 -298.401492)
			(xy 163.55289 -298.352062) (xy 163.54476 -298.300727) (xy 163.255196 -298.300727) (xy 163.247066 -298.352062)
			(xy 163.231005 -298.401492) (xy 163.207409 -298.447802) (xy 163.176859 -298.48985) (xy 163.140108 -298.526601)
			(xy 163.09806 -298.557151) (xy 163.05175 -298.580747) (xy 163.00232 -298.596808) (xy 162.950985 -298.604938)
			(xy 162.899011 -298.604938) (xy 162.847676 -298.596808) (xy 162.798246 -298.580747) (xy 162.751936 -298.557151)
			(xy 162.709888 -298.526601) (xy 162.673137 -298.48985) (xy 162.642587 -298.447802) (xy 162.618991 -298.401492)
			(xy 162.60293 -298.352062) (xy 162.5948 -298.300727) (xy 162.304117 -298.300727) (xy 162.302008 -298.327179)
			(xy 162.289563 -298.378324) (xy 162.269173 -298.426851) (xy 162.241353 -298.471535) (xy 162.206804 -298.511248)
			(xy 162.166401 -298.544985) (xy 162.121162 -298.571895) (xy 162.072232 -298.591298) (xy 162.046666 -298.597574)
			(xy 162.02914 -298.601384) (xy 162.006788 -298.629324) (xy 162.006788 -298.87037) (xy 162.02914 -298.89831)
			(xy 162.046666 -298.90212) (xy 162.072255 -298.908322) (xy 162.121198 -298.927729) (xy 162.166448 -298.954646)
			(xy 162.206862 -298.988392) (xy 162.24142 -299.028114) (xy 162.269247 -299.072809) (xy 162.289643 -299.121349)
			(xy 162.30209 -299.172506) (xy 162.306276 -299.22499) (xy 162.304208 -299.250941) (xy 162.5948 -299.250941)
			(xy 162.5948 -299.198967) (xy 162.60293 -299.147632) (xy 162.618991 -299.098202) (xy 162.642587 -299.051892)
			(xy 162.673137 -299.009844) (xy 162.709888 -298.973093) (xy 162.751936 -298.942543) (xy 162.798246 -298.918947)
			(xy 162.847676 -298.902886) (xy 162.899011 -298.894756) (xy 162.950985 -298.894756) (xy 163.00232 -298.902886)
			(xy 163.05175 -298.918947) (xy 163.09806 -298.942543) (xy 163.140108 -298.973093) (xy 163.176859 -299.009844)
			(xy 163.207409 -299.051892) (xy 163.231005 -299.098202) (xy 163.247066 -299.147632) (xy 163.255196 -299.198967)
			(xy 163.255706 -299.224954) (xy 163.255196 -299.250941) (xy 163.54476 -299.250941) (xy 163.54476 -299.198967)
			(xy 163.55289 -299.147632) (xy 163.568951 -299.098202) (xy 163.592547 -299.051892) (xy 163.623097 -299.009844)
			(xy 163.659848 -298.973093) (xy 163.701896 -298.942543) (xy 163.748206 -298.918947) (xy 163.797636 -298.902886)
			(xy 163.848971 -298.894756) (xy 163.900945 -298.894756) (xy 163.95228 -298.902886) (xy 164.00171 -298.918947)
			(xy 164.04802 -298.942543) (xy 164.090068 -298.973093) (xy 164.126819 -299.009844) (xy 164.157369 -299.051892)
			(xy 164.180965 -299.098202) (xy 164.197026 -299.147632) (xy 164.205156 -299.198967) (xy 164.205666 -299.224954)
			(xy 164.205156 -299.250941) (xy 164.49472 -299.250941) (xy 164.49472 -299.198967) (xy 164.50285 -299.147632)
			(xy 164.518911 -299.098202) (xy 164.542507 -299.051892) (xy 164.573057 -299.009844) (xy 164.609808 -298.973093)
			(xy 164.651856 -298.942543) (xy 164.698166 -298.918947) (xy 164.747596 -298.902886) (xy 164.798931 -298.894756)
			(xy 164.850905 -298.894756) (xy 164.90224 -298.902886) (xy 164.95167 -298.918947) (xy 164.99798 -298.942543)
			(xy 165.040028 -298.973093) (xy 165.076779 -299.009844) (xy 165.107329 -299.051892) (xy 165.130925 -299.098202)
			(xy 165.146986 -299.147632) (xy 165.155116 -299.198967) (xy 165.155626 -299.224954) (xy 165.155116 -299.250941)
			(xy 165.44468 -299.250941) (xy 165.44468 -299.198967) (xy 165.45281 -299.147632) (xy 165.468871 -299.098202)
			(xy 165.492467 -299.051892) (xy 165.523017 -299.009844) (xy 165.559768 -298.973093) (xy 165.601816 -298.942543)
			(xy 165.648126 -298.918947) (xy 165.697556 -298.902886) (xy 165.748891 -298.894756) (xy 165.800865 -298.894756)
			(xy 165.8522 -298.902886) (xy 165.90163 -298.918947) (xy 165.94794 -298.942543) (xy 165.989988 -298.973093)
			(xy 166.026739 -299.009844) (xy 166.057289 -299.051892) (xy 166.080885 -299.098202) (xy 166.096946 -299.147632)
			(xy 166.105076 -299.198967) (xy 166.105586 -299.224954) (xy 166.105076 -299.250941) (xy 166.394894 -299.250941)
			(xy 166.394894 -299.198967) (xy 166.403024 -299.147632) (xy 166.419085 -299.098202) (xy 166.442681 -299.051892)
			(xy 166.473231 -299.009844) (xy 166.509982 -298.973093) (xy 166.55203 -298.942543) (xy 166.59834 -298.918947)
			(xy 166.64777 -298.902886) (xy 166.699105 -298.894756) (xy 166.751079 -298.894756) (xy 166.802414 -298.902886)
			(xy 166.851844 -298.918947) (xy 166.898154 -298.942543) (xy 166.940202 -298.973093) (xy 166.976953 -299.009844)
			(xy 167.007503 -299.051892) (xy 167.031099 -299.098202) (xy 167.04716 -299.147632) (xy 167.05529 -299.198967)
			(xy 167.0558 -299.224954) (xy 167.05529 -299.250941) (xy 167.344854 -299.250941) (xy 167.344854 -299.198967)
			(xy 167.352984 -299.147632) (xy 167.369045 -299.098202) (xy 167.392641 -299.051892) (xy 167.423191 -299.009844)
			(xy 167.459942 -298.973093) (xy 167.50199 -298.942543) (xy 167.5483 -298.918947) (xy 167.59773 -298.902886)
			(xy 167.649065 -298.894756) (xy 167.701039 -298.894756) (xy 167.752374 -298.902886) (xy 167.801804 -298.918947)
			(xy 167.848114 -298.942543) (xy 167.890162 -298.973093) (xy 167.926913 -299.009844) (xy 167.957463 -299.051892)
			(xy 167.981059 -299.098202) (xy 167.99712 -299.147632) (xy 168.00525 -299.198967) (xy 168.00576 -299.224954)
			(xy 168.00525 -299.250941) (xy 168.294814 -299.250941) (xy 168.294814 -299.198967) (xy 168.302944 -299.147632)
			(xy 168.319005 -299.098202) (xy 168.342601 -299.051892) (xy 168.373151 -299.009844) (xy 168.409902 -298.973093)
			(xy 168.45195 -298.942543) (xy 168.49826 -298.918947) (xy 168.54769 -298.902886) (xy 168.599025 -298.894756)
			(xy 168.650999 -298.894756) (xy 168.702334 -298.902886) (xy 168.751764 -298.918947) (xy 168.798074 -298.942543)
			(xy 168.840122 -298.973093) (xy 168.876873 -299.009844) (xy 168.907423 -299.051892) (xy 168.931019 -299.098202)
			(xy 168.94708 -299.147632) (xy 168.95521 -299.198967) (xy 168.95572 -299.224954) (xy 168.95521 -299.250941)
			(xy 169.244774 -299.250941) (xy 169.244774 -299.198967) (xy 169.252904 -299.147632) (xy 169.268965 -299.098202)
			(xy 169.292561 -299.051892) (xy 169.323111 -299.009844) (xy 169.359862 -298.973093) (xy 169.40191 -298.942543)
			(xy 169.44822 -298.918947) (xy 169.49765 -298.902886) (xy 169.548985 -298.894756) (xy 169.600959 -298.894756)
			(xy 169.652294 -298.902886) (xy 169.701724 -298.918947) (xy 169.748034 -298.942543) (xy 169.790082 -298.973093)
			(xy 169.826833 -299.009844) (xy 169.857383 -299.051892) (xy 169.880979 -299.098202) (xy 169.89704 -299.147632)
			(xy 169.90517 -299.198967) (xy 169.90568 -299.224954) (xy 169.90517 -299.250941) (xy 170.194734 -299.250941)
			(xy 170.194734 -299.198967) (xy 170.202864 -299.147632) (xy 170.218925 -299.098202) (xy 170.242521 -299.051892)
			(xy 170.273071 -299.009844) (xy 170.309822 -298.973093) (xy 170.35187 -298.942543) (xy 170.39818 -298.918947)
			(xy 170.44761 -298.902886) (xy 170.498945 -298.894756) (xy 170.550919 -298.894756) (xy 170.602254 -298.902886)
			(xy 170.651684 -298.918947) (xy 170.697994 -298.942543) (xy 170.740042 -298.973093) (xy 170.776793 -299.009844)
			(xy 170.807343 -299.051892) (xy 170.830939 -299.098202) (xy 170.847 -299.147632) (xy 170.85513 -299.198967)
			(xy 170.85564 -299.224954) (xy 170.85513 -299.250941) (xy 171.144694 -299.250941) (xy 171.144694 -299.198967)
			(xy 171.152824 -299.147632) (xy 171.168885 -299.098202) (xy 171.192481 -299.051892) (xy 171.223031 -299.009844)
			(xy 171.259782 -298.973093) (xy 171.30183 -298.942543) (xy 171.34814 -298.918947) (xy 171.39757 -298.902886)
			(xy 171.448905 -298.894756) (xy 171.500879 -298.894756) (xy 171.552214 -298.902886) (xy 171.601644 -298.918947)
			(xy 171.647954 -298.942543) (xy 171.690002 -298.973093) (xy 171.726753 -299.009844) (xy 171.757303 -299.051892)
			(xy 171.780899 -299.098202) (xy 171.79696 -299.147632) (xy 171.80509 -299.198967) (xy 171.8056 -299.224954)
			(xy 171.80509 -299.250941) (xy 172.094654 -299.250941) (xy 172.094654 -299.198967) (xy 172.102784 -299.147632)
			(xy 172.118845 -299.098202) (xy 172.142441 -299.051892) (xy 172.172991 -299.009844) (xy 172.209742 -298.973093)
			(xy 172.25179 -298.942543) (xy 172.2981 -298.918947) (xy 172.34753 -298.902886) (xy 172.398865 -298.894756)
			(xy 172.450839 -298.894756) (xy 172.502174 -298.902886) (xy 172.551604 -298.918947) (xy 172.597914 -298.942543)
			(xy 172.639962 -298.973093) (xy 172.676713 -299.009844) (xy 172.707263 -299.051892) (xy 172.730859 -299.098202)
			(xy 172.74692 -299.147632) (xy 172.75505 -299.198967) (xy 172.75556 -299.224954) (xy 172.75505 -299.250941)
			(xy 173.044868 -299.250941) (xy 173.044868 -299.198967) (xy 173.052998 -299.147632) (xy 173.069059 -299.098202)
			(xy 173.092655 -299.051892) (xy 173.123205 -299.009844) (xy 173.159956 -298.973093) (xy 173.202004 -298.942543)
			(xy 173.248314 -298.918947) (xy 173.297744 -298.902886) (xy 173.349079 -298.894756) (xy 173.401053 -298.894756)
			(xy 173.452388 -298.902886) (xy 173.501818 -298.918947) (xy 173.548128 -298.942543) (xy 173.590176 -298.973093)
			(xy 173.626927 -299.009844) (xy 173.657477 -299.051892) (xy 173.681073 -299.098202) (xy 173.697134 -299.147632)
			(xy 173.705264 -299.198967) (xy 173.705774 -299.224954) (xy 173.705264 -299.250941) (xy 173.994828 -299.250941)
			(xy 173.994828 -299.198967) (xy 174.002958 -299.147632) (xy 174.019019 -299.098202) (xy 174.042615 -299.051892)
			(xy 174.073165 -299.009844) (xy 174.109916 -298.973093) (xy 174.151964 -298.942543) (xy 174.198274 -298.918947)
			(xy 174.247704 -298.902886) (xy 174.299039 -298.894756) (xy 174.351013 -298.894756) (xy 174.402348 -298.902886)
			(xy 174.451778 -298.918947) (xy 174.498088 -298.942543) (xy 174.540136 -298.973093) (xy 174.576887 -299.009844)
			(xy 174.607437 -299.051892) (xy 174.631033 -299.098202) (xy 174.647094 -299.147632) (xy 174.655224 -299.198967)
			(xy 174.655734 -299.224954) (xy 174.655224 -299.250941) (xy 175.894748 -299.250941) (xy 175.894748 -299.198967)
			(xy 175.902878 -299.147632) (xy 175.918939 -299.098202) (xy 175.942535 -299.051892) (xy 175.973085 -299.009844)
			(xy 176.009836 -298.973093) (xy 176.051884 -298.942543) (xy 176.098194 -298.918947) (xy 176.147624 -298.902886)
			(xy 176.198959 -298.894756) (xy 176.250933 -298.894756) (xy 176.302268 -298.902886) (xy 176.351698 -298.918947)
			(xy 176.398008 -298.942543) (xy 176.440056 -298.973093) (xy 176.476807 -299.009844) (xy 176.507357 -299.051892)
			(xy 176.530953 -299.098202) (xy 176.547014 -299.147632) (xy 176.555144 -299.198967) (xy 176.555654 -299.224954)
			(xy 176.555144 -299.250941) (xy 176.844708 -299.250941) (xy 176.844708 -299.198967) (xy 176.852838 -299.147632)
			(xy 176.868899 -299.098202) (xy 176.892495 -299.051892) (xy 176.923045 -299.009844) (xy 176.959796 -298.973093)
			(xy 177.001844 -298.942543) (xy 177.048154 -298.918947) (xy 177.097584 -298.902886) (xy 177.148919 -298.894756)
			(xy 177.200893 -298.894756) (xy 177.252228 -298.902886) (xy 177.301658 -298.918947) (xy 177.347968 -298.942543)
			(xy 177.390016 -298.973093) (xy 177.426767 -299.009844) (xy 177.457317 -299.051892) (xy 177.480913 -299.098202)
			(xy 177.496974 -299.147632) (xy 177.505104 -299.198967) (xy 177.505614 -299.224954) (xy 177.505104 -299.250941)
			(xy 177.794668 -299.250941) (xy 177.794668 -299.198967) (xy 177.802798 -299.147632) (xy 177.818859 -299.098202)
			(xy 177.842455 -299.051892) (xy 177.873005 -299.009844) (xy 177.909756 -298.973093) (xy 177.951804 -298.942543)
			(xy 177.998114 -298.918947) (xy 178.047544 -298.902886) (xy 178.098879 -298.894756) (xy 178.150853 -298.894756)
			(xy 178.202188 -298.902886) (xy 178.251618 -298.918947) (xy 178.297928 -298.942543) (xy 178.339976 -298.973093)
			(xy 178.376727 -299.009844) (xy 178.407277 -299.051892) (xy 178.430873 -299.098202) (xy 178.446934 -299.147632)
			(xy 178.455064 -299.198967) (xy 178.455574 -299.224954) (xy 178.455064 -299.250941) (xy 178.744882 -299.250941)
			(xy 178.744882 -299.198967) (xy 178.753012 -299.147632) (xy 178.769073 -299.098202) (xy 178.792669 -299.051892)
			(xy 178.823219 -299.009844) (xy 178.85997 -298.973093) (xy 178.902018 -298.942543) (xy 178.948328 -298.918947)
			(xy 178.997758 -298.902886) (xy 179.049093 -298.894756) (xy 179.101067 -298.894756) (xy 179.152402 -298.902886)
			(xy 179.201832 -298.918947) (xy 179.248142 -298.942543) (xy 179.29019 -298.973093) (xy 179.326941 -299.009844)
			(xy 179.357491 -299.051892) (xy 179.381087 -299.098202) (xy 179.397148 -299.147632) (xy 179.405278 -299.198967)
			(xy 179.405788 -299.224954) (xy 179.405278 -299.250941) (xy 179.694842 -299.250941) (xy 179.694842 -299.198967)
			(xy 179.702972 -299.147632) (xy 179.719033 -299.098202) (xy 179.742629 -299.051892) (xy 179.773179 -299.009844)
			(xy 179.80993 -298.973093) (xy 179.851978 -298.942543) (xy 179.898288 -298.918947) (xy 179.947718 -298.902886)
			(xy 179.999053 -298.894756) (xy 180.051027 -298.894756) (xy 180.102362 -298.902886) (xy 180.151792 -298.918947)
			(xy 180.198102 -298.942543) (xy 180.24015 -298.973093) (xy 180.276901 -299.009844) (xy 180.307451 -299.051892)
			(xy 180.331047 -299.098202) (xy 180.347108 -299.147632) (xy 180.355238 -299.198967) (xy 180.355748 -299.224954)
			(xy 180.355238 -299.250941) (xy 180.644802 -299.250941) (xy 180.644802 -299.198967) (xy 180.652932 -299.147632)
			(xy 180.668993 -299.098202) (xy 180.692589 -299.051892) (xy 180.723139 -299.009844) (xy 180.75989 -298.973093)
			(xy 180.801938 -298.942543) (xy 180.848248 -298.918947) (xy 180.897678 -298.902886) (xy 180.949013 -298.894756)
			(xy 181.000987 -298.894756) (xy 181.052322 -298.902886) (xy 181.101752 -298.918947) (xy 181.148062 -298.942543)
			(xy 181.19011 -298.973093) (xy 181.226861 -299.009844) (xy 181.257411 -299.051892) (xy 181.281007 -299.098202)
			(xy 181.297068 -299.147632) (xy 181.305198 -299.198967) (xy 181.305708 -299.224954) (xy 181.305198 -299.250941)
			(xy 181.594762 -299.250941) (xy 181.594762 -299.198967) (xy 181.602892 -299.147632) (xy 181.618953 -299.098202)
			(xy 181.642549 -299.051892) (xy 181.673099 -299.009844) (xy 181.70985 -298.973093) (xy 181.751898 -298.942543)
			(xy 181.798208 -298.918947) (xy 181.847638 -298.902886) (xy 181.898973 -298.894756) (xy 181.950947 -298.894756)
			(xy 182.002282 -298.902886) (xy 182.051712 -298.918947) (xy 182.098022 -298.942543) (xy 182.14007 -298.973093)
			(xy 182.176821 -299.009844) (xy 182.207371 -299.051892) (xy 182.230967 -299.098202) (xy 182.247028 -299.147632)
			(xy 182.255158 -299.198967) (xy 182.255668 -299.224954) (xy 182.255158 -299.250941) (xy 182.544722 -299.250941)
			(xy 182.544722 -299.198967) (xy 182.552852 -299.147632) (xy 182.568913 -299.098202) (xy 182.592509 -299.051892)
			(xy 182.623059 -299.009844) (xy 182.65981 -298.973093) (xy 182.701858 -298.942543) (xy 182.748168 -298.918947)
			(xy 182.797598 -298.902886) (xy 182.848933 -298.894756) (xy 182.900907 -298.894756) (xy 182.952242 -298.902886)
			(xy 183.001672 -298.918947) (xy 183.047982 -298.942543) (xy 183.09003 -298.973093) (xy 183.126781 -299.009844)
			(xy 183.157331 -299.051892) (xy 183.180927 -299.098202) (xy 183.196988 -299.147632) (xy 183.205118 -299.198967)
			(xy 183.205628 -299.224954) (xy 183.205118 -299.250941) (xy 183.494682 -299.250941) (xy 183.494682 -299.198967)
			(xy 183.502812 -299.147632) (xy 183.518873 -299.098202) (xy 183.542469 -299.051892) (xy 183.573019 -299.009844)
			(xy 183.60977 -298.973093) (xy 183.651818 -298.942543) (xy 183.698128 -298.918947) (xy 183.747558 -298.902886)
			(xy 183.798893 -298.894756) (xy 183.850867 -298.894756) (xy 183.902202 -298.902886) (xy 183.951632 -298.918947)
			(xy 183.997942 -298.942543) (xy 184.03999 -298.973093) (xy 184.076741 -299.009844) (xy 184.107291 -299.051892)
			(xy 184.130887 -299.098202) (xy 184.146948 -299.147632) (xy 184.155078 -299.198967) (xy 184.155588 -299.224954)
			(xy 184.155078 -299.250941) (xy 184.146948 -299.302276) (xy 184.130887 -299.351706) (xy 184.107291 -299.398016)
			(xy 184.076741 -299.440064) (xy 184.03999 -299.476815) (xy 183.997942 -299.507365) (xy 183.951632 -299.530961)
			(xy 183.902202 -299.547022) (xy 183.850867 -299.555152) (xy 183.798893 -299.555152) (xy 183.747558 -299.547022)
			(xy 183.698128 -299.530961) (xy 183.651818 -299.507365) (xy 183.60977 -299.476815) (xy 183.573019 -299.440064)
			(xy 183.542469 -299.398016) (xy 183.518873 -299.351706) (xy 183.502812 -299.302276) (xy 183.494682 -299.250941)
			(xy 183.205118 -299.250941) (xy 183.196988 -299.302276) (xy 183.180927 -299.351706) (xy 183.157331 -299.398016)
			(xy 183.126781 -299.440064) (xy 183.09003 -299.476815) (xy 183.047982 -299.507365) (xy 183.001672 -299.530961)
			(xy 182.952242 -299.547022) (xy 182.900907 -299.555152) (xy 182.848933 -299.555152) (xy 182.797598 -299.547022)
			(xy 182.748168 -299.530961) (xy 182.701858 -299.507365) (xy 182.65981 -299.476815) (xy 182.623059 -299.440064)
			(xy 182.592509 -299.398016) (xy 182.568913 -299.351706) (xy 182.552852 -299.302276) (xy 182.544722 -299.250941)
			(xy 182.255158 -299.250941) (xy 182.247028 -299.302276) (xy 182.230967 -299.351706) (xy 182.207371 -299.398016)
			(xy 182.176821 -299.440064) (xy 182.14007 -299.476815) (xy 182.098022 -299.507365) (xy 182.051712 -299.530961)
			(xy 182.002282 -299.547022) (xy 181.950947 -299.555152) (xy 181.898973 -299.555152) (xy 181.847638 -299.547022)
			(xy 181.798208 -299.530961) (xy 181.751898 -299.507365) (xy 181.70985 -299.476815) (xy 181.673099 -299.440064)
			(xy 181.642549 -299.398016) (xy 181.618953 -299.351706) (xy 181.602892 -299.302276) (xy 181.594762 -299.250941)
			(xy 181.305198 -299.250941) (xy 181.297068 -299.302276) (xy 181.281007 -299.351706) (xy 181.257411 -299.398016)
			(xy 181.226861 -299.440064) (xy 181.19011 -299.476815) (xy 181.148062 -299.507365) (xy 181.101752 -299.530961)
			(xy 181.052322 -299.547022) (xy 181.000987 -299.555152) (xy 180.949013 -299.555152) (xy 180.897678 -299.547022)
			(xy 180.848248 -299.530961) (xy 180.801938 -299.507365) (xy 180.75989 -299.476815) (xy 180.723139 -299.440064)
			(xy 180.692589 -299.398016) (xy 180.668993 -299.351706) (xy 180.652932 -299.302276) (xy 180.644802 -299.250941)
			(xy 180.355238 -299.250941) (xy 180.347108 -299.302276) (xy 180.331047 -299.351706) (xy 180.307451 -299.398016)
			(xy 180.276901 -299.440064) (xy 180.24015 -299.476815) (xy 180.198102 -299.507365) (xy 180.151792 -299.530961)
			(xy 180.102362 -299.547022) (xy 180.051027 -299.555152) (xy 179.999053 -299.555152) (xy 179.947718 -299.547022)
			(xy 179.898288 -299.530961) (xy 179.851978 -299.507365) (xy 179.80993 -299.476815) (xy 179.773179 -299.440064)
			(xy 179.742629 -299.398016) (xy 179.719033 -299.351706) (xy 179.702972 -299.302276) (xy 179.694842 -299.250941)
			(xy 179.405278 -299.250941) (xy 179.397148 -299.302276) (xy 179.381087 -299.351706) (xy 179.357491 -299.398016)
			(xy 179.326941 -299.440064) (xy 179.29019 -299.476815) (xy 179.248142 -299.507365) (xy 179.201832 -299.530961)
			(xy 179.152402 -299.547022) (xy 179.101067 -299.555152) (xy 179.049093 -299.555152) (xy 178.997758 -299.547022)
			(xy 178.948328 -299.530961) (xy 178.902018 -299.507365) (xy 178.85997 -299.476815) (xy 178.823219 -299.440064)
			(xy 178.792669 -299.398016) (xy 178.769073 -299.351706) (xy 178.753012 -299.302276) (xy 178.744882 -299.250941)
			(xy 178.455064 -299.250941) (xy 178.446934 -299.302276) (xy 178.430873 -299.351706) (xy 178.407277 -299.398016)
			(xy 178.376727 -299.440064) (xy 178.339976 -299.476815) (xy 178.297928 -299.507365) (xy 178.251618 -299.530961)
			(xy 178.202188 -299.547022) (xy 178.150853 -299.555152) (xy 178.098879 -299.555152) (xy 178.047544 -299.547022)
			(xy 177.998114 -299.530961) (xy 177.951804 -299.507365) (xy 177.909756 -299.476815) (xy 177.873005 -299.440064)
			(xy 177.842455 -299.398016) (xy 177.818859 -299.351706) (xy 177.802798 -299.302276) (xy 177.794668 -299.250941)
			(xy 177.505104 -299.250941) (xy 177.496974 -299.302276) (xy 177.480913 -299.351706) (xy 177.457317 -299.398016)
			(xy 177.426767 -299.440064) (xy 177.390016 -299.476815) (xy 177.347968 -299.507365) (xy 177.301658 -299.530961)
			(xy 177.252228 -299.547022) (xy 177.200893 -299.555152) (xy 177.148919 -299.555152) (xy 177.097584 -299.547022)
			(xy 177.048154 -299.530961) (xy 177.001844 -299.507365) (xy 176.959796 -299.476815) (xy 176.923045 -299.440064)
			(xy 176.892495 -299.398016) (xy 176.868899 -299.351706) (xy 176.852838 -299.302276) (xy 176.844708 -299.250941)
			(xy 176.555144 -299.250941) (xy 176.547014 -299.302276) (xy 176.530953 -299.351706) (xy 176.507357 -299.398016)
			(xy 176.476807 -299.440064) (xy 176.440056 -299.476815) (xy 176.398008 -299.507365) (xy 176.351698 -299.530961)
			(xy 176.302268 -299.547022) (xy 176.250933 -299.555152) (xy 176.198959 -299.555152) (xy 176.147624 -299.547022)
			(xy 176.098194 -299.530961) (xy 176.051884 -299.507365) (xy 176.009836 -299.476815) (xy 175.973085 -299.440064)
			(xy 175.942535 -299.398016) (xy 175.918939 -299.351706) (xy 175.902878 -299.302276) (xy 175.894748 -299.250941)
			(xy 174.655224 -299.250941) (xy 174.647094 -299.302276) (xy 174.631033 -299.351706) (xy 174.607437 -299.398016)
			(xy 174.576887 -299.440064) (xy 174.540136 -299.476815) (xy 174.498088 -299.507365) (xy 174.451778 -299.530961)
			(xy 174.402348 -299.547022) (xy 174.351013 -299.555152) (xy 174.299039 -299.555152) (xy 174.247704 -299.547022)
			(xy 174.198274 -299.530961) (xy 174.151964 -299.507365) (xy 174.109916 -299.476815) (xy 174.073165 -299.440064)
			(xy 174.042615 -299.398016) (xy 174.019019 -299.351706) (xy 174.002958 -299.302276) (xy 173.994828 -299.250941)
			(xy 173.705264 -299.250941) (xy 173.697134 -299.302276) (xy 173.681073 -299.351706) (xy 173.657477 -299.398016)
			(xy 173.626927 -299.440064) (xy 173.590176 -299.476815) (xy 173.548128 -299.507365) (xy 173.501818 -299.530961)
			(xy 173.452388 -299.547022) (xy 173.401053 -299.555152) (xy 173.349079 -299.555152) (xy 173.297744 -299.547022)
			(xy 173.248314 -299.530961) (xy 173.202004 -299.507365) (xy 173.159956 -299.476815) (xy 173.123205 -299.440064)
			(xy 173.092655 -299.398016) (xy 173.069059 -299.351706) (xy 173.052998 -299.302276) (xy 173.044868 -299.250941)
			(xy 172.75505 -299.250941) (xy 172.74692 -299.302276) (xy 172.730859 -299.351706) (xy 172.707263 -299.398016)
			(xy 172.676713 -299.440064) (xy 172.639962 -299.476815) (xy 172.597914 -299.507365) (xy 172.551604 -299.530961)
			(xy 172.502174 -299.547022) (xy 172.450839 -299.555152) (xy 172.398865 -299.555152) (xy 172.34753 -299.547022)
			(xy 172.2981 -299.530961) (xy 172.25179 -299.507365) (xy 172.209742 -299.476815) (xy 172.172991 -299.440064)
			(xy 172.142441 -299.398016) (xy 172.118845 -299.351706) (xy 172.102784 -299.302276) (xy 172.094654 -299.250941)
			(xy 171.80509 -299.250941) (xy 171.79696 -299.302276) (xy 171.780899 -299.351706) (xy 171.757303 -299.398016)
			(xy 171.726753 -299.440064) (xy 171.690002 -299.476815) (xy 171.647954 -299.507365) (xy 171.601644 -299.530961)
			(xy 171.552214 -299.547022) (xy 171.500879 -299.555152) (xy 171.448905 -299.555152) (xy 171.39757 -299.547022)
			(xy 171.34814 -299.530961) (xy 171.30183 -299.507365) (xy 171.259782 -299.476815) (xy 171.223031 -299.440064)
			(xy 171.192481 -299.398016) (xy 171.168885 -299.351706) (xy 171.152824 -299.302276) (xy 171.144694 -299.250941)
			(xy 170.85513 -299.250941) (xy 170.847 -299.302276) (xy 170.830939 -299.351706) (xy 170.807343 -299.398016)
			(xy 170.776793 -299.440064) (xy 170.740042 -299.476815) (xy 170.697994 -299.507365) (xy 170.651684 -299.530961)
			(xy 170.602254 -299.547022) (xy 170.550919 -299.555152) (xy 170.498945 -299.555152) (xy 170.44761 -299.547022)
			(xy 170.39818 -299.530961) (xy 170.35187 -299.507365) (xy 170.309822 -299.476815) (xy 170.273071 -299.440064)
			(xy 170.242521 -299.398016) (xy 170.218925 -299.351706) (xy 170.202864 -299.302276) (xy 170.194734 -299.250941)
			(xy 169.90517 -299.250941) (xy 169.89704 -299.302276) (xy 169.880979 -299.351706) (xy 169.857383 -299.398016)
			(xy 169.826833 -299.440064) (xy 169.790082 -299.476815) (xy 169.748034 -299.507365) (xy 169.701724 -299.530961)
			(xy 169.652294 -299.547022) (xy 169.600959 -299.555152) (xy 169.548985 -299.555152) (xy 169.49765 -299.547022)
			(xy 169.44822 -299.530961) (xy 169.40191 -299.507365) (xy 169.359862 -299.476815) (xy 169.323111 -299.440064)
			(xy 169.292561 -299.398016) (xy 169.268965 -299.351706) (xy 169.252904 -299.302276) (xy 169.244774 -299.250941)
			(xy 168.95521 -299.250941) (xy 168.94708 -299.302276) (xy 168.931019 -299.351706) (xy 168.907423 -299.398016)
			(xy 168.876873 -299.440064) (xy 168.840122 -299.476815) (xy 168.798074 -299.507365) (xy 168.751764 -299.530961)
			(xy 168.702334 -299.547022) (xy 168.650999 -299.555152) (xy 168.599025 -299.555152) (xy 168.54769 -299.547022)
			(xy 168.49826 -299.530961) (xy 168.45195 -299.507365) (xy 168.409902 -299.476815) (xy 168.373151 -299.440064)
			(xy 168.342601 -299.398016) (xy 168.319005 -299.351706) (xy 168.302944 -299.302276) (xy 168.294814 -299.250941)
			(xy 168.00525 -299.250941) (xy 167.99712 -299.302276) (xy 167.981059 -299.351706) (xy 167.957463 -299.398016)
			(xy 167.926913 -299.440064) (xy 167.890162 -299.476815) (xy 167.848114 -299.507365) (xy 167.801804 -299.530961)
			(xy 167.752374 -299.547022) (xy 167.701039 -299.555152) (xy 167.649065 -299.555152) (xy 167.59773 -299.547022)
			(xy 167.5483 -299.530961) (xy 167.50199 -299.507365) (xy 167.459942 -299.476815) (xy 167.423191 -299.440064)
			(xy 167.392641 -299.398016) (xy 167.369045 -299.351706) (xy 167.352984 -299.302276) (xy 167.344854 -299.250941)
			(xy 167.05529 -299.250941) (xy 167.04716 -299.302276) (xy 167.031099 -299.351706) (xy 167.007503 -299.398016)
			(xy 166.976953 -299.440064) (xy 166.940202 -299.476815) (xy 166.898154 -299.507365) (xy 166.851844 -299.530961)
			(xy 166.802414 -299.547022) (xy 166.751079 -299.555152) (xy 166.699105 -299.555152) (xy 166.64777 -299.547022)
			(xy 166.59834 -299.530961) (xy 166.55203 -299.507365) (xy 166.509982 -299.476815) (xy 166.473231 -299.440064)
			(xy 166.442681 -299.398016) (xy 166.419085 -299.351706) (xy 166.403024 -299.302276) (xy 166.394894 -299.250941)
			(xy 166.105076 -299.250941) (xy 166.096946 -299.302276) (xy 166.080885 -299.351706) (xy 166.057289 -299.398016)
			(xy 166.026739 -299.440064) (xy 165.989988 -299.476815) (xy 165.94794 -299.507365) (xy 165.90163 -299.530961)
			(xy 165.8522 -299.547022) (xy 165.800865 -299.555152) (xy 165.748891 -299.555152) (xy 165.697556 -299.547022)
			(xy 165.648126 -299.530961) (xy 165.601816 -299.507365) (xy 165.559768 -299.476815) (xy 165.523017 -299.440064)
			(xy 165.492467 -299.398016) (xy 165.468871 -299.351706) (xy 165.45281 -299.302276) (xy 165.44468 -299.250941)
			(xy 165.155116 -299.250941) (xy 165.146986 -299.302276) (xy 165.130925 -299.351706) (xy 165.107329 -299.398016)
			(xy 165.076779 -299.440064) (xy 165.040028 -299.476815) (xy 164.99798 -299.507365) (xy 164.95167 -299.530961)
			(xy 164.90224 -299.547022) (xy 164.850905 -299.555152) (xy 164.798931 -299.555152) (xy 164.747596 -299.547022)
			(xy 164.698166 -299.530961) (xy 164.651856 -299.507365) (xy 164.609808 -299.476815) (xy 164.573057 -299.440064)
			(xy 164.542507 -299.398016) (xy 164.518911 -299.351706) (xy 164.50285 -299.302276) (xy 164.49472 -299.250941)
			(xy 164.205156 -299.250941) (xy 164.197026 -299.302276) (xy 164.180965 -299.351706) (xy 164.157369 -299.398016)
			(xy 164.126819 -299.440064) (xy 164.090068 -299.476815) (xy 164.04802 -299.507365) (xy 164.00171 -299.530961)
			(xy 163.95228 -299.547022) (xy 163.900945 -299.555152) (xy 163.848971 -299.555152) (xy 163.797636 -299.547022)
			(xy 163.748206 -299.530961) (xy 163.701896 -299.507365) (xy 163.659848 -299.476815) (xy 163.623097 -299.440064)
			(xy 163.592547 -299.398016) (xy 163.568951 -299.351706) (xy 163.55289 -299.302276) (xy 163.54476 -299.250941)
			(xy 163.255196 -299.250941) (xy 163.247066 -299.302276) (xy 163.231005 -299.351706) (xy 163.207409 -299.398016)
			(xy 163.176859 -299.440064) (xy 163.140108 -299.476815) (xy 163.09806 -299.507365) (xy 163.05175 -299.530961)
			(xy 163.00232 -299.547022) (xy 162.950985 -299.555152) (xy 162.899011 -299.555152) (xy 162.847676 -299.547022)
			(xy 162.798246 -299.530961) (xy 162.751936 -299.507365) (xy 162.709888 -299.476815) (xy 162.673137 -299.440064)
			(xy 162.642587 -299.398016) (xy 162.618991 -299.351706) (xy 162.60293 -299.302276) (xy 162.5948 -299.250941)
			(xy 162.304208 -299.250941) (xy 162.302093 -299.277474) (xy 162.289649 -299.328633) (xy 162.269257 -299.377173)
			(xy 162.241432 -299.42187) (xy 162.206876 -299.461595) (xy 162.166464 -299.495342) (xy 162.121216 -299.522262)
			(xy 162.072274 -299.541672) (xy 162.046666 -299.547788) (xy 162.02914 -299.551598) (xy 162.006788 -299.579538)
			(xy 162.006788 -299.82033) (xy 162.02914 -299.84827) (xy 162.046666 -299.85208) (xy 162.072251 -299.858282)
			(xy 162.121184 -299.877688) (xy 162.166425 -299.904601) (xy 162.206831 -299.938342) (xy 162.24138 -299.978059)
			(xy 162.269201 -300.022747) (xy 162.289591 -300.071279) (xy 162.302035 -300.122428) (xy 162.306217 -300.174903)
			(xy 162.304145 -300.200901) (xy 162.5948 -300.200901) (xy 162.5948 -300.148927) (xy 162.60293 -300.097592)
			(xy 162.618991 -300.048162) (xy 162.642587 -300.001852) (xy 162.673137 -299.959804) (xy 162.709888 -299.923053)
			(xy 162.751936 -299.892503) (xy 162.798246 -299.868907) (xy 162.847676 -299.852846) (xy 162.899011 -299.844716)
			(xy 162.950985 -299.844716) (xy 163.00232 -299.852846) (xy 163.05175 -299.868907) (xy 163.09806 -299.892503)
			(xy 163.140108 -299.923053) (xy 163.176859 -299.959804) (xy 163.207409 -300.001852) (xy 163.231005 -300.048162)
			(xy 163.247066 -300.097592) (xy 163.255196 -300.148927) (xy 163.255706 -300.174914) (xy 163.255196 -300.200901)
			(xy 163.54476 -300.200901) (xy 163.54476 -300.148927) (xy 163.55289 -300.097592) (xy 163.568951 -300.048162)
			(xy 163.592547 -300.001852) (xy 163.623097 -299.959804) (xy 163.659848 -299.923053) (xy 163.701896 -299.892503)
			(xy 163.748206 -299.868907) (xy 163.797636 -299.852846) (xy 163.848971 -299.844716) (xy 163.900945 -299.844716)
			(xy 163.95228 -299.852846) (xy 164.00171 -299.868907) (xy 164.04802 -299.892503) (xy 164.090068 -299.923053)
			(xy 164.126819 -299.959804) (xy 164.157369 -300.001852) (xy 164.180965 -300.048162) (xy 164.197026 -300.097592)
			(xy 164.205156 -300.148927) (xy 164.205666 -300.174914) (xy 164.205156 -300.200901) (xy 164.49472 -300.200901)
			(xy 164.49472 -300.148927) (xy 164.50285 -300.097592) (xy 164.518911 -300.048162) (xy 164.542507 -300.001852)
			(xy 164.573057 -299.959804) (xy 164.609808 -299.923053) (xy 164.651856 -299.892503) (xy 164.698166 -299.868907)
			(xy 164.747596 -299.852846) (xy 164.798931 -299.844716) (xy 164.850905 -299.844716) (xy 164.90224 -299.852846)
			(xy 164.95167 -299.868907) (xy 164.99798 -299.892503) (xy 165.040028 -299.923053) (xy 165.076779 -299.959804)
			(xy 165.107329 -300.001852) (xy 165.130925 -300.048162) (xy 165.146986 -300.097592) (xy 165.155116 -300.148927)
			(xy 165.155626 -300.174914) (xy 165.155116 -300.200901) (xy 165.44468 -300.200901) (xy 165.44468 -300.148927)
			(xy 165.45281 -300.097592) (xy 165.468871 -300.048162) (xy 165.492467 -300.001852) (xy 165.523017 -299.959804)
			(xy 165.559768 -299.923053) (xy 165.601816 -299.892503) (xy 165.648126 -299.868907) (xy 165.697556 -299.852846)
			(xy 165.748891 -299.844716) (xy 165.800865 -299.844716) (xy 165.8522 -299.852846) (xy 165.90163 -299.868907)
			(xy 165.94794 -299.892503) (xy 165.989988 -299.923053) (xy 166.026739 -299.959804) (xy 166.057289 -300.001852)
			(xy 166.080885 -300.048162) (xy 166.096946 -300.097592) (xy 166.105076 -300.148927) (xy 166.105586 -300.174914)
			(xy 166.105076 -300.200901) (xy 166.394894 -300.200901) (xy 166.394894 -300.148927) (xy 166.403024 -300.097592)
			(xy 166.419085 -300.048162) (xy 166.442681 -300.001852) (xy 166.473231 -299.959804) (xy 166.509982 -299.923053)
			(xy 166.55203 -299.892503) (xy 166.59834 -299.868907) (xy 166.64777 -299.852846) (xy 166.699105 -299.844716)
			(xy 166.751079 -299.844716) (xy 166.802414 -299.852846) (xy 166.851844 -299.868907) (xy 166.898154 -299.892503)
			(xy 166.940202 -299.923053) (xy 166.976953 -299.959804) (xy 167.007503 -300.001852) (xy 167.031099 -300.048162)
			(xy 167.04716 -300.097592) (xy 167.05529 -300.148927) (xy 167.0558 -300.174914) (xy 167.05529 -300.200901)
			(xy 167.344854 -300.200901) (xy 167.344854 -300.148927) (xy 167.352984 -300.097592) (xy 167.369045 -300.048162)
			(xy 167.392641 -300.001852) (xy 167.423191 -299.959804) (xy 167.459942 -299.923053) (xy 167.50199 -299.892503)
			(xy 167.5483 -299.868907) (xy 167.59773 -299.852846) (xy 167.649065 -299.844716) (xy 167.701039 -299.844716)
			(xy 167.752374 -299.852846) (xy 167.801804 -299.868907) (xy 167.848114 -299.892503) (xy 167.890162 -299.923053)
			(xy 167.926913 -299.959804) (xy 167.957463 -300.001852) (xy 167.981059 -300.048162) (xy 167.99712 -300.097592)
			(xy 168.00525 -300.148927) (xy 168.00576 -300.174914) (xy 168.00525 -300.200901) (xy 168.294814 -300.200901)
			(xy 168.294814 -300.148927) (xy 168.302944 -300.097592) (xy 168.319005 -300.048162) (xy 168.342601 -300.001852)
			(xy 168.373151 -299.959804) (xy 168.409902 -299.923053) (xy 168.45195 -299.892503) (xy 168.49826 -299.868907)
			(xy 168.54769 -299.852846) (xy 168.599025 -299.844716) (xy 168.650999 -299.844716) (xy 168.702334 -299.852846)
			(xy 168.751764 -299.868907) (xy 168.798074 -299.892503) (xy 168.840122 -299.923053) (xy 168.876873 -299.959804)
			(xy 168.907423 -300.001852) (xy 168.931019 -300.048162) (xy 168.94708 -300.097592) (xy 168.95521 -300.148927)
			(xy 168.95572 -300.174914) (xy 168.95521 -300.200901) (xy 169.244774 -300.200901) (xy 169.244774 -300.148927)
			(xy 169.252904 -300.097592) (xy 169.268965 -300.048162) (xy 169.292561 -300.001852) (xy 169.323111 -299.959804)
			(xy 169.359862 -299.923053) (xy 169.40191 -299.892503) (xy 169.44822 -299.868907) (xy 169.49765 -299.852846)
			(xy 169.548985 -299.844716) (xy 169.600959 -299.844716) (xy 169.652294 -299.852846) (xy 169.701724 -299.868907)
			(xy 169.748034 -299.892503) (xy 169.790082 -299.923053) (xy 169.826833 -299.959804) (xy 169.857383 -300.001852)
			(xy 169.880979 -300.048162) (xy 169.89704 -300.097592) (xy 169.90517 -300.148927) (xy 169.90568 -300.174914)
			(xy 169.90517 -300.200901) (xy 170.194734 -300.200901) (xy 170.194734 -300.148927) (xy 170.202864 -300.097592)
			(xy 170.218925 -300.048162) (xy 170.242521 -300.001852) (xy 170.273071 -299.959804) (xy 170.309822 -299.923053)
			(xy 170.35187 -299.892503) (xy 170.39818 -299.868907) (xy 170.44761 -299.852846) (xy 170.498945 -299.844716)
			(xy 170.550919 -299.844716) (xy 170.602254 -299.852846) (xy 170.651684 -299.868907) (xy 170.697994 -299.892503)
			(xy 170.740042 -299.923053) (xy 170.776793 -299.959804) (xy 170.807343 -300.001852) (xy 170.830939 -300.048162)
			(xy 170.847 -300.097592) (xy 170.85513 -300.148927) (xy 170.85564 -300.174914) (xy 170.85513 -300.200901)
			(xy 171.144694 -300.200901) (xy 171.144694 -300.148927) (xy 171.152824 -300.097592) (xy 171.168885 -300.048162)
			(xy 171.192481 -300.001852) (xy 171.223031 -299.959804) (xy 171.259782 -299.923053) (xy 171.30183 -299.892503)
			(xy 171.34814 -299.868907) (xy 171.39757 -299.852846) (xy 171.448905 -299.844716) (xy 171.500879 -299.844716)
			(xy 171.552214 -299.852846) (xy 171.601644 -299.868907) (xy 171.647954 -299.892503) (xy 171.690002 -299.923053)
			(xy 171.726753 -299.959804) (xy 171.757303 -300.001852) (xy 171.780899 -300.048162) (xy 171.79696 -300.097592)
			(xy 171.80509 -300.148927) (xy 171.8056 -300.174914) (xy 171.80509 -300.200901) (xy 172.094654 -300.200901)
			(xy 172.094654 -300.148927) (xy 172.102784 -300.097592) (xy 172.118845 -300.048162) (xy 172.142441 -300.001852)
			(xy 172.172991 -299.959804) (xy 172.209742 -299.923053) (xy 172.25179 -299.892503) (xy 172.2981 -299.868907)
			(xy 172.34753 -299.852846) (xy 172.398865 -299.844716) (xy 172.450839 -299.844716) (xy 172.502174 -299.852846)
			(xy 172.551604 -299.868907) (xy 172.597914 -299.892503) (xy 172.639962 -299.923053) (xy 172.676713 -299.959804)
			(xy 172.707263 -300.001852) (xy 172.730859 -300.048162) (xy 172.74692 -300.097592) (xy 172.75505 -300.148927)
			(xy 172.75556 -300.174914) (xy 172.75505 -300.200901) (xy 173.044868 -300.200901) (xy 173.044868 -300.148927)
			(xy 173.052998 -300.097592) (xy 173.069059 -300.048162) (xy 173.092655 -300.001852) (xy 173.123205 -299.959804)
			(xy 173.159956 -299.923053) (xy 173.202004 -299.892503) (xy 173.248314 -299.868907) (xy 173.297744 -299.852846)
			(xy 173.349079 -299.844716) (xy 173.401053 -299.844716) (xy 173.452388 -299.852846) (xy 173.501818 -299.868907)
			(xy 173.548128 -299.892503) (xy 173.590176 -299.923053) (xy 173.626927 -299.959804) (xy 173.657477 -300.001852)
			(xy 173.681073 -300.048162) (xy 173.697134 -300.097592) (xy 173.705264 -300.148927) (xy 173.705774 -300.174914)
			(xy 173.705264 -300.200901) (xy 173.994828 -300.200901) (xy 173.994828 -300.148927) (xy 174.002958 -300.097592)
			(xy 174.019019 -300.048162) (xy 174.042615 -300.001852) (xy 174.073165 -299.959804) (xy 174.109916 -299.923053)
			(xy 174.151964 -299.892503) (xy 174.198274 -299.868907) (xy 174.247704 -299.852846) (xy 174.299039 -299.844716)
			(xy 174.351013 -299.844716) (xy 174.402348 -299.852846) (xy 174.451778 -299.868907) (xy 174.498088 -299.892503)
			(xy 174.540136 -299.923053) (xy 174.576887 -299.959804) (xy 174.607437 -300.001852) (xy 174.631033 -300.048162)
			(xy 174.647094 -300.097592) (xy 174.655224 -300.148927) (xy 174.655734 -300.174914) (xy 174.655224 -300.200901)
			(xy 175.894748 -300.200901) (xy 175.894748 -300.148927) (xy 175.902878 -300.097592) (xy 175.918939 -300.048162)
			(xy 175.942535 -300.001852) (xy 175.973085 -299.959804) (xy 176.009836 -299.923053) (xy 176.051884 -299.892503)
			(xy 176.098194 -299.868907) (xy 176.147624 -299.852846) (xy 176.198959 -299.844716) (xy 176.250933 -299.844716)
			(xy 176.302268 -299.852846) (xy 176.351698 -299.868907) (xy 176.398008 -299.892503) (xy 176.440056 -299.923053)
			(xy 176.476807 -299.959804) (xy 176.507357 -300.001852) (xy 176.530953 -300.048162) (xy 176.547014 -300.097592)
			(xy 176.555144 -300.148927) (xy 176.555654 -300.174914) (xy 176.555144 -300.200901) (xy 176.844708 -300.200901)
			(xy 176.844708 -300.148927) (xy 176.852838 -300.097592) (xy 176.868899 -300.048162) (xy 176.892495 -300.001852)
			(xy 176.923045 -299.959804) (xy 176.959796 -299.923053) (xy 177.001844 -299.892503) (xy 177.048154 -299.868907)
			(xy 177.097584 -299.852846) (xy 177.148919 -299.844716) (xy 177.200893 -299.844716) (xy 177.252228 -299.852846)
			(xy 177.301658 -299.868907) (xy 177.347968 -299.892503) (xy 177.390016 -299.923053) (xy 177.426767 -299.959804)
			(xy 177.457317 -300.001852) (xy 177.480913 -300.048162) (xy 177.496974 -300.097592) (xy 177.505104 -300.148927)
			(xy 177.505614 -300.174914) (xy 177.505104 -300.200901) (xy 177.794668 -300.200901) (xy 177.794668 -300.148927)
			(xy 177.802798 -300.097592) (xy 177.818859 -300.048162) (xy 177.842455 -300.001852) (xy 177.873005 -299.959804)
			(xy 177.909756 -299.923053) (xy 177.951804 -299.892503) (xy 177.998114 -299.868907) (xy 178.047544 -299.852846)
			(xy 178.098879 -299.844716) (xy 178.150853 -299.844716) (xy 178.202188 -299.852846) (xy 178.251618 -299.868907)
			(xy 178.297928 -299.892503) (xy 178.339976 -299.923053) (xy 178.376727 -299.959804) (xy 178.407277 -300.001852)
			(xy 178.430873 -300.048162) (xy 178.446934 -300.097592) (xy 178.455064 -300.148927) (xy 178.455574 -300.174914)
			(xy 178.455064 -300.200901) (xy 178.744882 -300.200901) (xy 178.744882 -300.148927) (xy 178.753012 -300.097592)
			(xy 178.769073 -300.048162) (xy 178.792669 -300.001852) (xy 178.823219 -299.959804) (xy 178.85997 -299.923053)
			(xy 178.902018 -299.892503) (xy 178.948328 -299.868907) (xy 178.997758 -299.852846) (xy 179.049093 -299.844716)
			(xy 179.101067 -299.844716) (xy 179.152402 -299.852846) (xy 179.201832 -299.868907) (xy 179.248142 -299.892503)
			(xy 179.29019 -299.923053) (xy 179.326941 -299.959804) (xy 179.357491 -300.001852) (xy 179.381087 -300.048162)
			(xy 179.397148 -300.097592) (xy 179.405278 -300.148927) (xy 179.405788 -300.174914) (xy 179.405278 -300.200901)
			(xy 179.694842 -300.200901) (xy 179.694842 -300.148927) (xy 179.702972 -300.097592) (xy 179.719033 -300.048162)
			(xy 179.742629 -300.001852) (xy 179.773179 -299.959804) (xy 179.80993 -299.923053) (xy 179.851978 -299.892503)
			(xy 179.898288 -299.868907) (xy 179.947718 -299.852846) (xy 179.999053 -299.844716) (xy 180.051027 -299.844716)
			(xy 180.102362 -299.852846) (xy 180.151792 -299.868907) (xy 180.198102 -299.892503) (xy 180.24015 -299.923053)
			(xy 180.276901 -299.959804) (xy 180.307451 -300.001852) (xy 180.331047 -300.048162) (xy 180.347108 -300.097592)
			(xy 180.355238 -300.148927) (xy 180.355748 -300.174914) (xy 180.355238 -300.200901) (xy 180.644802 -300.200901)
			(xy 180.644802 -300.148927) (xy 180.652932 -300.097592) (xy 180.668993 -300.048162) (xy 180.692589 -300.001852)
			(xy 180.723139 -299.959804) (xy 180.75989 -299.923053) (xy 180.801938 -299.892503) (xy 180.848248 -299.868907)
			(xy 180.897678 -299.852846) (xy 180.949013 -299.844716) (xy 181.000987 -299.844716) (xy 181.052322 -299.852846)
			(xy 181.101752 -299.868907) (xy 181.148062 -299.892503) (xy 181.19011 -299.923053) (xy 181.226861 -299.959804)
			(xy 181.257411 -300.001852) (xy 181.281007 -300.048162) (xy 181.297068 -300.097592) (xy 181.305198 -300.148927)
			(xy 181.305708 -300.174914) (xy 181.305198 -300.200901) (xy 181.594762 -300.200901) (xy 181.594762 -300.148927)
			(xy 181.602892 -300.097592) (xy 181.618953 -300.048162) (xy 181.642549 -300.001852) (xy 181.673099 -299.959804)
			(xy 181.70985 -299.923053) (xy 181.751898 -299.892503) (xy 181.798208 -299.868907) (xy 181.847638 -299.852846)
			(xy 181.898973 -299.844716) (xy 181.950947 -299.844716) (xy 182.002282 -299.852846) (xy 182.051712 -299.868907)
			(xy 182.098022 -299.892503) (xy 182.14007 -299.923053) (xy 182.176821 -299.959804) (xy 182.207371 -300.001852)
			(xy 182.230967 -300.048162) (xy 182.247028 -300.097592) (xy 182.255158 -300.148927) (xy 182.255668 -300.174914)
			(xy 182.255158 -300.200901) (xy 182.544722 -300.200901) (xy 182.544722 -300.148927) (xy 182.552852 -300.097592)
			(xy 182.568913 -300.048162) (xy 182.592509 -300.001852) (xy 182.623059 -299.959804) (xy 182.65981 -299.923053)
			(xy 182.701858 -299.892503) (xy 182.748168 -299.868907) (xy 182.797598 -299.852846) (xy 182.848933 -299.844716)
			(xy 182.900907 -299.844716) (xy 182.952242 -299.852846) (xy 183.001672 -299.868907) (xy 183.047982 -299.892503)
			(xy 183.09003 -299.923053) (xy 183.126781 -299.959804) (xy 183.157331 -300.001852) (xy 183.180927 -300.048162)
			(xy 183.196988 -300.097592) (xy 183.205118 -300.148927) (xy 183.205628 -300.174914) (xy 183.205118 -300.200901)
			(xy 183.494682 -300.200901) (xy 183.494682 -300.148927) (xy 183.502812 -300.097592) (xy 183.518873 -300.048162)
			(xy 183.542469 -300.001852) (xy 183.573019 -299.959804) (xy 183.60977 -299.923053) (xy 183.651818 -299.892503)
			(xy 183.698128 -299.868907) (xy 183.747558 -299.852846) (xy 183.798893 -299.844716) (xy 183.850867 -299.844716)
			(xy 183.902202 -299.852846) (xy 183.951632 -299.868907) (xy 183.997942 -299.892503) (xy 184.03999 -299.923053)
			(xy 184.076741 -299.959804) (xy 184.107291 -300.001852) (xy 184.130887 -300.048162) (xy 184.146948 -300.097592)
			(xy 184.155078 -300.148927) (xy 184.155588 -300.174914) (xy 184.155078 -300.200901) (xy 184.146948 -300.252236)
			(xy 184.130887 -300.301666) (xy 184.107291 -300.347976) (xy 184.076741 -300.390024) (xy 184.03999 -300.426775)
			(xy 183.997942 -300.457325) (xy 183.951632 -300.480921) (xy 183.902202 -300.496982) (xy 183.850867 -300.505112)
			(xy 183.798893 -300.505112) (xy 183.747558 -300.496982) (xy 183.698128 -300.480921) (xy 183.651818 -300.457325)
			(xy 183.60977 -300.426775) (xy 183.573019 -300.390024) (xy 183.542469 -300.347976) (xy 183.518873 -300.301666)
			(xy 183.502812 -300.252236) (xy 183.494682 -300.200901) (xy 183.205118 -300.200901) (xy 183.196988 -300.252236)
			(xy 183.180927 -300.301666) (xy 183.157331 -300.347976) (xy 183.126781 -300.390024) (xy 183.09003 -300.426775)
			(xy 183.047982 -300.457325) (xy 183.001672 -300.480921) (xy 182.952242 -300.496982) (xy 182.900907 -300.505112)
			(xy 182.848933 -300.505112) (xy 182.797598 -300.496982) (xy 182.748168 -300.480921) (xy 182.701858 -300.457325)
			(xy 182.65981 -300.426775) (xy 182.623059 -300.390024) (xy 182.592509 -300.347976) (xy 182.568913 -300.301666)
			(xy 182.552852 -300.252236) (xy 182.544722 -300.200901) (xy 182.255158 -300.200901) (xy 182.247028 -300.252236)
			(xy 182.230967 -300.301666) (xy 182.207371 -300.347976) (xy 182.176821 -300.390024) (xy 182.14007 -300.426775)
			(xy 182.098022 -300.457325) (xy 182.051712 -300.480921) (xy 182.002282 -300.496982) (xy 181.950947 -300.505112)
			(xy 181.898973 -300.505112) (xy 181.847638 -300.496982) (xy 181.798208 -300.480921) (xy 181.751898 -300.457325)
			(xy 181.70985 -300.426775) (xy 181.673099 -300.390024) (xy 181.642549 -300.347976) (xy 181.618953 -300.301666)
			(xy 181.602892 -300.252236) (xy 181.594762 -300.200901) (xy 181.305198 -300.200901) (xy 181.297068 -300.252236)
			(xy 181.281007 -300.301666) (xy 181.257411 -300.347976) (xy 181.226861 -300.390024) (xy 181.19011 -300.426775)
			(xy 181.148062 -300.457325) (xy 181.101752 -300.480921) (xy 181.052322 -300.496982) (xy 181.000987 -300.505112)
			(xy 180.949013 -300.505112) (xy 180.897678 -300.496982) (xy 180.848248 -300.480921) (xy 180.801938 -300.457325)
			(xy 180.75989 -300.426775) (xy 180.723139 -300.390024) (xy 180.692589 -300.347976) (xy 180.668993 -300.301666)
			(xy 180.652932 -300.252236) (xy 180.644802 -300.200901) (xy 180.355238 -300.200901) (xy 180.347108 -300.252236)
			(xy 180.331047 -300.301666) (xy 180.307451 -300.347976) (xy 180.276901 -300.390024) (xy 180.24015 -300.426775)
			(xy 180.198102 -300.457325) (xy 180.151792 -300.480921) (xy 180.102362 -300.496982) (xy 180.051027 -300.505112)
			(xy 179.999053 -300.505112) (xy 179.947718 -300.496982) (xy 179.898288 -300.480921) (xy 179.851978 -300.457325)
			(xy 179.80993 -300.426775) (xy 179.773179 -300.390024) (xy 179.742629 -300.347976) (xy 179.719033 -300.301666)
			(xy 179.702972 -300.252236) (xy 179.694842 -300.200901) (xy 179.405278 -300.200901) (xy 179.397148 -300.252236)
			(xy 179.381087 -300.301666) (xy 179.357491 -300.347976) (xy 179.326941 -300.390024) (xy 179.29019 -300.426775)
			(xy 179.248142 -300.457325) (xy 179.201832 -300.480921) (xy 179.152402 -300.496982) (xy 179.101067 -300.505112)
			(xy 179.049093 -300.505112) (xy 178.997758 -300.496982) (xy 178.948328 -300.480921) (xy 178.902018 -300.457325)
			(xy 178.85997 -300.426775) (xy 178.823219 -300.390024) (xy 178.792669 -300.347976) (xy 178.769073 -300.301666)
			(xy 178.753012 -300.252236) (xy 178.744882 -300.200901) (xy 178.455064 -300.200901) (xy 178.446934 -300.252236)
			(xy 178.430873 -300.301666) (xy 178.407277 -300.347976) (xy 178.376727 -300.390024) (xy 178.339976 -300.426775)
			(xy 178.297928 -300.457325) (xy 178.251618 -300.480921) (xy 178.202188 -300.496982) (xy 178.150853 -300.505112)
			(xy 178.098879 -300.505112) (xy 178.047544 -300.496982) (xy 177.998114 -300.480921) (xy 177.951804 -300.457325)
			(xy 177.909756 -300.426775) (xy 177.873005 -300.390024) (xy 177.842455 -300.347976) (xy 177.818859 -300.301666)
			(xy 177.802798 -300.252236) (xy 177.794668 -300.200901) (xy 177.505104 -300.200901) (xy 177.496974 -300.252236)
			(xy 177.480913 -300.301666) (xy 177.457317 -300.347976) (xy 177.426767 -300.390024) (xy 177.390016 -300.426775)
			(xy 177.347968 -300.457325) (xy 177.301658 -300.480921) (xy 177.252228 -300.496982) (xy 177.200893 -300.505112)
			(xy 177.148919 -300.505112) (xy 177.097584 -300.496982) (xy 177.048154 -300.480921) (xy 177.001844 -300.457325)
			(xy 176.959796 -300.426775) (xy 176.923045 -300.390024) (xy 176.892495 -300.347976) (xy 176.868899 -300.301666)
			(xy 176.852838 -300.252236) (xy 176.844708 -300.200901) (xy 176.555144 -300.200901) (xy 176.547014 -300.252236)
			(xy 176.530953 -300.301666) (xy 176.507357 -300.347976) (xy 176.476807 -300.390024) (xy 176.440056 -300.426775)
			(xy 176.398008 -300.457325) (xy 176.351698 -300.480921) (xy 176.302268 -300.496982) (xy 176.250933 -300.505112)
			(xy 176.198959 -300.505112) (xy 176.147624 -300.496982) (xy 176.098194 -300.480921) (xy 176.051884 -300.457325)
			(xy 176.009836 -300.426775) (xy 175.973085 -300.390024) (xy 175.942535 -300.347976) (xy 175.918939 -300.301666)
			(xy 175.902878 -300.252236) (xy 175.894748 -300.200901) (xy 174.655224 -300.200901) (xy 174.647094 -300.252236)
			(xy 174.631033 -300.301666) (xy 174.607437 -300.347976) (xy 174.576887 -300.390024) (xy 174.540136 -300.426775)
			(xy 174.498088 -300.457325) (xy 174.451778 -300.480921) (xy 174.402348 -300.496982) (xy 174.351013 -300.505112)
			(xy 174.299039 -300.505112) (xy 174.247704 -300.496982) (xy 174.198274 -300.480921) (xy 174.151964 -300.457325)
			(xy 174.109916 -300.426775) (xy 174.073165 -300.390024) (xy 174.042615 -300.347976) (xy 174.019019 -300.301666)
			(xy 174.002958 -300.252236) (xy 173.994828 -300.200901) (xy 173.705264 -300.200901) (xy 173.697134 -300.252236)
			(xy 173.681073 -300.301666) (xy 173.657477 -300.347976) (xy 173.626927 -300.390024) (xy 173.590176 -300.426775)
			(xy 173.548128 -300.457325) (xy 173.501818 -300.480921) (xy 173.452388 -300.496982) (xy 173.401053 -300.505112)
			(xy 173.349079 -300.505112) (xy 173.297744 -300.496982) (xy 173.248314 -300.480921) (xy 173.202004 -300.457325)
			(xy 173.159956 -300.426775) (xy 173.123205 -300.390024) (xy 173.092655 -300.347976) (xy 173.069059 -300.301666)
			(xy 173.052998 -300.252236) (xy 173.044868 -300.200901) (xy 172.75505 -300.200901) (xy 172.74692 -300.252236)
			(xy 172.730859 -300.301666) (xy 172.707263 -300.347976) (xy 172.676713 -300.390024) (xy 172.639962 -300.426775)
			(xy 172.597914 -300.457325) (xy 172.551604 -300.480921) (xy 172.502174 -300.496982) (xy 172.450839 -300.505112)
			(xy 172.398865 -300.505112) (xy 172.34753 -300.496982) (xy 172.2981 -300.480921) (xy 172.25179 -300.457325)
			(xy 172.209742 -300.426775) (xy 172.172991 -300.390024) (xy 172.142441 -300.347976) (xy 172.118845 -300.301666)
			(xy 172.102784 -300.252236) (xy 172.094654 -300.200901) (xy 171.80509 -300.200901) (xy 171.79696 -300.252236)
			(xy 171.780899 -300.301666) (xy 171.757303 -300.347976) (xy 171.726753 -300.390024) (xy 171.690002 -300.426775)
			(xy 171.647954 -300.457325) (xy 171.601644 -300.480921) (xy 171.552214 -300.496982) (xy 171.500879 -300.505112)
			(xy 171.448905 -300.505112) (xy 171.39757 -300.496982) (xy 171.34814 -300.480921) (xy 171.30183 -300.457325)
			(xy 171.259782 -300.426775) (xy 171.223031 -300.390024) (xy 171.192481 -300.347976) (xy 171.168885 -300.301666)
			(xy 171.152824 -300.252236) (xy 171.144694 -300.200901) (xy 170.85513 -300.200901) (xy 170.847 -300.252236)
			(xy 170.830939 -300.301666) (xy 170.807343 -300.347976) (xy 170.776793 -300.390024) (xy 170.740042 -300.426775)
			(xy 170.697994 -300.457325) (xy 170.651684 -300.480921) (xy 170.602254 -300.496982) (xy 170.550919 -300.505112)
			(xy 170.498945 -300.505112) (xy 170.44761 -300.496982) (xy 170.39818 -300.480921) (xy 170.35187 -300.457325)
			(xy 170.309822 -300.426775) (xy 170.273071 -300.390024) (xy 170.242521 -300.347976) (xy 170.218925 -300.301666)
			(xy 170.202864 -300.252236) (xy 170.194734 -300.200901) (xy 169.90517 -300.200901) (xy 169.89704 -300.252236)
			(xy 169.880979 -300.301666) (xy 169.857383 -300.347976) (xy 169.826833 -300.390024) (xy 169.790082 -300.426775)
			(xy 169.748034 -300.457325) (xy 169.701724 -300.480921) (xy 169.652294 -300.496982) (xy 169.600959 -300.505112)
			(xy 169.548985 -300.505112) (xy 169.49765 -300.496982) (xy 169.44822 -300.480921) (xy 169.40191 -300.457325)
			(xy 169.359862 -300.426775) (xy 169.323111 -300.390024) (xy 169.292561 -300.347976) (xy 169.268965 -300.301666)
			(xy 169.252904 -300.252236) (xy 169.244774 -300.200901) (xy 168.95521 -300.200901) (xy 168.94708 -300.252236)
			(xy 168.931019 -300.301666) (xy 168.907423 -300.347976) (xy 168.876873 -300.390024) (xy 168.840122 -300.426775)
			(xy 168.798074 -300.457325) (xy 168.751764 -300.480921) (xy 168.702334 -300.496982) (xy 168.650999 -300.505112)
			(xy 168.599025 -300.505112) (xy 168.54769 -300.496982) (xy 168.49826 -300.480921) (xy 168.45195 -300.457325)
			(xy 168.409902 -300.426775) (xy 168.373151 -300.390024) (xy 168.342601 -300.347976) (xy 168.319005 -300.301666)
			(xy 168.302944 -300.252236) (xy 168.294814 -300.200901) (xy 168.00525 -300.200901) (xy 167.99712 -300.252236)
			(xy 167.981059 -300.301666) (xy 167.957463 -300.347976) (xy 167.926913 -300.390024) (xy 167.890162 -300.426775)
			(xy 167.848114 -300.457325) (xy 167.801804 -300.480921) (xy 167.752374 -300.496982) (xy 167.701039 -300.505112)
			(xy 167.649065 -300.505112) (xy 167.59773 -300.496982) (xy 167.5483 -300.480921) (xy 167.50199 -300.457325)
			(xy 167.459942 -300.426775) (xy 167.423191 -300.390024) (xy 167.392641 -300.347976) (xy 167.369045 -300.301666)
			(xy 167.352984 -300.252236) (xy 167.344854 -300.200901) (xy 167.05529 -300.200901) (xy 167.04716 -300.252236)
			(xy 167.031099 -300.301666) (xy 167.007503 -300.347976) (xy 166.976953 -300.390024) (xy 166.940202 -300.426775)
			(xy 166.898154 -300.457325) (xy 166.851844 -300.480921) (xy 166.802414 -300.496982) (xy 166.751079 -300.505112)
			(xy 166.699105 -300.505112) (xy 166.64777 -300.496982) (xy 166.59834 -300.480921) (xy 166.55203 -300.457325)
			(xy 166.509982 -300.426775) (xy 166.473231 -300.390024) (xy 166.442681 -300.347976) (xy 166.419085 -300.301666)
			(xy 166.403024 -300.252236) (xy 166.394894 -300.200901) (xy 166.105076 -300.200901) (xy 166.096946 -300.252236)
			(xy 166.080885 -300.301666) (xy 166.057289 -300.347976) (xy 166.026739 -300.390024) (xy 165.989988 -300.426775)
			(xy 165.94794 -300.457325) (xy 165.90163 -300.480921) (xy 165.8522 -300.496982) (xy 165.800865 -300.505112)
			(xy 165.748891 -300.505112) (xy 165.697556 -300.496982) (xy 165.648126 -300.480921) (xy 165.601816 -300.457325)
			(xy 165.559768 -300.426775) (xy 165.523017 -300.390024) (xy 165.492467 -300.347976) (xy 165.468871 -300.301666)
			(xy 165.45281 -300.252236) (xy 165.44468 -300.200901) (xy 165.155116 -300.200901) (xy 165.146986 -300.252236)
			(xy 165.130925 -300.301666) (xy 165.107329 -300.347976) (xy 165.076779 -300.390024) (xy 165.040028 -300.426775)
			(xy 164.99798 -300.457325) (xy 164.95167 -300.480921) (xy 164.90224 -300.496982) (xy 164.850905 -300.505112)
			(xy 164.798931 -300.505112) (xy 164.747596 -300.496982) (xy 164.698166 -300.480921) (xy 164.651856 -300.457325)
			(xy 164.609808 -300.426775) (xy 164.573057 -300.390024) (xy 164.542507 -300.347976) (xy 164.518911 -300.301666)
			(xy 164.50285 -300.252236) (xy 164.49472 -300.200901) (xy 164.205156 -300.200901) (xy 164.197026 -300.252236)
			(xy 164.180965 -300.301666) (xy 164.157369 -300.347976) (xy 164.126819 -300.390024) (xy 164.090068 -300.426775)
			(xy 164.04802 -300.457325) (xy 164.00171 -300.480921) (xy 163.95228 -300.496982) (xy 163.900945 -300.505112)
			(xy 163.848971 -300.505112) (xy 163.797636 -300.496982) (xy 163.748206 -300.480921) (xy 163.701896 -300.457325)
			(xy 163.659848 -300.426775) (xy 163.623097 -300.390024) (xy 163.592547 -300.347976) (xy 163.568951 -300.301666)
			(xy 163.55289 -300.252236) (xy 163.54476 -300.200901) (xy 163.255196 -300.200901) (xy 163.247066 -300.252236)
			(xy 163.231005 -300.301666) (xy 163.207409 -300.347976) (xy 163.176859 -300.390024) (xy 163.140108 -300.426775)
			(xy 163.09806 -300.457325) (xy 163.05175 -300.480921) (xy 163.00232 -300.496982) (xy 162.950985 -300.505112)
			(xy 162.899011 -300.505112) (xy 162.847676 -300.496982) (xy 162.798246 -300.480921) (xy 162.751936 -300.457325)
			(xy 162.709888 -300.426775) (xy 162.673137 -300.390024) (xy 162.642587 -300.347976) (xy 162.618991 -300.301666)
			(xy 162.60293 -300.252236) (xy 162.5948 -300.200901) (xy 162.304145 -300.200901) (xy 162.302034 -300.227378)
			(xy 162.289589 -300.278527) (xy 162.269199 -300.327058) (xy 162.241377 -300.371746) (xy 162.206826 -300.411462)
			(xy 162.16642 -300.445202) (xy 162.121179 -300.472115) (xy 162.072245 -300.49152) (xy 162.046666 -300.497748)
			(xy 162.02914 -300.501558) (xy 162.006788 -300.529498) (xy 162.006788 -300.77029) (xy 162.02914 -300.79823)
			(xy 162.046666 -300.80204) (xy 162.072254 -300.808242) (xy 162.121193 -300.827649) (xy 162.16644 -300.854564)
			(xy 162.206852 -300.888308) (xy 162.241407 -300.928029) (xy 162.269232 -300.972722) (xy 162.289626 -301.021259)
			(xy 162.302072 -301.072414) (xy 162.306256 -301.124894) (xy 162.304187 -301.150861) (xy 163.54476 -301.150861)
			(xy 163.54476 -301.098887) (xy 163.55289 -301.047552) (xy 163.568951 -300.998122) (xy 163.592547 -300.951812)
			(xy 163.623097 -300.909764) (xy 163.659848 -300.873013) (xy 163.701896 -300.842463) (xy 163.748206 -300.818867)
			(xy 163.797636 -300.802806) (xy 163.848971 -300.794676) (xy 163.900945 -300.794676) (xy 163.95228 -300.802806)
			(xy 164.00171 -300.818867) (xy 164.04802 -300.842463) (xy 164.090068 -300.873013) (xy 164.126819 -300.909764)
			(xy 164.157369 -300.951812) (xy 164.180965 -300.998122) (xy 164.197026 -301.047552) (xy 164.205156 -301.098887)
			(xy 164.205666 -301.124874) (xy 164.205156 -301.150861) (xy 164.49472 -301.150861) (xy 164.49472 -301.098887)
			(xy 164.50285 -301.047552) (xy 164.518911 -300.998122) (xy 164.542507 -300.951812) (xy 164.573057 -300.909764)
			(xy 164.609808 -300.873013) (xy 164.651856 -300.842463) (xy 164.698166 -300.818867) (xy 164.747596 -300.802806)
			(xy 164.798931 -300.794676) (xy 164.850905 -300.794676) (xy 164.90224 -300.802806) (xy 164.95167 -300.818867)
			(xy 164.99798 -300.842463) (xy 165.040028 -300.873013) (xy 165.076779 -300.909764) (xy 165.107329 -300.951812)
			(xy 165.130925 -300.998122) (xy 165.146986 -301.047552) (xy 165.155116 -301.098887) (xy 165.155626 -301.124874)
			(xy 165.155116 -301.150861) (xy 165.44468 -301.150861) (xy 165.44468 -301.098887) (xy 165.45281 -301.047552)
			(xy 165.468871 -300.998122) (xy 165.492467 -300.951812) (xy 165.523017 -300.909764) (xy 165.559768 -300.873013)
			(xy 165.601816 -300.842463) (xy 165.648126 -300.818867) (xy 165.697556 -300.802806) (xy 165.748891 -300.794676)
			(xy 165.800865 -300.794676) (xy 165.8522 -300.802806) (xy 165.90163 -300.818867) (xy 165.94794 -300.842463)
			(xy 165.989988 -300.873013) (xy 166.026739 -300.909764) (xy 166.057289 -300.951812) (xy 166.080885 -300.998122)
			(xy 166.096946 -301.047552) (xy 166.105076 -301.098887) (xy 166.105586 -301.124874) (xy 166.105076 -301.150861)
			(xy 166.394894 -301.150861) (xy 166.394894 -301.098887) (xy 166.403024 -301.047552) (xy 166.419085 -300.998122)
			(xy 166.442681 -300.951812) (xy 166.473231 -300.909764) (xy 166.509982 -300.873013) (xy 166.55203 -300.842463)
			(xy 166.59834 -300.818867) (xy 166.64777 -300.802806) (xy 166.699105 -300.794676) (xy 166.751079 -300.794676)
			(xy 166.802414 -300.802806) (xy 166.851844 -300.818867) (xy 166.898154 -300.842463) (xy 166.940202 -300.873013)
			(xy 166.976953 -300.909764) (xy 167.007503 -300.951812) (xy 167.031099 -300.998122) (xy 167.04716 -301.047552)
			(xy 167.05529 -301.098887) (xy 167.0558 -301.124874) (xy 167.05529 -301.150861) (xy 167.344854 -301.150861)
			(xy 167.344854 -301.098887) (xy 167.352984 -301.047552) (xy 167.369045 -300.998122) (xy 167.392641 -300.951812)
			(xy 167.423191 -300.909764) (xy 167.459942 -300.873013) (xy 167.50199 -300.842463) (xy 167.5483 -300.818867)
			(xy 167.59773 -300.802806) (xy 167.649065 -300.794676) (xy 167.701039 -300.794676) (xy 167.752374 -300.802806)
			(xy 167.801804 -300.818867) (xy 167.848114 -300.842463) (xy 167.890162 -300.873013) (xy 167.926913 -300.909764)
			(xy 167.957463 -300.951812) (xy 167.981059 -300.998122) (xy 167.99712 -301.047552) (xy 168.00525 -301.098887)
			(xy 168.00576 -301.124874) (xy 168.00525 -301.150861) (xy 168.294814 -301.150861) (xy 168.294814 -301.098887)
			(xy 168.302944 -301.047552) (xy 168.319005 -300.998122) (xy 168.342601 -300.951812) (xy 168.373151 -300.909764)
			(xy 168.409902 -300.873013) (xy 168.45195 -300.842463) (xy 168.49826 -300.818867) (xy 168.54769 -300.802806)
			(xy 168.599025 -300.794676) (xy 168.650999 -300.794676) (xy 168.702334 -300.802806) (xy 168.751764 -300.818867)
			(xy 168.798074 -300.842463) (xy 168.840122 -300.873013) (xy 168.876873 -300.909764) (xy 168.907423 -300.951812)
			(xy 168.931019 -300.998122) (xy 168.94708 -301.047552) (xy 168.95521 -301.098887) (xy 168.95572 -301.124874)
			(xy 168.95521 -301.150861) (xy 169.244774 -301.150861) (xy 169.244774 -301.098887) (xy 169.252904 -301.047552)
			(xy 169.268965 -300.998122) (xy 169.292561 -300.951812) (xy 169.323111 -300.909764) (xy 169.359862 -300.873013)
			(xy 169.40191 -300.842463) (xy 169.44822 -300.818867) (xy 169.49765 -300.802806) (xy 169.548985 -300.794676)
			(xy 169.600959 -300.794676) (xy 169.652294 -300.802806) (xy 169.701724 -300.818867) (xy 169.748034 -300.842463)
			(xy 169.790082 -300.873013) (xy 169.826833 -300.909764) (xy 169.857383 -300.951812) (xy 169.880979 -300.998122)
			(xy 169.89704 -301.047552) (xy 169.90517 -301.098887) (xy 169.90568 -301.124874) (xy 169.90517 -301.150861)
			(xy 170.194734 -301.150861) (xy 170.194734 -301.098887) (xy 170.202864 -301.047552) (xy 170.218925 -300.998122)
			(xy 170.242521 -300.951812) (xy 170.273071 -300.909764) (xy 170.309822 -300.873013) (xy 170.35187 -300.842463)
			(xy 170.39818 -300.818867) (xy 170.44761 -300.802806) (xy 170.498945 -300.794676) (xy 170.550919 -300.794676)
			(xy 170.602254 -300.802806) (xy 170.651684 -300.818867) (xy 170.697994 -300.842463) (xy 170.740042 -300.873013)
			(xy 170.776793 -300.909764) (xy 170.807343 -300.951812) (xy 170.830939 -300.998122) (xy 170.847 -301.047552)
			(xy 170.85513 -301.098887) (xy 170.85564 -301.124874) (xy 170.85513 -301.150861) (xy 171.144694 -301.150861)
			(xy 171.144694 -301.098887) (xy 171.152824 -301.047552) (xy 171.168885 -300.998122) (xy 171.192481 -300.951812)
			(xy 171.223031 -300.909764) (xy 171.259782 -300.873013) (xy 171.30183 -300.842463) (xy 171.34814 -300.818867)
			(xy 171.39757 -300.802806) (xy 171.448905 -300.794676) (xy 171.500879 -300.794676) (xy 171.552214 -300.802806)
			(xy 171.601644 -300.818867) (xy 171.647954 -300.842463) (xy 171.690002 -300.873013) (xy 171.726753 -300.909764)
			(xy 171.757303 -300.951812) (xy 171.780899 -300.998122) (xy 171.79696 -301.047552) (xy 171.80509 -301.098887)
			(xy 171.8056 -301.124874) (xy 171.80509 -301.150861) (xy 172.094654 -301.150861) (xy 172.094654 -301.098887)
			(xy 172.102784 -301.047552) (xy 172.118845 -300.998122) (xy 172.142441 -300.951812) (xy 172.172991 -300.909764)
			(xy 172.209742 -300.873013) (xy 172.25179 -300.842463) (xy 172.2981 -300.818867) (xy 172.34753 -300.802806)
			(xy 172.398865 -300.794676) (xy 172.450839 -300.794676) (xy 172.502174 -300.802806) (xy 172.551604 -300.818867)
			(xy 172.597914 -300.842463) (xy 172.639962 -300.873013) (xy 172.676713 -300.909764) (xy 172.707263 -300.951812)
			(xy 172.730859 -300.998122) (xy 172.74692 -301.047552) (xy 172.75505 -301.098887) (xy 172.75556 -301.124874)
			(xy 172.75505 -301.150861) (xy 173.044868 -301.150861) (xy 173.044868 -301.098887) (xy 173.052998 -301.047552)
			(xy 173.069059 -300.998122) (xy 173.092655 -300.951812) (xy 173.123205 -300.909764) (xy 173.159956 -300.873013)
			(xy 173.202004 -300.842463) (xy 173.248314 -300.818867) (xy 173.297744 -300.802806) (xy 173.349079 -300.794676)
			(xy 173.401053 -300.794676) (xy 173.452388 -300.802806) (xy 173.501818 -300.818867) (xy 173.548128 -300.842463)
			(xy 173.590176 -300.873013) (xy 173.626927 -300.909764) (xy 173.657477 -300.951812) (xy 173.681073 -300.998122)
			(xy 173.697134 -301.047552) (xy 173.705264 -301.098887) (xy 173.705774 -301.124874) (xy 173.705264 -301.150861)
			(xy 173.994828 -301.150861) (xy 173.994828 -301.098887) (xy 174.002958 -301.047552) (xy 174.019019 -300.998122)
			(xy 174.042615 -300.951812) (xy 174.073165 -300.909764) (xy 174.109916 -300.873013) (xy 174.151964 -300.842463)
			(xy 174.198274 -300.818867) (xy 174.247704 -300.802806) (xy 174.299039 -300.794676) (xy 174.351013 -300.794676)
			(xy 174.402348 -300.802806) (xy 174.451778 -300.818867) (xy 174.498088 -300.842463) (xy 174.540136 -300.873013)
			(xy 174.576887 -300.909764) (xy 174.607437 -300.951812) (xy 174.631033 -300.998122) (xy 174.647094 -301.047552)
			(xy 174.655224 -301.098887) (xy 174.655734 -301.124874) (xy 174.655224 -301.150861) (xy 175.894748 -301.150861)
			(xy 175.894748 -301.098887) (xy 175.902878 -301.047552) (xy 175.918939 -300.998122) (xy 175.942535 -300.951812)
			(xy 175.973085 -300.909764) (xy 176.009836 -300.873013) (xy 176.051884 -300.842463) (xy 176.098194 -300.818867)
			(xy 176.147624 -300.802806) (xy 176.198959 -300.794676) (xy 176.250933 -300.794676) (xy 176.302268 -300.802806)
			(xy 176.351698 -300.818867) (xy 176.398008 -300.842463) (xy 176.440056 -300.873013) (xy 176.476807 -300.909764)
			(xy 176.507357 -300.951812) (xy 176.530953 -300.998122) (xy 176.547014 -301.047552) (xy 176.555144 -301.098887)
			(xy 176.555654 -301.124874) (xy 176.555144 -301.150861) (xy 176.844708 -301.150861) (xy 176.844708 -301.098887)
			(xy 176.852838 -301.047552) (xy 176.868899 -300.998122) (xy 176.892495 -300.951812) (xy 176.923045 -300.909764)
			(xy 176.959796 -300.873013) (xy 177.001844 -300.842463) (xy 177.048154 -300.818867) (xy 177.097584 -300.802806)
			(xy 177.148919 -300.794676) (xy 177.200893 -300.794676) (xy 177.252228 -300.802806) (xy 177.301658 -300.818867)
			(xy 177.347968 -300.842463) (xy 177.390016 -300.873013) (xy 177.426767 -300.909764) (xy 177.457317 -300.951812)
			(xy 177.480913 -300.998122) (xy 177.496974 -301.047552) (xy 177.505104 -301.098887) (xy 177.505614 -301.124874)
			(xy 177.505104 -301.150861) (xy 177.794668 -301.150861) (xy 177.794668 -301.098887) (xy 177.802798 -301.047552)
			(xy 177.818859 -300.998122) (xy 177.842455 -300.951812) (xy 177.873005 -300.909764) (xy 177.909756 -300.873013)
			(xy 177.951804 -300.842463) (xy 177.998114 -300.818867) (xy 178.047544 -300.802806) (xy 178.098879 -300.794676)
			(xy 178.150853 -300.794676) (xy 178.202188 -300.802806) (xy 178.251618 -300.818867) (xy 178.297928 -300.842463)
			(xy 178.339976 -300.873013) (xy 178.376727 -300.909764) (xy 178.407277 -300.951812) (xy 178.430873 -300.998122)
			(xy 178.446934 -301.047552) (xy 178.455064 -301.098887) (xy 178.455574 -301.124874) (xy 178.455064 -301.150861)
			(xy 178.744882 -301.150861) (xy 178.744882 -301.098887) (xy 178.753012 -301.047552) (xy 178.769073 -300.998122)
			(xy 178.792669 -300.951812) (xy 178.823219 -300.909764) (xy 178.85997 -300.873013) (xy 178.902018 -300.842463)
			(xy 178.948328 -300.818867) (xy 178.997758 -300.802806) (xy 179.049093 -300.794676) (xy 179.101067 -300.794676)
			(xy 179.152402 -300.802806) (xy 179.201832 -300.818867) (xy 179.248142 -300.842463) (xy 179.29019 -300.873013)
			(xy 179.326941 -300.909764) (xy 179.357491 -300.951812) (xy 179.381087 -300.998122) (xy 179.397148 -301.047552)
			(xy 179.405278 -301.098887) (xy 179.405788 -301.124874) (xy 179.405278 -301.150861) (xy 179.694842 -301.150861)
			(xy 179.694842 -301.098887) (xy 179.702972 -301.047552) (xy 179.719033 -300.998122) (xy 179.742629 -300.951812)
			(xy 179.773179 -300.909764) (xy 179.80993 -300.873013) (xy 179.851978 -300.842463) (xy 179.898288 -300.818867)
			(xy 179.947718 -300.802806) (xy 179.999053 -300.794676) (xy 180.051027 -300.794676) (xy 180.102362 -300.802806)
			(xy 180.151792 -300.818867) (xy 180.198102 -300.842463) (xy 180.24015 -300.873013) (xy 180.276901 -300.909764)
			(xy 180.307451 -300.951812) (xy 180.331047 -300.998122) (xy 180.347108 -301.047552) (xy 180.355238 -301.098887)
			(xy 180.355748 -301.124874) (xy 180.355238 -301.150861) (xy 180.644802 -301.150861) (xy 180.644802 -301.098887)
			(xy 180.652932 -301.047552) (xy 180.668993 -300.998122) (xy 180.692589 -300.951812) (xy 180.723139 -300.909764)
			(xy 180.75989 -300.873013) (xy 180.801938 -300.842463) (xy 180.848248 -300.818867) (xy 180.897678 -300.802806)
			(xy 180.949013 -300.794676) (xy 181.000987 -300.794676) (xy 181.052322 -300.802806) (xy 181.101752 -300.818867)
			(xy 181.148062 -300.842463) (xy 181.19011 -300.873013) (xy 181.226861 -300.909764) (xy 181.257411 -300.951812)
			(xy 181.281007 -300.998122) (xy 181.297068 -301.047552) (xy 181.305198 -301.098887) (xy 181.305708 -301.124874)
			(xy 181.305198 -301.150861) (xy 181.594762 -301.150861) (xy 181.594762 -301.098887) (xy 181.602892 -301.047552)
			(xy 181.618953 -300.998122) (xy 181.642549 -300.951812) (xy 181.673099 -300.909764) (xy 181.70985 -300.873013)
			(xy 181.751898 -300.842463) (xy 181.798208 -300.818867) (xy 181.847638 -300.802806) (xy 181.898973 -300.794676)
			(xy 181.950947 -300.794676) (xy 182.002282 -300.802806) (xy 182.051712 -300.818867) (xy 182.098022 -300.842463)
			(xy 182.14007 -300.873013) (xy 182.176821 -300.909764) (xy 182.207371 -300.951812) (xy 182.230967 -300.998122)
			(xy 182.247028 -301.047552) (xy 182.255158 -301.098887) (xy 182.255668 -301.124874) (xy 182.255158 -301.150861)
			(xy 182.544722 -301.150861) (xy 182.544722 -301.098887) (xy 182.552852 -301.047552) (xy 182.568913 -300.998122)
			(xy 182.592509 -300.951812) (xy 182.623059 -300.909764) (xy 182.65981 -300.873013) (xy 182.701858 -300.842463)
			(xy 182.748168 -300.818867) (xy 182.797598 -300.802806) (xy 182.848933 -300.794676) (xy 182.900907 -300.794676)
			(xy 182.952242 -300.802806) (xy 183.001672 -300.818867) (xy 183.047982 -300.842463) (xy 183.09003 -300.873013)
			(xy 183.126781 -300.909764) (xy 183.157331 -300.951812) (xy 183.180927 -300.998122) (xy 183.196988 -301.047552)
			(xy 183.205118 -301.098887) (xy 183.205628 -301.124874) (xy 183.205118 -301.150861) (xy 183.494682 -301.150861)
			(xy 183.494682 -301.098887) (xy 183.502812 -301.047552) (xy 183.518873 -300.998122) (xy 183.542469 -300.951812)
			(xy 183.573019 -300.909764) (xy 183.60977 -300.873013) (xy 183.651818 -300.842463) (xy 183.698128 -300.818867)
			(xy 183.747558 -300.802806) (xy 183.798893 -300.794676) (xy 183.850867 -300.794676) (xy 183.902202 -300.802806)
			(xy 183.951632 -300.818867) (xy 183.997942 -300.842463) (xy 184.03999 -300.873013) (xy 184.076741 -300.909764)
			(xy 184.107291 -300.951812) (xy 184.130887 -300.998122) (xy 184.146948 -301.047552) (xy 184.155078 -301.098887)
			(xy 184.155588 -301.124874) (xy 184.155078 -301.150861) (xy 184.444642 -301.150861) (xy 184.444642 -301.098887)
			(xy 184.452772 -301.047552) (xy 184.468833 -300.998122) (xy 184.492429 -300.951812) (xy 184.522979 -300.909764)
			(xy 184.55973 -300.873013) (xy 184.601778 -300.842463) (xy 184.648088 -300.818867) (xy 184.697518 -300.802806)
			(xy 184.748853 -300.794676) (xy 184.800827 -300.794676) (xy 184.852162 -300.802806) (xy 184.901592 -300.818867)
			(xy 184.947902 -300.842463) (xy 184.98995 -300.873013) (xy 185.026701 -300.909764) (xy 185.057251 -300.951812)
			(xy 185.080847 -300.998122) (xy 185.096908 -301.047552) (xy 185.105038 -301.098887) (xy 185.105548 -301.124874)
			(xy 185.105038 -301.150861) (xy 185.096908 -301.202196) (xy 185.080847 -301.251626) (xy 185.057251 -301.297936)
			(xy 185.026701 -301.339984) (xy 184.98995 -301.376735) (xy 184.947902 -301.407285) (xy 184.901592 -301.430881)
			(xy 184.852162 -301.446942) (xy 184.800827 -301.455072) (xy 184.748853 -301.455072) (xy 184.697518 -301.446942)
			(xy 184.648088 -301.430881) (xy 184.601778 -301.407285) (xy 184.55973 -301.376735) (xy 184.522979 -301.339984)
			(xy 184.492429 -301.297936) (xy 184.468833 -301.251626) (xy 184.452772 -301.202196) (xy 184.444642 -301.150861)
			(xy 184.155078 -301.150861) (xy 184.146948 -301.202196) (xy 184.130887 -301.251626) (xy 184.107291 -301.297936)
			(xy 184.076741 -301.339984) (xy 184.03999 -301.376735) (xy 183.997942 -301.407285) (xy 183.951632 -301.430881)
			(xy 183.902202 -301.446942) (xy 183.850867 -301.455072) (xy 183.798893 -301.455072) (xy 183.747558 -301.446942)
			(xy 183.698128 -301.430881) (xy 183.651818 -301.407285) (xy 183.60977 -301.376735) (xy 183.573019 -301.339984)
			(xy 183.542469 -301.297936) (xy 183.518873 -301.251626) (xy 183.502812 -301.202196) (xy 183.494682 -301.150861)
			(xy 183.205118 -301.150861) (xy 183.196988 -301.202196) (xy 183.180927 -301.251626) (xy 183.157331 -301.297936)
			(xy 183.126781 -301.339984) (xy 183.09003 -301.376735) (xy 183.047982 -301.407285) (xy 183.001672 -301.430881)
			(xy 182.952242 -301.446942) (xy 182.900907 -301.455072) (xy 182.848933 -301.455072) (xy 182.797598 -301.446942)
			(xy 182.748168 -301.430881) (xy 182.701858 -301.407285) (xy 182.65981 -301.376735) (xy 182.623059 -301.339984)
			(xy 182.592509 -301.297936) (xy 182.568913 -301.251626) (xy 182.552852 -301.202196) (xy 182.544722 -301.150861)
			(xy 182.255158 -301.150861) (xy 182.247028 -301.202196) (xy 182.230967 -301.251626) (xy 182.207371 -301.297936)
			(xy 182.176821 -301.339984) (xy 182.14007 -301.376735) (xy 182.098022 -301.407285) (xy 182.051712 -301.430881)
			(xy 182.002282 -301.446942) (xy 181.950947 -301.455072) (xy 181.898973 -301.455072) (xy 181.847638 -301.446942)
			(xy 181.798208 -301.430881) (xy 181.751898 -301.407285) (xy 181.70985 -301.376735) (xy 181.673099 -301.339984)
			(xy 181.642549 -301.297936) (xy 181.618953 -301.251626) (xy 181.602892 -301.202196) (xy 181.594762 -301.150861)
			(xy 181.305198 -301.150861) (xy 181.297068 -301.202196) (xy 181.281007 -301.251626) (xy 181.257411 -301.297936)
			(xy 181.226861 -301.339984) (xy 181.19011 -301.376735) (xy 181.148062 -301.407285) (xy 181.101752 -301.430881)
			(xy 181.052322 -301.446942) (xy 181.000987 -301.455072) (xy 180.949013 -301.455072) (xy 180.897678 -301.446942)
			(xy 180.848248 -301.430881) (xy 180.801938 -301.407285) (xy 180.75989 -301.376735) (xy 180.723139 -301.339984)
			(xy 180.692589 -301.297936) (xy 180.668993 -301.251626) (xy 180.652932 -301.202196) (xy 180.644802 -301.150861)
			(xy 180.355238 -301.150861) (xy 180.347108 -301.202196) (xy 180.331047 -301.251626) (xy 180.307451 -301.297936)
			(xy 180.276901 -301.339984) (xy 180.24015 -301.376735) (xy 180.198102 -301.407285) (xy 180.151792 -301.430881)
			(xy 180.102362 -301.446942) (xy 180.051027 -301.455072) (xy 179.999053 -301.455072) (xy 179.947718 -301.446942)
			(xy 179.898288 -301.430881) (xy 179.851978 -301.407285) (xy 179.80993 -301.376735) (xy 179.773179 -301.339984)
			(xy 179.742629 -301.297936) (xy 179.719033 -301.251626) (xy 179.702972 -301.202196) (xy 179.694842 -301.150861)
			(xy 179.405278 -301.150861) (xy 179.397148 -301.202196) (xy 179.381087 -301.251626) (xy 179.357491 -301.297936)
			(xy 179.326941 -301.339984) (xy 179.29019 -301.376735) (xy 179.248142 -301.407285) (xy 179.201832 -301.430881)
			(xy 179.152402 -301.446942) (xy 179.101067 -301.455072) (xy 179.049093 -301.455072) (xy 178.997758 -301.446942)
			(xy 178.948328 -301.430881) (xy 178.902018 -301.407285) (xy 178.85997 -301.376735) (xy 178.823219 -301.339984)
			(xy 178.792669 -301.297936) (xy 178.769073 -301.251626) (xy 178.753012 -301.202196) (xy 178.744882 -301.150861)
			(xy 178.455064 -301.150861) (xy 178.446934 -301.202196) (xy 178.430873 -301.251626) (xy 178.407277 -301.297936)
			(xy 178.376727 -301.339984) (xy 178.339976 -301.376735) (xy 178.297928 -301.407285) (xy 178.251618 -301.430881)
			(xy 178.202188 -301.446942) (xy 178.150853 -301.455072) (xy 178.098879 -301.455072) (xy 178.047544 -301.446942)
			(xy 177.998114 -301.430881) (xy 177.951804 -301.407285) (xy 177.909756 -301.376735) (xy 177.873005 -301.339984)
			(xy 177.842455 -301.297936) (xy 177.818859 -301.251626) (xy 177.802798 -301.202196) (xy 177.794668 -301.150861)
			(xy 177.505104 -301.150861) (xy 177.496974 -301.202196) (xy 177.480913 -301.251626) (xy 177.457317 -301.297936)
			(xy 177.426767 -301.339984) (xy 177.390016 -301.376735) (xy 177.347968 -301.407285) (xy 177.301658 -301.430881)
			(xy 177.252228 -301.446942) (xy 177.200893 -301.455072) (xy 177.148919 -301.455072) (xy 177.097584 -301.446942)
			(xy 177.048154 -301.430881) (xy 177.001844 -301.407285) (xy 176.959796 -301.376735) (xy 176.923045 -301.339984)
			(xy 176.892495 -301.297936) (xy 176.868899 -301.251626) (xy 176.852838 -301.202196) (xy 176.844708 -301.150861)
			(xy 176.555144 -301.150861) (xy 176.547014 -301.202196) (xy 176.530953 -301.251626) (xy 176.507357 -301.297936)
			(xy 176.476807 -301.339984) (xy 176.440056 -301.376735) (xy 176.398008 -301.407285) (xy 176.351698 -301.430881)
			(xy 176.302268 -301.446942) (xy 176.250933 -301.455072) (xy 176.198959 -301.455072) (xy 176.147624 -301.446942)
			(xy 176.098194 -301.430881) (xy 176.051884 -301.407285) (xy 176.009836 -301.376735) (xy 175.973085 -301.339984)
			(xy 175.942535 -301.297936) (xy 175.918939 -301.251626) (xy 175.902878 -301.202196) (xy 175.894748 -301.150861)
			(xy 174.655224 -301.150861) (xy 174.647094 -301.202196) (xy 174.631033 -301.251626) (xy 174.607437 -301.297936)
			(xy 174.576887 -301.339984) (xy 174.540136 -301.376735) (xy 174.498088 -301.407285) (xy 174.451778 -301.430881)
			(xy 174.402348 -301.446942) (xy 174.351013 -301.455072) (xy 174.299039 -301.455072) (xy 174.247704 -301.446942)
			(xy 174.198274 -301.430881) (xy 174.151964 -301.407285) (xy 174.109916 -301.376735) (xy 174.073165 -301.339984)
			(xy 174.042615 -301.297936) (xy 174.019019 -301.251626) (xy 174.002958 -301.202196) (xy 173.994828 -301.150861)
			(xy 173.705264 -301.150861) (xy 173.697134 -301.202196) (xy 173.681073 -301.251626) (xy 173.657477 -301.297936)
			(xy 173.626927 -301.339984) (xy 173.590176 -301.376735) (xy 173.548128 -301.407285) (xy 173.501818 -301.430881)
			(xy 173.452388 -301.446942) (xy 173.401053 -301.455072) (xy 173.349079 -301.455072) (xy 173.297744 -301.446942)
			(xy 173.248314 -301.430881) (xy 173.202004 -301.407285) (xy 173.159956 -301.376735) (xy 173.123205 -301.339984)
			(xy 173.092655 -301.297936) (xy 173.069059 -301.251626) (xy 173.052998 -301.202196) (xy 173.044868 -301.150861)
			(xy 172.75505 -301.150861) (xy 172.74692 -301.202196) (xy 172.730859 -301.251626) (xy 172.707263 -301.297936)
			(xy 172.676713 -301.339984) (xy 172.639962 -301.376735) (xy 172.597914 -301.407285) (xy 172.551604 -301.430881)
			(xy 172.502174 -301.446942) (xy 172.450839 -301.455072) (xy 172.398865 -301.455072) (xy 172.34753 -301.446942)
			(xy 172.2981 -301.430881) (xy 172.25179 -301.407285) (xy 172.209742 -301.376735) (xy 172.172991 -301.339984)
			(xy 172.142441 -301.297936) (xy 172.118845 -301.251626) (xy 172.102784 -301.202196) (xy 172.094654 -301.150861)
			(xy 171.80509 -301.150861) (xy 171.79696 -301.202196) (xy 171.780899 -301.251626) (xy 171.757303 -301.297936)
			(xy 171.726753 -301.339984) (xy 171.690002 -301.376735) (xy 171.647954 -301.407285) (xy 171.601644 -301.430881)
			(xy 171.552214 -301.446942) (xy 171.500879 -301.455072) (xy 171.448905 -301.455072) (xy 171.39757 -301.446942)
			(xy 171.34814 -301.430881) (xy 171.30183 -301.407285) (xy 171.259782 -301.376735) (xy 171.223031 -301.339984)
			(xy 171.192481 -301.297936) (xy 171.168885 -301.251626) (xy 171.152824 -301.202196) (xy 171.144694 -301.150861)
			(xy 170.85513 -301.150861) (xy 170.847 -301.202196) (xy 170.830939 -301.251626) (xy 170.807343 -301.297936)
			(xy 170.776793 -301.339984) (xy 170.740042 -301.376735) (xy 170.697994 -301.407285) (xy 170.651684 -301.430881)
			(xy 170.602254 -301.446942) (xy 170.550919 -301.455072) (xy 170.498945 -301.455072) (xy 170.44761 -301.446942)
			(xy 170.39818 -301.430881) (xy 170.35187 -301.407285) (xy 170.309822 -301.376735) (xy 170.273071 -301.339984)
			(xy 170.242521 -301.297936) (xy 170.218925 -301.251626) (xy 170.202864 -301.202196) (xy 170.194734 -301.150861)
			(xy 169.90517 -301.150861) (xy 169.89704 -301.202196) (xy 169.880979 -301.251626) (xy 169.857383 -301.297936)
			(xy 169.826833 -301.339984) (xy 169.790082 -301.376735) (xy 169.748034 -301.407285) (xy 169.701724 -301.430881)
			(xy 169.652294 -301.446942) (xy 169.600959 -301.455072) (xy 169.548985 -301.455072) (xy 169.49765 -301.446942)
			(xy 169.44822 -301.430881) (xy 169.40191 -301.407285) (xy 169.359862 -301.376735) (xy 169.323111 -301.339984)
			(xy 169.292561 -301.297936) (xy 169.268965 -301.251626) (xy 169.252904 -301.202196) (xy 169.244774 -301.150861)
			(xy 168.95521 -301.150861) (xy 168.94708 -301.202196) (xy 168.931019 -301.251626) (xy 168.907423 -301.297936)
			(xy 168.876873 -301.339984) (xy 168.840122 -301.376735) (xy 168.798074 -301.407285) (xy 168.751764 -301.430881)
			(xy 168.702334 -301.446942) (xy 168.650999 -301.455072) (xy 168.599025 -301.455072) (xy 168.54769 -301.446942)
			(xy 168.49826 -301.430881) (xy 168.45195 -301.407285) (xy 168.409902 -301.376735) (xy 168.373151 -301.339984)
			(xy 168.342601 -301.297936) (xy 168.319005 -301.251626) (xy 168.302944 -301.202196) (xy 168.294814 -301.150861)
			(xy 168.00525 -301.150861) (xy 167.99712 -301.202196) (xy 167.981059 -301.251626) (xy 167.957463 -301.297936)
			(xy 167.926913 -301.339984) (xy 167.890162 -301.376735) (xy 167.848114 -301.407285) (xy 167.801804 -301.430881)
			(xy 167.752374 -301.446942) (xy 167.701039 -301.455072) (xy 167.649065 -301.455072) (xy 167.59773 -301.446942)
			(xy 167.5483 -301.430881) (xy 167.50199 -301.407285) (xy 167.459942 -301.376735) (xy 167.423191 -301.339984)
			(xy 167.392641 -301.297936) (xy 167.369045 -301.251626) (xy 167.352984 -301.202196) (xy 167.344854 -301.150861)
			(xy 167.05529 -301.150861) (xy 167.04716 -301.202196) (xy 167.031099 -301.251626) (xy 167.007503 -301.297936)
			(xy 166.976953 -301.339984) (xy 166.940202 -301.376735) (xy 166.898154 -301.407285) (xy 166.851844 -301.430881)
			(xy 166.802414 -301.446942) (xy 166.751079 -301.455072) (xy 166.699105 -301.455072) (xy 166.64777 -301.446942)
			(xy 166.59834 -301.430881) (xy 166.55203 -301.407285) (xy 166.509982 -301.376735) (xy 166.473231 -301.339984)
			(xy 166.442681 -301.297936) (xy 166.419085 -301.251626) (xy 166.403024 -301.202196) (xy 166.394894 -301.150861)
			(xy 166.105076 -301.150861) (xy 166.096946 -301.202196) (xy 166.080885 -301.251626) (xy 166.057289 -301.297936)
			(xy 166.026739 -301.339984) (xy 165.989988 -301.376735) (xy 165.94794 -301.407285) (xy 165.90163 -301.430881)
			(xy 165.8522 -301.446942) (xy 165.800865 -301.455072) (xy 165.748891 -301.455072) (xy 165.697556 -301.446942)
			(xy 165.648126 -301.430881) (xy 165.601816 -301.407285) (xy 165.559768 -301.376735) (xy 165.523017 -301.339984)
			(xy 165.492467 -301.297936) (xy 165.468871 -301.251626) (xy 165.45281 -301.202196) (xy 165.44468 -301.150861)
			(xy 165.155116 -301.150861) (xy 165.146986 -301.202196) (xy 165.130925 -301.251626) (xy 165.107329 -301.297936)
			(xy 165.076779 -301.339984) (xy 165.040028 -301.376735) (xy 164.99798 -301.407285) (xy 164.95167 -301.430881)
			(xy 164.90224 -301.446942) (xy 164.850905 -301.455072) (xy 164.798931 -301.455072) (xy 164.747596 -301.446942)
			(xy 164.698166 -301.430881) (xy 164.651856 -301.407285) (xy 164.609808 -301.376735) (xy 164.573057 -301.339984)
			(xy 164.542507 -301.297936) (xy 164.518911 -301.251626) (xy 164.50285 -301.202196) (xy 164.49472 -301.150861)
			(xy 164.205156 -301.150861) (xy 164.197026 -301.202196) (xy 164.180965 -301.251626) (xy 164.157369 -301.297936)
			(xy 164.126819 -301.339984) (xy 164.090068 -301.376735) (xy 164.04802 -301.407285) (xy 164.00171 -301.430881)
			(xy 163.95228 -301.446942) (xy 163.900945 -301.455072) (xy 163.848971 -301.455072) (xy 163.797636 -301.446942)
			(xy 163.748206 -301.430881) (xy 163.701896 -301.407285) (xy 163.659848 -301.376735) (xy 163.623097 -301.339984)
			(xy 163.592547 -301.297936) (xy 163.568951 -301.251626) (xy 163.55289 -301.202196) (xy 163.54476 -301.150861)
			(xy 162.304187 -301.150861) (xy 162.302074 -301.177375) (xy 162.289629 -301.228531) (xy 162.269237 -301.277068)
			(xy 162.241413 -301.321762) (xy 162.20686 -301.361484) (xy 162.16645 -301.395229) (xy 162.121204 -301.422146)
			(xy 162.072265 -301.441555) (xy 162.046666 -301.447708) (xy 162.02914 -301.451518) (xy 162.006788 -301.479458)
			(xy 162.006788 -301.72025) (xy 162.02914 -301.74819) (xy 162.046666 -301.752) (xy 162.070505 -301.757752)
			(xy 162.116283 -301.775338) (xy 162.158964 -301.799487) (xy 162.197612 -301.829672) (xy 162.231383 -301.86523)
			(xy 162.259535 -301.905384) (xy 162.281452 -301.949252) (xy 162.296654 -301.995875) (xy 162.304809 -302.044232)
			(xy 162.305746 -302.068738) (xy 162.305746 -302.0695) (xy 162.306434 -302.079077) (xy 162.313995 -302.096709)
			(xy 162.31776 -302.100821) (xy 165.44468 -302.100821) (xy 165.44468 -302.048847) (xy 165.45281 -301.997512)
			(xy 165.468871 -301.948082) (xy 165.492467 -301.901772) (xy 165.523017 -301.859724) (xy 165.559768 -301.822973)
			(xy 165.601816 -301.792423) (xy 165.648126 -301.768827) (xy 165.697556 -301.752766) (xy 165.748891 -301.744636)
			(xy 165.800865 -301.744636) (xy 165.8522 -301.752766) (xy 165.90163 -301.768827) (xy 165.94794 -301.792423)
			(xy 165.989988 -301.822973) (xy 166.026739 -301.859724) (xy 166.057289 -301.901772) (xy 166.080885 -301.948082)
			(xy 166.096946 -301.997512) (xy 166.105076 -302.048847) (xy 166.105586 -302.074834) (xy 166.105076 -302.100821)
			(xy 166.394894 -302.100821) (xy 166.394894 -302.048847) (xy 166.403024 -301.997512) (xy 166.419085 -301.948082)
			(xy 166.442681 -301.901772) (xy 166.473231 -301.859724) (xy 166.509982 -301.822973) (xy 166.55203 -301.792423)
			(xy 166.59834 -301.768827) (xy 166.64777 -301.752766) (xy 166.699105 -301.744636) (xy 166.751079 -301.744636)
			(xy 166.802414 -301.752766) (xy 166.851844 -301.768827) (xy 166.898154 -301.792423) (xy 166.940202 -301.822973)
			(xy 166.976953 -301.859724) (xy 167.007503 -301.901772) (xy 167.031099 -301.948082) (xy 167.04716 -301.997512)
			(xy 167.05529 -302.048847) (xy 167.0558 -302.074834) (xy 167.05529 -302.100821) (xy 167.344854 -302.100821)
			(xy 167.344854 -302.048847) (xy 167.352984 -301.997512) (xy 167.369045 -301.948082) (xy 167.392641 -301.901772)
			(xy 167.423191 -301.859724) (xy 167.459942 -301.822973) (xy 167.50199 -301.792423) (xy 167.5483 -301.768827)
			(xy 167.59773 -301.752766) (xy 167.649065 -301.744636) (xy 167.701039 -301.744636) (xy 167.752374 -301.752766)
			(xy 167.801804 -301.768827) (xy 167.848114 -301.792423) (xy 167.890162 -301.822973) (xy 167.926913 -301.859724)
			(xy 167.957463 -301.901772) (xy 167.981059 -301.948082) (xy 167.99712 -301.997512) (xy 168.00525 -302.048847)
			(xy 168.00576 -302.074834) (xy 168.00525 -302.100821) (xy 168.294814 -302.100821) (xy 168.294814 -302.048847)
			(xy 168.302944 -301.997512) (xy 168.319005 -301.948082) (xy 168.342601 -301.901772) (xy 168.373151 -301.859724)
			(xy 168.409902 -301.822973) (xy 168.45195 -301.792423) (xy 168.49826 -301.768827) (xy 168.54769 -301.752766)
			(xy 168.599025 -301.744636) (xy 168.650999 -301.744636) (xy 168.702334 -301.752766) (xy 168.751764 -301.768827)
			(xy 168.798074 -301.792423) (xy 168.840122 -301.822973) (xy 168.876873 -301.859724) (xy 168.907423 -301.901772)
			(xy 168.931019 -301.948082) (xy 168.94708 -301.997512) (xy 168.95521 -302.048847) (xy 168.95572 -302.074834)
			(xy 168.95521 -302.100821) (xy 169.244774 -302.100821) (xy 169.244774 -302.048847) (xy 169.252904 -301.997512)
			(xy 169.268965 -301.948082) (xy 169.292561 -301.901772) (xy 169.323111 -301.859724) (xy 169.359862 -301.822973)
			(xy 169.40191 -301.792423) (xy 169.44822 -301.768827) (xy 169.49765 -301.752766) (xy 169.548985 -301.744636)
			(xy 169.600959 -301.744636) (xy 169.652294 -301.752766) (xy 169.701724 -301.768827) (xy 169.748034 -301.792423)
			(xy 169.790082 -301.822973) (xy 169.826833 -301.859724) (xy 169.857383 -301.901772) (xy 169.880979 -301.948082)
			(xy 169.89704 -301.997512) (xy 169.90517 -302.048847) (xy 169.90568 -302.074834) (xy 169.90517 -302.100821)
			(xy 170.194734 -302.100821) (xy 170.194734 -302.048847) (xy 170.202864 -301.997512) (xy 170.218925 -301.948082)
			(xy 170.242521 -301.901772) (xy 170.273071 -301.859724) (xy 170.309822 -301.822973) (xy 170.35187 -301.792423)
			(xy 170.39818 -301.768827) (xy 170.44761 -301.752766) (xy 170.498945 -301.744636) (xy 170.550919 -301.744636)
			(xy 170.602254 -301.752766) (xy 170.651684 -301.768827) (xy 170.697994 -301.792423) (xy 170.740042 -301.822973)
			(xy 170.776793 -301.859724) (xy 170.807343 -301.901772) (xy 170.830939 -301.948082) (xy 170.847 -301.997512)
			(xy 170.85513 -302.048847) (xy 170.85564 -302.074834) (xy 170.85513 -302.100821) (xy 171.144694 -302.100821)
			(xy 171.144694 -302.048847) (xy 171.152824 -301.997512) (xy 171.168885 -301.948082) (xy 171.192481 -301.901772)
			(xy 171.223031 -301.859724) (xy 171.259782 -301.822973) (xy 171.30183 -301.792423) (xy 171.34814 -301.768827)
			(xy 171.39757 -301.752766) (xy 171.448905 -301.744636) (xy 171.500879 -301.744636) (xy 171.552214 -301.752766)
			(xy 171.601644 -301.768827) (xy 171.647954 -301.792423) (xy 171.690002 -301.822973) (xy 171.726753 -301.859724)
			(xy 171.757303 -301.901772) (xy 171.780899 -301.948082) (xy 171.79696 -301.997512) (xy 171.80509 -302.048847)
			(xy 171.8056 -302.074834) (xy 171.80509 -302.100821) (xy 172.094654 -302.100821) (xy 172.094654 -302.048847)
			(xy 172.102784 -301.997512) (xy 172.118845 -301.948082) (xy 172.142441 -301.901772) (xy 172.172991 -301.859724)
			(xy 172.209742 -301.822973) (xy 172.25179 -301.792423) (xy 172.2981 -301.768827) (xy 172.34753 -301.752766)
			(xy 172.398865 -301.744636) (xy 172.450839 -301.744636) (xy 172.502174 -301.752766) (xy 172.551604 -301.768827)
			(xy 172.597914 -301.792423) (xy 172.639962 -301.822973) (xy 172.676713 -301.859724) (xy 172.707263 -301.901772)
			(xy 172.730859 -301.948082) (xy 172.74692 -301.997512) (xy 172.75505 -302.048847) (xy 172.75556 -302.074834)
			(xy 172.75505 -302.100821) (xy 173.044868 -302.100821) (xy 173.044868 -302.048847) (xy 173.052998 -301.997512)
			(xy 173.069059 -301.948082) (xy 173.092655 -301.901772) (xy 173.123205 -301.859724) (xy 173.159956 -301.822973)
			(xy 173.202004 -301.792423) (xy 173.248314 -301.768827) (xy 173.297744 -301.752766) (xy 173.349079 -301.744636)
			(xy 173.401053 -301.744636) (xy 173.452388 -301.752766) (xy 173.501818 -301.768827) (xy 173.548128 -301.792423)
			(xy 173.590176 -301.822973) (xy 173.626927 -301.859724) (xy 173.657477 -301.901772) (xy 173.681073 -301.948082)
			(xy 173.697134 -301.997512) (xy 173.705264 -302.048847) (xy 173.705774 -302.074834) (xy 173.705264 -302.100821)
			(xy 173.994828 -302.100821) (xy 173.994828 -302.048847) (xy 174.002958 -301.997512) (xy 174.019019 -301.948082)
			(xy 174.042615 -301.901772) (xy 174.073165 -301.859724) (xy 174.109916 -301.822973) (xy 174.151964 -301.792423)
			(xy 174.198274 -301.768827) (xy 174.247704 -301.752766) (xy 174.299039 -301.744636) (xy 174.351013 -301.744636)
			(xy 174.402348 -301.752766) (xy 174.451778 -301.768827) (xy 174.498088 -301.792423) (xy 174.540136 -301.822973)
			(xy 174.576887 -301.859724) (xy 174.607437 -301.901772) (xy 174.631033 -301.948082) (xy 174.647094 -301.997512)
			(xy 174.655224 -302.048847) (xy 174.655734 -302.074834) (xy 174.655224 -302.100821) (xy 175.894748 -302.100821)
			(xy 175.894748 -302.048847) (xy 175.902878 -301.997512) (xy 175.918939 -301.948082) (xy 175.942535 -301.901772)
			(xy 175.973085 -301.859724) (xy 176.009836 -301.822973) (xy 176.051884 -301.792423) (xy 176.098194 -301.768827)
			(xy 176.147624 -301.752766) (xy 176.198959 -301.744636) (xy 176.250933 -301.744636) (xy 176.302268 -301.752766)
			(xy 176.351698 -301.768827) (xy 176.398008 -301.792423) (xy 176.440056 -301.822973) (xy 176.476807 -301.859724)
			(xy 176.507357 -301.901772) (xy 176.530953 -301.948082) (xy 176.547014 -301.997512) (xy 176.555144 -302.048847)
			(xy 176.555654 -302.074834) (xy 176.555144 -302.100821) (xy 176.844708 -302.100821) (xy 176.844708 -302.048847)
			(xy 176.852838 -301.997512) (xy 176.868899 -301.948082) (xy 176.892495 -301.901772) (xy 176.923045 -301.859724)
			(xy 176.959796 -301.822973) (xy 177.001844 -301.792423) (xy 177.048154 -301.768827) (xy 177.097584 -301.752766)
			(xy 177.148919 -301.744636) (xy 177.200893 -301.744636) (xy 177.252228 -301.752766) (xy 177.301658 -301.768827)
			(xy 177.347968 -301.792423) (xy 177.390016 -301.822973) (xy 177.426767 -301.859724) (xy 177.457317 -301.901772)
			(xy 177.480913 -301.948082) (xy 177.496974 -301.997512) (xy 177.505104 -302.048847) (xy 177.505614 -302.074834)
			(xy 177.505104 -302.100821) (xy 177.794668 -302.100821) (xy 177.794668 -302.048847) (xy 177.802798 -301.997512)
			(xy 177.818859 -301.948082) (xy 177.842455 -301.901772) (xy 177.873005 -301.859724) (xy 177.909756 -301.822973)
			(xy 177.951804 -301.792423) (xy 177.998114 -301.768827) (xy 178.047544 -301.752766) (xy 178.098879 -301.744636)
			(xy 178.150853 -301.744636) (xy 178.202188 -301.752766) (xy 178.251618 -301.768827) (xy 178.297928 -301.792423)
			(xy 178.339976 -301.822973) (xy 178.376727 -301.859724) (xy 178.407277 -301.901772) (xy 178.430873 -301.948082)
			(xy 178.446934 -301.997512) (xy 178.455064 -302.048847) (xy 178.455574 -302.074834) (xy 178.455064 -302.100821)
			(xy 178.744882 -302.100821) (xy 178.744882 -302.048847) (xy 178.753012 -301.997512) (xy 178.769073 -301.948082)
			(xy 178.792669 -301.901772) (xy 178.823219 -301.859724) (xy 178.85997 -301.822973) (xy 178.902018 -301.792423)
			(xy 178.948328 -301.768827) (xy 178.997758 -301.752766) (xy 179.049093 -301.744636) (xy 179.101067 -301.744636)
			(xy 179.152402 -301.752766) (xy 179.201832 -301.768827) (xy 179.248142 -301.792423) (xy 179.29019 -301.822973)
			(xy 179.326941 -301.859724) (xy 179.357491 -301.901772) (xy 179.381087 -301.948082) (xy 179.397148 -301.997512)
			(xy 179.405278 -302.048847) (xy 179.405788 -302.074834) (xy 179.405278 -302.100821) (xy 179.694842 -302.100821)
			(xy 179.694842 -302.048847) (xy 179.702972 -301.997512) (xy 179.719033 -301.948082) (xy 179.742629 -301.901772)
			(xy 179.773179 -301.859724) (xy 179.80993 -301.822973) (xy 179.851978 -301.792423) (xy 179.898288 -301.768827)
			(xy 179.947718 -301.752766) (xy 179.999053 -301.744636) (xy 180.051027 -301.744636) (xy 180.102362 -301.752766)
			(xy 180.151792 -301.768827) (xy 180.198102 -301.792423) (xy 180.24015 -301.822973) (xy 180.276901 -301.859724)
			(xy 180.307451 -301.901772) (xy 180.331047 -301.948082) (xy 180.347108 -301.997512) (xy 180.355238 -302.048847)
			(xy 180.355748 -302.074834) (xy 180.355238 -302.100821) (xy 180.644802 -302.100821) (xy 180.644802 -302.048847)
			(xy 180.652932 -301.997512) (xy 180.668993 -301.948082) (xy 180.692589 -301.901772) (xy 180.723139 -301.859724)
			(xy 180.75989 -301.822973) (xy 180.801938 -301.792423) (xy 180.848248 -301.768827) (xy 180.897678 -301.752766)
			(xy 180.949013 -301.744636) (xy 181.000987 -301.744636) (xy 181.052322 -301.752766) (xy 181.101752 -301.768827)
			(xy 181.148062 -301.792423) (xy 181.19011 -301.822973) (xy 181.226861 -301.859724) (xy 181.257411 -301.901772)
			(xy 181.281007 -301.948082) (xy 181.297068 -301.997512) (xy 181.305198 -302.048847) (xy 181.305708 -302.074834)
			(xy 181.305198 -302.100821) (xy 181.594762 -302.100821) (xy 181.594762 -302.048847) (xy 181.602892 -301.997512)
			(xy 181.618953 -301.948082) (xy 181.642549 -301.901772) (xy 181.673099 -301.859724) (xy 181.70985 -301.822973)
			(xy 181.751898 -301.792423) (xy 181.798208 -301.768827) (xy 181.847638 -301.752766) (xy 181.898973 -301.744636)
			(xy 181.950947 -301.744636) (xy 182.002282 -301.752766) (xy 182.051712 -301.768827) (xy 182.098022 -301.792423)
			(xy 182.14007 -301.822973) (xy 182.176821 -301.859724) (xy 182.207371 -301.901772) (xy 182.230967 -301.948082)
			(xy 182.247028 -301.997512) (xy 182.255158 -302.048847) (xy 182.255668 -302.074834) (xy 182.255158 -302.100821)
			(xy 182.544722 -302.100821) (xy 182.544722 -302.048847) (xy 182.552852 -301.997512) (xy 182.568913 -301.948082)
			(xy 182.592509 -301.901772) (xy 182.623059 -301.859724) (xy 182.65981 -301.822973) (xy 182.701858 -301.792423)
			(xy 182.748168 -301.768827) (xy 182.797598 -301.752766) (xy 182.848933 -301.744636) (xy 182.900907 -301.744636)
			(xy 182.952242 -301.752766) (xy 183.001672 -301.768827) (xy 183.047982 -301.792423) (xy 183.09003 -301.822973)
			(xy 183.126781 -301.859724) (xy 183.157331 -301.901772) (xy 183.180927 -301.948082) (xy 183.196988 -301.997512)
			(xy 183.205118 -302.048847) (xy 183.205628 -302.074834) (xy 183.205118 -302.100821) (xy 183.494682 -302.100821)
			(xy 183.494682 -302.048847) (xy 183.502812 -301.997512) (xy 183.518873 -301.948082) (xy 183.542469 -301.901772)
			(xy 183.573019 -301.859724) (xy 183.60977 -301.822973) (xy 183.651818 -301.792423) (xy 183.698128 -301.768827)
			(xy 183.747558 -301.752766) (xy 183.798893 -301.744636) (xy 183.850867 -301.744636) (xy 183.902202 -301.752766)
			(xy 183.951632 -301.768827) (xy 183.997942 -301.792423) (xy 184.03999 -301.822973) (xy 184.076741 -301.859724)
			(xy 184.107291 -301.901772) (xy 184.130887 -301.948082) (xy 184.146948 -301.997512) (xy 184.155078 -302.048847)
			(xy 184.155588 -302.074834) (xy 184.155078 -302.100821) (xy 184.444642 -302.100821) (xy 184.444642 -302.048847)
			(xy 184.452772 -301.997512) (xy 184.468833 -301.948082) (xy 184.492429 -301.901772) (xy 184.522979 -301.859724)
			(xy 184.55973 -301.822973) (xy 184.601778 -301.792423) (xy 184.648088 -301.768827) (xy 184.697518 -301.752766)
			(xy 184.748853 -301.744636) (xy 184.800827 -301.744636) (xy 184.852162 -301.752766) (xy 184.901592 -301.768827)
			(xy 184.947902 -301.792423) (xy 184.98995 -301.822973) (xy 185.026701 -301.859724) (xy 185.057251 -301.901772)
			(xy 185.080847 -301.948082) (xy 185.096908 -301.997512) (xy 185.105038 -302.048847) (xy 185.105548 -302.074834)
			(xy 185.105038 -302.100821) (xy 185.096908 -302.152156) (xy 185.080847 -302.201586) (xy 185.057251 -302.247896)
			(xy 185.026701 -302.289944) (xy 184.98995 -302.326695) (xy 184.947902 -302.357245) (xy 184.901592 -302.380841)
			(xy 184.852162 -302.396902) (xy 184.800827 -302.405032) (xy 184.748853 -302.405032) (xy 184.697518 -302.396902)
			(xy 184.648088 -302.380841) (xy 184.601778 -302.357245) (xy 184.55973 -302.326695) (xy 184.522979 -302.289944)
			(xy 184.492429 -302.247896) (xy 184.468833 -302.201586) (xy 184.452772 -302.152156) (xy 184.444642 -302.100821)
			(xy 184.155078 -302.100821) (xy 184.146948 -302.152156) (xy 184.130887 -302.201586) (xy 184.107291 -302.247896)
			(xy 184.076741 -302.289944) (xy 184.03999 -302.326695) (xy 183.997942 -302.357245) (xy 183.951632 -302.380841)
			(xy 183.902202 -302.396902) (xy 183.850867 -302.405032) (xy 183.798893 -302.405032) (xy 183.747558 -302.396902)
			(xy 183.698128 -302.380841) (xy 183.651818 -302.357245) (xy 183.60977 -302.326695) (xy 183.573019 -302.289944)
			(xy 183.542469 -302.247896) (xy 183.518873 -302.201586) (xy 183.502812 -302.152156) (xy 183.494682 -302.100821)
			(xy 183.205118 -302.100821) (xy 183.196988 -302.152156) (xy 183.180927 -302.201586) (xy 183.157331 -302.247896)
			(xy 183.126781 -302.289944) (xy 183.09003 -302.326695) (xy 183.047982 -302.357245) (xy 183.001672 -302.380841)
			(xy 182.952242 -302.396902) (xy 182.900907 -302.405032) (xy 182.848933 -302.405032) (xy 182.797598 -302.396902)
			(xy 182.748168 -302.380841) (xy 182.701858 -302.357245) (xy 182.65981 -302.326695) (xy 182.623059 -302.289944)
			(xy 182.592509 -302.247896) (xy 182.568913 -302.201586) (xy 182.552852 -302.152156) (xy 182.544722 -302.100821)
			(xy 182.255158 -302.100821) (xy 182.247028 -302.152156) (xy 182.230967 -302.201586) (xy 182.207371 -302.247896)
			(xy 182.176821 -302.289944) (xy 182.14007 -302.326695) (xy 182.098022 -302.357245) (xy 182.051712 -302.380841)
			(xy 182.002282 -302.396902) (xy 181.950947 -302.405032) (xy 181.898973 -302.405032) (xy 181.847638 -302.396902)
			(xy 181.798208 -302.380841) (xy 181.751898 -302.357245) (xy 181.70985 -302.326695) (xy 181.673099 -302.289944)
			(xy 181.642549 -302.247896) (xy 181.618953 -302.201586) (xy 181.602892 -302.152156) (xy 181.594762 -302.100821)
			(xy 181.305198 -302.100821) (xy 181.297068 -302.152156) (xy 181.281007 -302.201586) (xy 181.257411 -302.247896)
			(xy 181.226861 -302.289944) (xy 181.19011 -302.326695) (xy 181.148062 -302.357245) (xy 181.101752 -302.380841)
			(xy 181.052322 -302.396902) (xy 181.000987 -302.405032) (xy 180.949013 -302.405032) (xy 180.897678 -302.396902)
			(xy 180.848248 -302.380841) (xy 180.801938 -302.357245) (xy 180.75989 -302.326695) (xy 180.723139 -302.289944)
			(xy 180.692589 -302.247896) (xy 180.668993 -302.201586) (xy 180.652932 -302.152156) (xy 180.644802 -302.100821)
			(xy 180.355238 -302.100821) (xy 180.347108 -302.152156) (xy 180.331047 -302.201586) (xy 180.307451 -302.247896)
			(xy 180.276901 -302.289944) (xy 180.24015 -302.326695) (xy 180.198102 -302.357245) (xy 180.151792 -302.380841)
			(xy 180.102362 -302.396902) (xy 180.051027 -302.405032) (xy 179.999053 -302.405032) (xy 179.947718 -302.396902)
			(xy 179.898288 -302.380841) (xy 179.851978 -302.357245) (xy 179.80993 -302.326695) (xy 179.773179 -302.289944)
			(xy 179.742629 -302.247896) (xy 179.719033 -302.201586) (xy 179.702972 -302.152156) (xy 179.694842 -302.100821)
			(xy 179.405278 -302.100821) (xy 179.397148 -302.152156) (xy 179.381087 -302.201586) (xy 179.357491 -302.247896)
			(xy 179.326941 -302.289944) (xy 179.29019 -302.326695) (xy 179.248142 -302.357245) (xy 179.201832 -302.380841)
			(xy 179.152402 -302.396902) (xy 179.101067 -302.405032) (xy 179.049093 -302.405032) (xy 178.997758 -302.396902)
			(xy 178.948328 -302.380841) (xy 178.902018 -302.357245) (xy 178.85997 -302.326695) (xy 178.823219 -302.289944)
			(xy 178.792669 -302.247896) (xy 178.769073 -302.201586) (xy 178.753012 -302.152156) (xy 178.744882 -302.100821)
			(xy 178.455064 -302.100821) (xy 178.446934 -302.152156) (xy 178.430873 -302.201586) (xy 178.407277 -302.247896)
			(xy 178.376727 -302.289944) (xy 178.339976 -302.326695) (xy 178.297928 -302.357245) (xy 178.251618 -302.380841)
			(xy 178.202188 -302.396902) (xy 178.150853 -302.405032) (xy 178.098879 -302.405032) (xy 178.047544 -302.396902)
			(xy 177.998114 -302.380841) (xy 177.951804 -302.357245) (xy 177.909756 -302.326695) (xy 177.873005 -302.289944)
			(xy 177.842455 -302.247896) (xy 177.818859 -302.201586) (xy 177.802798 -302.152156) (xy 177.794668 -302.100821)
			(xy 177.505104 -302.100821) (xy 177.496974 -302.152156) (xy 177.480913 -302.201586) (xy 177.457317 -302.247896)
			(xy 177.426767 -302.289944) (xy 177.390016 -302.326695) (xy 177.347968 -302.357245) (xy 177.301658 -302.380841)
			(xy 177.252228 -302.396902) (xy 177.200893 -302.405032) (xy 177.148919 -302.405032) (xy 177.097584 -302.396902)
			(xy 177.048154 -302.380841) (xy 177.001844 -302.357245) (xy 176.959796 -302.326695) (xy 176.923045 -302.289944)
			(xy 176.892495 -302.247896) (xy 176.868899 -302.201586) (xy 176.852838 -302.152156) (xy 176.844708 -302.100821)
			(xy 176.555144 -302.100821) (xy 176.547014 -302.152156) (xy 176.530953 -302.201586) (xy 176.507357 -302.247896)
			(xy 176.476807 -302.289944) (xy 176.440056 -302.326695) (xy 176.398008 -302.357245) (xy 176.351698 -302.380841)
			(xy 176.302268 -302.396902) (xy 176.250933 -302.405032) (xy 176.198959 -302.405032) (xy 176.147624 -302.396902)
			(xy 176.098194 -302.380841) (xy 176.051884 -302.357245) (xy 176.009836 -302.326695) (xy 175.973085 -302.289944)
			(xy 175.942535 -302.247896) (xy 175.918939 -302.201586) (xy 175.902878 -302.152156) (xy 175.894748 -302.100821)
			(xy 174.655224 -302.100821) (xy 174.647094 -302.152156) (xy 174.631033 -302.201586) (xy 174.607437 -302.247896)
			(xy 174.576887 -302.289944) (xy 174.540136 -302.326695) (xy 174.498088 -302.357245) (xy 174.451778 -302.380841)
			(xy 174.402348 -302.396902) (xy 174.351013 -302.405032) (xy 174.299039 -302.405032) (xy 174.247704 -302.396902)
			(xy 174.198274 -302.380841) (xy 174.151964 -302.357245) (xy 174.109916 -302.326695) (xy 174.073165 -302.289944)
			(xy 174.042615 -302.247896) (xy 174.019019 -302.201586) (xy 174.002958 -302.152156) (xy 173.994828 -302.100821)
			(xy 173.705264 -302.100821) (xy 173.697134 -302.152156) (xy 173.681073 -302.201586) (xy 173.657477 -302.247896)
			(xy 173.626927 -302.289944) (xy 173.590176 -302.326695) (xy 173.548128 -302.357245) (xy 173.501818 -302.380841)
			(xy 173.452388 -302.396902) (xy 173.401053 -302.405032) (xy 173.349079 -302.405032) (xy 173.297744 -302.396902)
			(xy 173.248314 -302.380841) (xy 173.202004 -302.357245) (xy 173.159956 -302.326695) (xy 173.123205 -302.289944)
			(xy 173.092655 -302.247896) (xy 173.069059 -302.201586) (xy 173.052998 -302.152156) (xy 173.044868 -302.100821)
			(xy 172.75505 -302.100821) (xy 172.74692 -302.152156) (xy 172.730859 -302.201586) (xy 172.707263 -302.247896)
			(xy 172.676713 -302.289944) (xy 172.639962 -302.326695) (xy 172.597914 -302.357245) (xy 172.551604 -302.380841)
			(xy 172.502174 -302.396902) (xy 172.450839 -302.405032) (xy 172.398865 -302.405032) (xy 172.34753 -302.396902)
			(xy 172.2981 -302.380841) (xy 172.25179 -302.357245) (xy 172.209742 -302.326695) (xy 172.172991 -302.289944)
			(xy 172.142441 -302.247896) (xy 172.118845 -302.201586) (xy 172.102784 -302.152156) (xy 172.094654 -302.100821)
			(xy 171.80509 -302.100821) (xy 171.79696 -302.152156) (xy 171.780899 -302.201586) (xy 171.757303 -302.247896)
			(xy 171.726753 -302.289944) (xy 171.690002 -302.326695) (xy 171.647954 -302.357245) (xy 171.601644 -302.380841)
			(xy 171.552214 -302.396902) (xy 171.500879 -302.405032) (xy 171.448905 -302.405032) (xy 171.39757 -302.396902)
			(xy 171.34814 -302.380841) (xy 171.30183 -302.357245) (xy 171.259782 -302.326695) (xy 171.223031 -302.289944)
			(xy 171.192481 -302.247896) (xy 171.168885 -302.201586) (xy 171.152824 -302.152156) (xy 171.144694 -302.100821)
			(xy 170.85513 -302.100821) (xy 170.847 -302.152156) (xy 170.830939 -302.201586) (xy 170.807343 -302.247896)
			(xy 170.776793 -302.289944) (xy 170.740042 -302.326695) (xy 170.697994 -302.357245) (xy 170.651684 -302.380841)
			(xy 170.602254 -302.396902) (xy 170.550919 -302.405032) (xy 170.498945 -302.405032) (xy 170.44761 -302.396902)
			(xy 170.39818 -302.380841) (xy 170.35187 -302.357245) (xy 170.309822 -302.326695) (xy 170.273071 -302.289944)
			(xy 170.242521 -302.247896) (xy 170.218925 -302.201586) (xy 170.202864 -302.152156) (xy 170.194734 -302.100821)
			(xy 169.90517 -302.100821) (xy 169.89704 -302.152156) (xy 169.880979 -302.201586) (xy 169.857383 -302.247896)
			(xy 169.826833 -302.289944) (xy 169.790082 -302.326695) (xy 169.748034 -302.357245) (xy 169.701724 -302.380841)
			(xy 169.652294 -302.396902) (xy 169.600959 -302.405032) (xy 169.548985 -302.405032) (xy 169.49765 -302.396902)
			(xy 169.44822 -302.380841) (xy 169.40191 -302.357245) (xy 169.359862 -302.326695) (xy 169.323111 -302.289944)
			(xy 169.292561 -302.247896) (xy 169.268965 -302.201586) (xy 169.252904 -302.152156) (xy 169.244774 -302.100821)
			(xy 168.95521 -302.100821) (xy 168.94708 -302.152156) (xy 168.931019 -302.201586) (xy 168.907423 -302.247896)
			(xy 168.876873 -302.289944) (xy 168.840122 -302.326695) (xy 168.798074 -302.357245) (xy 168.751764 -302.380841)
			(xy 168.702334 -302.396902) (xy 168.650999 -302.405032) (xy 168.599025 -302.405032) (xy 168.54769 -302.396902)
			(xy 168.49826 -302.380841) (xy 168.45195 -302.357245) (xy 168.409902 -302.326695) (xy 168.373151 -302.289944)
			(xy 168.342601 -302.247896) (xy 168.319005 -302.201586) (xy 168.302944 -302.152156) (xy 168.294814 -302.100821)
			(xy 168.00525 -302.100821) (xy 167.99712 -302.152156) (xy 167.981059 -302.201586) (xy 167.957463 -302.247896)
			(xy 167.926913 -302.289944) (xy 167.890162 -302.326695) (xy 167.848114 -302.357245) (xy 167.801804 -302.380841)
			(xy 167.752374 -302.396902) (xy 167.701039 -302.405032) (xy 167.649065 -302.405032) (xy 167.59773 -302.396902)
			(xy 167.5483 -302.380841) (xy 167.50199 -302.357245) (xy 167.459942 -302.326695) (xy 167.423191 -302.289944)
			(xy 167.392641 -302.247896) (xy 167.369045 -302.201586) (xy 167.352984 -302.152156) (xy 167.344854 -302.100821)
			(xy 167.05529 -302.100821) (xy 167.04716 -302.152156) (xy 167.031099 -302.201586) (xy 167.007503 -302.247896)
			(xy 166.976953 -302.289944) (xy 166.940202 -302.326695) (xy 166.898154 -302.357245) (xy 166.851844 -302.380841)
			(xy 166.802414 -302.396902) (xy 166.751079 -302.405032) (xy 166.699105 -302.405032) (xy 166.64777 -302.396902)
			(xy 166.59834 -302.380841) (xy 166.55203 -302.357245) (xy 166.509982 -302.326695) (xy 166.473231 -302.289944)
			(xy 166.442681 -302.247896) (xy 166.419085 -302.201586) (xy 166.403024 -302.152156) (xy 166.394894 -302.100821)
			(xy 166.105076 -302.100821) (xy 166.096946 -302.152156) (xy 166.080885 -302.201586) (xy 166.057289 -302.247896)
			(xy 166.026739 -302.289944) (xy 165.989988 -302.326695) (xy 165.94794 -302.357245) (xy 165.90163 -302.380841)
			(xy 165.8522 -302.396902) (xy 165.800865 -302.405032) (xy 165.748891 -302.405032) (xy 165.697556 -302.396902)
			(xy 165.648126 -302.380841) (xy 165.601816 -302.357245) (xy 165.559768 -302.326695) (xy 165.523017 -302.289944)
			(xy 165.492467 -302.247896) (xy 165.468871 -302.201586) (xy 165.45281 -302.152156) (xy 165.44468 -302.100821)
			(xy 162.31776 -302.100821) (xy 162.320478 -302.10379) (xy 162.557206 -302.340518) (xy 162.557714 -302.341026)
			(xy 162.565092 -302.347617) (xy 162.583391 -302.355086) (xy 162.593274 -302.355504) (xy 165.172644 -302.355504)
			(xy 165.182711 -302.355935) (xy 165.201303 -302.363661) (xy 165.208712 -302.37049) (xy 165.491414 -302.653192)
			(xy 165.498271 -302.660586) (xy 165.506022 -302.679185) (xy 165.5064 -302.68926) (xy 165.5064 -302.695102)
			(xy 165.521132 -302.719232) (xy 165.560248 -302.739552) (xy 165.567973 -302.743235) (xy 165.584893 -302.745738)
			(xy 165.60169 -302.742513) (xy 165.60927 -302.738536) (xy 165.63461 -302.724564) (xy 165.688969 -302.704739)
			(xy 165.745947 -302.694672) (xy 165.774878 -302.694086) (xy 165.800869 -302.694567) (xy 165.852211 -302.702696)
			(xy 165.901649 -302.718757) (xy 165.947966 -302.742354) (xy 165.990022 -302.772906) (xy 166.02678 -302.809661)
			(xy 166.057335 -302.851715) (xy 166.080935 -302.89803) (xy 166.096999 -302.947468) (xy 166.105131 -302.998809)
			(xy 166.105131 -303.050781) (xy 166.394894 -303.050781) (xy 166.394894 -302.998807) (xy 166.403024 -302.947472)
			(xy 166.419085 -302.898042) (xy 166.442681 -302.851732) (xy 166.473231 -302.809684) (xy 166.509982 -302.772933)
			(xy 166.55203 -302.742383) (xy 166.59834 -302.718787) (xy 166.64777 -302.702726) (xy 166.699105 -302.694596)
			(xy 166.751079 -302.694596) (xy 166.802414 -302.702726) (xy 166.851844 -302.718787) (xy 166.898154 -302.742383)
			(xy 166.940202 -302.772933) (xy 166.976953 -302.809684) (xy 167.007503 -302.851732) (xy 167.031099 -302.898042)
			(xy 167.04716 -302.947472) (xy 167.05529 -302.998807) (xy 167.0558 -303.024794) (xy 167.05529 -303.050781)
			(xy 167.344854 -303.050781) (xy 167.344854 -302.998807) (xy 167.352984 -302.947472) (xy 167.369045 -302.898042)
			(xy 167.392641 -302.851732) (xy 167.423191 -302.809684) (xy 167.459942 -302.772933) (xy 167.50199 -302.742383)
			(xy 167.5483 -302.718787) (xy 167.59773 -302.702726) (xy 167.649065 -302.694596) (xy 167.701039 -302.694596)
			(xy 167.752374 -302.702726) (xy 167.801804 -302.718787) (xy 167.848114 -302.742383) (xy 167.890162 -302.772933)
			(xy 167.926913 -302.809684) (xy 167.957463 -302.851732) (xy 167.981059 -302.898042) (xy 167.99712 -302.947472)
			(xy 168.00525 -302.998807) (xy 168.00576 -303.024794) (xy 168.00525 -303.050781) (xy 168.294814 -303.050781)
			(xy 168.294814 -302.998807) (xy 168.302944 -302.947472) (xy 168.319005 -302.898042) (xy 168.342601 -302.851732)
			(xy 168.373151 -302.809684) (xy 168.409902 -302.772933) (xy 168.45195 -302.742383) (xy 168.49826 -302.718787)
			(xy 168.54769 -302.702726) (xy 168.599025 -302.694596) (xy 168.650999 -302.694596) (xy 168.702334 -302.702726)
			(xy 168.751764 -302.718787) (xy 168.798074 -302.742383) (xy 168.840122 -302.772933) (xy 168.876873 -302.809684)
			(xy 168.907423 -302.851732) (xy 168.931019 -302.898042) (xy 168.94708 -302.947472) (xy 168.95521 -302.998807)
			(xy 168.95572 -303.024794) (xy 168.95521 -303.050781) (xy 169.244774 -303.050781) (xy 169.244774 -302.998807)
			(xy 169.252904 -302.947472) (xy 169.268965 -302.898042) (xy 169.292561 -302.851732) (xy 169.323111 -302.809684)
			(xy 169.359862 -302.772933) (xy 169.40191 -302.742383) (xy 169.44822 -302.718787) (xy 169.49765 -302.702726)
			(xy 169.548985 -302.694596) (xy 169.600959 -302.694596) (xy 169.652294 -302.702726) (xy 169.701724 -302.718787)
			(xy 169.748034 -302.742383) (xy 169.790082 -302.772933) (xy 169.826833 -302.809684) (xy 169.857383 -302.851732)
			(xy 169.880979 -302.898042) (xy 169.89704 -302.947472) (xy 169.90517 -302.998807) (xy 169.90568 -303.024794)
			(xy 169.90517 -303.050781) (xy 170.194734 -303.050781) (xy 170.194734 -302.998807) (xy 170.202864 -302.947472)
			(xy 170.218925 -302.898042) (xy 170.242521 -302.851732) (xy 170.273071 -302.809684) (xy 170.309822 -302.772933)
			(xy 170.35187 -302.742383) (xy 170.39818 -302.718787) (xy 170.44761 -302.702726) (xy 170.498945 -302.694596)
			(xy 170.550919 -302.694596) (xy 170.602254 -302.702726) (xy 170.651684 -302.718787) (xy 170.697994 -302.742383)
			(xy 170.740042 -302.772933) (xy 170.776793 -302.809684) (xy 170.807343 -302.851732) (xy 170.830939 -302.898042)
			(xy 170.847 -302.947472) (xy 170.85513 -302.998807) (xy 170.85564 -303.024794) (xy 170.85513 -303.050781)
			(xy 171.144694 -303.050781) (xy 171.144694 -302.998807) (xy 171.152824 -302.947472) (xy 171.168885 -302.898042)
			(xy 171.192481 -302.851732) (xy 171.223031 -302.809684) (xy 171.259782 -302.772933) (xy 171.30183 -302.742383)
			(xy 171.34814 -302.718787) (xy 171.39757 -302.702726) (xy 171.448905 -302.694596) (xy 171.500879 -302.694596)
			(xy 171.552214 -302.702726) (xy 171.601644 -302.718787) (xy 171.647954 -302.742383) (xy 171.690002 -302.772933)
			(xy 171.726753 -302.809684) (xy 171.757303 -302.851732) (xy 171.780899 -302.898042) (xy 171.79696 -302.947472)
			(xy 171.80509 -302.998807) (xy 171.8056 -303.024794) (xy 171.80509 -303.050781) (xy 172.094654 -303.050781)
			(xy 172.094654 -302.998807) (xy 172.102784 -302.947472) (xy 172.118845 -302.898042) (xy 172.142441 -302.851732)
			(xy 172.172991 -302.809684) (xy 172.209742 -302.772933) (xy 172.25179 -302.742383) (xy 172.2981 -302.718787)
			(xy 172.34753 -302.702726) (xy 172.398865 -302.694596) (xy 172.450839 -302.694596) (xy 172.502174 -302.702726)
			(xy 172.551604 -302.718787) (xy 172.597914 -302.742383) (xy 172.639962 -302.772933) (xy 172.676713 -302.809684)
			(xy 172.707263 -302.851732) (xy 172.730859 -302.898042) (xy 172.74692 -302.947472) (xy 172.75505 -302.998807)
			(xy 172.75556 -303.024794) (xy 172.75505 -303.050781) (xy 173.044868 -303.050781) (xy 173.044868 -302.998807)
			(xy 173.052998 -302.947472) (xy 173.069059 -302.898042) (xy 173.092655 -302.851732) (xy 173.123205 -302.809684)
			(xy 173.159956 -302.772933) (xy 173.202004 -302.742383) (xy 173.248314 -302.718787) (xy 173.297744 -302.702726)
			(xy 173.349079 -302.694596) (xy 173.401053 -302.694596) (xy 173.452388 -302.702726) (xy 173.501818 -302.718787)
			(xy 173.548128 -302.742383) (xy 173.590176 -302.772933) (xy 173.626927 -302.809684) (xy 173.657477 -302.851732)
			(xy 173.681073 -302.898042) (xy 173.697134 -302.947472) (xy 173.705264 -302.998807) (xy 173.705774 -303.024794)
			(xy 173.705264 -303.050781) (xy 173.994828 -303.050781) (xy 173.994828 -302.998807) (xy 174.002958 -302.947472)
			(xy 174.019019 -302.898042) (xy 174.042615 -302.851732) (xy 174.073165 -302.809684) (xy 174.109916 -302.772933)
			(xy 174.151964 -302.742383) (xy 174.198274 -302.718787) (xy 174.247704 -302.702726) (xy 174.299039 -302.694596)
			(xy 174.351013 -302.694596) (xy 174.402348 -302.702726) (xy 174.451778 -302.718787) (xy 174.498088 -302.742383)
			(xy 174.540136 -302.772933) (xy 174.576887 -302.809684) (xy 174.607437 -302.851732) (xy 174.631033 -302.898042)
			(xy 174.647094 -302.947472) (xy 174.655224 -302.998807) (xy 174.655734 -303.024794) (xy 174.655224 -303.050781)
			(xy 175.894748 -303.050781) (xy 175.894748 -302.998807) (xy 175.902878 -302.947472) (xy 175.918939 -302.898042)
			(xy 175.942535 -302.851732) (xy 175.973085 -302.809684) (xy 176.009836 -302.772933) (xy 176.051884 -302.742383)
			(xy 176.098194 -302.718787) (xy 176.147624 -302.702726) (xy 176.198959 -302.694596) (xy 176.250933 -302.694596)
			(xy 176.302268 -302.702726) (xy 176.351698 -302.718787) (xy 176.398008 -302.742383) (xy 176.440056 -302.772933)
			(xy 176.476807 -302.809684) (xy 176.507357 -302.851732) (xy 176.530953 -302.898042) (xy 176.547014 -302.947472)
			(xy 176.555144 -302.998807) (xy 176.555654 -303.024794) (xy 176.555144 -303.050781) (xy 176.844708 -303.050781)
			(xy 176.844708 -302.998807) (xy 176.852838 -302.947472) (xy 176.868899 -302.898042) (xy 176.892495 -302.851732)
			(xy 176.923045 -302.809684) (xy 176.959796 -302.772933) (xy 177.001844 -302.742383) (xy 177.048154 -302.718787)
			(xy 177.097584 -302.702726) (xy 177.148919 -302.694596) (xy 177.200893 -302.694596) (xy 177.252228 -302.702726)
			(xy 177.301658 -302.718787) (xy 177.347968 -302.742383) (xy 177.390016 -302.772933) (xy 177.426767 -302.809684)
			(xy 177.457317 -302.851732) (xy 177.480913 -302.898042) (xy 177.496974 -302.947472) (xy 177.505104 -302.998807)
			(xy 177.505614 -303.024794) (xy 177.505104 -303.050781) (xy 177.794668 -303.050781) (xy 177.794668 -302.998807)
			(xy 177.802798 -302.947472) (xy 177.818859 -302.898042) (xy 177.842455 -302.851732) (xy 177.873005 -302.809684)
			(xy 177.909756 -302.772933) (xy 177.951804 -302.742383) (xy 177.998114 -302.718787) (xy 178.047544 -302.702726)
			(xy 178.098879 -302.694596) (xy 178.150853 -302.694596) (xy 178.202188 -302.702726) (xy 178.251618 -302.718787)
			(xy 178.297928 -302.742383) (xy 178.339976 -302.772933) (xy 178.376727 -302.809684) (xy 178.407277 -302.851732)
			(xy 178.430873 -302.898042) (xy 178.446934 -302.947472) (xy 178.455064 -302.998807) (xy 178.455574 -303.024794)
			(xy 178.455064 -303.050781) (xy 178.744882 -303.050781) (xy 178.744882 -302.998807) (xy 178.753012 -302.947472)
			(xy 178.769073 -302.898042) (xy 178.792669 -302.851732) (xy 178.823219 -302.809684) (xy 178.85997 -302.772933)
			(xy 178.902018 -302.742383) (xy 178.948328 -302.718787) (xy 178.997758 -302.702726) (xy 179.049093 -302.694596)
			(xy 179.101067 -302.694596) (xy 179.152402 -302.702726) (xy 179.201832 -302.718787) (xy 179.248142 -302.742383)
			(xy 179.29019 -302.772933) (xy 179.326941 -302.809684) (xy 179.357491 -302.851732) (xy 179.381087 -302.898042)
			(xy 179.397148 -302.947472) (xy 179.405278 -302.998807) (xy 179.405788 -303.024794) (xy 179.405278 -303.050781)
			(xy 179.694842 -303.050781) (xy 179.694842 -302.998807) (xy 179.702972 -302.947472) (xy 179.719033 -302.898042)
			(xy 179.742629 -302.851732) (xy 179.773179 -302.809684) (xy 179.80993 -302.772933) (xy 179.851978 -302.742383)
			(xy 179.898288 -302.718787) (xy 179.947718 -302.702726) (xy 179.999053 -302.694596) (xy 180.051027 -302.694596)
			(xy 180.102362 -302.702726) (xy 180.151792 -302.718787) (xy 180.198102 -302.742383) (xy 180.24015 -302.772933)
			(xy 180.276901 -302.809684) (xy 180.307451 -302.851732) (xy 180.331047 -302.898042) (xy 180.347108 -302.947472)
			(xy 180.355238 -302.998807) (xy 180.355748 -303.024794) (xy 180.355238 -303.050781) (xy 180.644802 -303.050781)
			(xy 180.644802 -302.998807) (xy 180.652932 -302.947472) (xy 180.668993 -302.898042) (xy 180.692589 -302.851732)
			(xy 180.723139 -302.809684) (xy 180.75989 -302.772933) (xy 180.801938 -302.742383) (xy 180.848248 -302.718787)
			(xy 180.897678 -302.702726) (xy 180.949013 -302.694596) (xy 181.000987 -302.694596) (xy 181.052322 -302.702726)
			(xy 181.101752 -302.718787) (xy 181.148062 -302.742383) (xy 181.19011 -302.772933) (xy 181.226861 -302.809684)
			(xy 181.257411 -302.851732) (xy 181.281007 -302.898042) (xy 181.297068 -302.947472) (xy 181.305198 -302.998807)
			(xy 181.305708 -303.024794) (xy 181.305198 -303.050781) (xy 181.594762 -303.050781) (xy 181.594762 -302.998807)
			(xy 181.602892 -302.947472) (xy 181.618953 -302.898042) (xy 181.642549 -302.851732) (xy 181.673099 -302.809684)
			(xy 181.70985 -302.772933) (xy 181.751898 -302.742383) (xy 181.798208 -302.718787) (xy 181.847638 -302.702726)
			(xy 181.898973 -302.694596) (xy 181.950947 -302.694596) (xy 182.002282 -302.702726) (xy 182.051712 -302.718787)
			(xy 182.098022 -302.742383) (xy 182.14007 -302.772933) (xy 182.176821 -302.809684) (xy 182.207371 -302.851732)
			(xy 182.230967 -302.898042) (xy 182.247028 -302.947472) (xy 182.255158 -302.998807) (xy 182.255668 -303.024794)
			(xy 182.255158 -303.050781) (xy 182.544722 -303.050781) (xy 182.544722 -302.998807) (xy 182.552852 -302.947472)
			(xy 182.568913 -302.898042) (xy 182.592509 -302.851732) (xy 182.623059 -302.809684) (xy 182.65981 -302.772933)
			(xy 182.701858 -302.742383) (xy 182.748168 -302.718787) (xy 182.797598 -302.702726) (xy 182.848933 -302.694596)
			(xy 182.900907 -302.694596) (xy 182.952242 -302.702726) (xy 183.001672 -302.718787) (xy 183.047982 -302.742383)
			(xy 183.09003 -302.772933) (xy 183.126781 -302.809684) (xy 183.157331 -302.851732) (xy 183.180927 -302.898042)
			(xy 183.196988 -302.947472) (xy 183.205118 -302.998807) (xy 183.205628 -303.024794) (xy 183.205118 -303.050781)
			(xy 183.494682 -303.050781) (xy 183.494682 -302.998807) (xy 183.502812 -302.947472) (xy 183.518873 -302.898042)
			(xy 183.542469 -302.851732) (xy 183.573019 -302.809684) (xy 183.60977 -302.772933) (xy 183.651818 -302.742383)
			(xy 183.698128 -302.718787) (xy 183.747558 -302.702726) (xy 183.798893 -302.694596) (xy 183.850867 -302.694596)
			(xy 183.902202 -302.702726) (xy 183.951632 -302.718787) (xy 183.997942 -302.742383) (xy 184.03999 -302.772933)
			(xy 184.076741 -302.809684) (xy 184.107291 -302.851732) (xy 184.130887 -302.898042) (xy 184.146948 -302.947472)
			(xy 184.155078 -302.998807) (xy 184.155588 -303.024794) (xy 184.155078 -303.050781) (xy 184.444642 -303.050781)
			(xy 184.444642 -302.998807) (xy 184.452772 -302.947472) (xy 184.468833 -302.898042) (xy 184.492429 -302.851732)
			(xy 184.522979 -302.809684) (xy 184.55973 -302.772933) (xy 184.601778 -302.742383) (xy 184.648088 -302.718787)
			(xy 184.697518 -302.702726) (xy 184.748853 -302.694596) (xy 184.800827 -302.694596) (xy 184.852162 -302.702726)
			(xy 184.901592 -302.718787) (xy 184.947902 -302.742383) (xy 184.98995 -302.772933) (xy 185.026701 -302.809684)
			(xy 185.057251 -302.851732) (xy 185.080847 -302.898042) (xy 185.096908 -302.947472) (xy 185.105038 -302.998807)
			(xy 185.105548 -303.024794) (xy 185.105038 -303.050781) (xy 185.096908 -303.102116) (xy 185.080847 -303.151546)
			(xy 185.057251 -303.197856) (xy 185.026701 -303.239904) (xy 184.98995 -303.276655) (xy 184.947902 -303.307205)
			(xy 184.901592 -303.330801) (xy 184.852162 -303.346862) (xy 184.800827 -303.354992) (xy 184.748853 -303.354992)
			(xy 184.697518 -303.346862) (xy 184.648088 -303.330801) (xy 184.601778 -303.307205) (xy 184.55973 -303.276655)
			(xy 184.522979 -303.239904) (xy 184.492429 -303.197856) (xy 184.468833 -303.151546) (xy 184.452772 -303.102116)
			(xy 184.444642 -303.050781) (xy 184.155078 -303.050781) (xy 184.146948 -303.102116) (xy 184.130887 -303.151546)
			(xy 184.107291 -303.197856) (xy 184.076741 -303.239904) (xy 184.03999 -303.276655) (xy 183.997942 -303.307205)
			(xy 183.951632 -303.330801) (xy 183.902202 -303.346862) (xy 183.850867 -303.354992) (xy 183.798893 -303.354992)
			(xy 183.747558 -303.346862) (xy 183.698128 -303.330801) (xy 183.651818 -303.307205) (xy 183.60977 -303.276655)
			(xy 183.573019 -303.239904) (xy 183.542469 -303.197856) (xy 183.518873 -303.151546) (xy 183.502812 -303.102116)
			(xy 183.494682 -303.050781) (xy 183.205118 -303.050781) (xy 183.196988 -303.102116) (xy 183.180927 -303.151546)
			(xy 183.157331 -303.197856) (xy 183.126781 -303.239904) (xy 183.09003 -303.276655) (xy 183.047982 -303.307205)
			(xy 183.001672 -303.330801) (xy 182.952242 -303.346862) (xy 182.900907 -303.354992) (xy 182.848933 -303.354992)
			(xy 182.797598 -303.346862) (xy 182.748168 -303.330801) (xy 182.701858 -303.307205) (xy 182.65981 -303.276655)
			(xy 182.623059 -303.239904) (xy 182.592509 -303.197856) (xy 182.568913 -303.151546) (xy 182.552852 -303.102116)
			(xy 182.544722 -303.050781) (xy 182.255158 -303.050781) (xy 182.247028 -303.102116) (xy 182.230967 -303.151546)
			(xy 182.207371 -303.197856) (xy 182.176821 -303.239904) (xy 182.14007 -303.276655) (xy 182.098022 -303.307205)
			(xy 182.051712 -303.330801) (xy 182.002282 -303.346862) (xy 181.950947 -303.354992) (xy 181.898973 -303.354992)
			(xy 181.847638 -303.346862) (xy 181.798208 -303.330801) (xy 181.751898 -303.307205) (xy 181.70985 -303.276655)
			(xy 181.673099 -303.239904) (xy 181.642549 -303.197856) (xy 181.618953 -303.151546) (xy 181.602892 -303.102116)
			(xy 181.594762 -303.050781) (xy 181.305198 -303.050781) (xy 181.297068 -303.102116) (xy 181.281007 -303.151546)
			(xy 181.257411 -303.197856) (xy 181.226861 -303.239904) (xy 181.19011 -303.276655) (xy 181.148062 -303.307205)
			(xy 181.101752 -303.330801) (xy 181.052322 -303.346862) (xy 181.000987 -303.354992) (xy 180.949013 -303.354992)
			(xy 180.897678 -303.346862) (xy 180.848248 -303.330801) (xy 180.801938 -303.307205) (xy 180.75989 -303.276655)
			(xy 180.723139 -303.239904) (xy 180.692589 -303.197856) (xy 180.668993 -303.151546) (xy 180.652932 -303.102116)
			(xy 180.644802 -303.050781) (xy 180.355238 -303.050781) (xy 180.347108 -303.102116) (xy 180.331047 -303.151546)
			(xy 180.307451 -303.197856) (xy 180.276901 -303.239904) (xy 180.24015 -303.276655) (xy 180.198102 -303.307205)
			(xy 180.151792 -303.330801) (xy 180.102362 -303.346862) (xy 180.051027 -303.354992) (xy 179.999053 -303.354992)
			(xy 179.947718 -303.346862) (xy 179.898288 -303.330801) (xy 179.851978 -303.307205) (xy 179.80993 -303.276655)
			(xy 179.773179 -303.239904) (xy 179.742629 -303.197856) (xy 179.719033 -303.151546) (xy 179.702972 -303.102116)
			(xy 179.694842 -303.050781) (xy 179.405278 -303.050781) (xy 179.397148 -303.102116) (xy 179.381087 -303.151546)
			(xy 179.357491 -303.197856) (xy 179.326941 -303.239904) (xy 179.29019 -303.276655) (xy 179.248142 -303.307205)
			(xy 179.201832 -303.330801) (xy 179.152402 -303.346862) (xy 179.101067 -303.354992) (xy 179.049093 -303.354992)
			(xy 178.997758 -303.346862) (xy 178.948328 -303.330801) (xy 178.902018 -303.307205) (xy 178.85997 -303.276655)
			(xy 178.823219 -303.239904) (xy 178.792669 -303.197856) (xy 178.769073 -303.151546) (xy 178.753012 -303.102116)
			(xy 178.744882 -303.050781) (xy 178.455064 -303.050781) (xy 178.446934 -303.102116) (xy 178.430873 -303.151546)
			(xy 178.407277 -303.197856) (xy 178.376727 -303.239904) (xy 178.339976 -303.276655) (xy 178.297928 -303.307205)
			(xy 178.251618 -303.330801) (xy 178.202188 -303.346862) (xy 178.150853 -303.354992) (xy 178.098879 -303.354992)
			(xy 178.047544 -303.346862) (xy 177.998114 -303.330801) (xy 177.951804 -303.307205) (xy 177.909756 -303.276655)
			(xy 177.873005 -303.239904) (xy 177.842455 -303.197856) (xy 177.818859 -303.151546) (xy 177.802798 -303.102116)
			(xy 177.794668 -303.050781) (xy 177.505104 -303.050781) (xy 177.496974 -303.102116) (xy 177.480913 -303.151546)
			(xy 177.457317 -303.197856) (xy 177.426767 -303.239904) (xy 177.390016 -303.276655) (xy 177.347968 -303.307205)
			(xy 177.301658 -303.330801) (xy 177.252228 -303.346862) (xy 177.200893 -303.354992) (xy 177.148919 -303.354992)
			(xy 177.097584 -303.346862) (xy 177.048154 -303.330801) (xy 177.001844 -303.307205) (xy 176.959796 -303.276655)
			(xy 176.923045 -303.239904) (xy 176.892495 -303.197856) (xy 176.868899 -303.151546) (xy 176.852838 -303.102116)
			(xy 176.844708 -303.050781) (xy 176.555144 -303.050781) (xy 176.547014 -303.102116) (xy 176.530953 -303.151546)
			(xy 176.507357 -303.197856) (xy 176.476807 -303.239904) (xy 176.440056 -303.276655) (xy 176.398008 -303.307205)
			(xy 176.351698 -303.330801) (xy 176.302268 -303.346862) (xy 176.250933 -303.354992) (xy 176.198959 -303.354992)
			(xy 176.147624 -303.346862) (xy 176.098194 -303.330801) (xy 176.051884 -303.307205) (xy 176.009836 -303.276655)
			(xy 175.973085 -303.239904) (xy 175.942535 -303.197856) (xy 175.918939 -303.151546) (xy 175.902878 -303.102116)
			(xy 175.894748 -303.050781) (xy 174.655224 -303.050781) (xy 174.647094 -303.102116) (xy 174.631033 -303.151546)
			(xy 174.607437 -303.197856) (xy 174.576887 -303.239904) (xy 174.540136 -303.276655) (xy 174.498088 -303.307205)
			(xy 174.451778 -303.330801) (xy 174.402348 -303.346862) (xy 174.351013 -303.354992) (xy 174.299039 -303.354992)
			(xy 174.247704 -303.346862) (xy 174.198274 -303.330801) (xy 174.151964 -303.307205) (xy 174.109916 -303.276655)
			(xy 174.073165 -303.239904) (xy 174.042615 -303.197856) (xy 174.019019 -303.151546) (xy 174.002958 -303.102116)
			(xy 173.994828 -303.050781) (xy 173.705264 -303.050781) (xy 173.697134 -303.102116) (xy 173.681073 -303.151546)
			(xy 173.657477 -303.197856) (xy 173.626927 -303.239904) (xy 173.590176 -303.276655) (xy 173.548128 -303.307205)
			(xy 173.501818 -303.330801) (xy 173.452388 -303.346862) (xy 173.401053 -303.354992) (xy 173.349079 -303.354992)
			(xy 173.297744 -303.346862) (xy 173.248314 -303.330801) (xy 173.202004 -303.307205) (xy 173.159956 -303.276655)
			(xy 173.123205 -303.239904) (xy 173.092655 -303.197856) (xy 173.069059 -303.151546) (xy 173.052998 -303.102116)
			(xy 173.044868 -303.050781) (xy 172.75505 -303.050781) (xy 172.74692 -303.102116) (xy 172.730859 -303.151546)
			(xy 172.707263 -303.197856) (xy 172.676713 -303.239904) (xy 172.639962 -303.276655) (xy 172.597914 -303.307205)
			(xy 172.551604 -303.330801) (xy 172.502174 -303.346862) (xy 172.450839 -303.354992) (xy 172.398865 -303.354992)
			(xy 172.34753 -303.346862) (xy 172.2981 -303.330801) (xy 172.25179 -303.307205) (xy 172.209742 -303.276655)
			(xy 172.172991 -303.239904) (xy 172.142441 -303.197856) (xy 172.118845 -303.151546) (xy 172.102784 -303.102116)
			(xy 172.094654 -303.050781) (xy 171.80509 -303.050781) (xy 171.79696 -303.102116) (xy 171.780899 -303.151546)
			(xy 171.757303 -303.197856) (xy 171.726753 -303.239904) (xy 171.690002 -303.276655) (xy 171.647954 -303.307205)
			(xy 171.601644 -303.330801) (xy 171.552214 -303.346862) (xy 171.500879 -303.354992) (xy 171.448905 -303.354992)
			(xy 171.39757 -303.346862) (xy 171.34814 -303.330801) (xy 171.30183 -303.307205) (xy 171.259782 -303.276655)
			(xy 171.223031 -303.239904) (xy 171.192481 -303.197856) (xy 171.168885 -303.151546) (xy 171.152824 -303.102116)
			(xy 171.144694 -303.050781) (xy 170.85513 -303.050781) (xy 170.847 -303.102116) (xy 170.830939 -303.151546)
			(xy 170.807343 -303.197856) (xy 170.776793 -303.239904) (xy 170.740042 -303.276655) (xy 170.697994 -303.307205)
			(xy 170.651684 -303.330801) (xy 170.602254 -303.346862) (xy 170.550919 -303.354992) (xy 170.498945 -303.354992)
			(xy 170.44761 -303.346862) (xy 170.39818 -303.330801) (xy 170.35187 -303.307205) (xy 170.309822 -303.276655)
			(xy 170.273071 -303.239904) (xy 170.242521 -303.197856) (xy 170.218925 -303.151546) (xy 170.202864 -303.102116)
			(xy 170.194734 -303.050781) (xy 169.90517 -303.050781) (xy 169.89704 -303.102116) (xy 169.880979 -303.151546)
			(xy 169.857383 -303.197856) (xy 169.826833 -303.239904) (xy 169.790082 -303.276655) (xy 169.748034 -303.307205)
			(xy 169.701724 -303.330801) (xy 169.652294 -303.346862) (xy 169.600959 -303.354992) (xy 169.548985 -303.354992)
			(xy 169.49765 -303.346862) (xy 169.44822 -303.330801) (xy 169.40191 -303.307205) (xy 169.359862 -303.276655)
			(xy 169.323111 -303.239904) (xy 169.292561 -303.197856) (xy 169.268965 -303.151546) (xy 169.252904 -303.102116)
			(xy 169.244774 -303.050781) (xy 168.95521 -303.050781) (xy 168.94708 -303.102116) (xy 168.931019 -303.151546)
			(xy 168.907423 -303.197856) (xy 168.876873 -303.239904) (xy 168.840122 -303.276655) (xy 168.798074 -303.307205)
			(xy 168.751764 -303.330801) (xy 168.702334 -303.346862) (xy 168.650999 -303.354992) (xy 168.599025 -303.354992)
			(xy 168.54769 -303.346862) (xy 168.49826 -303.330801) (xy 168.45195 -303.307205) (xy 168.409902 -303.276655)
			(xy 168.373151 -303.239904) (xy 168.342601 -303.197856) (xy 168.319005 -303.151546) (xy 168.302944 -303.102116)
			(xy 168.294814 -303.050781) (xy 168.00525 -303.050781) (xy 167.99712 -303.102116) (xy 167.981059 -303.151546)
			(xy 167.957463 -303.197856) (xy 167.926913 -303.239904) (xy 167.890162 -303.276655) (xy 167.848114 -303.307205)
			(xy 167.801804 -303.330801) (xy 167.752374 -303.346862) (xy 167.701039 -303.354992) (xy 167.649065 -303.354992)
			(xy 167.59773 -303.346862) (xy 167.5483 -303.330801) (xy 167.50199 -303.307205) (xy 167.459942 -303.276655)
			(xy 167.423191 -303.239904) (xy 167.392641 -303.197856) (xy 167.369045 -303.151546) (xy 167.352984 -303.102116)
			(xy 167.344854 -303.050781) (xy 167.05529 -303.050781) (xy 167.04716 -303.102116) (xy 167.031099 -303.151546)
			(xy 167.007503 -303.197856) (xy 166.976953 -303.239904) (xy 166.940202 -303.276655) (xy 166.898154 -303.307205)
			(xy 166.851844 -303.330801) (xy 166.802414 -303.346862) (xy 166.751079 -303.354992) (xy 166.699105 -303.354992)
			(xy 166.64777 -303.346862) (xy 166.59834 -303.330801) (xy 166.55203 -303.307205) (xy 166.509982 -303.276655)
			(xy 166.473231 -303.239904) (xy 166.442681 -303.197856) (xy 166.419085 -303.151546) (xy 166.403024 -303.102116)
			(xy 166.394894 -303.050781) (xy 166.105131 -303.050781) (xy 166.105131 -303.050791) (xy 166.096999 -303.102132)
			(xy 166.080935 -303.15157) (xy 166.057335 -303.197885) (xy 166.02678 -303.239939) (xy 165.990022 -303.276694)
			(xy 165.947966 -303.307246) (xy 165.901649 -303.330843) (xy 165.852211 -303.346904) (xy 165.800869 -303.355033)
			(xy 165.774878 -303.355502) (xy 165.753008 -303.355149) (xy 165.70965 -303.349385) (xy 165.667429 -303.337961)
			(xy 165.647116 -303.329848) (xy 165.635178 -303.324768) (xy 165.610286 -303.327308) (xy 165.529006 -303.38141)
			(xy 165.518953 -303.388931) (xy 165.507113 -303.411038) (xy 165.5064 -303.423574) (xy 165.5064 -303.575974)
			(xy 165.507036 -303.588534) (xy 165.518884 -303.61068) (xy 165.529006 -303.618138) (xy 165.610286 -303.67224)
			(xy 165.635178 -303.67478) (xy 165.647116 -303.6697) (xy 165.667426 -303.661581) (xy 165.709648 -303.650155)
			(xy 165.753008 -303.64439) (xy 165.774878 -303.644046) (xy 165.800868 -303.644554) (xy 165.852207 -303.652681)
			(xy 165.901644 -303.66874) (xy 165.94796 -303.692334) (xy 165.990015 -303.722882) (xy 166.026773 -303.759633)
			(xy 166.057331 -303.801682) (xy 166.080934 -303.847993) (xy 166.097003 -303.897426) (xy 166.105141 -303.948764)
			(xy 166.105586 -303.974754) (xy 166.105032 -304.002372) (xy 166.095851 -304.056839) (xy 166.077737 -304.109021)
			(xy 166.064946 -304.133504) (xy 166.058342 -304.145442) (xy 166.05885 -304.172112) (xy 166.110412 -304.25898)
			(xy 166.115211 -304.266356) (xy 166.128764 -304.277557) (xy 166.145309 -304.283509) (xy 166.1541 -304.283872)
		)
		(stroke
			(width 0)
			(type solid)
		)
		(fill yes)
		(layer "In9.Cu")
		(net "P1V8_PEX")
	)
	(gr_poly
		(pts
			(xy 398.545812 -304.283872) (xy 398.554601 -304.283501) (xy 398.571141 -304.277547) (xy 398.584689 -304.266346)
			(xy 398.5895 -304.25898) (xy 398.641062 -304.172112) (xy 398.64157 -304.145442) (xy 398.634966 -304.133504)
			(xy 398.622187 -304.109015) (xy 398.604074 -304.056835) (xy 398.594885 -304.002371) (xy 398.594326 -303.974754)
			(xy 398.594836 -303.948767) (xy 398.602966 -303.897432) (xy 398.619027 -303.848002) (xy 398.642623 -303.801692)
			(xy 398.673173 -303.759644) (xy 398.709924 -303.722893) (xy 398.751972 -303.692343) (xy 398.798282 -303.668747)
			(xy 398.847712 -303.652686) (xy 398.899047 -303.644556) (xy 398.951021 -303.644556) (xy 399.002356 -303.652686)
			(xy 399.051786 -303.668747) (xy 399.098096 -303.692343) (xy 399.140144 -303.722893) (xy 399.176895 -303.759644)
			(xy 399.207445 -303.801692) (xy 399.231041 -303.848002) (xy 399.247102 -303.897432) (xy 399.255232 -303.948767)
			(xy 399.255742 -303.974754) (xy 399.255188 -304.002372) (xy 399.246009 -304.05684) (xy 399.227898 -304.109023)
			(xy 399.215102 -304.133504) (xy 399.208498 -304.145442) (xy 399.209006 -304.172112) (xy 399.260568 -304.25898)
			(xy 399.265364 -304.266361) (xy 399.278916 -304.277574) (xy 399.295462 -304.283539) (xy 399.304256 -304.283872)
			(xy 399.495772 -304.283872) (xy 399.504565 -304.283507) (xy 399.521115 -304.277562) (xy 399.534674 -304.266364)
			(xy 399.53946 -304.25898) (xy 399.591022 -304.172112) (xy 399.59153 -304.145442) (xy 399.584926 -304.133504)
			(xy 399.572148 -304.109015) (xy 399.554037 -304.056835) (xy 399.544849 -304.002371) (xy 399.544286 -303.974754)
			(xy 399.544796 -303.948767) (xy 399.552926 -303.897432) (xy 399.568987 -303.848002) (xy 399.592583 -303.801692)
			(xy 399.623133 -303.759644) (xy 399.659884 -303.722893) (xy 399.701932 -303.692343) (xy 399.748242 -303.668747)
			(xy 399.797672 -303.652686) (xy 399.849007 -303.644556) (xy 399.900981 -303.644556) (xy 399.952316 -303.652686)
			(xy 400.001746 -303.668747) (xy 400.048056 -303.692343) (xy 400.090104 -303.722893) (xy 400.126855 -303.759644)
			(xy 400.157405 -303.801692) (xy 400.181001 -303.848002) (xy 400.197062 -303.897432) (xy 400.205192 -303.948767)
			(xy 400.205702 -303.974754) (xy 400.205148 -304.002372) (xy 400.195968 -304.05684) (xy 400.177855 -304.109021)
			(xy 400.165062 -304.133504) (xy 400.158458 -304.145442) (xy 400.158966 -304.172112) (xy 400.210528 -304.25898)
			(xy 400.215327 -304.266354) (xy 400.228881 -304.277551) (xy 400.245426 -304.283498) (xy 400.254216 -304.283872)
			(xy 400.445732 -304.283872) (xy 400.45452 -304.283498) (xy 400.471054 -304.277539) (xy 400.484597 -304.266337)
			(xy 400.48942 -304.25898) (xy 400.540982 -304.172112) (xy 400.54149 -304.145442) (xy 400.534886 -304.133504)
			(xy 400.522106 -304.109015) (xy 400.503992 -304.056836) (xy 400.494802 -304.002371) (xy 400.494246 -303.974754)
			(xy 400.494756 -303.948767) (xy 400.502886 -303.897432) (xy 400.518947 -303.848002) (xy 400.542543 -303.801692)
			(xy 400.573093 -303.759644) (xy 400.609844 -303.722893) (xy 400.651892 -303.692343) (xy 400.698202 -303.668747)
			(xy 400.747632 -303.652686) (xy 400.798967 -303.644556) (xy 400.850941 -303.644556) (xy 400.902276 -303.652686)
			(xy 400.951706 -303.668747) (xy 400.998016 -303.692343) (xy 401.040064 -303.722893) (xy 401.076815 -303.759644)
			(xy 401.107365 -303.801692) (xy 401.130961 -303.848002) (xy 401.147022 -303.897432) (xy 401.155152 -303.948767)
			(xy 401.155662 -303.974754) (xy 401.155108 -304.002372) (xy 401.145927 -304.056839) (xy 401.127812 -304.10902)
			(xy 401.115022 -304.133504) (xy 401.108418 -304.145442) (xy 401.108926 -304.172112) (xy 401.160488 -304.25898)
			(xy 401.165285 -304.266358) (xy 401.178837 -304.277566) (xy 401.195383 -304.283526) (xy 401.204176 -304.283872)
			(xy 401.395692 -304.283872) (xy 401.404483 -304.283504) (xy 401.421028 -304.277554) (xy 401.434582 -304.266355)
			(xy 401.43938 -304.25898) (xy 401.490942 -304.172112) (xy 401.49145 -304.145442) (xy 401.484846 -304.133504)
			(xy 401.472068 -304.109015) (xy 401.453955 -304.056835) (xy 401.444767 -304.002371) (xy 401.444206 -303.974754)
			(xy 401.444716 -303.948767) (xy 401.452846 -303.897432) (xy 401.468907 -303.848002) (xy 401.492503 -303.801692)
			(xy 401.523053 -303.759644) (xy 401.559804 -303.722893) (xy 401.601852 -303.692343) (xy 401.648162 -303.668747)
			(xy 401.697592 -303.652686) (xy 401.748927 -303.644556) (xy 401.800901 -303.644556) (xy 401.852236 -303.652686)
			(xy 401.901666 -303.668747) (xy 401.947976 -303.692343) (xy 401.990024 -303.722893) (xy 402.026775 -303.759644)
			(xy 402.057325 -303.801692) (xy 402.080921 -303.848002) (xy 402.096982 -303.897432) (xy 402.105112 -303.948767)
			(xy 402.105622 -303.974754) (xy 402.105068 -304.002372) (xy 402.095888 -304.05684) (xy 402.077776 -304.109022)
			(xy 402.064982 -304.133504) (xy 402.058378 -304.145442) (xy 402.058886 -304.172112) (xy 402.110448 -304.25898)
			(xy 402.115243 -304.266363) (xy 402.128794 -304.277581) (xy 402.145341 -304.283553) (xy 402.154136 -304.283872)
			(xy 402.345652 -304.283872) (xy 402.354447 -304.28351) (xy 402.371001 -304.27757) (xy 402.384566 -304.266373)
			(xy 402.38934 -304.25898) (xy 402.440902 -304.172112) (xy 402.44141 -304.145442) (xy 402.434806 -304.133504)
			(xy 402.422029 -304.109014) (xy 402.403919 -304.056834) (xy 402.394732 -304.002371) (xy 402.394166 -303.974754)
			(xy 402.394676 -303.948767) (xy 402.402806 -303.897432) (xy 402.418867 -303.848002) (xy 402.442463 -303.801692)
			(xy 402.473013 -303.759644) (xy 402.509764 -303.722893) (xy 402.551812 -303.692343) (xy 402.598122 -303.668747)
			(xy 402.647552 -303.652686) (xy 402.698887 -303.644556) (xy 402.750861 -303.644556) (xy 402.802196 -303.652686)
			(xy 402.851626 -303.668747) (xy 402.897936 -303.692343) (xy 402.939984 -303.722893) (xy 402.976735 -303.759644)
			(xy 403.007285 -303.801692) (xy 403.030881 -303.848002) (xy 403.046942 -303.897432) (xy 403.055072 -303.948767)
			(xy 403.055582 -303.974754) (xy 403.055028 -304.002372) (xy 403.045847 -304.056839) (xy 403.027733 -304.109021)
			(xy 403.014942 -304.133504) (xy 403.008338 -304.145442) (xy 403.008846 -304.172112) (xy 403.060408 -304.25898)
			(xy 403.065206 -304.266356) (xy 403.078759 -304.277558) (xy 403.095304 -304.283511) (xy 403.104096 -304.283872)
			(xy 403.295612 -304.283872) (xy 403.304401 -304.283501) (xy 403.320941 -304.277547) (xy 403.334489 -304.266346)
			(xy 403.3393 -304.25898) (xy 403.390862 -304.172112) (xy 403.39137 -304.145442) (xy 403.384766 -304.133504)
			(xy 403.371987 -304.109015) (xy 403.353874 -304.056835) (xy 403.344685 -304.002371) (xy 403.344126 -303.974754)
			(xy 403.344636 -303.948767) (xy 403.352766 -303.897432) (xy 403.368827 -303.848002) (xy 403.392423 -303.801692)
			(xy 403.422973 -303.759644) (xy 403.459724 -303.722893) (xy 403.501772 -303.692343) (xy 403.548082 -303.668747)
			(xy 403.597512 -303.652686) (xy 403.648847 -303.644556) (xy 403.700821 -303.644556) (xy 403.752156 -303.652686)
			(xy 403.801586 -303.668747) (xy 403.847896 -303.692343) (xy 403.889944 -303.722893) (xy 403.926695 -303.759644)
			(xy 403.957245 -303.801692) (xy 403.980841 -303.848002) (xy 403.996902 -303.897432) (xy 404.005032 -303.948767)
			(xy 404.005542 -303.974754) (xy 404.004988 -304.002372) (xy 403.995809 -304.05684) (xy 403.977698 -304.109023)
			(xy 403.964902 -304.133504) (xy 403.958298 -304.145442) (xy 403.958806 -304.172112) (xy 404.010368 -304.25898)
			(xy 404.015164 -304.266361) (xy 404.028716 -304.277574) (xy 404.045262 -304.283539) (xy 404.054056 -304.283872)
			(xy 404.245572 -304.283872) (xy 404.254365 -304.283507) (xy 404.270915 -304.277562) (xy 404.284474 -304.266364)
			(xy 404.28926 -304.25898) (xy 404.340822 -304.172112) (xy 404.34133 -304.145442) (xy 404.334726 -304.133504)
			(xy 404.321948 -304.109015) (xy 404.303837 -304.056835) (xy 404.294649 -304.002371) (xy 404.294086 -303.974754)
			(xy 404.294596 -303.948767) (xy 404.302726 -303.897432) (xy 404.318787 -303.848002) (xy 404.342383 -303.801692)
			(xy 404.372933 -303.759644) (xy 404.409684 -303.722893) (xy 404.451732 -303.692343) (xy 404.498042 -303.668747)
			(xy 404.547472 -303.652686) (xy 404.598807 -303.644556) (xy 404.650781 -303.644556) (xy 404.702116 -303.652686)
			(xy 404.751546 -303.668747) (xy 404.797856 -303.692343) (xy 404.839904 -303.722893) (xy 404.876655 -303.759644)
			(xy 404.907205 -303.801692) (xy 404.930801 -303.848002) (xy 404.946862 -303.897432) (xy 404.954992 -303.948767)
			(xy 404.955502 -303.974754) (xy 404.954948 -304.002372) (xy 404.945768 -304.05684) (xy 404.927655 -304.109021)
			(xy 404.914862 -304.133504) (xy 404.908258 -304.145442) (xy 404.908766 -304.172112) (xy 404.960328 -304.25898)
			(xy 404.965127 -304.266354) (xy 404.978681 -304.277551) (xy 404.995226 -304.283498) (xy 405.004016 -304.283872)
			(xy 405.195786 -304.283872) (xy 405.204578 -304.283505) (xy 405.221124 -304.277557) (xy 405.234679 -304.266358)
			(xy 405.239474 -304.25898) (xy 405.291036 -304.172112) (xy 405.291544 -304.145442) (xy 405.28494 -304.133504)
			(xy 405.272162 -304.109015) (xy 405.25405 -304.056835) (xy 405.244862 -304.002371) (xy 405.2443 -303.974754)
			(xy 405.24481 -303.948767) (xy 405.25294 -303.897432) (xy 405.269001 -303.848002) (xy 405.292597 -303.801692)
			(xy 405.323147 -303.759644) (xy 405.359898 -303.722893) (xy 405.401946 -303.692343) (xy 405.448256 -303.668747)
			(xy 405.497686 -303.652686) (xy 405.549021 -303.644556) (xy 405.600995 -303.644556) (xy 405.65233 -303.652686)
			(xy 405.70176 -303.668747) (xy 405.74807 -303.692343) (xy 405.790118 -303.722893) (xy 405.826869 -303.759644)
			(xy 405.857419 -303.801692) (xy 405.881015 -303.848002) (xy 405.897076 -303.897432) (xy 405.905206 -303.948767)
			(xy 405.905716 -303.974754) (xy 405.905162 -304.002372) (xy 405.895982 -304.05684) (xy 405.87787 -304.109022)
			(xy 405.865076 -304.133504) (xy 405.858472 -304.145442) (xy 405.85898 -304.172112) (xy 405.910542 -304.25898)
			(xy 405.915337 -304.266363) (xy 405.928887 -304.277583) (xy 405.945434 -304.283557) (xy 405.95423 -304.283872)
			(xy 406.145746 -304.283872) (xy 406.154541 -304.283511) (xy 406.171098 -304.277572) (xy 406.184664 -304.266376)
			(xy 406.189434 -304.25898) (xy 406.240996 -304.172112) (xy 406.241504 -304.145442) (xy 406.2349 -304.133504)
			(xy 406.22212 -304.109016) (xy 406.204004 -304.056836) (xy 406.194815 -304.002371) (xy 406.19426 -303.974754)
			(xy 406.19477 -303.948767) (xy 406.2029 -303.897432) (xy 406.218961 -303.848002) (xy 406.242557 -303.801692)
			(xy 406.273107 -303.759644) (xy 406.309858 -303.722893) (xy 406.351906 -303.692343) (xy 406.398216 -303.668747)
			(xy 406.447646 -303.652686) (xy 406.498981 -303.644556) (xy 406.550955 -303.644556) (xy 406.60229 -303.652686)
			(xy 406.65172 -303.668747) (xy 406.69803 -303.692343) (xy 406.740078 -303.722893) (xy 406.776829 -303.759644)
			(xy 406.807379 -303.801692) (xy 406.830975 -303.848002) (xy 406.847036 -303.897432) (xy 406.855166 -303.948767)
			(xy 406.855676 -303.974754) (xy 406.855122 -304.002372) (xy 406.845941 -304.056839) (xy 406.827827 -304.10902)
			(xy 406.815036 -304.133504) (xy 406.808432 -304.145442) (xy 406.80894 -304.172112) (xy 406.860502 -304.25898)
			(xy 406.8653 -304.266357) (xy 406.878853 -304.27756) (xy 406.895398 -304.283516) (xy 406.90419 -304.283872)
			(xy 408.045666 -304.283872) (xy 408.054459 -304.283508) (xy 408.071011 -304.277564) (xy 408.084572 -304.266367)
			(xy 408.089354 -304.25898) (xy 408.140916 -304.172112) (xy 408.141424 -304.145442) (xy 408.13482 -304.133504)
			(xy 408.122042 -304.109015) (xy 408.103932 -304.056835) (xy 408.094744 -304.002371) (xy 408.09418 -303.974754)
			(xy 408.09469 -303.948767) (xy 408.10282 -303.897432) (xy 408.118881 -303.848002) (xy 408.142477 -303.801692)
			(xy 408.173027 -303.759644) (xy 408.209778 -303.722893) (xy 408.251826 -303.692343) (xy 408.298136 -303.668747)
			(xy 408.347566 -303.652686) (xy 408.398901 -303.644556) (xy 408.450875 -303.644556) (xy 408.50221 -303.652686)
			(xy 408.55164 -303.668747) (xy 408.59795 -303.692343) (xy 408.639998 -303.722893) (xy 408.676749 -303.759644)
			(xy 408.707299 -303.801692) (xy 408.730895 -303.848002) (xy 408.746956 -303.897432) (xy 408.755086 -303.948767)
			(xy 408.755596 -303.974754) (xy 408.755042 -304.002372) (xy 408.745862 -304.05684) (xy 408.727748 -304.109021)
			(xy 408.714956 -304.133504) (xy 408.708352 -304.145442) (xy 408.70886 -304.172112) (xy 408.760422 -304.25898)
			(xy 408.765221 -304.266355) (xy 408.778775 -304.277553) (xy 408.795319 -304.283502) (xy 408.80411 -304.283872)
			(xy 408.995626 -304.283872) (xy 409.004414 -304.283499) (xy 409.02095 -304.277542) (xy 409.034495 -304.26634)
			(xy 409.039314 -304.25898) (xy 409.090876 -304.172112) (xy 409.091384 -304.145442) (xy 409.08478 -304.133504)
			(xy 409.072 -304.109015) (xy 409.053886 -304.056836) (xy 409.044697 -304.002371) (xy 409.04414 -303.974754)
			(xy 409.04465 -303.948767) (xy 409.05278 -303.897432) (xy 409.068841 -303.848002) (xy 409.092437 -303.801692)
			(xy 409.122987 -303.759644) (xy 409.159738 -303.722893) (xy 409.201786 -303.692343) (xy 409.248096 -303.668747)
			(xy 409.297526 -303.652686) (xy 409.348861 -303.644556) (xy 409.400835 -303.644556) (xy 409.45217 -303.652686)
			(xy 409.5016 -303.668747) (xy 409.54791 -303.692343) (xy 409.589958 -303.722893) (xy 409.626709 -303.759644)
			(xy 409.657259 -303.801692) (xy 409.680855 -303.848002) (xy 409.696916 -303.897432) (xy 409.705046 -303.948767)
			(xy 409.705556 -303.974754) (xy 409.705002 -304.002372) (xy 409.69582 -304.056839) (xy 409.677705 -304.10902)
			(xy 409.664916 -304.133504) (xy 409.658312 -304.145442) (xy 409.65882 -304.172112) (xy 409.710382 -304.25898)
			(xy 409.715179 -304.266359) (xy 409.728731 -304.277568) (xy 409.745277 -304.28353) (xy 409.75407 -304.283872)
			(xy 409.945586 -304.283872) (xy 409.954378 -304.283505) (xy 409.970924 -304.277557) (xy 409.984479 -304.266358)
			(xy 409.989274 -304.25898) (xy 410.040836 -304.172112) (xy 410.041344 -304.145442) (xy 410.03474 -304.133504)
			(xy 410.021962 -304.109015) (xy 410.00385 -304.056835) (xy 409.994662 -304.002371) (xy 409.9941 -303.974754)
			(xy 409.99461 -303.948767) (xy 410.00274 -303.897432) (xy 410.018801 -303.848002) (xy 410.042397 -303.801692)
			(xy 410.072947 -303.759644) (xy 410.109698 -303.722893) (xy 410.151746 -303.692343) (xy 410.198056 -303.668747)
			(xy 410.247486 -303.652686) (xy 410.298821 -303.644556) (xy 410.350795 -303.644556) (xy 410.40213 -303.652686)
			(xy 410.45156 -303.668747) (xy 410.49787 -303.692343) (xy 410.539918 -303.722893) (xy 410.576669 -303.759644)
			(xy 410.607219 -303.801692) (xy 410.630815 -303.848002) (xy 410.646876 -303.897432) (xy 410.655006 -303.948767)
			(xy 410.655516 -303.974754) (xy 410.654962 -304.002372) (xy 410.645782 -304.05684) (xy 410.62767 -304.109022)
			(xy 410.614876 -304.133504) (xy 410.608272 -304.145442) (xy 410.60878 -304.172112) (xy 410.660342 -304.25898)
			(xy 410.665137 -304.266363) (xy 410.678687 -304.277583) (xy 410.695234 -304.283557) (xy 410.70403 -304.283872)
			(xy 410.8958 -304.283872) (xy 410.90459 -304.283503) (xy 410.921133 -304.277551) (xy 410.934685 -304.266352)
			(xy 410.939488 -304.25898) (xy 410.99105 -304.172112) (xy 410.991558 -304.145442) (xy 410.984954 -304.133504)
			(xy 410.972175 -304.109015) (xy 410.954063 -304.056835) (xy 410.944874 -304.002371) (xy 410.944314 -303.974754)
			(xy 410.944824 -303.948767) (xy 410.952954 -303.897432) (xy 410.969015 -303.848002) (xy 410.992611 -303.801692)
			(xy 411.023161 -303.759644) (xy 411.059912 -303.722893) (xy 411.10196 -303.692343) (xy 411.14827 -303.668747)
			(xy 411.1977 -303.652686) (xy 411.249035 -303.644556) (xy 411.301009 -303.644556) (xy 411.352344 -303.652686)
			(xy 411.401774 -303.668747) (xy 411.448084 -303.692343) (xy 411.490132 -303.722893) (xy 411.526883 -303.759644)
			(xy 411.557433 -303.801692) (xy 411.581029 -303.848002) (xy 411.59709 -303.897432) (xy 411.60522 -303.948767)
			(xy 411.60573 -303.974754) (xy 411.605176 -304.002372) (xy 411.595996 -304.05684) (xy 411.577885 -304.109022)
			(xy 411.56509 -304.133504) (xy 411.558486 -304.145442) (xy 411.558994 -304.172112) (xy 411.610556 -304.25898)
			(xy 411.615352 -304.266362) (xy 411.628903 -304.277578) (xy 411.645449 -304.283548) (xy 411.654244 -304.283872)
			(xy 411.84576 -304.283872) (xy 411.854554 -304.283509) (xy 411.871107 -304.277567) (xy 411.884669 -304.26637)
			(xy 411.889448 -304.25898) (xy 411.94101 -304.172112) (xy 411.941518 -304.145442) (xy 411.934914 -304.133504)
			(xy 411.922137 -304.109015) (xy 411.904026 -304.056835) (xy 411.894839 -304.002371) (xy 411.894274 -303.974754)
			(xy 411.894784 -303.948767) (xy 411.902914 -303.897432) (xy 411.918975 -303.848002) (xy 411.942571 -303.801692)
			(xy 411.973121 -303.759644) (xy 412.009872 -303.722893) (xy 412.05192 -303.692343) (xy 412.09823 -303.668747)
			(xy 412.14766 -303.652686) (xy 412.198995 -303.644556) (xy 412.250969 -303.644556) (xy 412.302304 -303.652686)
			(xy 412.351734 -303.668747) (xy 412.398044 -303.692343) (xy 412.440092 -303.722893) (xy 412.476843 -303.759644)
			(xy 412.507393 -303.801692) (xy 412.530989 -303.848002) (xy 412.54705 -303.897432) (xy 412.55518 -303.948767)
			(xy 412.55569 -303.974754) (xy 412.555136 -304.002372) (xy 412.545955 -304.05684) (xy 412.527842 -304.109021)
			(xy 412.51505 -304.133504) (xy 412.508446 -304.145442) (xy 412.508954 -304.172112) (xy 412.560516 -304.25898)
			(xy 412.565315 -304.266355) (xy 412.578868 -304.277555) (xy 412.595413 -304.283506) (xy 412.604204 -304.283872)
			(xy 412.79572 -304.283872) (xy 412.804509 -304.2835) (xy 412.821046 -304.277544) (xy 412.834593 -304.266343)
			(xy 412.839408 -304.25898) (xy 412.89097 -304.172112) (xy 412.891478 -304.145442) (xy 412.884874 -304.133504)
			(xy 412.872095 -304.109015) (xy 412.853981 -304.056836) (xy 412.844792 -304.002371) (xy 412.844234 -303.974754)
			(xy 412.844744 -303.948767) (xy 412.852874 -303.897432) (xy 412.868935 -303.848002) (xy 412.892531 -303.801692)
			(xy 412.923081 -303.759644) (xy 412.959832 -303.722893) (xy 413.00188 -303.692343) (xy 413.04819 -303.668747)
			(xy 413.09762 -303.652686) (xy 413.148955 -303.644556) (xy 413.200929 -303.644556) (xy 413.252264 -303.652686)
			(xy 413.301694 -303.668747) (xy 413.348004 -303.692343) (xy 413.390052 -303.722893) (xy 413.426803 -303.759644)
			(xy 413.457353 -303.801692) (xy 413.480949 -303.848002) (xy 413.49701 -303.897432) (xy 413.50514 -303.948767)
			(xy 413.50565 -303.974754) (xy 413.505096 -304.002372) (xy 413.495917 -304.05684) (xy 413.477806 -304.109023)
			(xy 413.46501 -304.133504) (xy 413.458406 -304.145442) (xy 413.458914 -304.172112) (xy 413.510476 -304.25898)
			(xy 413.515273 -304.26636) (xy 413.528824 -304.277571) (xy 413.54537 -304.283534) (xy 413.554164 -304.283872)
			(xy 413.74568 -304.283872) (xy 413.754472 -304.283506) (xy 413.77102 -304.277559) (xy 413.784577 -304.266361)
			(xy 413.789368 -304.25898) (xy 413.84093 -304.172112) (xy 413.841438 -304.145442) (xy 413.834834 -304.133504)
			(xy 413.822056 -304.109015) (xy 413.803944 -304.056835) (xy 413.794756 -304.002371) (xy 413.794194 -303.974754)
			(xy 413.794704 -303.948767) (xy 413.802834 -303.897432) (xy 413.818895 -303.848002) (xy 413.842491 -303.801692)
			(xy 413.873041 -303.759644) (xy 413.909792 -303.722893) (xy 413.95184 -303.692343) (xy 413.99815 -303.668747)
			(xy 414.04758 -303.652686) (xy 414.098915 -303.644556) (xy 414.150889 -303.644556) (xy 414.202224 -303.652686)
			(xy 414.251654 -303.668747) (xy 414.297964 -303.692343) (xy 414.340012 -303.722893) (xy 414.376763 -303.759644)
			(xy 414.407313 -303.801692) (xy 414.430909 -303.848002) (xy 414.44697 -303.897432) (xy 414.4551 -303.948767)
			(xy 414.45561 -303.974754) (xy 414.455056 -304.002372) (xy 414.445876 -304.05684) (xy 414.427763 -304.109022)
			(xy 414.41497 -304.133504) (xy 414.408366 -304.145442) (xy 414.408874 -304.172112) (xy 414.460436 -304.25898)
			(xy 414.465236 -304.266353) (xy 414.47879 -304.277548) (xy 414.495334 -304.283492) (xy 414.504124 -304.283872)
			(xy 414.69564 -304.283872) (xy 414.704427 -304.283496) (xy 414.72096 -304.277536) (xy 414.7345 -304.266334)
			(xy 414.739328 -304.25898) (xy 414.79089 -304.172112) (xy 414.791398 -304.145442) (xy 414.784794 -304.133504)
			(xy 414.772014 -304.109015) (xy 414.753899 -304.056836) (xy 414.744709 -304.002371) (xy 414.744154 -303.974754)
			(xy 414.744664 -303.948767) (xy 414.752794 -303.897432) (xy 414.768855 -303.848002) (xy 414.792451 -303.801692)
			(xy 414.823001 -303.759644) (xy 414.859752 -303.722893) (xy 414.9018 -303.692343) (xy 414.94811 -303.668747)
			(xy 414.99754 -303.652686) (xy 415.048875 -303.644556) (xy 415.100849 -303.644556) (xy 415.152184 -303.652686)
			(xy 415.201614 -303.668747) (xy 415.247924 -303.692343) (xy 415.289972 -303.722893) (xy 415.326723 -303.759644)
			(xy 415.357273 -303.801692) (xy 415.380869 -303.848002) (xy 415.39693 -303.897432) (xy 415.40506 -303.948767)
			(xy 415.40557 -303.974754) (xy 415.405016 -304.002372) (xy 415.395835 -304.056839) (xy 415.37772 -304.10902)
			(xy 415.36493 -304.133504) (xy 415.358326 -304.145442) (xy 415.358834 -304.172112) (xy 415.410396 -304.25898)
			(xy 415.415193 -304.266358) (xy 415.428746 -304.277563) (xy 415.445292 -304.28352) (xy 415.454084 -304.283872)
			(xy 415.6456 -304.283872) (xy 415.65439 -304.283503) (xy 415.670933 -304.277551) (xy 415.684485 -304.266352)
			(xy 415.689288 -304.25898) (xy 415.74085 -304.172112) (xy 415.741358 -304.145442) (xy 415.734754 -304.133504)
			(xy 415.721975 -304.109015) (xy 415.703863 -304.056835) (xy 415.694674 -304.002371) (xy 415.694114 -303.974754)
			(xy 415.694624 -303.948767) (xy 415.702754 -303.897432) (xy 415.718815 -303.848002) (xy 415.742411 -303.801692)
			(xy 415.772961 -303.759644) (xy 415.809712 -303.722893) (xy 415.85176 -303.692343) (xy 415.89807 -303.668747)
			(xy 415.9475 -303.652686) (xy 415.998835 -303.644556) (xy 416.050809 -303.644556) (xy 416.102144 -303.652686)
			(xy 416.151574 -303.668747) (xy 416.197884 -303.692343) (xy 416.239932 -303.722893) (xy 416.276683 -303.759644)
			(xy 416.307233 -303.801692) (xy 416.330829 -303.848002) (xy 416.34689 -303.897432) (xy 416.35502 -303.948767)
			(xy 416.35553 -303.974754) (xy 416.354976 -304.002372) (xy 416.345796 -304.05684) (xy 416.327685 -304.109022)
			(xy 416.31489 -304.133504) (xy 416.308286 -304.145442) (xy 416.308794 -304.172112) (xy 416.360356 -304.25898)
			(xy 416.365152 -304.266362) (xy 416.378703 -304.277578) (xy 416.395249 -304.283548) (xy 416.404044 -304.283872)
			(xy 416.603434 -304.283872) (xy 416.61224 -304.283449) (xy 416.628787 -304.277399) (xy 416.642323 -304.266123)
			(xy 416.647122 -304.258726) (xy 416.69843 -304.171096) (xy 416.69843 -304.144172) (xy 416.691826 -304.132488)
			(xy 416.678409 -304.107517) (xy 416.659379 -304.054124) (xy 416.64972 -303.998269) (xy 416.649154 -303.969928)
			(xy 416.649664 -303.943941) (xy 416.657794 -303.892606) (xy 416.673855 -303.843176) (xy 416.697451 -303.796866)
			(xy 416.728001 -303.754818) (xy 416.764752 -303.718067) (xy 416.8068 -303.687517) (xy 416.85311 -303.663921)
			(xy 416.90254 -303.64786) (xy 416.953875 -303.63973) (xy 417.005849 -303.63973) (xy 417.057184 -303.64786)
			(xy 417.106614 -303.663921) (xy 417.152924 -303.687517) (xy 417.194972 -303.718067) (xy 417.231723 -303.754818)
			(xy 417.262273 -303.796866) (xy 417.285869 -303.843176) (xy 417.30193 -303.892606) (xy 417.31006 -303.943941)
			(xy 417.31057 -303.969928) (xy 417.309986 -303.998268) (xy 417.300329 -304.054119) (xy 417.281301 -304.10751)
			(xy 417.267898 -304.132488) (xy 417.261294 -304.144172) (xy 417.261294 -304.171096) (xy 417.312602 -304.258726)
			(xy 417.317364 -304.266156) (xy 417.330897 -304.277462) (xy 417.347473 -304.283476) (xy 417.35629 -304.283872)
			(xy 417.545774 -304.283872) (xy 417.554567 -304.283507) (xy 417.571116 -304.277561) (xy 417.584675 -304.266363)
			(xy 417.589462 -304.25898) (xy 417.641024 -304.172112) (xy 417.641532 -304.145442) (xy 417.634928 -304.133504)
			(xy 417.62215 -304.109015) (xy 417.604039 -304.056835) (xy 417.594851 -304.002371) (xy 417.594288 -303.974754)
			(xy 417.594801 -303.948769) (xy 417.602937 -303.89744) (xy 417.619002 -303.848015) (xy 417.6426 -303.801712)
			(xy 417.673151 -303.75967) (xy 417.709902 -303.722924) (xy 417.751948 -303.692378) (xy 417.798254 -303.668786)
			(xy 417.847681 -303.652727) (xy 417.899011 -303.644598) (xy 417.924996 -303.644046) (xy 417.948264 -303.644443)
			(xy 417.994341 -303.650969) (xy 418.039046 -303.663893) (xy 418.081497 -303.68296) (xy 418.120855 -303.707793)
			(xy 418.138864 -303.722532) (xy 418.150294 -303.732184) (xy 418.179504 -303.736248) (xy 418.276786 -303.69129)
			(xy 418.285419 -303.686856) (xy 418.298764 -303.672787) (xy 418.305906 -303.654759) (xy 418.30625 -303.645062)
			(xy 418.30625 -300.978062) (xy 418.305818 -300.967996) (xy 418.298089 -300.949406) (xy 418.291264 -300.941994)
			(xy 417.967668 -300.618398) (xy 417.960268 -300.611557) (xy 417.94167 -300.603834) (xy 417.9316 -300.603412)
			(xy 416.613086 -300.603412) (xy 416.603017 -300.602987) (xy 416.584415 -300.59527) (xy 416.577018 -300.588426)
			(xy 416.55492 -300.566328) (xy 416.548083 -300.558926) (xy 416.540371 -300.540328) (xy 416.539934 -300.53026)
			(xy 416.539934 -297.41114) (xy 416.540369 -297.401075) (xy 416.548102 -297.38249) (xy 416.55492 -297.375072)
			(xy 416.640518 -297.289474) (xy 416.64763 -297.275758) (xy 416.6489 -297.267884) (xy 416.653798 -297.242647)
			(xy 416.670364 -297.193982) (xy 416.694263 -297.148467) (xy 416.724919 -297.107201) (xy 416.761592 -297.071176)
			(xy 416.803399 -297.041262) (xy 416.849333 -297.018179) (xy 416.898286 -297.002484) (xy 416.949078 -296.994556)
			(xy 416.974782 -296.994072) (xy 417.00182 -296.99461) (xy 417.055175 -297.003406) (xy 417.106387 -297.020768)
			(xy 417.154092 -297.046232) (xy 417.197017 -297.07912) (xy 417.234018 -297.118555) (xy 417.264109 -297.163485)
			(xy 417.286487 -297.212713) (xy 417.29406 -297.238674) (xy 417.298632 -297.255438) (xy 417.32581 -297.276266)
			(xy 417.573968 -297.276266) (xy 417.601146 -297.255438) (xy 417.605718 -297.238674) (xy 417.612795 -297.214228)
			(xy 417.633417 -297.167703) (xy 417.660924 -297.124887) (xy 417.694666 -297.08679) (xy 417.733846 -297.054312)
			(xy 417.777539 -297.02822) (xy 417.824713 -297.00913) (xy 417.874256 -296.997493) (xy 417.924996 -296.993583)
			(xy 417.975736 -296.997493) (xy 418.025279 -297.00913) (xy 418.072453 -297.02822) (xy 418.116146 -297.054312)
			(xy 418.155326 -297.08679) (xy 418.189068 -297.124887) (xy 418.216575 -297.167703) (xy 418.237197 -297.214228)
			(xy 418.244274 -297.238674) (xy 418.248846 -297.255438) (xy 418.276024 -297.276266) (xy 418.523928 -297.276266)
			(xy 418.551106 -297.255438) (xy 418.555678 -297.238674) (xy 418.562489 -297.215119) (xy 418.582106 -297.170182)
			(xy 418.608146 -297.128635) (xy 418.640038 -297.091392) (xy 418.677082 -297.059269) (xy 418.718465 -297.032972)
			(xy 418.76328 -297.013077) (xy 418.810542 -297.00002) (xy 418.834824 -296.996612) (xy 418.854128 -296.994072)
			(xy 418.879528 -296.96537) (xy 418.879528 -296.73423) (xy 418.854128 -296.705528) (xy 418.834824 -296.702988)
			(xy 418.809841 -296.69945) (xy 418.761272 -296.685781) (xy 418.715344 -296.664892) (xy 418.673123 -296.637267)
			(xy 418.635589 -296.603548) (xy 418.603614 -296.564518) (xy 418.57794 -296.521083) (xy 418.559163 -296.474252)
			(xy 418.54772 -296.425111) (xy 418.543876 -296.374802) (xy 418.547719 -296.324494) (xy 418.559162 -296.275353)
			(xy 418.577938 -296.228521) (xy 418.603611 -296.185086) (xy 418.635586 -296.146055) (xy 418.673119 -296.112336)
			(xy 418.71534 -296.08471) (xy 418.761268 -296.06382) (xy 418.809836 -296.050151) (xy 418.834824 -296.046652)
			(xy 418.854128 -296.044112) (xy 418.879528 -296.01541) (xy 418.879528 -294.83431) (xy 418.854128 -294.805608)
			(xy 418.834824 -294.803068) (xy 418.809843 -294.79953) (xy 418.761277 -294.785862) (xy 418.715352 -294.764974)
			(xy 418.673133 -294.73735) (xy 418.635602 -294.703633) (xy 418.603629 -294.664605) (xy 418.577957 -294.621172)
			(xy 418.559182 -294.574344) (xy 418.547739 -294.525206) (xy 418.543895 -294.4749) (xy 418.547739 -294.424594)
			(xy 418.559182 -294.375456) (xy 418.577957 -294.328628) (xy 418.603629 -294.285195) (xy 418.635602 -294.246167)
			(xy 418.673133 -294.21245) (xy 418.715352 -294.184826) (xy 418.761277 -294.163938) (xy 418.809843 -294.15027)
			(xy 418.834824 -294.146732) (xy 418.854128 -294.144192) (xy 418.879528 -294.11549) (xy 418.879528 -293.88435)
			(xy 418.854128 -293.855648) (xy 418.834824 -293.853108) (xy 418.80984 -293.84957) (xy 418.761268 -293.835901)
			(xy 418.715337 -293.815011) (xy 418.673113 -293.787385) (xy 418.635576 -293.753664) (xy 418.603599 -293.714632)
			(xy 418.577923 -293.671194) (xy 418.559145 -293.62436) (xy 418.547701 -293.575217) (xy 418.543856 -293.524905)
			(xy 418.547699 -293.474593) (xy 418.559142 -293.425449) (xy 418.577919 -293.378614) (xy 418.603594 -293.335176)
			(xy 418.63557 -293.296143) (xy 418.673105 -293.262421) (xy 418.715328 -293.234794) (xy 418.761259 -293.213902)
			(xy 418.80983 -293.200232) (xy 418.834824 -293.196772) (xy 418.854128 -293.194232) (xy 418.879528 -293.16553)
			(xy 418.879528 -292.93439) (xy 418.854128 -292.905688) (xy 418.834824 -292.903148) (xy 418.809844 -292.89961)
			(xy 418.761281 -292.885942) (xy 418.715359 -292.865055) (xy 418.673143 -292.837433) (xy 418.635615 -292.803718)
			(xy 418.603644 -292.764692) (xy 418.577974 -292.721261) (xy 418.5592 -292.674435) (xy 418.547758 -292.6253)
			(xy 418.543915 -292.574998) (xy 418.547759 -292.524695) (xy 418.559201 -292.47556) (xy 418.577976 -292.428734)
			(xy 418.603647 -292.385304) (xy 418.635618 -292.346279) (xy 418.673147 -292.312564) (xy 418.715363 -292.284943)
			(xy 418.761286 -292.264056) (xy 418.809849 -292.250389) (xy 418.834824 -292.246812) (xy 418.854128 -292.244272)
			(xy 418.879528 -292.21557) (xy 418.879528 -291.984176) (xy 418.854128 -291.955474) (xy 418.834824 -291.952934)
			(xy 418.809845 -291.949396) (xy 418.761285 -291.935729) (xy 418.715364 -291.914842) (xy 418.673151 -291.887221)
			(xy 418.635623 -291.853507) (xy 418.603654 -291.814482) (xy 418.577985 -291.771054) (xy 418.559213 -291.724229)
			(xy 418.547772 -291.675097) (xy 418.543929 -291.624796) (xy 418.547773 -291.574495) (xy 418.559215 -291.525363)
			(xy 418.577989 -291.478539) (xy 418.603659 -291.435111) (xy 418.635629 -291.396087) (xy 418.673157 -291.362374)
			(xy 418.715372 -291.334754) (xy 418.761292 -291.313868) (xy 418.809853 -291.300202) (xy 418.834824 -291.296598)
			(xy 418.854128 -291.294058) (xy 418.879528 -291.265356) (xy 418.879528 -291.034216) (xy 418.854128 -291.005514)
			(xy 418.834824 -291.002974) (xy 418.809842 -290.999436) (xy 418.761275 -290.985768) (xy 418.715349 -290.964879)
			(xy 418.67313 -290.937255) (xy 418.635598 -290.903538) (xy 418.603624 -290.864509) (xy 418.577952 -290.821076)
			(xy 418.559176 -290.774246) (xy 418.547733 -290.725107) (xy 418.543889 -290.674801) (xy 418.547733 -290.624494)
			(xy 418.559176 -290.575355) (xy 418.577951 -290.528526) (xy 418.603624 -290.485092) (xy 418.635597 -290.446063)
			(xy 418.673129 -290.412346) (xy 418.715348 -290.384722) (xy 418.761274 -290.363833) (xy 418.809841 -290.350164)
			(xy 418.834824 -290.346638) (xy 418.854128 -290.344098) (xy 418.879528 -290.315396) (xy 418.879528 -290.084256)
			(xy 418.854128 -290.055554) (xy 418.834824 -290.053014) (xy 418.809839 -290.049476) (xy 418.761266 -290.035807)
			(xy 418.715335 -290.014916) (xy 418.67311 -289.98729) (xy 418.635573 -289.953569) (xy 418.603595 -289.914536)
			(xy 418.577918 -289.871098) (xy 418.55914 -289.824263) (xy 418.547695 -289.775118) (xy 418.54385 -289.724806)
			(xy 418.547693 -289.674493) (xy 418.559136 -289.625348) (xy 418.577913 -289.578512) (xy 418.603588 -289.535073)
			(xy 418.635565 -289.496039) (xy 418.673101 -289.462317) (xy 418.715325 -289.434689) (xy 418.761256 -289.413797)
			(xy 418.809828 -289.400126) (xy 418.834824 -289.396678) (xy 418.854128 -289.394138) (xy 418.879528 -289.365436)
			(xy 418.879528 -289.134296) (xy 418.854128 -289.105594) (xy 418.834824 -289.103054) (xy 418.808637 -289.099319)
			(xy 418.75783 -289.084607) (xy 418.710011 -289.061999) (xy 418.666399 -289.032069) (xy 418.628106 -288.995581)
			(xy 418.596106 -288.953465) (xy 418.571215 -288.906793) (xy 418.554068 -288.856756) (xy 418.545101 -288.804627)
			(xy 418.544248 -288.778188) (xy 418.544248 -288.774632) (xy 418.544668 -288.750731) (xy 418.551551 -288.703427)
			(xy 418.557964 -288.680398) (xy 418.560206 -288.671564) (xy 418.558967 -288.653393) (xy 418.551437 -288.63681)
			(xy 418.545264 -288.630106) (xy 418.328602 -288.413444) (xy 418.32149 -288.406078) (xy 418.302694 -288.398458)
			(xy 417.308538 -288.398458) (xy 417.29895 -288.398867) (xy 417.281104 -288.405885) (xy 417.267049 -288.418932)
			(xy 417.262564 -288.427414) (xy 417.223448 -288.510472) (xy 417.219685 -288.519337) (xy 417.218401 -288.538538)
			(xy 417.224284 -288.55686) (xy 417.230052 -288.564574) (xy 417.24771 -288.586963) (xy 417.275872 -288.63654)
			(xy 417.295128 -288.690206) (xy 417.30491 -288.746378) (xy 417.30549 -288.774886) (xy 417.30498 -288.800873)
			(xy 417.29685 -288.852208) (xy 417.280789 -288.901638) (xy 417.257193 -288.947948) (xy 417.226643 -288.989996)
			(xy 417.189892 -289.026747) (xy 417.147844 -289.057297) (xy 417.101534 -289.080893) (xy 417.052104 -289.096954)
			(xy 417.000769 -289.105084) (xy 416.948795 -289.105084) (xy 416.89746 -289.096954) (xy 416.84803 -289.080893)
			(xy 416.80172 -289.057297) (xy 416.759672 -289.026747) (xy 416.722921 -288.989996) (xy 416.692371 -288.947948)
			(xy 416.668775 -288.901638) (xy 416.652714 -288.852208) (xy 416.644584 -288.800873) (xy 416.644074 -288.774886)
			(xy 416.644165 -288.762136) (xy 416.646072 -288.736707) (xy 416.647884 -288.724086) (xy 416.653042 -288.694978)
			(xy 416.672312 -288.639099) (xy 416.701214 -288.587538) (xy 416.719512 -288.56432) (xy 416.725284 -288.556661)
			(xy 416.731148 -288.538417) (xy 416.72987 -288.519297) (xy 416.726116 -288.510472) (xy 416.687 -288.427414)
			(xy 416.682526 -288.418914) (xy 416.668498 -288.405815) (xy 416.650625 -288.398823) (xy 416.641026 -288.398458)
			(xy 416.358578 -288.398458) (xy 416.348964 -288.398875) (xy 416.331092 -288.405971) (xy 416.317095 -288.419154)
			(xy 416.312604 -288.427668) (xy 416.266884 -288.524188) (xy 416.270694 -288.553144) (xy 416.280092 -288.564574)
			(xy 416.297748 -288.586964) (xy 416.325906 -288.636541) (xy 416.34516 -288.690208) (xy 416.354941 -288.746378)
			(xy 416.35553 -288.774886) (xy 416.35502 -288.800873) (xy 416.34689 -288.852208) (xy 416.330829 -288.901638)
			(xy 416.307233 -288.947948) (xy 416.276683 -288.989996) (xy 416.239932 -289.026747) (xy 416.197884 -289.057297)
			(xy 416.151574 -289.080893) (xy 416.102144 -289.096954) (xy 416.050809 -289.105084) (xy 415.998835 -289.105084)
			(xy 415.9475 -289.096954) (xy 415.89807 -289.080893) (xy 415.85176 -289.057297) (xy 415.809712 -289.026747)
			(xy 415.772961 -288.989996) (xy 415.742411 -288.947948) (xy 415.718815 -288.901638) (xy 415.702754 -288.852208)
			(xy 415.694624 -288.800873) (xy 415.694114 -288.774886) (xy 415.694712 -288.746379) (xy 415.704486 -288.690209)
			(xy 415.723742 -288.636545) (xy 415.751912 -288.586976) (xy 415.769552 -288.564574) (xy 415.77895 -288.553144)
			(xy 415.78276 -288.524188) (xy 415.73704 -288.427668) (xy 415.732578 -288.419136) (xy 415.718565 -288.405955)
			(xy 415.700685 -288.398854) (xy 415.691066 -288.398458) (xy 415.408618 -288.398458) (xy 415.399 -288.398868)
			(xy 415.381116 -288.405955) (xy 415.367107 -288.419137) (xy 415.362644 -288.427668) (xy 415.316924 -288.524188)
			(xy 415.320734 -288.553144) (xy 415.330132 -288.564574) (xy 415.347791 -288.586963) (xy 415.375954 -288.636539)
			(xy 415.395212 -288.690206) (xy 415.404995 -288.746378) (xy 415.40557 -288.774886) (xy 415.40506 -288.800873)
			(xy 415.39693 -288.852208) (xy 415.380869 -288.901638) (xy 415.357273 -288.947948) (xy 415.326723 -288.989996)
			(xy 415.289972 -289.026747) (xy 415.247924 -289.057297) (xy 415.201614 -289.080893) (xy 415.152184 -289.096954)
			(xy 415.100849 -289.105084) (xy 415.048875 -289.105084) (xy 414.99754 -289.096954) (xy 414.94811 -289.080893)
			(xy 414.9018 -289.057297) (xy 414.859752 -289.026747) (xy 414.823001 -288.989996) (xy 414.792451 -288.947948)
			(xy 414.768855 -288.901638) (xy 414.752794 -288.852208) (xy 414.744664 -288.800873) (xy 414.744154 -288.774886)
			(xy 414.744751 -288.746379) (xy 414.754524 -288.690208) (xy 414.773778 -288.636542) (xy 414.801943 -288.58697)
			(xy 414.819592 -288.564574) (xy 414.82899 -288.553144) (xy 414.8328 -288.524188) (xy 414.78708 -288.427668)
			(xy 414.782615 -288.419143) (xy 414.768599 -288.405978) (xy 414.750721 -288.398898) (xy 414.741106 -288.398458)
			(xy 414.458658 -288.398458) (xy 414.449036 -288.398862) (xy 414.431141 -288.40594) (xy 414.417119 -288.41912)
			(xy 414.412684 -288.427668) (xy 414.366964 -288.524188) (xy 414.370774 -288.553144) (xy 414.380172 -288.564574)
			(xy 414.397829 -288.586964) (xy 414.425989 -288.636541) (xy 414.445244 -288.690207) (xy 414.455026 -288.746378)
			(xy 414.45561 -288.774886) (xy 414.4551 -288.800873) (xy 414.44697 -288.852208) (xy 414.430909 -288.901638)
			(xy 414.407313 -288.947948) (xy 414.376763 -288.989996) (xy 414.340012 -289.026747) (xy 414.297964 -289.057297)
			(xy 414.251654 -289.080893) (xy 414.202224 -289.096954) (xy 414.150889 -289.105084) (xy 414.098915 -289.105084)
			(xy 414.04758 -289.096954) (xy 413.99815 -289.080893) (xy 413.95184 -289.057297) (xy 413.909792 -289.026747)
			(xy 413.873041 -288.989996) (xy 413.842491 -288.947948) (xy 413.818895 -288.901638) (xy 413.802834 -288.852208)
			(xy 413.794704 -288.800873) (xy 413.794194 -288.774886) (xy 413.794791 -288.746379) (xy 413.804565 -288.690209)
			(xy 413.823821 -288.636544) (xy 413.851989 -288.586974) (xy 413.869632 -288.564574) (xy 413.87903 -288.553144)
			(xy 413.88284 -288.524188) (xy 413.83712 -288.427668) (xy 413.832657 -288.419139) (xy 413.818643 -288.405963)
			(xy 413.800763 -288.398869) (xy 413.791146 -288.398458) (xy 413.508698 -288.398458) (xy 413.499082 -288.398872)
			(xy 413.481204 -288.405963) (xy 413.467201 -288.419146) (xy 413.462724 -288.427668) (xy 413.417004 -288.524188)
			(xy 413.420814 -288.553144) (xy 413.430212 -288.564574) (xy 413.447872 -288.586962) (xy 413.476037 -288.636538)
			(xy 413.495296 -288.690205) (xy 413.505079 -288.746377) (xy 413.50565 -288.774886) (xy 413.50514 -288.800873)
			(xy 413.49701 -288.852208) (xy 413.480949 -288.901638) (xy 413.457353 -288.947948) (xy 413.426803 -288.989996)
			(xy 413.390052 -289.026747) (xy 413.348004 -289.057297) (xy 413.301694 -289.080893) (xy 413.252264 -289.096954)
			(xy 413.200929 -289.105084) (xy 413.148955 -289.105084) (xy 413.09762 -289.096954) (xy 413.04819 -289.080893)
			(xy 413.00188 -289.057297) (xy 412.959832 -289.026747) (xy 412.923081 -288.989996) (xy 412.892531 -288.947948)
			(xy 412.868935 -288.901638) (xy 412.852874 -288.852208) (xy 412.844744 -288.800873) (xy 412.844234 -288.774886)
			(xy 412.844832 -288.746379) (xy 412.854607 -288.69021) (xy 412.873864 -288.636547) (xy 412.902035 -288.586979)
			(xy 412.919672 -288.564574) (xy 412.92907 -288.553144) (xy 412.93288 -288.524188) (xy 412.88716 -288.427668)
			(xy 412.882694 -288.419145) (xy 412.868677 -288.405986) (xy 412.850799 -288.398912) (xy 412.841186 -288.398458)
			(xy 412.558738 -288.398458) (xy 412.549118 -288.398865) (xy 412.531229 -288.405948) (xy 412.517213 -288.419129)
			(xy 412.512764 -288.427668) (xy 412.467044 -288.524188) (xy 412.470854 -288.553144) (xy 412.480252 -288.564574)
			(xy 412.49791 -288.586963) (xy 412.526072 -288.63654) (xy 412.545328 -288.690206) (xy 412.55511 -288.746378)
			(xy 412.55569 -288.774886) (xy 412.55518 -288.800873) (xy 412.54705 -288.852208) (xy 412.530989 -288.901638)
			(xy 412.507393 -288.947948) (xy 412.476843 -288.989996) (xy 412.440092 -289.026747) (xy 412.398044 -289.057297)
			(xy 412.351734 -289.080893) (xy 412.302304 -289.096954) (xy 412.250969 -289.105084) (xy 412.198995 -289.105084)
			(xy 412.14766 -289.096954) (xy 412.09823 -289.080893) (xy 412.05192 -289.057297) (xy 412.009872 -289.026747)
			(xy 411.973121 -288.989996) (xy 411.942571 -288.947948) (xy 411.918975 -288.901638) (xy 411.902914 -288.852208)
			(xy 411.894784 -288.800873) (xy 411.894274 -288.774886) (xy 411.894871 -288.746379) (xy 411.904645 -288.690208)
			(xy 411.923899 -288.636543) (xy 411.952066 -288.586972) (xy 411.969712 -288.564574) (xy 411.97911 -288.553144)
			(xy 411.98292 -288.524188) (xy 411.9372 -288.427668) (xy 411.932736 -288.419141) (xy 411.918721 -288.405971)
			(xy 411.900842 -288.398883) (xy 411.891226 -288.398458) (xy 411.608778 -288.398458) (xy 411.599164 -288.398875)
			(xy 411.581292 -288.405971) (xy 411.567295 -288.419154) (xy 411.562804 -288.427668) (xy 411.517084 -288.524188)
			(xy 411.520894 -288.553144) (xy 411.530292 -288.564574) (xy 411.547948 -288.586964) (xy 411.576106 -288.636541)
			(xy 411.59536 -288.690208) (xy 411.605141 -288.746378) (xy 411.60573 -288.774886) (xy 411.60522 -288.800873)
			(xy 411.59709 -288.852208) (xy 411.581029 -288.901638) (xy 411.557433 -288.947948) (xy 411.526883 -288.989996)
			(xy 411.490132 -289.026747) (xy 411.448084 -289.057297) (xy 411.401774 -289.080893) (xy 411.352344 -289.096954)
			(xy 411.301009 -289.105084) (xy 411.249035 -289.105084) (xy 411.1977 -289.096954) (xy 411.14827 -289.080893)
			(xy 411.10196 -289.057297) (xy 411.059912 -289.026747) (xy 411.023161 -288.989996) (xy 410.992611 -288.947948)
			(xy 410.969015 -288.901638) (xy 410.952954 -288.852208) (xy 410.944824 -288.800873) (xy 410.944314 -288.774886)
			(xy 410.944912 -288.746379) (xy 410.954686 -288.690209) (xy 410.973942 -288.636545) (xy 411.002112 -288.586976)
			(xy 411.019752 -288.564574) (xy 411.02915 -288.553144) (xy 411.03296 -288.524188) (xy 410.98724 -288.427668)
			(xy 410.982778 -288.419136) (xy 410.968765 -288.405955) (xy 410.950885 -288.398854) (xy 410.941266 -288.398458)
			(xy 410.658564 -288.398458) (xy 410.648951 -288.398878) (xy 410.631084 -288.405976) (xy 410.61709 -288.41916)
			(xy 410.61259 -288.427668) (xy 410.56687 -288.524188) (xy 410.57068 -288.553144) (xy 410.580078 -288.564574)
			(xy 410.597735 -288.586964) (xy 410.625894 -288.636541) (xy 410.645149 -288.690207) (xy 410.654931 -288.746378)
			(xy 410.655516 -288.774886) (xy 410.655006 -288.800873) (xy 410.646876 -288.852208) (xy 410.630815 -288.901638)
			(xy 410.607219 -288.947948) (xy 410.576669 -288.989996) (xy 410.539918 -289.026747) (xy 410.49787 -289.057297)
			(xy 410.45156 -289.080893) (xy 410.40213 -289.096954) (xy 410.350795 -289.105084) (xy 410.298821 -289.105084)
			(xy 410.247486 -289.096954) (xy 410.198056 -289.080893) (xy 410.151746 -289.057297) (xy 410.109698 -289.026747)
			(xy 410.072947 -288.989996) (xy 410.042397 -288.947948) (xy 410.018801 -288.901638) (xy 410.00274 -288.852208)
			(xy 409.99461 -288.800873) (xy 409.9941 -288.774886) (xy 409.994697 -288.746379) (xy 410.004471 -288.690209)
			(xy 410.023727 -288.636545) (xy 410.051896 -288.586975) (xy 410.069538 -288.564574) (xy 410.078936 -288.553144)
			(xy 410.082746 -288.524188) (xy 410.037026 -288.427668) (xy 410.032563 -288.419138) (xy 410.018549 -288.405961)
			(xy 410.00067 -288.398865) (xy 409.991052 -288.398458) (xy 409.708604 -288.398458) (xy 409.698987 -288.398871)
			(xy 409.681108 -288.405961) (xy 409.667103 -288.419143) (xy 409.66263 -288.427668) (xy 409.61691 -288.524188)
			(xy 409.62072 -288.553144) (xy 409.630118 -288.564574) (xy 409.647778 -288.586962) (xy 409.675942 -288.636538)
			(xy 409.6952 -288.690205) (xy 409.704984 -288.746377) (xy 409.705556 -288.774886) (xy 409.705046 -288.800873)
			(xy 409.696916 -288.852208) (xy 409.680855 -288.901638) (xy 409.657259 -288.947948) (xy 409.626709 -288.989996)
			(xy 409.589958 -289.026747) (xy 409.54791 -289.057297) (xy 409.5016 -289.080893) (xy 409.45217 -289.096954)
			(xy 409.400835 -289.105084) (xy 409.348861 -289.105084) (xy 409.297526 -289.096954) (xy 409.248096 -289.080893)
			(xy 409.201786 -289.057297) (xy 409.159738 -289.026747) (xy 409.122987 -288.989996) (xy 409.092437 -288.947948)
			(xy 409.068841 -288.901638) (xy 409.05278 -288.852208) (xy 409.04465 -288.800873) (xy 409.04414 -288.774886)
			(xy 409.044738 -288.746379) (xy 409.054513 -288.69021) (xy 409.073771 -288.636547) (xy 409.101942 -288.586979)
			(xy 409.119578 -288.564574) (xy 409.128976 -288.553144) (xy 409.132786 -288.524188) (xy 409.087066 -288.427668)
			(xy 409.0826 -288.419145) (xy 409.068583 -288.405984) (xy 409.050706 -288.398908) (xy 409.041092 -288.398458)
			(xy 408.758644 -288.398458) (xy 408.749023 -288.398864) (xy 408.731132 -288.405945) (xy 408.717115 -288.419126)
			(xy 408.71267 -288.427668) (xy 408.66695 -288.524188) (xy 408.67076 -288.553144) (xy 408.680158 -288.564574)
			(xy 408.697816 -288.586963) (xy 408.725977 -288.63654) (xy 408.745233 -288.690207) (xy 408.755015 -288.746378)
			(xy 408.755596 -288.774886) (xy 408.755086 -288.800873) (xy 408.746956 -288.852208) (xy 408.730895 -288.901638)
			(xy 408.707299 -288.947948) (xy 408.676749 -288.989996) (xy 408.639998 -289.026747) (xy 408.59795 -289.057297)
			(xy 408.55164 -289.080893) (xy 408.50221 -289.096954) (xy 408.450875 -289.105084) (xy 408.398901 -289.105084)
			(xy 408.347566 -289.096954) (xy 408.298136 -289.080893) (xy 408.251826 -289.057297) (xy 408.209778 -289.026747)
			(xy 408.173027 -288.989996) (xy 408.142477 -288.947948) (xy 408.118881 -288.901638) (xy 408.10282 -288.852208)
			(xy 408.09469 -288.800873) (xy 408.09418 -288.774886) (xy 408.094777 -288.746379) (xy 408.104551 -288.690208)
			(xy 408.123806 -288.636544) (xy 408.151973 -288.586973) (xy 408.169618 -288.564574) (xy 408.179016 -288.553144)
			(xy 408.182826 -288.524188) (xy 408.137106 -288.427668) (xy 408.132642 -288.41914) (xy 408.118627 -288.405968)
			(xy 408.100748 -288.398879) (xy 408.091132 -288.398458) (xy 406.858724 -288.398458) (xy 406.849105 -288.398867)
			(xy 406.83122 -288.405953) (xy 406.817209 -288.419135) (xy 406.81275 -288.427668) (xy 406.76703 -288.524188)
			(xy 406.77084 -288.553144) (xy 406.780238 -288.564574) (xy 406.797897 -288.586963) (xy 406.826059 -288.636539)
			(xy 406.845317 -288.690206) (xy 406.855099 -288.746378) (xy 406.855676 -288.774886) (xy 406.855166 -288.800873)
			(xy 406.847036 -288.852208) (xy 406.830975 -288.901638) (xy 406.807379 -288.947948) (xy 406.776829 -288.989996)
			(xy 406.740078 -289.026747) (xy 406.69803 -289.057297) (xy 406.65172 -289.080893) (xy 406.60229 -289.096954)
			(xy 406.550955 -289.105084) (xy 406.498981 -289.105084) (xy 406.447646 -289.096954) (xy 406.398216 -289.080893)
			(xy 406.351906 -289.057297) (xy 406.309858 -289.026747) (xy 406.273107 -288.989996) (xy 406.242557 -288.947948)
			(xy 406.218961 -288.901638) (xy 406.2029 -288.852208) (xy 406.19477 -288.800873) (xy 406.19426 -288.774886)
			(xy 406.194857 -288.746379) (xy 406.20463 -288.690208) (xy 406.223884 -288.636542) (xy 406.25205 -288.586971)
			(xy 406.269698 -288.564574) (xy 406.279096 -288.553144) (xy 406.282906 -288.524188) (xy 406.237186 -288.427668)
			(xy 406.232721 -288.419142) (xy 406.218705 -288.405976) (xy 406.200827 -288.398893) (xy 406.191212 -288.398458)
			(xy 405.908764 -288.398458) (xy 405.899151 -288.398878) (xy 405.881284 -288.405976) (xy 405.86729 -288.41916)
			(xy 405.86279 -288.427668) (xy 405.81707 -288.524188) (xy 405.82088 -288.553144) (xy 405.830278 -288.564574)
			(xy 405.847935 -288.586964) (xy 405.876094 -288.636541) (xy 405.895349 -288.690207) (xy 405.905131 -288.746378)
			(xy 405.905716 -288.774886) (xy 405.905206 -288.800873) (xy 405.897076 -288.852208) (xy 405.881015 -288.901638)
			(xy 405.857419 -288.947948) (xy 405.826869 -288.989996) (xy 405.790118 -289.026747) (xy 405.74807 -289.057297)
			(xy 405.70176 -289.080893) (xy 405.65233 -289.096954) (xy 405.600995 -289.105084) (xy 405.549021 -289.105084)
			(xy 405.497686 -289.096954) (xy 405.448256 -289.080893) (xy 405.401946 -289.057297) (xy 405.359898 -289.026747)
			(xy 405.323147 -288.989996) (xy 405.292597 -288.947948) (xy 405.269001 -288.901638) (xy 405.25294 -288.852208)
			(xy 405.24481 -288.800873) (xy 405.2443 -288.774886) (xy 405.244897 -288.746379) (xy 405.254671 -288.690209)
			(xy 405.273927 -288.636545) (xy 405.302096 -288.586975) (xy 405.319738 -288.564574) (xy 405.329136 -288.553144)
			(xy 405.332946 -288.524188) (xy 405.287226 -288.427668) (xy 405.282763 -288.419138) (xy 405.268749 -288.405961)
			(xy 405.25087 -288.398865) (xy 405.241252 -288.398458) (xy 404.95855 -288.398458) (xy 404.948928 -288.398863)
			(xy 404.931036 -288.405943) (xy 404.917017 -288.419124) (xy 404.912576 -288.427668) (xy 404.866856 -288.524188)
			(xy 404.870666 -288.553144) (xy 404.880064 -288.564574) (xy 404.897722 -288.586963) (xy 404.925882 -288.63654)
			(xy 404.945138 -288.690207) (xy 404.95492 -288.746378) (xy 404.955502 -288.774886) (xy 404.954992 -288.800873)
			(xy 404.946862 -288.852208) (xy 404.930801 -288.901638) (xy 404.907205 -288.947948) (xy 404.876655 -288.989996)
			(xy 404.839904 -289.026747) (xy 404.797856 -289.057297) (xy 404.751546 -289.080893) (xy 404.702116 -289.096954)
			(xy 404.650781 -289.105084) (xy 404.598807 -289.105084) (xy 404.547472 -289.096954) (xy 404.498042 -289.080893)
			(xy 404.451732 -289.057297) (xy 404.409684 -289.026747) (xy 404.372933 -288.989996) (xy 404.342383 -288.947948)
			(xy 404.318787 -288.901638) (xy 404.302726 -288.852208) (xy 404.294596 -288.800873) (xy 404.294086 -288.774886)
			(xy 404.294683 -288.746379) (xy 404.304457 -288.690208) (xy 404.323712 -288.636544) (xy 404.35188 -288.586973)
			(xy 404.369524 -288.564574) (xy 404.378922 -288.553144) (xy 404.382732 -288.524188) (xy 404.337012 -288.427668)
			(xy 404.332549 -288.41914) (xy 404.318534 -288.405966) (xy 404.300655 -288.398875) (xy 404.291038 -288.398458)
			(xy 404.00859 -288.398458) (xy 403.998975 -288.398873) (xy 403.981099 -288.405966) (xy 403.967098 -288.419149)
			(xy 403.962616 -288.427668) (xy 403.916896 -288.524188) (xy 403.920706 -288.553144) (xy 403.930104 -288.564574)
			(xy 403.94776 -288.586964) (xy 403.975917 -288.636542) (xy 403.99517 -288.690208) (xy 404.004951 -288.746378)
			(xy 404.005542 -288.774886) (xy 404.005032 -288.800873) (xy 403.996902 -288.852208) (xy 403.980841 -288.901638)
			(xy 403.957245 -288.947948) (xy 403.926695 -288.989996) (xy 403.889944 -289.026747) (xy 403.847896 -289.057297)
			(xy 403.801586 -289.080893) (xy 403.752156 -289.096954) (xy 403.700821 -289.105084) (xy 403.648847 -289.105084)
			(xy 403.597512 -289.096954) (xy 403.548082 -289.080893) (xy 403.501772 -289.057297) (xy 403.459724 -289.026747)
			(xy 403.422973 -288.989996) (xy 403.392423 -288.947948) (xy 403.368827 -288.901638) (xy 403.352766 -288.852208)
			(xy 403.344636 -288.800873) (xy 403.344126 -288.774886) (xy 403.344724 -288.746379) (xy 403.354498 -288.690209)
			(xy 403.373755 -288.636546) (xy 403.401925 -288.586978) (xy 403.419564 -288.564574) (xy 403.428962 -288.553144)
			(xy 403.432772 -288.524188) (xy 403.387052 -288.427668) (xy 403.382586 -288.419146) (xy 403.368568 -288.405989)
			(xy 403.350691 -288.398918) (xy 403.341078 -288.398458) (xy 403.05863 -288.398458) (xy 403.04901 -288.398866)
			(xy 403.031124 -288.405951) (xy 403.017111 -288.419132) (xy 403.012656 -288.427668) (xy 402.966936 -288.524188)
			(xy 402.970746 -288.553144) (xy 402.980144 -288.564574) (xy 402.997803 -288.586963) (xy 403.025965 -288.63654)
			(xy 403.045221 -288.690206) (xy 403.055004 -288.746378) (xy 403.055582 -288.774886) (xy 403.055072 -288.800873)
			(xy 403.046942 -288.852208) (xy 403.030881 -288.901638) (xy 403.007285 -288.947948) (xy 402.976735 -288.989996)
			(xy 402.939984 -289.026747) (xy 402.897936 -289.057297) (xy 402.851626 -289.080893) (xy 402.802196 -289.096954)
			(xy 402.750861 -289.105084) (xy 402.698887 -289.105084) (xy 402.647552 -289.096954) (xy 402.598122 -289.080893)
			(xy 402.551812 -289.057297) (xy 402.509764 -289.026747) (xy 402.473013 -288.989996) (xy 402.442463 -288.947948)
			(xy 402.418867 -288.901638) (xy 402.402806 -288.852208) (xy 402.394676 -288.800873) (xy 402.394166 -288.774886)
			(xy 402.394763 -288.746379) (xy 402.404536 -288.690208) (xy 402.423791 -288.636543) (xy 402.451957 -288.586971)
			(xy 402.469604 -288.564574) (xy 402.479002 -288.553144) (xy 402.482812 -288.524188) (xy 402.437092 -288.427668)
			(xy 402.432628 -288.419142) (xy 402.418612 -288.405974) (xy 402.400733 -288.398889) (xy 402.391118 -288.398458)
			(xy 402.10867 -288.398458) (xy 402.099057 -288.398877) (xy 402.081187 -288.405974) (xy 402.067192 -288.419158)
			(xy 402.062696 -288.427668) (xy 402.016976 -288.524188) (xy 402.020786 -288.553144) (xy 402.030184 -288.564574)
			(xy 402.047841 -288.586964) (xy 402.075999 -288.636541) (xy 402.095254 -288.690208) (xy 402.105035 -288.746378)
			(xy 402.105622 -288.774886) (xy 402.105112 -288.800873) (xy 402.096982 -288.852208) (xy 402.080921 -288.901638)
			(xy 402.057325 -288.947948) (xy 402.026775 -288.989996) (xy 401.990024 -289.026747) (xy 401.947976 -289.057297)
			(xy 401.901666 -289.080893) (xy 401.852236 -289.096954) (xy 401.800901 -289.105084) (xy 401.748927 -289.105084)
			(xy 401.697592 -289.096954) (xy 401.648162 -289.080893) (xy 401.601852 -289.057297) (xy 401.559804 -289.026747)
			(xy 401.523053 -288.989996) (xy 401.492503 -288.947948) (xy 401.468907 -288.901638) (xy 401.452846 -288.852208)
			(xy 401.444716 -288.800873) (xy 401.444206 -288.774886) (xy 401.444803 -288.746379) (xy 401.454577 -288.690209)
			(xy 401.473834 -288.636545) (xy 401.502003 -288.586975) (xy 401.519644 -288.564574) (xy 401.529042 -288.553144)
			(xy 401.532852 -288.524188) (xy 401.487132 -288.427668) (xy 401.482669 -288.419137) (xy 401.468656 -288.405959)
			(xy 401.450776 -288.39886) (xy 401.441158 -288.398458) (xy 401.15871 -288.398458) (xy 401.149093 -288.39887)
			(xy 401.131212 -288.405959) (xy 401.117204 -288.419141) (xy 401.112736 -288.427668) (xy 401.067016 -288.524188)
			(xy 401.070826 -288.553144) (xy 401.080224 -288.564574) (xy 401.097883 -288.586963) (xy 401.126047 -288.636539)
			(xy 401.145305 -288.690206) (xy 401.155089 -288.746377) (xy 401.155662 -288.774886) (xy 401.155152 -288.800873)
			(xy 401.147022 -288.852208) (xy 401.130961 -288.901638) (xy 401.107365 -288.947948) (xy 401.076815 -288.989996)
			(xy 401.040064 -289.026747) (xy 400.998016 -289.057297) (xy 400.951706 -289.080893) (xy 400.902276 -289.096954)
			(xy 400.850941 -289.105084) (xy 400.798967 -289.105084) (xy 400.747632 -289.096954) (xy 400.698202 -289.080893)
			(xy 400.651892 -289.057297) (xy 400.609844 -289.026747) (xy 400.573093 -288.989996) (xy 400.542543 -288.947948)
			(xy 400.518947 -288.901638) (xy 400.502886 -288.852208) (xy 400.494756 -288.800873) (xy 400.494246 -288.774886)
			(xy 400.494843 -288.746379) (xy 400.504616 -288.690207) (xy 400.523869 -288.636542) (xy 400.552034 -288.586969)
			(xy 400.569684 -288.564574) (xy 400.579082 -288.553144) (xy 400.582892 -288.524188) (xy 400.537172 -288.427668)
			(xy 400.532706 -288.419144) (xy 400.51869 -288.405982) (xy 400.500812 -288.398904) (xy 400.491198 -288.398458)
			(xy 400.20875 -288.398458) (xy 400.199128 -288.398863) (xy 400.181236 -288.405943) (xy 400.167217 -288.419124)
			(xy 400.162776 -288.427668) (xy 400.117056 -288.524188) (xy 400.120866 -288.553144) (xy 400.130264 -288.564574)
			(xy 400.147922 -288.586963) (xy 400.176082 -288.63654) (xy 400.195338 -288.690207) (xy 400.20512 -288.746378)
			(xy 400.205702 -288.774886) (xy 400.205192 -288.800873) (xy 400.197062 -288.852208) (xy 400.181001 -288.901638)
			(xy 400.157405 -288.947948) (xy 400.126855 -288.989996) (xy 400.090104 -289.026747) (xy 400.048056 -289.057297)
			(xy 400.001746 -289.080893) (xy 399.952316 -289.096954) (xy 399.900981 -289.105084) (xy 399.849007 -289.105084)
			(xy 399.797672 -289.096954) (xy 399.748242 -289.080893) (xy 399.701932 -289.057297) (xy 399.659884 -289.026747)
			(xy 399.623133 -288.989996) (xy 399.592583 -288.947948) (xy 399.568987 -288.901638) (xy 399.552926 -288.852208)
			(xy 399.544796 -288.800873) (xy 399.544286 -288.774886) (xy 399.544883 -288.746379) (xy 399.554657 -288.690208)
			(xy 399.573912 -288.636544) (xy 399.60208 -288.586973) (xy 399.619724 -288.564574) (xy 399.629122 -288.553144)
			(xy 399.632932 -288.524188) (xy 399.587212 -288.427668) (xy 399.582749 -288.41914) (xy 399.568734 -288.405966)
			(xy 399.550855 -288.398875) (xy 399.541238 -288.398458) (xy 399.25879 -288.398458) (xy 399.249175 -288.398873)
			(xy 399.231299 -288.405966) (xy 399.217298 -288.419149) (xy 399.212816 -288.427668) (xy 399.167096 -288.524188)
			(xy 399.170906 -288.553144) (xy 399.180304 -288.564574) (xy 399.19796 -288.586964) (xy 399.226117 -288.636542)
			(xy 399.24537 -288.690208) (xy 399.255151 -288.746378) (xy 399.255742 -288.774886) (xy 399.255232 -288.800873)
			(xy 399.247102 -288.852208) (xy 399.231041 -288.901638) (xy 399.207445 -288.947948) (xy 399.176895 -288.989996)
			(xy 399.140144 -289.026747) (xy 399.098096 -289.057297) (xy 399.051786 -289.080893) (xy 399.002356 -289.096954)
			(xy 398.951021 -289.105084) (xy 398.899047 -289.105084) (xy 398.847712 -289.096954) (xy 398.798282 -289.080893)
			(xy 398.751972 -289.057297) (xy 398.709924 -289.026747) (xy 398.673173 -288.989996) (xy 398.642623 -288.947948)
			(xy 398.619027 -288.901638) (xy 398.602966 -288.852208) (xy 398.594836 -288.800873) (xy 398.594326 -288.774886)
			(xy 398.594924 -288.746379) (xy 398.604698 -288.690209) (xy 398.623955 -288.636546) (xy 398.652125 -288.586978)
			(xy 398.669764 -288.564574) (xy 398.679162 -288.553144) (xy 398.682972 -288.524188) (xy 398.637252 -288.427668)
			(xy 398.632786 -288.419146) (xy 398.618768 -288.405989) (xy 398.600891 -288.398918) (xy 398.591278 -288.398458)
			(xy 398.382744 -288.398458) (xy 398.37268 -288.398893) (xy 398.354095 -288.406628) (xy 398.346676 -288.413444)
			(xy 398.233138 -288.526982) (xy 398.230344 -288.564066) (xy 398.24152 -288.579306) (xy 398.256598 -288.600706)
			(xy 398.280519 -288.647267) (xy 398.296802 -288.697018) (xy 398.305039 -288.748712) (xy 398.305528 -288.774886)
			(xy 398.30502 -288.800874) (xy 398.296891 -288.852212) (xy 398.280831 -288.901646) (xy 398.257237 -288.947958)
			(xy 398.226687 -288.99001) (xy 398.189936 -289.026765) (xy 398.147887 -289.057319) (xy 398.101577 -289.080918)
			(xy 398.052145 -289.096983) (xy 398.000808 -289.105117) (xy 397.97482 -289.105594) (xy 397.948646 -289.105098)
			(xy 397.896952 -289.09686) (xy 397.847199 -289.080584) (xy 397.800629 -289.056678) (xy 397.77924 -289.041586)
			(xy 397.764 -289.03041) (xy 397.726916 -289.033204) (xy 397.416274 -289.343846) (xy 397.408877 -289.350694)
			(xy 397.390278 -289.358428) (xy 397.380206 -289.358832) (xy 397.366744 -289.358832) (xy 397.357312 -289.359327)
			(xy 397.339755 -289.366246) (xy 397.325868 -289.379023) (xy 397.321278 -289.38728) (xy 397.274542 -289.482276)
			(xy 397.27759 -289.510978) (xy 397.28648 -289.522662) (xy 397.30269 -289.544525) (xy 397.328485 -289.592448)
			(xy 397.346082 -289.643948) (xy 397.355005 -289.697634) (xy 397.355568 -289.724846) (xy 397.355058 -289.750833)
			(xy 397.644622 -289.750833) (xy 397.644622 -289.698859) (xy 397.652752 -289.647524) (xy 397.668813 -289.598094)
			(xy 397.692409 -289.551784) (xy 397.722959 -289.509736) (xy 397.75971 -289.472985) (xy 397.801758 -289.442435)
			(xy 397.848068 -289.418839) (xy 397.897498 -289.402778) (xy 397.948833 -289.394648) (xy 398.000807 -289.394648)
			(xy 398.052142 -289.402778) (xy 398.101572 -289.418839) (xy 398.147882 -289.442435) (xy 398.18993 -289.472985)
			(xy 398.226681 -289.509736) (xy 398.257231 -289.551784) (xy 398.280827 -289.598094) (xy 398.296888 -289.647524)
			(xy 398.305018 -289.698859) (xy 398.305528 -289.724846) (xy 398.305018 -289.750833) (xy 398.594836 -289.750833)
			(xy 398.594836 -289.698859) (xy 398.602966 -289.647524) (xy 398.619027 -289.598094) (xy 398.642623 -289.551784)
			(xy 398.673173 -289.509736) (xy 398.709924 -289.472985) (xy 398.751972 -289.442435) (xy 398.798282 -289.418839)
			(xy 398.847712 -289.402778) (xy 398.899047 -289.394648) (xy 398.951021 -289.394648) (xy 399.002356 -289.402778)
			(xy 399.051786 -289.418839) (xy 399.098096 -289.442435) (xy 399.140144 -289.472985) (xy 399.176895 -289.509736)
			(xy 399.207445 -289.551784) (xy 399.231041 -289.598094) (xy 399.247102 -289.647524) (xy 399.255232 -289.698859)
			(xy 399.255742 -289.724846) (xy 399.255232 -289.750833) (xy 399.544796 -289.750833) (xy 399.544796 -289.698859)
			(xy 399.552926 -289.647524) (xy 399.568987 -289.598094) (xy 399.592583 -289.551784) (xy 399.623133 -289.509736)
			(xy 399.659884 -289.472985) (xy 399.701932 -289.442435) (xy 399.748242 -289.418839) (xy 399.797672 -289.402778)
			(xy 399.849007 -289.394648) (xy 399.900981 -289.394648) (xy 399.952316 -289.402778) (xy 400.001746 -289.418839)
			(xy 400.048056 -289.442435) (xy 400.090104 -289.472985) (xy 400.126855 -289.509736) (xy 400.157405 -289.551784)
			(xy 400.181001 -289.598094) (xy 400.197062 -289.647524) (xy 400.205192 -289.698859) (xy 400.205702 -289.724846)
			(xy 400.205192 -289.750833) (xy 400.494756 -289.750833) (xy 400.494756 -289.698859) (xy 400.502886 -289.647524)
			(xy 400.518947 -289.598094) (xy 400.542543 -289.551784) (xy 400.573093 -289.509736) (xy 400.609844 -289.472985)
			(xy 400.651892 -289.442435) (xy 400.698202 -289.418839) (xy 400.747632 -289.402778) (xy 400.798967 -289.394648)
			(xy 400.850941 -289.394648) (xy 400.902276 -289.402778) (xy 400.951706 -289.418839) (xy 400.998016 -289.442435)
			(xy 401.040064 -289.472985) (xy 401.076815 -289.509736) (xy 401.107365 -289.551784) (xy 401.130961 -289.598094)
			(xy 401.147022 -289.647524) (xy 401.155152 -289.698859) (xy 401.155662 -289.724846) (xy 401.155152 -289.750833)
			(xy 401.444716 -289.750833) (xy 401.444716 -289.698859) (xy 401.452846 -289.647524) (xy 401.468907 -289.598094)
			(xy 401.492503 -289.551784) (xy 401.523053 -289.509736) (xy 401.559804 -289.472985) (xy 401.601852 -289.442435)
			(xy 401.648162 -289.418839) (xy 401.697592 -289.402778) (xy 401.748927 -289.394648) (xy 401.800901 -289.394648)
			(xy 401.852236 -289.402778) (xy 401.901666 -289.418839) (xy 401.947976 -289.442435) (xy 401.990024 -289.472985)
			(xy 402.026775 -289.509736) (xy 402.057325 -289.551784) (xy 402.080921 -289.598094) (xy 402.096982 -289.647524)
			(xy 402.105112 -289.698859) (xy 402.105622 -289.724846) (xy 402.105112 -289.750833) (xy 402.394676 -289.750833)
			(xy 402.394676 -289.698859) (xy 402.402806 -289.647524) (xy 402.418867 -289.598094) (xy 402.442463 -289.551784)
			(xy 402.473013 -289.509736) (xy 402.509764 -289.472985) (xy 402.551812 -289.442435) (xy 402.598122 -289.418839)
			(xy 402.647552 -289.402778) (xy 402.698887 -289.394648) (xy 402.750861 -289.394648) (xy 402.802196 -289.402778)
			(xy 402.851626 -289.418839) (xy 402.897936 -289.442435) (xy 402.939984 -289.472985) (xy 402.976735 -289.509736)
			(xy 403.007285 -289.551784) (xy 403.030881 -289.598094) (xy 403.046942 -289.647524) (xy 403.055072 -289.698859)
			(xy 403.055582 -289.724846) (xy 403.055072 -289.750833) (xy 403.344636 -289.750833) (xy 403.344636 -289.698859)
			(xy 403.352766 -289.647524) (xy 403.368827 -289.598094) (xy 403.392423 -289.551784) (xy 403.422973 -289.509736)
			(xy 403.459724 -289.472985) (xy 403.501772 -289.442435) (xy 403.548082 -289.418839) (xy 403.597512 -289.402778)
			(xy 403.648847 -289.394648) (xy 403.700821 -289.394648) (xy 403.752156 -289.402778) (xy 403.801586 -289.418839)
			(xy 403.847896 -289.442435) (xy 403.889944 -289.472985) (xy 403.926695 -289.509736) (xy 403.957245 -289.551784)
			(xy 403.980841 -289.598094) (xy 403.996902 -289.647524) (xy 404.005032 -289.698859) (xy 404.005542 -289.724846)
			(xy 404.005032 -289.750833) (xy 404.294596 -289.750833) (xy 404.294596 -289.698859) (xy 404.302726 -289.647524)
			(xy 404.318787 -289.598094) (xy 404.342383 -289.551784) (xy 404.372933 -289.509736) (xy 404.409684 -289.472985)
			(xy 404.451732 -289.442435) (xy 404.498042 -289.418839) (xy 404.547472 -289.402778) (xy 404.598807 -289.394648)
			(xy 404.650781 -289.394648) (xy 404.702116 -289.402778) (xy 404.751546 -289.418839) (xy 404.797856 -289.442435)
			(xy 404.839904 -289.472985) (xy 404.876655 -289.509736) (xy 404.907205 -289.551784) (xy 404.930801 -289.598094)
			(xy 404.946862 -289.647524) (xy 404.954992 -289.698859) (xy 404.955502 -289.724846) (xy 404.954992 -289.750833)
			(xy 405.24481 -289.750833) (xy 405.24481 -289.698859) (xy 405.25294 -289.647524) (xy 405.269001 -289.598094)
			(xy 405.292597 -289.551784) (xy 405.323147 -289.509736) (xy 405.359898 -289.472985) (xy 405.401946 -289.442435)
			(xy 405.448256 -289.418839) (xy 405.497686 -289.402778) (xy 405.549021 -289.394648) (xy 405.600995 -289.394648)
			(xy 405.65233 -289.402778) (xy 405.70176 -289.418839) (xy 405.74807 -289.442435) (xy 405.790118 -289.472985)
			(xy 405.826869 -289.509736) (xy 405.857419 -289.551784) (xy 405.881015 -289.598094) (xy 405.897076 -289.647524)
			(xy 405.905206 -289.698859) (xy 405.905716 -289.724846) (xy 405.905206 -289.750833) (xy 406.19477 -289.750833)
			(xy 406.19477 -289.698859) (xy 406.2029 -289.647524) (xy 406.218961 -289.598094) (xy 406.242557 -289.551784)
			(xy 406.273107 -289.509736) (xy 406.309858 -289.472985) (xy 406.351906 -289.442435) (xy 406.398216 -289.418839)
			(xy 406.447646 -289.402778) (xy 406.498981 -289.394648) (xy 406.550955 -289.394648) (xy 406.60229 -289.402778)
			(xy 406.65172 -289.418839) (xy 406.69803 -289.442435) (xy 406.740078 -289.472985) (xy 406.776829 -289.509736)
			(xy 406.807379 -289.551784) (xy 406.830975 -289.598094) (xy 406.847036 -289.647524) (xy 406.855166 -289.698859)
			(xy 406.855676 -289.724846) (xy 406.855166 -289.750833) (xy 408.09469 -289.750833) (xy 408.09469 -289.698859)
			(xy 408.10282 -289.647524) (xy 408.118881 -289.598094) (xy 408.142477 -289.551784) (xy 408.173027 -289.509736)
			(xy 408.209778 -289.472985) (xy 408.251826 -289.442435) (xy 408.298136 -289.418839) (xy 408.347566 -289.402778)
			(xy 408.398901 -289.394648) (xy 408.450875 -289.394648) (xy 408.50221 -289.402778) (xy 408.55164 -289.418839)
			(xy 408.59795 -289.442435) (xy 408.639998 -289.472985) (xy 408.676749 -289.509736) (xy 408.707299 -289.551784)
			(xy 408.730895 -289.598094) (xy 408.746956 -289.647524) (xy 408.755086 -289.698859) (xy 408.755596 -289.724846)
			(xy 408.755086 -289.750833) (xy 409.04465 -289.750833) (xy 409.04465 -289.698859) (xy 409.05278 -289.647524)
			(xy 409.068841 -289.598094) (xy 409.092437 -289.551784) (xy 409.122987 -289.509736) (xy 409.159738 -289.472985)
			(xy 409.201786 -289.442435) (xy 409.248096 -289.418839) (xy 409.297526 -289.402778) (xy 409.348861 -289.394648)
			(xy 409.400835 -289.394648) (xy 409.45217 -289.402778) (xy 409.5016 -289.418839) (xy 409.54791 -289.442435)
			(xy 409.589958 -289.472985) (xy 409.626709 -289.509736) (xy 409.657259 -289.551784) (xy 409.680855 -289.598094)
			(xy 409.696916 -289.647524) (xy 409.705046 -289.698859) (xy 409.705556 -289.724846) (xy 409.705046 -289.750833)
			(xy 409.99461 -289.750833) (xy 409.99461 -289.698859) (xy 410.00274 -289.647524) (xy 410.018801 -289.598094)
			(xy 410.042397 -289.551784) (xy 410.072947 -289.509736) (xy 410.109698 -289.472985) (xy 410.151746 -289.442435)
			(xy 410.198056 -289.418839) (xy 410.247486 -289.402778) (xy 410.298821 -289.394648) (xy 410.350795 -289.394648)
			(xy 410.40213 -289.402778) (xy 410.45156 -289.418839) (xy 410.49787 -289.442435) (xy 410.539918 -289.472985)
			(xy 410.576669 -289.509736) (xy 410.607219 -289.551784) (xy 410.630815 -289.598094) (xy 410.646876 -289.647524)
			(xy 410.655006 -289.698859) (xy 410.655516 -289.724846) (xy 410.655006 -289.750833) (xy 410.944824 -289.750833)
			(xy 410.944824 -289.698859) (xy 410.952954 -289.647524) (xy 410.969015 -289.598094) (xy 410.992611 -289.551784)
			(xy 411.023161 -289.509736) (xy 411.059912 -289.472985) (xy 411.10196 -289.442435) (xy 411.14827 -289.418839)
			(xy 411.1977 -289.402778) (xy 411.249035 -289.394648) (xy 411.301009 -289.394648) (xy 411.352344 -289.402778)
			(xy 411.401774 -289.418839) (xy 411.448084 -289.442435) (xy 411.490132 -289.472985) (xy 411.526883 -289.509736)
			(xy 411.557433 -289.551784) (xy 411.581029 -289.598094) (xy 411.59709 -289.647524) (xy 411.60522 -289.698859)
			(xy 411.60573 -289.724846) (xy 411.60522 -289.750833) (xy 411.894784 -289.750833) (xy 411.894784 -289.698859)
			(xy 411.902914 -289.647524) (xy 411.918975 -289.598094) (xy 411.942571 -289.551784) (xy 411.973121 -289.509736)
			(xy 412.009872 -289.472985) (xy 412.05192 -289.442435) (xy 412.09823 -289.418839) (xy 412.14766 -289.402778)
			(xy 412.198995 -289.394648) (xy 412.250969 -289.394648) (xy 412.302304 -289.402778) (xy 412.351734 -289.418839)
			(xy 412.398044 -289.442435) (xy 412.440092 -289.472985) (xy 412.476843 -289.509736) (xy 412.507393 -289.551784)
			(xy 412.530989 -289.598094) (xy 412.54705 -289.647524) (xy 412.55518 -289.698859) (xy 412.55569 -289.724846)
			(xy 412.55518 -289.750833) (xy 412.844744 -289.750833) (xy 412.844744 -289.698859) (xy 412.852874 -289.647524)
			(xy 412.868935 -289.598094) (xy 412.892531 -289.551784) (xy 412.923081 -289.509736) (xy 412.959832 -289.472985)
			(xy 413.00188 -289.442435) (xy 413.04819 -289.418839) (xy 413.09762 -289.402778) (xy 413.148955 -289.394648)
			(xy 413.200929 -289.394648) (xy 413.252264 -289.402778) (xy 413.301694 -289.418839) (xy 413.348004 -289.442435)
			(xy 413.390052 -289.472985) (xy 413.426803 -289.509736) (xy 413.457353 -289.551784) (xy 413.480949 -289.598094)
			(xy 413.49701 -289.647524) (xy 413.50514 -289.698859) (xy 413.50565 -289.724846) (xy 413.50514 -289.750833)
			(xy 413.794704 -289.750833) (xy 413.794704 -289.698859) (xy 413.802834 -289.647524) (xy 413.818895 -289.598094)
			(xy 413.842491 -289.551784) (xy 413.873041 -289.509736) (xy 413.909792 -289.472985) (xy 413.95184 -289.442435)
			(xy 413.99815 -289.418839) (xy 414.04758 -289.402778) (xy 414.098915 -289.394648) (xy 414.150889 -289.394648)
			(xy 414.202224 -289.402778) (xy 414.251654 -289.418839) (xy 414.297964 -289.442435) (xy 414.340012 -289.472985)
			(xy 414.376763 -289.509736) (xy 414.407313 -289.551784) (xy 414.430909 -289.598094) (xy 414.44697 -289.647524)
			(xy 414.4551 -289.698859) (xy 414.45561 -289.724846) (xy 414.4551 -289.750833) (xy 414.744664 -289.750833)
			(xy 414.744664 -289.698859) (xy 414.752794 -289.647524) (xy 414.768855 -289.598094) (xy 414.792451 -289.551784)
			(xy 414.823001 -289.509736) (xy 414.859752 -289.472985) (xy 414.9018 -289.442435) (xy 414.94811 -289.418839)
			(xy 414.99754 -289.402778) (xy 415.048875 -289.394648) (xy 415.100849 -289.394648) (xy 415.152184 -289.402778)
			(xy 415.201614 -289.418839) (xy 415.247924 -289.442435) (xy 415.289972 -289.472985) (xy 415.326723 -289.509736)
			(xy 415.357273 -289.551784) (xy 415.380869 -289.598094) (xy 415.39693 -289.647524) (xy 415.40506 -289.698859)
			(xy 415.40557 -289.724846) (xy 415.40506 -289.750833) (xy 415.694624 -289.750833) (xy 415.694624 -289.698859)
			(xy 415.702754 -289.647524) (xy 415.718815 -289.598094) (xy 415.742411 -289.551784) (xy 415.772961 -289.509736)
			(xy 415.809712 -289.472985) (xy 415.85176 -289.442435) (xy 415.89807 -289.418839) (xy 415.9475 -289.402778)
			(xy 415.998835 -289.394648) (xy 416.050809 -289.394648) (xy 416.102144 -289.402778) (xy 416.151574 -289.418839)
			(xy 416.197884 -289.442435) (xy 416.239932 -289.472985) (xy 416.276683 -289.509736) (xy 416.307233 -289.551784)
			(xy 416.330829 -289.598094) (xy 416.34689 -289.647524) (xy 416.35502 -289.698859) (xy 416.35553 -289.724846)
			(xy 416.35502 -289.750833) (xy 416.644584 -289.750833) (xy 416.644584 -289.698859) (xy 416.652714 -289.647524)
			(xy 416.668775 -289.598094) (xy 416.692371 -289.551784) (xy 416.722921 -289.509736) (xy 416.759672 -289.472985)
			(xy 416.80172 -289.442435) (xy 416.84803 -289.418839) (xy 416.89746 -289.402778) (xy 416.948795 -289.394648)
			(xy 417.000769 -289.394648) (xy 417.052104 -289.402778) (xy 417.101534 -289.418839) (xy 417.147844 -289.442435)
			(xy 417.189892 -289.472985) (xy 417.226643 -289.509736) (xy 417.257193 -289.551784) (xy 417.280789 -289.598094)
			(xy 417.29685 -289.647524) (xy 417.30498 -289.698859) (xy 417.30549 -289.724846) (xy 417.30498 -289.750833)
			(xy 417.29685 -289.802168) (xy 417.280789 -289.851598) (xy 417.257193 -289.897908) (xy 417.226643 -289.939956)
			(xy 417.189892 -289.976707) (xy 417.147844 -290.007257) (xy 417.101534 -290.030853) (xy 417.052104 -290.046914)
			(xy 417.000769 -290.055044) (xy 416.948795 -290.055044) (xy 416.89746 -290.046914) (xy 416.84803 -290.030853)
			(xy 416.80172 -290.007257) (xy 416.759672 -289.976707) (xy 416.722921 -289.939956) (xy 416.692371 -289.897908)
			(xy 416.668775 -289.851598) (xy 416.652714 -289.802168) (xy 416.644584 -289.750833) (xy 416.35502 -289.750833)
			(xy 416.34689 -289.802168) (xy 416.330829 -289.851598) (xy 416.307233 -289.897908) (xy 416.276683 -289.939956)
			(xy 416.239932 -289.976707) (xy 416.197884 -290.007257) (xy 416.151574 -290.030853) (xy 416.102144 -290.046914)
			(xy 416.050809 -290.055044) (xy 415.998835 -290.055044) (xy 415.9475 -290.046914) (xy 415.89807 -290.030853)
			(xy 415.85176 -290.007257) (xy 415.809712 -289.976707) (xy 415.772961 -289.939956) (xy 415.742411 -289.897908)
			(xy 415.718815 -289.851598) (xy 415.702754 -289.802168) (xy 415.694624 -289.750833) (xy 415.40506 -289.750833)
			(xy 415.39693 -289.802168) (xy 415.380869 -289.851598) (xy 415.357273 -289.897908) (xy 415.326723 -289.939956)
			(xy 415.289972 -289.976707) (xy 415.247924 -290.007257) (xy 415.201614 -290.030853) (xy 415.152184 -290.046914)
			(xy 415.100849 -290.055044) (xy 415.048875 -290.055044) (xy 414.99754 -290.046914) (xy 414.94811 -290.030853)
			(xy 414.9018 -290.007257) (xy 414.859752 -289.976707) (xy 414.823001 -289.939956) (xy 414.792451 -289.897908)
			(xy 414.768855 -289.851598) (xy 414.752794 -289.802168) (xy 414.744664 -289.750833) (xy 414.4551 -289.750833)
			(xy 414.44697 -289.802168) (xy 414.430909 -289.851598) (xy 414.407313 -289.897908) (xy 414.376763 -289.939956)
			(xy 414.340012 -289.976707) (xy 414.297964 -290.007257) (xy 414.251654 -290.030853) (xy 414.202224 -290.046914)
			(xy 414.150889 -290.055044) (xy 414.098915 -290.055044) (xy 414.04758 -290.046914) (xy 413.99815 -290.030853)
			(xy 413.95184 -290.007257) (xy 413.909792 -289.976707) (xy 413.873041 -289.939956) (xy 413.842491 -289.897908)
			(xy 413.818895 -289.851598) (xy 413.802834 -289.802168) (xy 413.794704 -289.750833) (xy 413.50514 -289.750833)
			(xy 413.49701 -289.802168) (xy 413.480949 -289.851598) (xy 413.457353 -289.897908) (xy 413.426803 -289.939956)
			(xy 413.390052 -289.976707) (xy 413.348004 -290.007257) (xy 413.301694 -290.030853) (xy 413.252264 -290.046914)
			(xy 413.200929 -290.055044) (xy 413.148955 -290.055044) (xy 413.09762 -290.046914) (xy 413.04819 -290.030853)
			(xy 413.00188 -290.007257) (xy 412.959832 -289.976707) (xy 412.923081 -289.939956) (xy 412.892531 -289.897908)
			(xy 412.868935 -289.851598) (xy 412.852874 -289.802168) (xy 412.844744 -289.750833) (xy 412.55518 -289.750833)
			(xy 412.54705 -289.802168) (xy 412.530989 -289.851598) (xy 412.507393 -289.897908) (xy 412.476843 -289.939956)
			(xy 412.440092 -289.976707) (xy 412.398044 -290.007257) (xy 412.351734 -290.030853) (xy 412.302304 -290.046914)
			(xy 412.250969 -290.055044) (xy 412.198995 -290.055044) (xy 412.14766 -290.046914) (xy 412.09823 -290.030853)
			(xy 412.05192 -290.007257) (xy 412.009872 -289.976707) (xy 411.973121 -289.939956) (xy 411.942571 -289.897908)
			(xy 411.918975 -289.851598) (xy 411.902914 -289.802168) (xy 411.894784 -289.750833) (xy 411.60522 -289.750833)
			(xy 411.59709 -289.802168) (xy 411.581029 -289.851598) (xy 411.557433 -289.897908) (xy 411.526883 -289.939956)
			(xy 411.490132 -289.976707) (xy 411.448084 -290.007257) (xy 411.401774 -290.030853) (xy 411.352344 -290.046914)
			(xy 411.301009 -290.055044) (xy 411.249035 -290.055044) (xy 411.1977 -290.046914) (xy 411.14827 -290.030853)
			(xy 411.10196 -290.007257) (xy 411.059912 -289.976707) (xy 411.023161 -289.939956) (xy 410.992611 -289.897908)
			(xy 410.969015 -289.851598) (xy 410.952954 -289.802168) (xy 410.944824 -289.750833) (xy 410.655006 -289.750833)
			(xy 410.646876 -289.802168) (xy 410.630815 -289.851598) (xy 410.607219 -289.897908) (xy 410.576669 -289.939956)
			(xy 410.539918 -289.976707) (xy 410.49787 -290.007257) (xy 410.45156 -290.030853) (xy 410.40213 -290.046914)
			(xy 410.350795 -290.055044) (xy 410.298821 -290.055044) (xy 410.247486 -290.046914) (xy 410.198056 -290.030853)
			(xy 410.151746 -290.007257) (xy 410.109698 -289.976707) (xy 410.072947 -289.939956) (xy 410.042397 -289.897908)
			(xy 410.018801 -289.851598) (xy 410.00274 -289.802168) (xy 409.99461 -289.750833) (xy 409.705046 -289.750833)
			(xy 409.696916 -289.802168) (xy 409.680855 -289.851598) (xy 409.657259 -289.897908) (xy 409.626709 -289.939956)
			(xy 409.589958 -289.976707) (xy 409.54791 -290.007257) (xy 409.5016 -290.030853) (xy 409.45217 -290.046914)
			(xy 409.400835 -290.055044) (xy 409.348861 -290.055044) (xy 409.297526 -290.046914) (xy 409.248096 -290.030853)
			(xy 409.201786 -290.007257) (xy 409.159738 -289.976707) (xy 409.122987 -289.939956) (xy 409.092437 -289.897908)
			(xy 409.068841 -289.851598) (xy 409.05278 -289.802168) (xy 409.04465 -289.750833) (xy 408.755086 -289.750833)
			(xy 408.746956 -289.802168) (xy 408.730895 -289.851598) (xy 408.707299 -289.897908) (xy 408.676749 -289.939956)
			(xy 408.639998 -289.976707) (xy 408.59795 -290.007257) (xy 408.55164 -290.030853) (xy 408.50221 -290.046914)
			(xy 408.450875 -290.055044) (xy 408.398901 -290.055044) (xy 408.347566 -290.046914) (xy 408.298136 -290.030853)
			(xy 408.251826 -290.007257) (xy 408.209778 -289.976707) (xy 408.173027 -289.939956) (xy 408.142477 -289.897908)
			(xy 408.118881 -289.851598) (xy 408.10282 -289.802168) (xy 408.09469 -289.750833) (xy 406.855166 -289.750833)
			(xy 406.847036 -289.802168) (xy 406.830975 -289.851598) (xy 406.807379 -289.897908) (xy 406.776829 -289.939956)
			(xy 406.740078 -289.976707) (xy 406.69803 -290.007257) (xy 406.65172 -290.030853) (xy 406.60229 -290.046914)
			(xy 406.550955 -290.055044) (xy 406.498981 -290.055044) (xy 406.447646 -290.046914) (xy 406.398216 -290.030853)
			(xy 406.351906 -290.007257) (xy 406.309858 -289.976707) (xy 406.273107 -289.939956) (xy 406.242557 -289.897908)
			(xy 406.218961 -289.851598) (xy 406.2029 -289.802168) (xy 406.19477 -289.750833) (xy 405.905206 -289.750833)
			(xy 405.897076 -289.802168) (xy 405.881015 -289.851598) (xy 405.857419 -289.897908) (xy 405.826869 -289.939956)
			(xy 405.790118 -289.976707) (xy 405.74807 -290.007257) (xy 405.70176 -290.030853) (xy 405.65233 -290.046914)
			(xy 405.600995 -290.055044) (xy 405.549021 -290.055044) (xy 405.497686 -290.046914) (xy 405.448256 -290.030853)
			(xy 405.401946 -290.007257) (xy 405.359898 -289.976707) (xy 405.323147 -289.939956) (xy 405.292597 -289.897908)
			(xy 405.269001 -289.851598) (xy 405.25294 -289.802168) (xy 405.24481 -289.750833) (xy 404.954992 -289.750833)
			(xy 404.946862 -289.802168) (xy 404.930801 -289.851598) (xy 404.907205 -289.897908) (xy 404.876655 -289.939956)
			(xy 404.839904 -289.976707) (xy 404.797856 -290.007257) (xy 404.751546 -290.030853) (xy 404.702116 -290.046914)
			(xy 404.650781 -290.055044) (xy 404.598807 -290.055044) (xy 404.547472 -290.046914) (xy 404.498042 -290.030853)
			(xy 404.451732 -290.007257) (xy 404.409684 -289.976707) (xy 404.372933 -289.939956) (xy 404.342383 -289.897908)
			(xy 404.318787 -289.851598) (xy 404.302726 -289.802168) (xy 404.294596 -289.750833) (xy 404.005032 -289.750833)
			(xy 403.996902 -289.802168) (xy 403.980841 -289.851598) (xy 403.957245 -289.897908) (xy 403.926695 -289.939956)
			(xy 403.889944 -289.976707) (xy 403.847896 -290.007257) (xy 403.801586 -290.030853) (xy 403.752156 -290.046914)
			(xy 403.700821 -290.055044) (xy 403.648847 -290.055044) (xy 403.597512 -290.046914) (xy 403.548082 -290.030853)
			(xy 403.501772 -290.007257) (xy 403.459724 -289.976707) (xy 403.422973 -289.939956) (xy 403.392423 -289.897908)
			(xy 403.368827 -289.851598) (xy 403.352766 -289.802168) (xy 403.344636 -289.750833) (xy 403.055072 -289.750833)
			(xy 403.046942 -289.802168) (xy 403.030881 -289.851598) (xy 403.007285 -289.897908) (xy 402.976735 -289.939956)
			(xy 402.939984 -289.976707) (xy 402.897936 -290.007257) (xy 402.851626 -290.030853) (xy 402.802196 -290.046914)
			(xy 402.750861 -290.055044) (xy 402.698887 -290.055044) (xy 402.647552 -290.046914) (xy 402.598122 -290.030853)
			(xy 402.551812 -290.007257) (xy 402.509764 -289.976707) (xy 402.473013 -289.939956) (xy 402.442463 -289.897908)
			(xy 402.418867 -289.851598) (xy 402.402806 -289.802168) (xy 402.394676 -289.750833) (xy 402.105112 -289.750833)
			(xy 402.096982 -289.802168) (xy 402.080921 -289.851598) (xy 402.057325 -289.897908) (xy 402.026775 -289.939956)
			(xy 401.990024 -289.976707) (xy 401.947976 -290.007257) (xy 401.901666 -290.030853) (xy 401.852236 -290.046914)
			(xy 401.800901 -290.055044) (xy 401.748927 -290.055044) (xy 401.697592 -290.046914) (xy 401.648162 -290.030853)
			(xy 401.601852 -290.007257) (xy 401.559804 -289.976707) (xy 401.523053 -289.939956) (xy 401.492503 -289.897908)
			(xy 401.468907 -289.851598) (xy 401.452846 -289.802168) (xy 401.444716 -289.750833) (xy 401.155152 -289.750833)
			(xy 401.147022 -289.802168) (xy 401.130961 -289.851598) (xy 401.107365 -289.897908) (xy 401.076815 -289.939956)
			(xy 401.040064 -289.976707) (xy 400.998016 -290.007257) (xy 400.951706 -290.030853) (xy 400.902276 -290.046914)
			(xy 400.850941 -290.055044) (xy 400.798967 -290.055044) (xy 400.747632 -290.046914) (xy 400.698202 -290.030853)
			(xy 400.651892 -290.007257) (xy 400.609844 -289.976707) (xy 400.573093 -289.939956) (xy 400.542543 -289.897908)
			(xy 400.518947 -289.851598) (xy 400.502886 -289.802168) (xy 400.494756 -289.750833) (xy 400.205192 -289.750833)
			(xy 400.197062 -289.802168) (xy 400.181001 -289.851598) (xy 400.157405 -289.897908) (xy 400.126855 -289.939956)
			(xy 400.090104 -289.976707) (xy 400.048056 -290.007257) (xy 400.001746 -290.030853) (xy 399.952316 -290.046914)
			(xy 399.900981 -290.055044) (xy 399.849007 -290.055044) (xy 399.797672 -290.046914) (xy 399.748242 -290.030853)
			(xy 399.701932 -290.007257) (xy 399.659884 -289.976707) (xy 399.623133 -289.939956) (xy 399.592583 -289.897908)
			(xy 399.568987 -289.851598) (xy 399.552926 -289.802168) (xy 399.544796 -289.750833) (xy 399.255232 -289.750833)
			(xy 399.247102 -289.802168) (xy 399.231041 -289.851598) (xy 399.207445 -289.897908) (xy 399.176895 -289.939956)
			(xy 399.140144 -289.976707) (xy 399.098096 -290.007257) (xy 399.051786 -290.030853) (xy 399.002356 -290.046914)
			(xy 398.951021 -290.055044) (xy 398.899047 -290.055044) (xy 398.847712 -290.046914) (xy 398.798282 -290.030853)
			(xy 398.751972 -290.007257) (xy 398.709924 -289.976707) (xy 398.673173 -289.939956) (xy 398.642623 -289.897908)
			(xy 398.619027 -289.851598) (xy 398.602966 -289.802168) (xy 398.594836 -289.750833) (xy 398.305018 -289.750833)
			(xy 398.296888 -289.802168) (xy 398.280827 -289.851598) (xy 398.257231 -289.897908) (xy 398.226681 -289.939956)
			(xy 398.18993 -289.976707) (xy 398.147882 -290.007257) (xy 398.101572 -290.030853) (xy 398.052142 -290.046914)
			(xy 398.000807 -290.055044) (xy 397.948833 -290.055044) (xy 397.897498 -290.046914) (xy 397.848068 -290.030853)
			(xy 397.801758 -290.007257) (xy 397.75971 -289.976707) (xy 397.722959 -289.939956) (xy 397.692409 -289.897908)
			(xy 397.668813 -289.851598) (xy 397.652752 -289.802168) (xy 397.644622 -289.750833) (xy 397.355058 -289.750833)
			(xy 397.346928 -289.802168) (xy 397.330867 -289.851598) (xy 397.307271 -289.897908) (xy 397.276721 -289.939956)
			(xy 397.23997 -289.976707) (xy 397.197922 -290.007257) (xy 397.151612 -290.030853) (xy 397.102182 -290.046914)
			(xy 397.050847 -290.055044) (xy 396.998873 -290.055044) (xy 396.947538 -290.046914) (xy 396.898108 -290.030853)
			(xy 396.851798 -290.007257) (xy 396.80975 -289.976707) (xy 396.772999 -289.939956) (xy 396.742449 -289.897908)
			(xy 396.718853 -289.851598) (xy 396.702792 -289.802168) (xy 396.694662 -289.750833) (xy 396.694152 -289.724846)
			(xy 396.694703 -289.697633) (xy 396.703617 -289.643941) (xy 396.721211 -289.592436) (xy 396.74701 -289.544513)
			(xy 396.76324 -289.522662) (xy 396.77213 -289.510978) (xy 396.775178 -289.482276) (xy 396.728442 -289.38728)
			(xy 396.723953 -289.378947) (xy 396.710051 -289.366124) (xy 396.692433 -289.359245) (xy 396.682976 -289.358832)
			(xy 396.416784 -289.358832) (xy 396.407348 -289.35932) (xy 396.38978 -289.36623) (xy 396.375881 -289.379006)
			(xy 396.371318 -289.38728) (xy 396.324582 -289.482276) (xy 396.32763 -289.510978) (xy 396.33652 -289.522662)
			(xy 396.352728 -289.544526) (xy 396.37852 -289.592449) (xy 396.396115 -289.643949) (xy 396.405037 -289.697635)
			(xy 396.405608 -289.724846) (xy 396.405098 -289.750833) (xy 396.396968 -289.802168) (xy 396.380907 -289.851598)
			(xy 396.357311 -289.897908) (xy 396.326761 -289.939956) (xy 396.29001 -289.976707) (xy 396.247962 -290.007257)
			(xy 396.201652 -290.030853) (xy 396.152222 -290.046914) (xy 396.100887 -290.055044) (xy 396.048913 -290.055044)
			(xy 395.997578 -290.046914) (xy 395.948148 -290.030853) (xy 395.901838 -290.007257) (xy 395.85979 -289.976707)
			(xy 395.823039 -289.939956) (xy 395.792489 -289.897908) (xy 395.768893 -289.851598) (xy 395.752832 -289.802168)
			(xy 395.744702 -289.750833) (xy 395.744192 -289.724846) (xy 395.744743 -289.697633) (xy 395.753658 -289.643942)
			(xy 395.771254 -289.592438) (xy 395.797056 -289.544516) (xy 395.81328 -289.522662) (xy 395.82217 -289.510978)
			(xy 395.825218 -289.482276) (xy 395.778482 -289.38728) (xy 395.773996 -289.378943) (xy 395.760095 -289.366109)
			(xy 395.742476 -289.359215) (xy 395.733016 -289.358832) (xy 395.466824 -289.358832) (xy 395.457394 -289.35933)
			(xy 395.439842 -289.366253) (xy 395.425961 -289.379032) (xy 395.421358 -289.38728) (xy 395.374622 -289.482276)
			(xy 395.37767 -289.510978) (xy 395.38656 -289.522662) (xy 395.402771 -289.544525) (xy 395.428568 -289.592447)
			(xy 395.446165 -289.643947) (xy 395.455089 -289.697634) (xy 395.455648 -289.724846) (xy 395.455138 -289.750833)
			(xy 395.447008 -289.802168) (xy 395.430947 -289.851598) (xy 395.407351 -289.897908) (xy 395.376801 -289.939956)
			(xy 395.34005 -289.976707) (xy 395.298002 -290.007257) (xy 395.251692 -290.030853) (xy 395.202262 -290.046914)
			(xy 395.150927 -290.055044) (xy 395.098953 -290.055044) (xy 395.047618 -290.046914) (xy 394.998188 -290.030853)
			(xy 394.951878 -290.007257) (xy 394.90983 -289.976707) (xy 394.873079 -289.939956) (xy 394.842529 -289.897908)
			(xy 394.818933 -289.851598) (xy 394.802872 -289.802168) (xy 394.794742 -289.750833) (xy 394.794232 -289.724846)
			(xy 394.794783 -289.697632) (xy 394.803697 -289.64394) (xy 394.82129 -289.592435) (xy 394.847088 -289.544511)
			(xy 394.86332 -289.522662) (xy 394.87221 -289.510978) (xy 394.875258 -289.482276) (xy 394.828522 -289.38728)
			(xy 394.824038 -289.378938) (xy 394.810139 -289.366093) (xy 394.792518 -289.359186) (xy 394.783056 -289.358832)
			(xy 394.516864 -289.358832) (xy 394.50743 -289.359323) (xy 394.489867 -289.366238) (xy 394.475974 -289.379015)
			(xy 394.471398 -289.38728) (xy 394.424662 -289.482276) (xy 394.42771 -289.510978) (xy 394.4366 -289.522662)
			(xy 394.452809 -289.544526) (xy 394.478603 -289.592448) (xy 394.496198 -289.643948) (xy 394.505121 -289.697635)
			(xy 394.505688 -289.724846) (xy 394.505178 -289.750833) (xy 394.497048 -289.802168) (xy 394.480987 -289.851598)
			(xy 394.457391 -289.897908) (xy 394.426841 -289.939956) (xy 394.39009 -289.976707) (xy 394.348042 -290.007257)
			(xy 394.301732 -290.030853) (xy 394.252302 -290.046914) (xy 394.200967 -290.055044) (xy 394.148993 -290.055044)
			(xy 394.097658 -290.046914) (xy 394.048228 -290.030853) (xy 394.001918 -290.007257) (xy 393.95987 -289.976707)
			(xy 393.923119 -289.939956) (xy 393.892569 -289.897908) (xy 393.868973 -289.851598) (xy 393.852912 -289.802168)
			(xy 393.844782 -289.750833) (xy 393.844272 -289.724846) (xy 393.844823 -289.697633) (xy 393.853738 -289.643941)
			(xy 393.871333 -289.592437) (xy 393.897133 -289.544515) (xy 393.91336 -289.522662) (xy 393.92225 -289.510978)
			(xy 393.925298 -289.482276) (xy 393.878562 -289.38728) (xy 393.874074 -289.378945) (xy 393.860173 -289.366117)
			(xy 393.842554 -289.35923) (xy 393.833096 -289.358832) (xy 393.566904 -289.358832) (xy 393.557466 -289.359317)
			(xy 393.539892 -289.366223) (xy 393.525988 -289.378998) (xy 393.521438 -289.38728) (xy 393.474702 -289.482276)
			(xy 393.47775 -289.510978) (xy 393.48664 -289.522662) (xy 393.502852 -289.544525) (xy 393.52865 -289.592446)
			(xy 393.546249 -289.643946) (xy 393.555173 -289.697634) (xy 393.555728 -289.724846) (xy 393.555218 -289.750833)
			(xy 393.547088 -289.802168) (xy 393.531027 -289.851598) (xy 393.507431 -289.897908) (xy 393.476881 -289.939956)
			(xy 393.44013 -289.976707) (xy 393.398082 -290.007257) (xy 393.351772 -290.030853) (xy 393.302342 -290.046914)
			(xy 393.251007 -290.055044) (xy 393.199033 -290.055044) (xy 393.147698 -290.046914) (xy 393.098268 -290.030853)
			(xy 393.051958 -290.007257) (xy 393.00991 -289.976707) (xy 392.973159 -289.939956) (xy 392.942609 -289.897908)
			(xy 392.919013 -289.851598) (xy 392.902952 -289.802168) (xy 392.894822 -289.750833) (xy 392.894312 -289.724846)
			(xy 392.894863 -289.697633) (xy 392.903779 -289.643942) (xy 392.921376 -289.592439) (xy 392.947178 -289.544518)
			(xy 392.9634 -289.522662) (xy 392.97229 -289.510978) (xy 392.975338 -289.482276) (xy 392.928602 -289.38728)
			(xy 392.924116 -289.378941) (xy 392.910217 -289.366101) (xy 392.892597 -289.359201) (xy 392.883136 -289.358832)
			(xy 392.61669 -289.358832) (xy 392.607253 -289.359319) (xy 392.589683 -289.366228) (xy 392.575783 -289.379004)
			(xy 392.571224 -289.38728) (xy 392.524488 -289.482276) (xy 392.527536 -289.510978) (xy 392.536426 -289.522662)
			(xy 392.552634 -289.544526) (xy 392.578425 -289.592449) (xy 392.59602 -289.643949) (xy 392.604942 -289.697635)
			(xy 392.605514 -289.724846) (xy 392.605004 -289.750833) (xy 392.596874 -289.802168) (xy 392.580813 -289.851598)
			(xy 392.557217 -289.897908) (xy 392.526667 -289.939956) (xy 392.489916 -289.976707) (xy 392.447868 -290.007257)
			(xy 392.401558 -290.030853) (xy 392.352128 -290.046914) (xy 392.300793 -290.055044) (xy 392.248819 -290.055044)
			(xy 392.197484 -290.046914) (xy 392.148054 -290.030853) (xy 392.101744 -290.007257) (xy 392.059696 -289.976707)
			(xy 392.022945 -289.939956) (xy 391.992395 -289.897908) (xy 391.968799 -289.851598) (xy 391.952738 -289.802168)
			(xy 391.944608 -289.750833) (xy 391.944098 -289.724846) (xy 391.944649 -289.697633) (xy 391.953564 -289.643942)
			(xy 391.971161 -289.592439) (xy 391.996962 -289.544517) (xy 392.013186 -289.522662) (xy 392.022076 -289.510978)
			(xy 392.025124 -289.482276) (xy 391.978388 -289.38728) (xy 391.973902 -289.378942) (xy 391.960001 -289.366106)
			(xy 391.942382 -289.359211) (xy 391.932922 -289.358832) (xy 391.552176 -289.358832) (xy 391.542108 -289.35926)
			(xy 391.523513 -289.366984) (xy 391.516108 -289.373818) (xy 391.511028 -289.378898) (xy 391.504347 -289.38631)
			(xy 391.496755 -289.404741) (xy 391.496758 -289.424675) (xy 391.504356 -289.443105) (xy 391.511028 -289.450526)
			(xy 391.514076 -289.453574) (xy 391.517378 -289.456114) (xy 391.538366 -289.471749) (xy 391.575592 -289.508533)
			(xy 391.606556 -289.550725) (xy 391.630485 -289.597268) (xy 391.64678 -289.647) (xy 391.655035 -289.698679)
			(xy 391.655554 -289.724846) (xy 391.655021 -289.752243) (xy 391.645994 -289.806288) (xy 391.62818 -289.858104)
			(xy 391.602064 -289.906274) (xy 391.568364 -289.949478) (xy 391.528 -289.986534) (xy 391.482079 -290.016426)
			(xy 391.45718 -290.027868) (xy 391.44321 -290.033964) (xy 391.4267 -290.059364) (xy 391.4267 -290.145724)
			(xy 391.426272 -290.155792) (xy 391.418552 -290.17439) (xy 391.411714 -290.181792) (xy 391.411714 -290.318952)
			(xy 391.411966 -290.326599) (xy 391.416477 -290.341212) (xy 391.420604 -290.347654) (xy 391.425176 -290.354258)
			(xy 391.43686 -290.363656) (xy 391.444226 -290.36645) (xy 391.468745 -290.376508) (xy 391.514476 -290.403283)
			(xy 391.555352 -290.43701) (xy 391.590326 -290.476824) (xy 391.618502 -290.521706) (xy 391.639159 -290.570507)
			(xy 391.651768 -290.621979) (xy 391.656007 -290.674802) (xy 391.653921 -290.700793) (xy 391.944608 -290.700793)
			(xy 391.944608 -290.648819) (xy 391.952738 -290.597484) (xy 391.968799 -290.548054) (xy 391.992395 -290.501744)
			(xy 392.022945 -290.459696) (xy 392.059696 -290.422945) (xy 392.101744 -290.392395) (xy 392.148054 -290.368799)
			(xy 392.197484 -290.352738) (xy 392.248819 -290.344608) (xy 392.300793 -290.344608) (xy 392.352128 -290.352738)
			(xy 392.401558 -290.368799) (xy 392.447868 -290.392395) (xy 392.489916 -290.422945) (xy 392.526667 -290.459696)
			(xy 392.557217 -290.501744) (xy 392.580813 -290.548054) (xy 392.596874 -290.597484) (xy 392.605004 -290.648819)
			(xy 392.605514 -290.674806) (xy 392.605004 -290.700793) (xy 393.844782 -290.700793) (xy 393.844782 -290.648819)
			(xy 393.852912 -290.597484) (xy 393.868973 -290.548054) (xy 393.892569 -290.501744) (xy 393.923119 -290.459696)
			(xy 393.95987 -290.422945) (xy 394.001918 -290.392395) (xy 394.048228 -290.368799) (xy 394.097658 -290.352738)
			(xy 394.148993 -290.344608) (xy 394.200967 -290.344608) (xy 394.252302 -290.352738) (xy 394.301732 -290.368799)
			(xy 394.348042 -290.392395) (xy 394.39009 -290.422945) (xy 394.426841 -290.459696) (xy 394.457391 -290.501744)
			(xy 394.480987 -290.548054) (xy 394.497048 -290.597484) (xy 394.505178 -290.648819) (xy 394.505688 -290.674806)
			(xy 394.505178 -290.700793) (xy 395.744702 -290.700793) (xy 395.744702 -290.648819) (xy 395.752832 -290.597484)
			(xy 395.768893 -290.548054) (xy 395.792489 -290.501744) (xy 395.823039 -290.459696) (xy 395.85979 -290.422945)
			(xy 395.901838 -290.392395) (xy 395.948148 -290.368799) (xy 395.997578 -290.352738) (xy 396.048913 -290.344608)
			(xy 396.100887 -290.344608) (xy 396.152222 -290.352738) (xy 396.201652 -290.368799) (xy 396.247962 -290.392395)
			(xy 396.29001 -290.422945) (xy 396.326761 -290.459696) (xy 396.357311 -290.501744) (xy 396.380907 -290.548054)
			(xy 396.396968 -290.597484) (xy 396.405098 -290.648819) (xy 396.405608 -290.674806) (xy 396.405098 -290.700793)
			(xy 396.694662 -290.700793) (xy 396.694662 -290.648819) (xy 396.702792 -290.597484) (xy 396.718853 -290.548054)
			(xy 396.742449 -290.501744) (xy 396.772999 -290.459696) (xy 396.80975 -290.422945) (xy 396.851798 -290.392395)
			(xy 396.898108 -290.368799) (xy 396.947538 -290.352738) (xy 396.998873 -290.344608) (xy 397.050847 -290.344608)
			(xy 397.102182 -290.352738) (xy 397.151612 -290.368799) (xy 397.197922 -290.392395) (xy 397.23997 -290.422945)
			(xy 397.276721 -290.459696) (xy 397.307271 -290.501744) (xy 397.330867 -290.548054) (xy 397.346928 -290.597484)
			(xy 397.355058 -290.648819) (xy 397.355568 -290.674806) (xy 397.355058 -290.700793) (xy 397.644622 -290.700793)
			(xy 397.644622 -290.648819) (xy 397.652752 -290.597484) (xy 397.668813 -290.548054) (xy 397.692409 -290.501744)
			(xy 397.722959 -290.459696) (xy 397.75971 -290.422945) (xy 397.801758 -290.392395) (xy 397.848068 -290.368799)
			(xy 397.897498 -290.352738) (xy 397.948833 -290.344608) (xy 398.000807 -290.344608) (xy 398.052142 -290.352738)
			(xy 398.101572 -290.368799) (xy 398.147882 -290.392395) (xy 398.18993 -290.422945) (xy 398.226681 -290.459696)
			(xy 398.257231 -290.501744) (xy 398.280827 -290.548054) (xy 398.296888 -290.597484) (xy 398.305018 -290.648819)
			(xy 398.305528 -290.674806) (xy 398.305018 -290.700793) (xy 398.594836 -290.700793) (xy 398.594836 -290.648819)
			(xy 398.602966 -290.597484) (xy 398.619027 -290.548054) (xy 398.642623 -290.501744) (xy 398.673173 -290.459696)
			(xy 398.709924 -290.422945) (xy 398.751972 -290.392395) (xy 398.798282 -290.368799) (xy 398.847712 -290.352738)
			(xy 398.899047 -290.344608) (xy 398.951021 -290.344608) (xy 399.002356 -290.352738) (xy 399.051786 -290.368799)
			(xy 399.098096 -290.392395) (xy 399.140144 -290.422945) (xy 399.176895 -290.459696) (xy 399.207445 -290.501744)
			(xy 399.231041 -290.548054) (xy 399.247102 -290.597484) (xy 399.255232 -290.648819) (xy 399.255742 -290.674806)
			(xy 399.255232 -290.700793) (xy 399.544796 -290.700793) (xy 399.544796 -290.648819) (xy 399.552926 -290.597484)
			(xy 399.568987 -290.548054) (xy 399.592583 -290.501744) (xy 399.623133 -290.459696) (xy 399.659884 -290.422945)
			(xy 399.701932 -290.392395) (xy 399.748242 -290.368799) (xy 399.797672 -290.352738) (xy 399.849007 -290.344608)
			(xy 399.900981 -290.344608) (xy 399.952316 -290.352738) (xy 400.001746 -290.368799) (xy 400.048056 -290.392395)
			(xy 400.090104 -290.422945) (xy 400.126855 -290.459696) (xy 400.157405 -290.501744) (xy 400.181001 -290.548054)
			(xy 400.197062 -290.597484) (xy 400.205192 -290.648819) (xy 400.205702 -290.674806) (xy 400.205192 -290.700793)
			(xy 400.494756 -290.700793) (xy 400.494756 -290.648819) (xy 400.502886 -290.597484) (xy 400.518947 -290.548054)
			(xy 400.542543 -290.501744) (xy 400.573093 -290.459696) (xy 400.609844 -290.422945) (xy 400.651892 -290.392395)
			(xy 400.698202 -290.368799) (xy 400.747632 -290.352738) (xy 400.798967 -290.344608) (xy 400.850941 -290.344608)
			(xy 400.902276 -290.352738) (xy 400.951706 -290.368799) (xy 400.998016 -290.392395) (xy 401.040064 -290.422945)
			(xy 401.076815 -290.459696) (xy 401.107365 -290.501744) (xy 401.130961 -290.548054) (xy 401.147022 -290.597484)
			(xy 401.155152 -290.648819) (xy 401.155662 -290.674806) (xy 401.155152 -290.700793) (xy 401.444716 -290.700793)
			(xy 401.444716 -290.648819) (xy 401.452846 -290.597484) (xy 401.468907 -290.548054) (xy 401.492503 -290.501744)
			(xy 401.523053 -290.459696) (xy 401.559804 -290.422945) (xy 401.601852 -290.392395) (xy 401.648162 -290.368799)
			(xy 401.697592 -290.352738) (xy 401.748927 -290.344608) (xy 401.800901 -290.344608) (xy 401.852236 -290.352738)
			(xy 401.901666 -290.368799) (xy 401.947976 -290.392395) (xy 401.990024 -290.422945) (xy 402.026775 -290.459696)
			(xy 402.057325 -290.501744) (xy 402.080921 -290.548054) (xy 402.096982 -290.597484) (xy 402.105112 -290.648819)
			(xy 402.105622 -290.674806) (xy 402.105112 -290.700793) (xy 402.394676 -290.700793) (xy 402.394676 -290.648819)
			(xy 402.402806 -290.597484) (xy 402.418867 -290.548054) (xy 402.442463 -290.501744) (xy 402.473013 -290.459696)
			(xy 402.509764 -290.422945) (xy 402.551812 -290.392395) (xy 402.598122 -290.368799) (xy 402.647552 -290.352738)
			(xy 402.698887 -290.344608) (xy 402.750861 -290.344608) (xy 402.802196 -290.352738) (xy 402.851626 -290.368799)
			(xy 402.897936 -290.392395) (xy 402.939984 -290.422945) (xy 402.976735 -290.459696) (xy 403.007285 -290.501744)
			(xy 403.030881 -290.548054) (xy 403.046942 -290.597484) (xy 403.055072 -290.648819) (xy 403.055582 -290.674806)
			(xy 403.055072 -290.700793) (xy 403.344636 -290.700793) (xy 403.344636 -290.648819) (xy 403.352766 -290.597484)
			(xy 403.368827 -290.548054) (xy 403.392423 -290.501744) (xy 403.422973 -290.459696) (xy 403.459724 -290.422945)
			(xy 403.501772 -290.392395) (xy 403.548082 -290.368799) (xy 403.597512 -290.352738) (xy 403.648847 -290.344608)
			(xy 403.700821 -290.344608) (xy 403.752156 -290.352738) (xy 403.801586 -290.368799) (xy 403.847896 -290.392395)
			(xy 403.889944 -290.422945) (xy 403.926695 -290.459696) (xy 403.957245 -290.501744) (xy 403.980841 -290.548054)
			(xy 403.996902 -290.597484) (xy 404.005032 -290.648819) (xy 404.005542 -290.674806) (xy 404.005032 -290.700793)
			(xy 404.294596 -290.700793) (xy 404.294596 -290.648819) (xy 404.302726 -290.597484) (xy 404.318787 -290.548054)
			(xy 404.342383 -290.501744) (xy 404.372933 -290.459696) (xy 404.409684 -290.422945) (xy 404.451732 -290.392395)
			(xy 404.498042 -290.368799) (xy 404.547472 -290.352738) (xy 404.598807 -290.344608) (xy 404.650781 -290.344608)
			(xy 404.702116 -290.352738) (xy 404.751546 -290.368799) (xy 404.797856 -290.392395) (xy 404.839904 -290.422945)
			(xy 404.876655 -290.459696) (xy 404.907205 -290.501744) (xy 404.930801 -290.548054) (xy 404.946862 -290.597484)
			(xy 404.954992 -290.648819) (xy 404.955502 -290.674806) (xy 404.954992 -290.700793) (xy 405.24481 -290.700793)
			(xy 405.24481 -290.648819) (xy 405.25294 -290.597484) (xy 405.269001 -290.548054) (xy 405.292597 -290.501744)
			(xy 405.323147 -290.459696) (xy 405.359898 -290.422945) (xy 405.401946 -290.392395) (xy 405.448256 -290.368799)
			(xy 405.497686 -290.352738) (xy 405.549021 -290.344608) (xy 405.600995 -290.344608) (xy 405.65233 -290.352738)
			(xy 405.70176 -290.368799) (xy 405.74807 -290.392395) (xy 405.790118 -290.422945) (xy 405.826869 -290.459696)
			(xy 405.857419 -290.501744) (xy 405.881015 -290.548054) (xy 405.897076 -290.597484) (xy 405.905206 -290.648819)
			(xy 405.905716 -290.674806) (xy 405.905206 -290.700793) (xy 406.19477 -290.700793) (xy 406.19477 -290.648819)
			(xy 406.2029 -290.597484) (xy 406.218961 -290.548054) (xy 406.242557 -290.501744) (xy 406.273107 -290.459696)
			(xy 406.309858 -290.422945) (xy 406.351906 -290.392395) (xy 406.398216 -290.368799) (xy 406.447646 -290.352738)
			(xy 406.498981 -290.344608) (xy 406.550955 -290.344608) (xy 406.60229 -290.352738) (xy 406.65172 -290.368799)
			(xy 406.69803 -290.392395) (xy 406.740078 -290.422945) (xy 406.776829 -290.459696) (xy 406.807379 -290.501744)
			(xy 406.830975 -290.548054) (xy 406.847036 -290.597484) (xy 406.855166 -290.648819) (xy 406.855676 -290.674806)
			(xy 406.855166 -290.700793) (xy 408.09469 -290.700793) (xy 408.09469 -290.648819) (xy 408.10282 -290.597484)
			(xy 408.118881 -290.548054) (xy 408.142477 -290.501744) (xy 408.173027 -290.459696) (xy 408.209778 -290.422945)
			(xy 408.251826 -290.392395) (xy 408.298136 -290.368799) (xy 408.347566 -290.352738) (xy 408.398901 -290.344608)
			(xy 408.450875 -290.344608) (xy 408.50221 -290.352738) (xy 408.55164 -290.368799) (xy 408.59795 -290.392395)
			(xy 408.639998 -290.422945) (xy 408.676749 -290.459696) (xy 408.707299 -290.501744) (xy 408.730895 -290.548054)
			(xy 408.746956 -290.597484) (xy 408.755086 -290.648819) (xy 408.755596 -290.674806) (xy 408.755086 -290.700793)
			(xy 409.04465 -290.700793) (xy 409.04465 -290.648819) (xy 409.05278 -290.597484) (xy 409.068841 -290.548054)
			(xy 409.092437 -290.501744) (xy 409.122987 -290.459696) (xy 409.159738 -290.422945) (xy 409.201786 -290.392395)
			(xy 409.248096 -290.368799) (xy 409.297526 -290.352738) (xy 409.348861 -290.344608) (xy 409.400835 -290.344608)
			(xy 409.45217 -290.352738) (xy 409.5016 -290.368799) (xy 409.54791 -290.392395) (xy 409.589958 -290.422945)
			(xy 409.626709 -290.459696) (xy 409.657259 -290.501744) (xy 409.680855 -290.548054) (xy 409.696916 -290.597484)
			(xy 409.705046 -290.648819) (xy 409.705556 -290.674806) (xy 409.705046 -290.700793) (xy 409.99461 -290.700793)
			(xy 409.99461 -290.648819) (xy 410.00274 -290.597484) (xy 410.018801 -290.548054) (xy 410.042397 -290.501744)
			(xy 410.072947 -290.459696) (xy 410.109698 -290.422945) (xy 410.151746 -290.392395) (xy 410.198056 -290.368799)
			(xy 410.247486 -290.352738) (xy 410.298821 -290.344608) (xy 410.350795 -290.344608) (xy 410.40213 -290.352738)
			(xy 410.45156 -290.368799) (xy 410.49787 -290.392395) (xy 410.539918 -290.422945) (xy 410.576669 -290.459696)
			(xy 410.607219 -290.501744) (xy 410.630815 -290.548054) (xy 410.646876 -290.597484) (xy 410.655006 -290.648819)
			(xy 410.655516 -290.674806) (xy 410.655006 -290.700793) (xy 410.944824 -290.700793) (xy 410.944824 -290.648819)
			(xy 410.952954 -290.597484) (xy 410.969015 -290.548054) (xy 410.992611 -290.501744) (xy 411.023161 -290.459696)
			(xy 411.059912 -290.422945) (xy 411.10196 -290.392395) (xy 411.14827 -290.368799) (xy 411.1977 -290.352738)
			(xy 411.249035 -290.344608) (xy 411.301009 -290.344608) (xy 411.352344 -290.352738) (xy 411.401774 -290.368799)
			(xy 411.448084 -290.392395) (xy 411.490132 -290.422945) (xy 411.526883 -290.459696) (xy 411.557433 -290.501744)
			(xy 411.581029 -290.548054) (xy 411.59709 -290.597484) (xy 411.60522 -290.648819) (xy 411.60573 -290.674806)
			(xy 411.60522 -290.700793) (xy 411.894784 -290.700793) (xy 411.894784 -290.648819) (xy 411.902914 -290.597484)
			(xy 411.918975 -290.548054) (xy 411.942571 -290.501744) (xy 411.973121 -290.459696) (xy 412.009872 -290.422945)
			(xy 412.05192 -290.392395) (xy 412.09823 -290.368799) (xy 412.14766 -290.352738) (xy 412.198995 -290.344608)
			(xy 412.250969 -290.344608) (xy 412.302304 -290.352738) (xy 412.351734 -290.368799) (xy 412.398044 -290.392395)
			(xy 412.440092 -290.422945) (xy 412.476843 -290.459696) (xy 412.507393 -290.501744) (xy 412.530989 -290.548054)
			(xy 412.54705 -290.597484) (xy 412.55518 -290.648819) (xy 412.55569 -290.674806) (xy 412.55518 -290.700793)
			(xy 412.844744 -290.700793) (xy 412.844744 -290.648819) (xy 412.852874 -290.597484) (xy 412.868935 -290.548054)
			(xy 412.892531 -290.501744) (xy 412.923081 -290.459696) (xy 412.959832 -290.422945) (xy 413.00188 -290.392395)
			(xy 413.04819 -290.368799) (xy 413.09762 -290.352738) (xy 413.148955 -290.344608) (xy 413.200929 -290.344608)
			(xy 413.252264 -290.352738) (xy 413.301694 -290.368799) (xy 413.348004 -290.392395) (xy 413.390052 -290.422945)
			(xy 413.426803 -290.459696) (xy 413.457353 -290.501744) (xy 413.480949 -290.548054) (xy 413.49701 -290.597484)
			(xy 413.50514 -290.648819) (xy 413.50565 -290.674806) (xy 413.50514 -290.700793) (xy 413.794704 -290.700793)
			(xy 413.794704 -290.648819) (xy 413.802834 -290.597484) (xy 413.818895 -290.548054) (xy 413.842491 -290.501744)
			(xy 413.873041 -290.459696) (xy 413.909792 -290.422945) (xy 413.95184 -290.392395) (xy 413.99815 -290.368799)
			(xy 414.04758 -290.352738) (xy 414.098915 -290.344608) (xy 414.150889 -290.344608) (xy 414.202224 -290.352738)
			(xy 414.251654 -290.368799) (xy 414.297964 -290.392395) (xy 414.340012 -290.422945) (xy 414.376763 -290.459696)
			(xy 414.407313 -290.501744) (xy 414.430909 -290.548054) (xy 414.44697 -290.597484) (xy 414.4551 -290.648819)
			(xy 414.45561 -290.674806) (xy 414.4551 -290.700793) (xy 414.744664 -290.700793) (xy 414.744664 -290.648819)
			(xy 414.752794 -290.597484) (xy 414.768855 -290.548054) (xy 414.792451 -290.501744) (xy 414.823001 -290.459696)
			(xy 414.859752 -290.422945) (xy 414.9018 -290.392395) (xy 414.94811 -290.368799) (xy 414.99754 -290.352738)
			(xy 415.048875 -290.344608) (xy 415.100849 -290.344608) (xy 415.152184 -290.352738) (xy 415.201614 -290.368799)
			(xy 415.247924 -290.392395) (xy 415.289972 -290.422945) (xy 415.326723 -290.459696) (xy 415.357273 -290.501744)
			(xy 415.380869 -290.548054) (xy 415.39693 -290.597484) (xy 415.40506 -290.648819) (xy 415.40557 -290.674806)
			(xy 415.40506 -290.700793) (xy 415.694624 -290.700793) (xy 415.694624 -290.648819) (xy 415.702754 -290.597484)
			(xy 415.718815 -290.548054) (xy 415.742411 -290.501744) (xy 415.772961 -290.459696) (xy 415.809712 -290.422945)
			(xy 415.85176 -290.392395) (xy 415.89807 -290.368799) (xy 415.9475 -290.352738) (xy 415.998835 -290.344608)
			(xy 416.050809 -290.344608) (xy 416.102144 -290.352738) (xy 416.151574 -290.368799) (xy 416.197884 -290.392395)
			(xy 416.239932 -290.422945) (xy 416.276683 -290.459696) (xy 416.307233 -290.501744) (xy 416.330829 -290.548054)
			(xy 416.34689 -290.597484) (xy 416.35502 -290.648819) (xy 416.35553 -290.674806) (xy 416.35502 -290.700793)
			(xy 416.644584 -290.700793) (xy 416.644584 -290.648819) (xy 416.652714 -290.597484) (xy 416.668775 -290.548054)
			(xy 416.692371 -290.501744) (xy 416.722921 -290.459696) (xy 416.759672 -290.422945) (xy 416.80172 -290.392395)
			(xy 416.84803 -290.368799) (xy 416.89746 -290.352738) (xy 416.948795 -290.344608) (xy 417.000769 -290.344608)
			(xy 417.052104 -290.352738) (xy 417.101534 -290.368799) (xy 417.147844 -290.392395) (xy 417.189892 -290.422945)
			(xy 417.226643 -290.459696) (xy 417.257193 -290.501744) (xy 417.280789 -290.548054) (xy 417.29685 -290.597484)
			(xy 417.30498 -290.648819) (xy 417.30549 -290.674806) (xy 417.30498 -290.700793) (xy 417.29685 -290.752128)
			(xy 417.280789 -290.801558) (xy 417.257193 -290.847868) (xy 417.226643 -290.889916) (xy 417.189892 -290.926667)
			(xy 417.147844 -290.957217) (xy 417.101534 -290.980813) (xy 417.052104 -290.996874) (xy 417.000769 -291.005004)
			(xy 416.948795 -291.005004) (xy 416.89746 -290.996874) (xy 416.84803 -290.980813) (xy 416.80172 -290.957217)
			(xy 416.759672 -290.926667) (xy 416.722921 -290.889916) (xy 416.692371 -290.847868) (xy 416.668775 -290.801558)
			(xy 416.652714 -290.752128) (xy 416.644584 -290.700793) (xy 416.35502 -290.700793) (xy 416.34689 -290.752128)
			(xy 416.330829 -290.801558) (xy 416.307233 -290.847868) (xy 416.276683 -290.889916) (xy 416.239932 -290.926667)
			(xy 416.197884 -290.957217) (xy 416.151574 -290.980813) (xy 416.102144 -290.996874) (xy 416.050809 -291.005004)
			(xy 415.998835 -291.005004) (xy 415.9475 -290.996874) (xy 415.89807 -290.980813) (xy 415.85176 -290.957217)
			(xy 415.809712 -290.926667) (xy 415.772961 -290.889916) (xy 415.742411 -290.847868) (xy 415.718815 -290.801558)
			(xy 415.702754 -290.752128) (xy 415.694624 -290.700793) (xy 415.40506 -290.700793) (xy 415.39693 -290.752128)
			(xy 415.380869 -290.801558) (xy 415.357273 -290.847868) (xy 415.326723 -290.889916) (xy 415.289972 -290.926667)
			(xy 415.247924 -290.957217) (xy 415.201614 -290.980813) (xy 415.152184 -290.996874) (xy 415.100849 -291.005004)
			(xy 415.048875 -291.005004) (xy 414.99754 -290.996874) (xy 414.94811 -290.980813) (xy 414.9018 -290.957217)
			(xy 414.859752 -290.926667) (xy 414.823001 -290.889916) (xy 414.792451 -290.847868) (xy 414.768855 -290.801558)
			(xy 414.752794 -290.752128) (xy 414.744664 -290.700793) (xy 414.4551 -290.700793) (xy 414.44697 -290.752128)
			(xy 414.430909 -290.801558) (xy 414.407313 -290.847868) (xy 414.376763 -290.889916) (xy 414.340012 -290.926667)
			(xy 414.297964 -290.957217) (xy 414.251654 -290.980813) (xy 414.202224 -290.996874) (xy 414.150889 -291.005004)
			(xy 414.098915 -291.005004) (xy 414.04758 -290.996874) (xy 413.99815 -290.980813) (xy 413.95184 -290.957217)
			(xy 413.909792 -290.926667) (xy 413.873041 -290.889916) (xy 413.842491 -290.847868) (xy 413.818895 -290.801558)
			(xy 413.802834 -290.752128) (xy 413.794704 -290.700793) (xy 413.50514 -290.700793) (xy 413.49701 -290.752128)
			(xy 413.480949 -290.801558) (xy 413.457353 -290.847868) (xy 413.426803 -290.889916) (xy 413.390052 -290.926667)
			(xy 413.348004 -290.957217) (xy 413.301694 -290.980813) (xy 413.252264 -290.996874) (xy 413.200929 -291.005004)
			(xy 413.148955 -291.005004) (xy 413.09762 -290.996874) (xy 413.04819 -290.980813) (xy 413.00188 -290.957217)
			(xy 412.959832 -290.926667) (xy 412.923081 -290.889916) (xy 412.892531 -290.847868) (xy 412.868935 -290.801558)
			(xy 412.852874 -290.752128) (xy 412.844744 -290.700793) (xy 412.55518 -290.700793) (xy 412.54705 -290.752128)
			(xy 412.530989 -290.801558) (xy 412.507393 -290.847868) (xy 412.476843 -290.889916) (xy 412.440092 -290.926667)
			(xy 412.398044 -290.957217) (xy 412.351734 -290.980813) (xy 412.302304 -290.996874) (xy 412.250969 -291.005004)
			(xy 412.198995 -291.005004) (xy 412.14766 -290.996874) (xy 412.09823 -290.980813) (xy 412.05192 -290.957217)
			(xy 412.009872 -290.926667) (xy 411.973121 -290.889916) (xy 411.942571 -290.847868) (xy 411.918975 -290.801558)
			(xy 411.902914 -290.752128) (xy 411.894784 -290.700793) (xy 411.60522 -290.700793) (xy 411.59709 -290.752128)
			(xy 411.581029 -290.801558) (xy 411.557433 -290.847868) (xy 411.526883 -290.889916) (xy 411.490132 -290.926667)
			(xy 411.448084 -290.957217) (xy 411.401774 -290.980813) (xy 411.352344 -290.996874) (xy 411.301009 -291.005004)
			(xy 411.249035 -291.005004) (xy 411.1977 -290.996874) (xy 411.14827 -290.980813) (xy 411.10196 -290.957217)
			(xy 411.059912 -290.926667) (xy 411.023161 -290.889916) (xy 410.992611 -290.847868) (xy 410.969015 -290.801558)
			(xy 410.952954 -290.752128) (xy 410.944824 -290.700793) (xy 410.655006 -290.700793) (xy 410.646876 -290.752128)
			(xy 410.630815 -290.801558) (xy 410.607219 -290.847868) (xy 410.576669 -290.889916) (xy 410.539918 -290.926667)
			(xy 410.49787 -290.957217) (xy 410.45156 -290.980813) (xy 410.40213 -290.996874) (xy 410.350795 -291.005004)
			(xy 410.298821 -291.005004) (xy 410.247486 -290.996874) (xy 410.198056 -290.980813) (xy 410.151746 -290.957217)
			(xy 410.109698 -290.926667) (xy 410.072947 -290.889916) (xy 410.042397 -290.847868) (xy 410.018801 -290.801558)
			(xy 410.00274 -290.752128) (xy 409.99461 -290.700793) (xy 409.705046 -290.700793) (xy 409.696916 -290.752128)
			(xy 409.680855 -290.801558) (xy 409.657259 -290.847868) (xy 409.626709 -290.889916) (xy 409.589958 -290.926667)
			(xy 409.54791 -290.957217) (xy 409.5016 -290.980813) (xy 409.45217 -290.996874) (xy 409.400835 -291.005004)
			(xy 409.348861 -291.005004) (xy 409.297526 -290.996874) (xy 409.248096 -290.980813) (xy 409.201786 -290.957217)
			(xy 409.159738 -290.926667) (xy 409.122987 -290.889916) (xy 409.092437 -290.847868) (xy 409.068841 -290.801558)
			(xy 409.05278 -290.752128) (xy 409.04465 -290.700793) (xy 408.755086 -290.700793) (xy 408.746956 -290.752128)
			(xy 408.730895 -290.801558) (xy 408.707299 -290.847868) (xy 408.676749 -290.889916) (xy 408.639998 -290.926667)
			(xy 408.59795 -290.957217) (xy 408.55164 -290.980813) (xy 408.50221 -290.996874) (xy 408.450875 -291.005004)
			(xy 408.398901 -291.005004) (xy 408.347566 -290.996874) (xy 408.298136 -290.980813) (xy 408.251826 -290.957217)
			(xy 408.209778 -290.926667) (xy 408.173027 -290.889916) (xy 408.142477 -290.847868) (xy 408.118881 -290.801558)
			(xy 408.10282 -290.752128) (xy 408.09469 -290.700793) (xy 406.855166 -290.700793) (xy 406.847036 -290.752128)
			(xy 406.830975 -290.801558) (xy 406.807379 -290.847868) (xy 406.776829 -290.889916) (xy 406.740078 -290.926667)
			(xy 406.69803 -290.957217) (xy 406.65172 -290.980813) (xy 406.60229 -290.996874) (xy 406.550955 -291.005004)
			(xy 406.498981 -291.005004) (xy 406.447646 -290.996874) (xy 406.398216 -290.980813) (xy 406.351906 -290.957217)
			(xy 406.309858 -290.926667) (xy 406.273107 -290.889916) (xy 406.242557 -290.847868) (xy 406.218961 -290.801558)
			(xy 406.2029 -290.752128) (xy 406.19477 -290.700793) (xy 405.905206 -290.700793) (xy 405.897076 -290.752128)
			(xy 405.881015 -290.801558) (xy 405.857419 -290.847868) (xy 405.826869 -290.889916) (xy 405.790118 -290.926667)
			(xy 405.74807 -290.957217) (xy 405.70176 -290.980813) (xy 405.65233 -290.996874) (xy 405.600995 -291.005004)
			(xy 405.549021 -291.005004) (xy 405.497686 -290.996874) (xy 405.448256 -290.980813) (xy 405.401946 -290.957217)
			(xy 405.359898 -290.926667) (xy 405.323147 -290.889916) (xy 405.292597 -290.847868) (xy 405.269001 -290.801558)
			(xy 405.25294 -290.752128) (xy 405.24481 -290.700793) (xy 404.954992 -290.700793) (xy 404.946862 -290.752128)
			(xy 404.930801 -290.801558) (xy 404.907205 -290.847868) (xy 404.876655 -290.889916) (xy 404.839904 -290.926667)
			(xy 404.797856 -290.957217) (xy 404.751546 -290.980813) (xy 404.702116 -290.996874) (xy 404.650781 -291.005004)
			(xy 404.598807 -291.005004) (xy 404.547472 -290.996874) (xy 404.498042 -290.980813) (xy 404.451732 -290.957217)
			(xy 404.409684 -290.926667) (xy 404.372933 -290.889916) (xy 404.342383 -290.847868) (xy 404.318787 -290.801558)
			(xy 404.302726 -290.752128) (xy 404.294596 -290.700793) (xy 404.005032 -290.700793) (xy 403.996902 -290.752128)
			(xy 403.980841 -290.801558) (xy 403.957245 -290.847868) (xy 403.926695 -290.889916) (xy 403.889944 -290.926667)
			(xy 403.847896 -290.957217) (xy 403.801586 -290.980813) (xy 403.752156 -290.996874) (xy 403.700821 -291.005004)
			(xy 403.648847 -291.005004) (xy 403.597512 -290.996874) (xy 403.548082 -290.980813) (xy 403.501772 -290.957217)
			(xy 403.459724 -290.926667) (xy 403.422973 -290.889916) (xy 403.392423 -290.847868) (xy 403.368827 -290.801558)
			(xy 403.352766 -290.752128) (xy 403.344636 -290.700793) (xy 403.055072 -290.700793) (xy 403.046942 -290.752128)
			(xy 403.030881 -290.801558) (xy 403.007285 -290.847868) (xy 402.976735 -290.889916) (xy 402.939984 -290.926667)
			(xy 402.897936 -290.957217) (xy 402.851626 -290.980813) (xy 402.802196 -290.996874) (xy 402.750861 -291.005004)
			(xy 402.698887 -291.005004) (xy 402.647552 -290.996874) (xy 402.598122 -290.980813) (xy 402.551812 -290.957217)
			(xy 402.509764 -290.926667) (xy 402.473013 -290.889916) (xy 402.442463 -290.847868) (xy 402.418867 -290.801558)
			(xy 402.402806 -290.752128) (xy 402.394676 -290.700793) (xy 402.105112 -290.700793) (xy 402.096982 -290.752128)
			(xy 402.080921 -290.801558) (xy 402.057325 -290.847868) (xy 402.026775 -290.889916) (xy 401.990024 -290.926667)
			(xy 401.947976 -290.957217) (xy 401.901666 -290.980813) (xy 401.852236 -290.996874) (xy 401.800901 -291.005004)
			(xy 401.748927 -291.005004) (xy 401.697592 -290.996874) (xy 401.648162 -290.980813) (xy 401.601852 -290.957217)
			(xy 401.559804 -290.926667) (xy 401.523053 -290.889916) (xy 401.492503 -290.847868) (xy 401.468907 -290.801558)
			(xy 401.452846 -290.752128) (xy 401.444716 -290.700793) (xy 401.155152 -290.700793) (xy 401.147022 -290.752128)
			(xy 401.130961 -290.801558) (xy 401.107365 -290.847868) (xy 401.076815 -290.889916) (xy 401.040064 -290.926667)
			(xy 400.998016 -290.957217) (xy 400.951706 -290.980813) (xy 400.902276 -290.996874) (xy 400.850941 -291.005004)
			(xy 400.798967 -291.005004) (xy 400.747632 -290.996874) (xy 400.698202 -290.980813) (xy 400.651892 -290.957217)
			(xy 400.609844 -290.926667) (xy 400.573093 -290.889916) (xy 400.542543 -290.847868) (xy 400.518947 -290.801558)
			(xy 400.502886 -290.752128) (xy 400.494756 -290.700793) (xy 400.205192 -290.700793) (xy 400.197062 -290.752128)
			(xy 400.181001 -290.801558) (xy 400.157405 -290.847868) (xy 400.126855 -290.889916) (xy 400.090104 -290.926667)
			(xy 400.048056 -290.957217) (xy 400.001746 -290.980813) (xy 399.952316 -290.996874) (xy 399.900981 -291.005004)
			(xy 399.849007 -291.005004) (xy 399.797672 -290.996874) (xy 399.748242 -290.980813) (xy 399.701932 -290.957217)
			(xy 399.659884 -290.926667) (xy 399.623133 -290.889916) (xy 399.592583 -290.847868) (xy 399.568987 -290.801558)
			(xy 399.552926 -290.752128) (xy 399.544796 -290.700793) (xy 399.255232 -290.700793) (xy 399.247102 -290.752128)
			(xy 399.231041 -290.801558) (xy 399.207445 -290.847868) (xy 399.176895 -290.889916) (xy 399.140144 -290.926667)
			(xy 399.098096 -290.957217) (xy 399.051786 -290.980813) (xy 399.002356 -290.996874) (xy 398.951021 -291.005004)
			(xy 398.899047 -291.005004) (xy 398.847712 -290.996874) (xy 398.798282 -290.980813) (xy 398.751972 -290.957217)
			(xy 398.709924 -290.926667) (xy 398.673173 -290.889916) (xy 398.642623 -290.847868) (xy 398.619027 -290.801558)
			(xy 398.602966 -290.752128) (xy 398.594836 -290.700793) (xy 398.305018 -290.700793) (xy 398.296888 -290.752128)
			(xy 398.280827 -290.801558) (xy 398.257231 -290.847868) (xy 398.226681 -290.889916) (xy 398.18993 -290.926667)
			(xy 398.147882 -290.957217) (xy 398.101572 -290.980813) (xy 398.052142 -290.996874) (xy 398.000807 -291.005004)
			(xy 397.948833 -291.005004) (xy 397.897498 -290.996874) (xy 397.848068 -290.980813) (xy 397.801758 -290.957217)
			(xy 397.75971 -290.926667) (xy 397.722959 -290.889916) (xy 397.692409 -290.847868) (xy 397.668813 -290.801558)
			(xy 397.652752 -290.752128) (xy 397.644622 -290.700793) (xy 397.355058 -290.700793) (xy 397.346928 -290.752128)
			(xy 397.330867 -290.801558) (xy 397.307271 -290.847868) (xy 397.276721 -290.889916) (xy 397.23997 -290.926667)
			(xy 397.197922 -290.957217) (xy 397.151612 -290.980813) (xy 397.102182 -290.996874) (xy 397.050847 -291.005004)
			(xy 396.998873 -291.005004) (xy 396.947538 -290.996874) (xy 396.898108 -290.980813) (xy 396.851798 -290.957217)
			(xy 396.80975 -290.926667) (xy 396.772999 -290.889916) (xy 396.742449 -290.847868) (xy 396.718853 -290.801558)
			(xy 396.702792 -290.752128) (xy 396.694662 -290.700793) (xy 396.405098 -290.700793) (xy 396.396968 -290.752128)
			(xy 396.380907 -290.801558) (xy 396.357311 -290.847868) (xy 396.326761 -290.889916) (xy 396.29001 -290.926667)
			(xy 396.247962 -290.957217) (xy 396.201652 -290.980813) (xy 396.152222 -290.996874) (xy 396.100887 -291.005004)
			(xy 396.048913 -291.005004) (xy 395.997578 -290.996874) (xy 395.948148 -290.980813) (xy 395.901838 -290.957217)
			(xy 395.85979 -290.926667) (xy 395.823039 -290.889916) (xy 395.792489 -290.847868) (xy 395.768893 -290.801558)
			(xy 395.752832 -290.752128) (xy 395.744702 -290.700793) (xy 394.505178 -290.700793) (xy 394.497048 -290.752128)
			(xy 394.480987 -290.801558) (xy 394.457391 -290.847868) (xy 394.426841 -290.889916) (xy 394.39009 -290.926667)
			(xy 394.348042 -290.957217) (xy 394.301732 -290.980813) (xy 394.252302 -290.996874) (xy 394.200967 -291.005004)
			(xy 394.148993 -291.005004) (xy 394.097658 -290.996874) (xy 394.048228 -290.980813) (xy 394.001918 -290.957217)
			(xy 393.95987 -290.926667) (xy 393.923119 -290.889916) (xy 393.892569 -290.847868) (xy 393.868973 -290.801558)
			(xy 393.852912 -290.752128) (xy 393.844782 -290.700793) (xy 392.605004 -290.700793) (xy 392.596874 -290.752128)
			(xy 392.580813 -290.801558) (xy 392.557217 -290.847868) (xy 392.526667 -290.889916) (xy 392.489916 -290.926667)
			(xy 392.447868 -290.957217) (xy 392.401558 -290.980813) (xy 392.352128 -290.996874) (xy 392.300793 -291.005004)
			(xy 392.248819 -291.005004) (xy 392.197484 -290.996874) (xy 392.148054 -290.980813) (xy 392.101744 -290.957217)
			(xy 392.059696 -290.926667) (xy 392.022945 -290.889916) (xy 391.992395 -290.847868) (xy 391.968799 -290.801558)
			(xy 391.952738 -290.752128) (xy 391.944608 -290.700793) (xy 391.653921 -290.700793) (xy 391.651768 -290.727626)
			(xy 391.639157 -290.779097) (xy 391.6185 -290.827898) (xy 391.590323 -290.87278) (xy 391.555349 -290.912593)
			(xy 391.514473 -290.946319) (xy 391.468741 -290.973094) (xy 391.444226 -290.983162) (xy 391.43686 -290.985956)
			(xy 391.425176 -290.995354) (xy 391.420604 -291.001958) (xy 391.416492 -291.008409) (xy 391.411957 -291.023014)
			(xy 391.411714 -291.03066) (xy 391.411714 -291.268912) (xy 391.411974 -291.276556) (xy 391.4165 -291.291159)
			(xy 391.420604 -291.297614) (xy 391.425176 -291.304218) (xy 391.43686 -291.313616) (xy 391.444226 -291.31641)
			(xy 391.468748 -291.326468) (xy 391.514486 -291.353245) (xy 391.555368 -291.386973) (xy 391.590347 -291.42679)
			(xy 391.618528 -291.471676) (xy 391.63919 -291.520482) (xy 391.651803 -291.571958) (xy 391.656045 -291.624788)
			(xy 391.653962 -291.650753) (xy 391.944608 -291.650753) (xy 391.944608 -291.598779) (xy 391.952738 -291.547444)
			(xy 391.968799 -291.498014) (xy 391.992395 -291.451704) (xy 392.022945 -291.409656) (xy 392.059696 -291.372905)
			(xy 392.101744 -291.342355) (xy 392.148054 -291.318759) (xy 392.197484 -291.302698) (xy 392.248819 -291.294568)
			(xy 392.300793 -291.294568) (xy 392.352128 -291.302698) (xy 392.401558 -291.318759) (xy 392.447868 -291.342355)
			(xy 392.489916 -291.372905) (xy 392.526667 -291.409656) (xy 392.557217 -291.451704) (xy 392.580813 -291.498014)
			(xy 392.596874 -291.547444) (xy 392.605004 -291.598779) (xy 392.605514 -291.624766) (xy 392.605004 -291.650753)
			(xy 393.844782 -291.650753) (xy 393.844782 -291.598779) (xy 393.852912 -291.547444) (xy 393.868973 -291.498014)
			(xy 393.892569 -291.451704) (xy 393.923119 -291.409656) (xy 393.95987 -291.372905) (xy 394.001918 -291.342355)
			(xy 394.048228 -291.318759) (xy 394.097658 -291.302698) (xy 394.148993 -291.294568) (xy 394.200967 -291.294568)
			(xy 394.252302 -291.302698) (xy 394.301732 -291.318759) (xy 394.348042 -291.342355) (xy 394.39009 -291.372905)
			(xy 394.426841 -291.409656) (xy 394.457391 -291.451704) (xy 394.480987 -291.498014) (xy 394.497048 -291.547444)
			(xy 394.505178 -291.598779) (xy 394.505688 -291.624766) (xy 394.505178 -291.650753) (xy 394.794742 -291.650753)
			(xy 394.794742 -291.598779) (xy 394.802872 -291.547444) (xy 394.818933 -291.498014) (xy 394.842529 -291.451704)
			(xy 394.873079 -291.409656) (xy 394.90983 -291.372905) (xy 394.951878 -291.342355) (xy 394.998188 -291.318759)
			(xy 395.047618 -291.302698) (xy 395.098953 -291.294568) (xy 395.150927 -291.294568) (xy 395.202262 -291.302698)
			(xy 395.251692 -291.318759) (xy 395.298002 -291.342355) (xy 395.34005 -291.372905) (xy 395.376801 -291.409656)
			(xy 395.407351 -291.451704) (xy 395.430947 -291.498014) (xy 395.447008 -291.547444) (xy 395.455138 -291.598779)
			(xy 395.455648 -291.624766) (xy 395.455138 -291.650753) (xy 395.744702 -291.650753) (xy 395.744702 -291.598779)
			(xy 395.752832 -291.547444) (xy 395.768893 -291.498014) (xy 395.792489 -291.451704) (xy 395.823039 -291.409656)
			(xy 395.85979 -291.372905) (xy 395.901838 -291.342355) (xy 395.948148 -291.318759) (xy 395.997578 -291.302698)
			(xy 396.048913 -291.294568) (xy 396.100887 -291.294568) (xy 396.152222 -291.302698) (xy 396.201652 -291.318759)
			(xy 396.247962 -291.342355) (xy 396.29001 -291.372905) (xy 396.326761 -291.409656) (xy 396.357311 -291.451704)
			(xy 396.380907 -291.498014) (xy 396.396968 -291.547444) (xy 396.405098 -291.598779) (xy 396.405608 -291.624766)
			(xy 396.405098 -291.650753) (xy 396.694662 -291.650753) (xy 396.694662 -291.598779) (xy 396.702792 -291.547444)
			(xy 396.718853 -291.498014) (xy 396.742449 -291.451704) (xy 396.772999 -291.409656) (xy 396.80975 -291.372905)
			(xy 396.851798 -291.342355) (xy 396.898108 -291.318759) (xy 396.947538 -291.302698) (xy 396.998873 -291.294568)
			(xy 397.050847 -291.294568) (xy 397.102182 -291.302698) (xy 397.151612 -291.318759) (xy 397.197922 -291.342355)
			(xy 397.23997 -291.372905) (xy 397.276721 -291.409656) (xy 397.307271 -291.451704) (xy 397.330867 -291.498014)
			(xy 397.346928 -291.547444) (xy 397.355058 -291.598779) (xy 397.355568 -291.624766) (xy 397.355058 -291.650753)
			(xy 397.644622 -291.650753) (xy 397.644622 -291.598779) (xy 397.652752 -291.547444) (xy 397.668813 -291.498014)
			(xy 397.692409 -291.451704) (xy 397.722959 -291.409656) (xy 397.75971 -291.372905) (xy 397.801758 -291.342355)
			(xy 397.848068 -291.318759) (xy 397.897498 -291.302698) (xy 397.948833 -291.294568) (xy 398.000807 -291.294568)
			(xy 398.052142 -291.302698) (xy 398.101572 -291.318759) (xy 398.147882 -291.342355) (xy 398.18993 -291.372905)
			(xy 398.226681 -291.409656) (xy 398.257231 -291.451704) (xy 398.280827 -291.498014) (xy 398.296888 -291.547444)
			(xy 398.305018 -291.598779) (xy 398.305528 -291.624766) (xy 398.305018 -291.650753) (xy 398.594836 -291.650753)
			(xy 398.594836 -291.598779) (xy 398.602966 -291.547444) (xy 398.619027 -291.498014) (xy 398.642623 -291.451704)
			(xy 398.673173 -291.409656) (xy 398.709924 -291.372905) (xy 398.751972 -291.342355) (xy 398.798282 -291.318759)
			(xy 398.847712 -291.302698) (xy 398.899047 -291.294568) (xy 398.951021 -291.294568) (xy 399.002356 -291.302698)
			(xy 399.051786 -291.318759) (xy 399.098096 -291.342355) (xy 399.140144 -291.372905) (xy 399.176895 -291.409656)
			(xy 399.207445 -291.451704) (xy 399.231041 -291.498014) (xy 399.247102 -291.547444) (xy 399.255232 -291.598779)
			(xy 399.255742 -291.624766) (xy 399.255232 -291.650753) (xy 399.544796 -291.650753) (xy 399.544796 -291.598779)
			(xy 399.552926 -291.547444) (xy 399.568987 -291.498014) (xy 399.592583 -291.451704) (xy 399.623133 -291.409656)
			(xy 399.659884 -291.372905) (xy 399.701932 -291.342355) (xy 399.748242 -291.318759) (xy 399.797672 -291.302698)
			(xy 399.849007 -291.294568) (xy 399.900981 -291.294568) (xy 399.952316 -291.302698) (xy 400.001746 -291.318759)
			(xy 400.048056 -291.342355) (xy 400.090104 -291.372905) (xy 400.126855 -291.409656) (xy 400.157405 -291.451704)
			(xy 400.181001 -291.498014) (xy 400.197062 -291.547444) (xy 400.205192 -291.598779) (xy 400.205702 -291.624766)
			(xy 400.205192 -291.650753) (xy 400.494756 -291.650753) (xy 400.494756 -291.598779) (xy 400.502886 -291.547444)
			(xy 400.518947 -291.498014) (xy 400.542543 -291.451704) (xy 400.573093 -291.409656) (xy 400.609844 -291.372905)
			(xy 400.651892 -291.342355) (xy 400.698202 -291.318759) (xy 400.747632 -291.302698) (xy 400.798967 -291.294568)
			(xy 400.850941 -291.294568) (xy 400.902276 -291.302698) (xy 400.951706 -291.318759) (xy 400.998016 -291.342355)
			(xy 401.040064 -291.372905) (xy 401.076815 -291.409656) (xy 401.107365 -291.451704) (xy 401.130961 -291.498014)
			(xy 401.147022 -291.547444) (xy 401.155152 -291.598779) (xy 401.155662 -291.624766) (xy 401.155152 -291.650753)
			(xy 401.444716 -291.650753) (xy 401.444716 -291.598779) (xy 401.452846 -291.547444) (xy 401.468907 -291.498014)
			(xy 401.492503 -291.451704) (xy 401.523053 -291.409656) (xy 401.559804 -291.372905) (xy 401.601852 -291.342355)
			(xy 401.648162 -291.318759) (xy 401.697592 -291.302698) (xy 401.748927 -291.294568) (xy 401.800901 -291.294568)
			(xy 401.852236 -291.302698) (xy 401.901666 -291.318759) (xy 401.947976 -291.342355) (xy 401.990024 -291.372905)
			(xy 402.026775 -291.409656) (xy 402.057325 -291.451704) (xy 402.080921 -291.498014) (xy 402.096982 -291.547444)
			(xy 402.105112 -291.598779) (xy 402.105622 -291.624766) (xy 402.105112 -291.650753) (xy 402.394676 -291.650753)
			(xy 402.394676 -291.598779) (xy 402.402806 -291.547444) (xy 402.418867 -291.498014) (xy 402.442463 -291.451704)
			(xy 402.473013 -291.409656) (xy 402.509764 -291.372905) (xy 402.551812 -291.342355) (xy 402.598122 -291.318759)
			(xy 402.647552 -291.302698) (xy 402.698887 -291.294568) (xy 402.750861 -291.294568) (xy 402.802196 -291.302698)
			(xy 402.851626 -291.318759) (xy 402.897936 -291.342355) (xy 402.939984 -291.372905) (xy 402.976735 -291.409656)
			(xy 403.007285 -291.451704) (xy 403.030881 -291.498014) (xy 403.046942 -291.547444) (xy 403.055072 -291.598779)
			(xy 403.055582 -291.624766) (xy 403.055072 -291.650753) (xy 403.344636 -291.650753) (xy 403.344636 -291.598779)
			(xy 403.352766 -291.547444) (xy 403.368827 -291.498014) (xy 403.392423 -291.451704) (xy 403.422973 -291.409656)
			(xy 403.459724 -291.372905) (xy 403.501772 -291.342355) (xy 403.548082 -291.318759) (xy 403.597512 -291.302698)
			(xy 403.648847 -291.294568) (xy 403.700821 -291.294568) (xy 403.752156 -291.302698) (xy 403.801586 -291.318759)
			(xy 403.847896 -291.342355) (xy 403.889944 -291.372905) (xy 403.926695 -291.409656) (xy 403.957245 -291.451704)
			(xy 403.980841 -291.498014) (xy 403.996902 -291.547444) (xy 404.005032 -291.598779) (xy 404.005542 -291.624766)
			(xy 404.005032 -291.650753) (xy 404.294596 -291.650753) (xy 404.294596 -291.598779) (xy 404.302726 -291.547444)
			(xy 404.318787 -291.498014) (xy 404.342383 -291.451704) (xy 404.372933 -291.409656) (xy 404.409684 -291.372905)
			(xy 404.451732 -291.342355) (xy 404.498042 -291.318759) (xy 404.547472 -291.302698) (xy 404.598807 -291.294568)
			(xy 404.650781 -291.294568) (xy 404.702116 -291.302698) (xy 404.751546 -291.318759) (xy 404.797856 -291.342355)
			(xy 404.839904 -291.372905) (xy 404.876655 -291.409656) (xy 404.907205 -291.451704) (xy 404.930801 -291.498014)
			(xy 404.946862 -291.547444) (xy 404.954992 -291.598779) (xy 404.955502 -291.624766) (xy 404.954992 -291.650753)
			(xy 405.24481 -291.650753) (xy 405.24481 -291.598779) (xy 405.25294 -291.547444) (xy 405.269001 -291.498014)
			(xy 405.292597 -291.451704) (xy 405.323147 -291.409656) (xy 405.359898 -291.372905) (xy 405.401946 -291.342355)
			(xy 405.448256 -291.318759) (xy 405.497686 -291.302698) (xy 405.549021 -291.294568) (xy 405.600995 -291.294568)
			(xy 405.65233 -291.302698) (xy 405.70176 -291.318759) (xy 405.74807 -291.342355) (xy 405.790118 -291.372905)
			(xy 405.826869 -291.409656) (xy 405.857419 -291.451704) (xy 405.881015 -291.498014) (xy 405.897076 -291.547444)
			(xy 405.905206 -291.598779) (xy 405.905716 -291.624766) (xy 405.905206 -291.650753) (xy 406.19477 -291.650753)
			(xy 406.19477 -291.598779) (xy 406.2029 -291.547444) (xy 406.218961 -291.498014) (xy 406.242557 -291.451704)
			(xy 406.273107 -291.409656) (xy 406.309858 -291.372905) (xy 406.351906 -291.342355) (xy 406.398216 -291.318759)
			(xy 406.447646 -291.302698) (xy 406.498981 -291.294568) (xy 406.550955 -291.294568) (xy 406.60229 -291.302698)
			(xy 406.65172 -291.318759) (xy 406.69803 -291.342355) (xy 406.740078 -291.372905) (xy 406.776829 -291.409656)
			(xy 406.807379 -291.451704) (xy 406.830975 -291.498014) (xy 406.847036 -291.547444) (xy 406.855166 -291.598779)
			(xy 406.855676 -291.624766) (xy 406.855166 -291.650753) (xy 408.09469 -291.650753) (xy 408.09469 -291.598779)
			(xy 408.10282 -291.547444) (xy 408.118881 -291.498014) (xy 408.142477 -291.451704) (xy 408.173027 -291.409656)
			(xy 408.209778 -291.372905) (xy 408.251826 -291.342355) (xy 408.298136 -291.318759) (xy 408.347566 -291.302698)
			(xy 408.398901 -291.294568) (xy 408.450875 -291.294568) (xy 408.50221 -291.302698) (xy 408.55164 -291.318759)
			(xy 408.59795 -291.342355) (xy 408.639998 -291.372905) (xy 408.676749 -291.409656) (xy 408.707299 -291.451704)
			(xy 408.730895 -291.498014) (xy 408.746956 -291.547444) (xy 408.755086 -291.598779) (xy 408.755596 -291.624766)
			(xy 408.755086 -291.650753) (xy 409.04465 -291.650753) (xy 409.04465 -291.598779) (xy 409.05278 -291.547444)
			(xy 409.068841 -291.498014) (xy 409.092437 -291.451704) (xy 409.122987 -291.409656) (xy 409.159738 -291.372905)
			(xy 409.201786 -291.342355) (xy 409.248096 -291.318759) (xy 409.297526 -291.302698) (xy 409.348861 -291.294568)
			(xy 409.400835 -291.294568) (xy 409.45217 -291.302698) (xy 409.5016 -291.318759) (xy 409.54791 -291.342355)
			(xy 409.589958 -291.372905) (xy 409.626709 -291.409656) (xy 409.657259 -291.451704) (xy 409.680855 -291.498014)
			(xy 409.696916 -291.547444) (xy 409.705046 -291.598779) (xy 409.705556 -291.624766) (xy 409.705046 -291.650753)
			(xy 409.99461 -291.650753) (xy 409.99461 -291.598779) (xy 410.00274 -291.547444) (xy 410.018801 -291.498014)
			(xy 410.042397 -291.451704) (xy 410.072947 -291.409656) (xy 410.109698 -291.372905) (xy 410.151746 -291.342355)
			(xy 410.198056 -291.318759) (xy 410.247486 -291.302698) (xy 410.298821 -291.294568) (xy 410.350795 -291.294568)
			(xy 410.40213 -291.302698) (xy 410.45156 -291.318759) (xy 410.49787 -291.342355) (xy 410.539918 -291.372905)
			(xy 410.576669 -291.409656) (xy 410.607219 -291.451704) (xy 410.630815 -291.498014) (xy 410.646876 -291.547444)
			(xy 410.655006 -291.598779) (xy 410.655516 -291.624766) (xy 410.655006 -291.650753) (xy 410.944824 -291.650753)
			(xy 410.944824 -291.598779) (xy 410.952954 -291.547444) (xy 410.969015 -291.498014) (xy 410.992611 -291.451704)
			(xy 411.023161 -291.409656) (xy 411.059912 -291.372905) (xy 411.10196 -291.342355) (xy 411.14827 -291.318759)
			(xy 411.1977 -291.302698) (xy 411.249035 -291.294568) (xy 411.301009 -291.294568) (xy 411.352344 -291.302698)
			(xy 411.401774 -291.318759) (xy 411.448084 -291.342355) (xy 411.490132 -291.372905) (xy 411.526883 -291.409656)
			(xy 411.557433 -291.451704) (xy 411.581029 -291.498014) (xy 411.59709 -291.547444) (xy 411.60522 -291.598779)
			(xy 411.60573 -291.624766) (xy 411.60522 -291.650753) (xy 411.894784 -291.650753) (xy 411.894784 -291.598779)
			(xy 411.902914 -291.547444) (xy 411.918975 -291.498014) (xy 411.942571 -291.451704) (xy 411.973121 -291.409656)
			(xy 412.009872 -291.372905) (xy 412.05192 -291.342355) (xy 412.09823 -291.318759) (xy 412.14766 -291.302698)
			(xy 412.198995 -291.294568) (xy 412.250969 -291.294568) (xy 412.302304 -291.302698) (xy 412.351734 -291.318759)
			(xy 412.398044 -291.342355) (xy 412.440092 -291.372905) (xy 412.476843 -291.409656) (xy 412.507393 -291.451704)
			(xy 412.530989 -291.498014) (xy 412.54705 -291.547444) (xy 412.55518 -291.598779) (xy 412.55569 -291.624766)
			(xy 412.55518 -291.650753) (xy 412.844744 -291.650753) (xy 412.844744 -291.598779) (xy 412.852874 -291.547444)
			(xy 412.868935 -291.498014) (xy 412.892531 -291.451704) (xy 412.923081 -291.409656) (xy 412.959832 -291.372905)
			(xy 413.00188 -291.342355) (xy 413.04819 -291.318759) (xy 413.09762 -291.302698) (xy 413.148955 -291.294568)
			(xy 413.200929 -291.294568) (xy 413.252264 -291.302698) (xy 413.301694 -291.318759) (xy 413.348004 -291.342355)
			(xy 413.390052 -291.372905) (xy 413.426803 -291.409656) (xy 413.457353 -291.451704) (xy 413.480949 -291.498014)
			(xy 413.49701 -291.547444) (xy 413.50514 -291.598779) (xy 413.50565 -291.624766) (xy 413.50514 -291.650753)
			(xy 413.794704 -291.650753) (xy 413.794704 -291.598779) (xy 413.802834 -291.547444) (xy 413.818895 -291.498014)
			(xy 413.842491 -291.451704) (xy 413.873041 -291.409656) (xy 413.909792 -291.372905) (xy 413.95184 -291.342355)
			(xy 413.99815 -291.318759) (xy 414.04758 -291.302698) (xy 414.098915 -291.294568) (xy 414.150889 -291.294568)
			(xy 414.202224 -291.302698) (xy 414.251654 -291.318759) (xy 414.297964 -291.342355) (xy 414.340012 -291.372905)
			(xy 414.376763 -291.409656) (xy 414.407313 -291.451704) (xy 414.430909 -291.498014) (xy 414.44697 -291.547444)
			(xy 414.4551 -291.598779) (xy 414.45561 -291.624766) (xy 414.4551 -291.650753) (xy 414.744664 -291.650753)
			(xy 414.744664 -291.598779) (xy 414.752794 -291.547444) (xy 414.768855 -291.498014) (xy 414.792451 -291.451704)
			(xy 414.823001 -291.409656) (xy 414.859752 -291.372905) (xy 414.9018 -291.342355) (xy 414.94811 -291.318759)
			(xy 414.99754 -291.302698) (xy 415.048875 -291.294568) (xy 415.100849 -291.294568) (xy 415.152184 -291.302698)
			(xy 415.201614 -291.318759) (xy 415.247924 -291.342355) (xy 415.289972 -291.372905) (xy 415.326723 -291.409656)
			(xy 415.357273 -291.451704) (xy 415.380869 -291.498014) (xy 415.39693 -291.547444) (xy 415.40506 -291.598779)
			(xy 415.40557 -291.624766) (xy 415.40506 -291.650753) (xy 415.694624 -291.650753) (xy 415.694624 -291.598779)
			(xy 415.702754 -291.547444) (xy 415.718815 -291.498014) (xy 415.742411 -291.451704) (xy 415.772961 -291.409656)
			(xy 415.809712 -291.372905) (xy 415.85176 -291.342355) (xy 415.89807 -291.318759) (xy 415.9475 -291.302698)
			(xy 415.998835 -291.294568) (xy 416.050809 -291.294568) (xy 416.102144 -291.302698) (xy 416.151574 -291.318759)
			(xy 416.197884 -291.342355) (xy 416.239932 -291.372905) (xy 416.276683 -291.409656) (xy 416.307233 -291.451704)
			(xy 416.330829 -291.498014) (xy 416.34689 -291.547444) (xy 416.35502 -291.598779) (xy 416.35553 -291.624766)
			(xy 416.35502 -291.650753) (xy 416.644584 -291.650753) (xy 416.644584 -291.598779) (xy 416.652714 -291.547444)
			(xy 416.668775 -291.498014) (xy 416.692371 -291.451704) (xy 416.722921 -291.409656) (xy 416.759672 -291.372905)
			(xy 416.80172 -291.342355) (xy 416.84803 -291.318759) (xy 416.89746 -291.302698) (xy 416.948795 -291.294568)
			(xy 417.000769 -291.294568) (xy 417.052104 -291.302698) (xy 417.101534 -291.318759) (xy 417.147844 -291.342355)
			(xy 417.189892 -291.372905) (xy 417.226643 -291.409656) (xy 417.257193 -291.451704) (xy 417.280789 -291.498014)
			(xy 417.29685 -291.547444) (xy 417.30498 -291.598779) (xy 417.30549 -291.624766) (xy 417.30498 -291.650753)
			(xy 417.594798 -291.650753) (xy 417.594798 -291.598779) (xy 417.602928 -291.547444) (xy 417.618989 -291.498014)
			(xy 417.642585 -291.451704) (xy 417.673135 -291.409656) (xy 417.709886 -291.372905) (xy 417.751934 -291.342355)
			(xy 417.798244 -291.318759) (xy 417.847674 -291.302698) (xy 417.899009 -291.294568) (xy 417.950983 -291.294568)
			(xy 418.002318 -291.302698) (xy 418.051748 -291.318759) (xy 418.098058 -291.342355) (xy 418.140106 -291.372905)
			(xy 418.176857 -291.409656) (xy 418.207407 -291.451704) (xy 418.231003 -291.498014) (xy 418.247064 -291.547444)
			(xy 418.255194 -291.598779) (xy 418.255704 -291.624766) (xy 418.255194 -291.650753) (xy 418.247064 -291.702088)
			(xy 418.231003 -291.751518) (xy 418.207407 -291.797828) (xy 418.176857 -291.839876) (xy 418.140106 -291.876627)
			(xy 418.098058 -291.907177) (xy 418.051748 -291.930773) (xy 418.002318 -291.946834) (xy 417.950983 -291.954964)
			(xy 417.899009 -291.954964) (xy 417.847674 -291.946834) (xy 417.798244 -291.930773) (xy 417.751934 -291.907177)
			(xy 417.709886 -291.876627) (xy 417.673135 -291.839876) (xy 417.642585 -291.797828) (xy 417.618989 -291.751518)
			(xy 417.602928 -291.702088) (xy 417.594798 -291.650753) (xy 417.30498 -291.650753) (xy 417.29685 -291.702088)
			(xy 417.280789 -291.751518) (xy 417.257193 -291.797828) (xy 417.226643 -291.839876) (xy 417.189892 -291.876627)
			(xy 417.147844 -291.907177) (xy 417.101534 -291.930773) (xy 417.052104 -291.946834) (xy 417.000769 -291.954964)
			(xy 416.948795 -291.954964) (xy 416.89746 -291.946834) (xy 416.84803 -291.930773) (xy 416.80172 -291.907177)
			(xy 416.759672 -291.876627) (xy 416.722921 -291.839876) (xy 416.692371 -291.797828) (xy 416.668775 -291.751518)
			(xy 416.652714 -291.702088) (xy 416.644584 -291.650753) (xy 416.35502 -291.650753) (xy 416.34689 -291.702088)
			(xy 416.330829 -291.751518) (xy 416.307233 -291.797828) (xy 416.276683 -291.839876) (xy 416.239932 -291.876627)
			(xy 416.197884 -291.907177) (xy 416.151574 -291.930773) (xy 416.102144 -291.946834) (xy 416.050809 -291.954964)
			(xy 415.998835 -291.954964) (xy 415.9475 -291.946834) (xy 415.89807 -291.930773) (xy 415.85176 -291.907177)
			(xy 415.809712 -291.876627) (xy 415.772961 -291.839876) (xy 415.742411 -291.797828) (xy 415.718815 -291.751518)
			(xy 415.702754 -291.702088) (xy 415.694624 -291.650753) (xy 415.40506 -291.650753) (xy 415.39693 -291.702088)
			(xy 415.380869 -291.751518) (xy 415.357273 -291.797828) (xy 415.326723 -291.839876) (xy 415.289972 -291.876627)
			(xy 415.247924 -291.907177) (xy 415.201614 -291.930773) (xy 415.152184 -291.946834) (xy 415.100849 -291.954964)
			(xy 415.048875 -291.954964) (xy 414.99754 -291.946834) (xy 414.94811 -291.930773) (xy 414.9018 -291.907177)
			(xy 414.859752 -291.876627) (xy 414.823001 -291.839876) (xy 414.792451 -291.797828) (xy 414.768855 -291.751518)
			(xy 414.752794 -291.702088) (xy 414.744664 -291.650753) (xy 414.4551 -291.650753) (xy 414.44697 -291.702088)
			(xy 414.430909 -291.751518) (xy 414.407313 -291.797828) (xy 414.376763 -291.839876) (xy 414.340012 -291.876627)
			(xy 414.297964 -291.907177) (xy 414.251654 -291.930773) (xy 414.202224 -291.946834) (xy 414.150889 -291.954964)
			(xy 414.098915 -291.954964) (xy 414.04758 -291.946834) (xy 413.99815 -291.930773) (xy 413.95184 -291.907177)
			(xy 413.909792 -291.876627) (xy 413.873041 -291.839876) (xy 413.842491 -291.797828) (xy 413.818895 -291.751518)
			(xy 413.802834 -291.702088) (xy 413.794704 -291.650753) (xy 413.50514 -291.650753) (xy 413.49701 -291.702088)
			(xy 413.480949 -291.751518) (xy 413.457353 -291.797828) (xy 413.426803 -291.839876) (xy 413.390052 -291.876627)
			(xy 413.348004 -291.907177) (xy 413.301694 -291.930773) (xy 413.252264 -291.946834) (xy 413.200929 -291.954964)
			(xy 413.148955 -291.954964) (xy 413.09762 -291.946834) (xy 413.04819 -291.930773) (xy 413.00188 -291.907177)
			(xy 412.959832 -291.876627) (xy 412.923081 -291.839876) (xy 412.892531 -291.797828) (xy 412.868935 -291.751518)
			(xy 412.852874 -291.702088) (xy 412.844744 -291.650753) (xy 412.55518 -291.650753) (xy 412.54705 -291.702088)
			(xy 412.530989 -291.751518) (xy 412.507393 -291.797828) (xy 412.476843 -291.839876) (xy 412.440092 -291.876627)
			(xy 412.398044 -291.907177) (xy 412.351734 -291.930773) (xy 412.302304 -291.946834) (xy 412.250969 -291.954964)
			(xy 412.198995 -291.954964) (xy 412.14766 -291.946834) (xy 412.09823 -291.930773) (xy 412.05192 -291.907177)
			(xy 412.009872 -291.876627) (xy 411.973121 -291.839876) (xy 411.942571 -291.797828) (xy 411.918975 -291.751518)
			(xy 411.902914 -291.702088) (xy 411.894784 -291.650753) (xy 411.60522 -291.650753) (xy 411.59709 -291.702088)
			(xy 411.581029 -291.751518) (xy 411.557433 -291.797828) (xy 411.526883 -291.839876) (xy 411.490132 -291.876627)
			(xy 411.448084 -291.907177) (xy 411.401774 -291.930773) (xy 411.352344 -291.946834) (xy 411.301009 -291.954964)
			(xy 411.249035 -291.954964) (xy 411.1977 -291.946834) (xy 411.14827 -291.930773) (xy 411.10196 -291.907177)
			(xy 411.059912 -291.876627) (xy 411.023161 -291.839876) (xy 410.992611 -291.797828) (xy 410.969015 -291.751518)
			(xy 410.952954 -291.702088) (xy 410.944824 -291.650753) (xy 410.655006 -291.650753) (xy 410.646876 -291.702088)
			(xy 410.630815 -291.751518) (xy 410.607219 -291.797828) (xy 410.576669 -291.839876) (xy 410.539918 -291.876627)
			(xy 410.49787 -291.907177) (xy 410.45156 -291.930773) (xy 410.40213 -291.946834) (xy 410.350795 -291.954964)
			(xy 410.298821 -291.954964) (xy 410.247486 -291.946834) (xy 410.198056 -291.930773) (xy 410.151746 -291.907177)
			(xy 410.109698 -291.876627) (xy 410.072947 -291.839876) (xy 410.042397 -291.797828) (xy 410.018801 -291.751518)
			(xy 410.00274 -291.702088) (xy 409.99461 -291.650753) (xy 409.705046 -291.650753) (xy 409.696916 -291.702088)
			(xy 409.680855 -291.751518) (xy 409.657259 -291.797828) (xy 409.626709 -291.839876) (xy 409.589958 -291.876627)
			(xy 409.54791 -291.907177) (xy 409.5016 -291.930773) (xy 409.45217 -291.946834) (xy 409.400835 -291.954964)
			(xy 409.348861 -291.954964) (xy 409.297526 -291.946834) (xy 409.248096 -291.930773) (xy 409.201786 -291.907177)
			(xy 409.159738 -291.876627) (xy 409.122987 -291.839876) (xy 409.092437 -291.797828) (xy 409.068841 -291.751518)
			(xy 409.05278 -291.702088) (xy 409.04465 -291.650753) (xy 408.755086 -291.650753) (xy 408.746956 -291.702088)
			(xy 408.730895 -291.751518) (xy 408.707299 -291.797828) (xy 408.676749 -291.839876) (xy 408.639998 -291.876627)
			(xy 408.59795 -291.907177) (xy 408.55164 -291.930773) (xy 408.50221 -291.946834) (xy 408.450875 -291.954964)
			(xy 408.398901 -291.954964) (xy 408.347566 -291.946834) (xy 408.298136 -291.930773) (xy 408.251826 -291.907177)
			(xy 408.209778 -291.876627) (xy 408.173027 -291.839876) (xy 408.142477 -291.797828) (xy 408.118881 -291.751518)
			(xy 408.10282 -291.702088) (xy 408.09469 -291.650753) (xy 406.855166 -291.650753) (xy 406.847036 -291.702088)
			(xy 406.830975 -291.751518) (xy 406.807379 -291.797828) (xy 406.776829 -291.839876) (xy 406.740078 -291.876627)
			(xy 406.69803 -291.907177) (xy 406.65172 -291.930773) (xy 406.60229 -291.946834) (xy 406.550955 -291.954964)
			(xy 406.498981 -291.954964) (xy 406.447646 -291.946834) (xy 406.398216 -291.930773) (xy 406.351906 -291.907177)
			(xy 406.309858 -291.876627) (xy 406.273107 -291.839876) (xy 406.242557 -291.797828) (xy 406.218961 -291.751518)
			(xy 406.2029 -291.702088) (xy 406.19477 -291.650753) (xy 405.905206 -291.650753) (xy 405.897076 -291.702088)
			(xy 405.881015 -291.751518) (xy 405.857419 -291.797828) (xy 405.826869 -291.839876) (xy 405.790118 -291.876627)
			(xy 405.74807 -291.907177) (xy 405.70176 -291.930773) (xy 405.65233 -291.946834) (xy 405.600995 -291.954964)
			(xy 405.549021 -291.954964) (xy 405.497686 -291.946834) (xy 405.448256 -291.930773) (xy 405.401946 -291.907177)
			(xy 405.359898 -291.876627) (xy 405.323147 -291.839876) (xy 405.292597 -291.797828) (xy 405.269001 -291.751518)
			(xy 405.25294 -291.702088) (xy 405.24481 -291.650753) (xy 404.954992 -291.650753) (xy 404.946862 -291.702088)
			(xy 404.930801 -291.751518) (xy 404.907205 -291.797828) (xy 404.876655 -291.839876) (xy 404.839904 -291.876627)
			(xy 404.797856 -291.907177) (xy 404.751546 -291.930773) (xy 404.702116 -291.946834) (xy 404.650781 -291.954964)
			(xy 404.598807 -291.954964) (xy 404.547472 -291.946834) (xy 404.498042 -291.930773) (xy 404.451732 -291.907177)
			(xy 404.409684 -291.876627) (xy 404.372933 -291.839876) (xy 404.342383 -291.797828) (xy 404.318787 -291.751518)
			(xy 404.302726 -291.702088) (xy 404.294596 -291.650753) (xy 404.005032 -291.650753) (xy 403.996902 -291.702088)
			(xy 403.980841 -291.751518) (xy 403.957245 -291.797828) (xy 403.926695 -291.839876) (xy 403.889944 -291.876627)
			(xy 403.847896 -291.907177) (xy 403.801586 -291.930773) (xy 403.752156 -291.946834) (xy 403.700821 -291.954964)
			(xy 403.648847 -291.954964) (xy 403.597512 -291.946834) (xy 403.548082 -291.930773) (xy 403.501772 -291.907177)
			(xy 403.459724 -291.876627) (xy 403.422973 -291.839876) (xy 403.392423 -291.797828) (xy 403.368827 -291.751518)
			(xy 403.352766 -291.702088) (xy 403.344636 -291.650753) (xy 403.055072 -291.650753) (xy 403.046942 -291.702088)
			(xy 403.030881 -291.751518) (xy 403.007285 -291.797828) (xy 402.976735 -291.839876) (xy 402.939984 -291.876627)
			(xy 402.897936 -291.907177) (xy 402.851626 -291.930773) (xy 402.802196 -291.946834) (xy 402.750861 -291.954964)
			(xy 402.698887 -291.954964) (xy 402.647552 -291.946834) (xy 402.598122 -291.930773) (xy 402.551812 -291.907177)
			(xy 402.509764 -291.876627) (xy 402.473013 -291.839876) (xy 402.442463 -291.797828) (xy 402.418867 -291.751518)
			(xy 402.402806 -291.702088) (xy 402.394676 -291.650753) (xy 402.105112 -291.650753) (xy 402.096982 -291.702088)
			(xy 402.080921 -291.751518) (xy 402.057325 -291.797828) (xy 402.026775 -291.839876) (xy 401.990024 -291.876627)
			(xy 401.947976 -291.907177) (xy 401.901666 -291.930773) (xy 401.852236 -291.946834) (xy 401.800901 -291.954964)
			(xy 401.748927 -291.954964) (xy 401.697592 -291.946834) (xy 401.648162 -291.930773) (xy 401.601852 -291.907177)
			(xy 401.559804 -291.876627) (xy 401.523053 -291.839876) (xy 401.492503 -291.797828) (xy 401.468907 -291.751518)
			(xy 401.452846 -291.702088) (xy 401.444716 -291.650753) (xy 401.155152 -291.650753) (xy 401.147022 -291.702088)
			(xy 401.130961 -291.751518) (xy 401.107365 -291.797828) (xy 401.076815 -291.839876) (xy 401.040064 -291.876627)
			(xy 400.998016 -291.907177) (xy 400.951706 -291.930773) (xy 400.902276 -291.946834) (xy 400.850941 -291.954964)
			(xy 400.798967 -291.954964) (xy 400.747632 -291.946834) (xy 400.698202 -291.930773) (xy 400.651892 -291.907177)
			(xy 400.609844 -291.876627) (xy 400.573093 -291.839876) (xy 400.542543 -291.797828) (xy 400.518947 -291.751518)
			(xy 400.502886 -291.702088) (xy 400.494756 -291.650753) (xy 400.205192 -291.650753) (xy 400.197062 -291.702088)
			(xy 400.181001 -291.751518) (xy 400.157405 -291.797828) (xy 400.126855 -291.839876) (xy 400.090104 -291.876627)
			(xy 400.048056 -291.907177) (xy 400.001746 -291.930773) (xy 399.952316 -291.946834) (xy 399.900981 -291.954964)
			(xy 399.849007 -291.954964) (xy 399.797672 -291.946834) (xy 399.748242 -291.930773) (xy 399.701932 -291.907177)
			(xy 399.659884 -291.876627) (xy 399.623133 -291.839876) (xy 399.592583 -291.797828) (xy 399.568987 -291.751518)
			(xy 399.552926 -291.702088) (xy 399.544796 -291.650753) (xy 399.255232 -291.650753) (xy 399.247102 -291.702088)
			(xy 399.231041 -291.751518) (xy 399.207445 -291.797828) (xy 399.176895 -291.839876) (xy 399.140144 -291.876627)
			(xy 399.098096 -291.907177) (xy 399.051786 -291.930773) (xy 399.002356 -291.946834) (xy 398.951021 -291.954964)
			(xy 398.899047 -291.954964) (xy 398.847712 -291.946834) (xy 398.798282 -291.930773) (xy 398.751972 -291.907177)
			(xy 398.709924 -291.876627) (xy 398.673173 -291.839876) (xy 398.642623 -291.797828) (xy 398.619027 -291.751518)
			(xy 398.602966 -291.702088) (xy 398.594836 -291.650753) (xy 398.305018 -291.650753) (xy 398.296888 -291.702088)
			(xy 398.280827 -291.751518) (xy 398.257231 -291.797828) (xy 398.226681 -291.839876) (xy 398.18993 -291.876627)
			(xy 398.147882 -291.907177) (xy 398.101572 -291.930773) (xy 398.052142 -291.946834) (xy 398.000807 -291.954964)
			(xy 397.948833 -291.954964) (xy 397.897498 -291.946834) (xy 397.848068 -291.930773) (xy 397.801758 -291.907177)
			(xy 397.75971 -291.876627) (xy 397.722959 -291.839876) (xy 397.692409 -291.797828) (xy 397.668813 -291.751518)
			(xy 397.652752 -291.702088) (xy 397.644622 -291.650753) (xy 397.355058 -291.650753) (xy 397.346928 -291.702088)
			(xy 397.330867 -291.751518) (xy 397.307271 -291.797828) (xy 397.276721 -291.839876) (xy 397.23997 -291.876627)
			(xy 397.197922 -291.907177) (xy 397.151612 -291.930773) (xy 397.102182 -291.946834) (xy 397.050847 -291.954964)
			(xy 396.998873 -291.954964) (xy 396.947538 -291.946834) (xy 396.898108 -291.930773) (xy 396.851798 -291.907177)
			(xy 396.80975 -291.876627) (xy 396.772999 -291.839876) (xy 396.742449 -291.797828) (xy 396.718853 -291.751518)
			(xy 396.702792 -291.702088) (xy 396.694662 -291.650753) (xy 396.405098 -291.650753) (xy 396.396968 -291.702088)
			(xy 396.380907 -291.751518) (xy 396.357311 -291.797828) (xy 396.326761 -291.839876) (xy 396.29001 -291.876627)
			(xy 396.247962 -291.907177) (xy 396.201652 -291.930773) (xy 396.152222 -291.946834) (xy 396.100887 -291.954964)
			(xy 396.048913 -291.954964) (xy 395.997578 -291.946834) (xy 395.948148 -291.930773) (xy 395.901838 -291.907177)
			(xy 395.85979 -291.876627) (xy 395.823039 -291.839876) (xy 395.792489 -291.797828) (xy 395.768893 -291.751518)
			(xy 395.752832 -291.702088) (xy 395.744702 -291.650753) (xy 395.455138 -291.650753) (xy 395.447008 -291.702088)
			(xy 395.430947 -291.751518) (xy 395.407351 -291.797828) (xy 395.376801 -291.839876) (xy 395.34005 -291.876627)
			(xy 395.298002 -291.907177) (xy 395.251692 -291.930773) (xy 395.202262 -291.946834) (xy 395.150927 -291.954964)
			(xy 395.098953 -291.954964) (xy 395.047618 -291.946834) (xy 394.998188 -291.930773) (xy 394.951878 -291.907177)
			(xy 394.90983 -291.876627) (xy 394.873079 -291.839876) (xy 394.842529 -291.797828) (xy 394.818933 -291.751518)
			(xy 394.802872 -291.702088) (xy 394.794742 -291.650753) (xy 394.505178 -291.650753) (xy 394.497048 -291.702088)
			(xy 394.480987 -291.751518) (xy 394.457391 -291.797828) (xy 394.426841 -291.839876) (xy 394.39009 -291.876627)
			(xy 394.348042 -291.907177) (xy 394.301732 -291.930773) (xy 394.252302 -291.946834) (xy 394.200967 -291.954964)
			(xy 394.148993 -291.954964) (xy 394.097658 -291.946834) (xy 394.048228 -291.930773) (xy 394.001918 -291.907177)
			(xy 393.95987 -291.876627) (xy 393.923119 -291.839876) (xy 393.892569 -291.797828) (xy 393.868973 -291.751518)
			(xy 393.852912 -291.702088) (xy 393.844782 -291.650753) (xy 392.605004 -291.650753) (xy 392.596874 -291.702088)
			(xy 392.580813 -291.751518) (xy 392.557217 -291.797828) (xy 392.526667 -291.839876) (xy 392.489916 -291.876627)
			(xy 392.447868 -291.907177) (xy 392.401558 -291.930773) (xy 392.352128 -291.946834) (xy 392.300793 -291.954964)
			(xy 392.248819 -291.954964) (xy 392.197484 -291.946834) (xy 392.148054 -291.930773) (xy 392.101744 -291.907177)
			(xy 392.059696 -291.876627) (xy 392.022945 -291.839876) (xy 391.992395 -291.797828) (xy 391.968799 -291.751518)
			(xy 391.952738 -291.702088) (xy 391.944608 -291.650753) (xy 391.653962 -291.650753) (xy 391.651807 -291.677617)
			(xy 391.639197 -291.729095) (xy 391.618539 -291.777902) (xy 391.590362 -291.82279) (xy 391.555385 -291.86261)
			(xy 391.514506 -291.896341) (xy 391.46877 -291.923121) (xy 391.444226 -291.933122) (xy 391.43686 -291.935916)
			(xy 391.425176 -291.945314) (xy 391.420604 -291.951918) (xy 391.416499 -291.958371) (xy 391.411982 -291.972976)
			(xy 391.411714 -291.98062) (xy 391.411714 -292.219126) (xy 391.411976 -292.226769) (xy 391.416505 -292.24137)
			(xy 391.420604 -292.247828) (xy 391.425176 -292.254432) (xy 391.43686 -292.26383) (xy 391.444226 -292.266624)
			(xy 391.468747 -292.276682) (xy 391.514483 -292.303458) (xy 391.555362 -292.337186) (xy 391.590339 -292.377002)
			(xy 391.618519 -292.421886) (xy 391.639179 -292.470691) (xy 391.651791 -292.522166) (xy 391.656032 -292.574993)
			(xy 391.653948 -292.600967) (xy 391.944608 -292.600967) (xy 391.944608 -292.548993) (xy 391.952738 -292.497658)
			(xy 391.968799 -292.448228) (xy 391.992395 -292.401918) (xy 392.022945 -292.35987) (xy 392.059696 -292.323119)
			(xy 392.101744 -292.292569) (xy 392.148054 -292.268973) (xy 392.197484 -292.252912) (xy 392.248819 -292.244782)
			(xy 392.300793 -292.244782) (xy 392.352128 -292.252912) (xy 392.401558 -292.268973) (xy 392.447868 -292.292569)
			(xy 392.489916 -292.323119) (xy 392.526667 -292.35987) (xy 392.557217 -292.401918) (xy 392.580813 -292.448228)
			(xy 392.596874 -292.497658) (xy 392.605004 -292.548993) (xy 392.605514 -292.57498) (xy 392.605004 -292.600967)
			(xy 393.844782 -292.600967) (xy 393.844782 -292.548993) (xy 393.852912 -292.497658) (xy 393.868973 -292.448228)
			(xy 393.892569 -292.401918) (xy 393.923119 -292.35987) (xy 393.95987 -292.323119) (xy 394.001918 -292.292569)
			(xy 394.048228 -292.268973) (xy 394.097658 -292.252912) (xy 394.148993 -292.244782) (xy 394.200967 -292.244782)
			(xy 394.252302 -292.252912) (xy 394.301732 -292.268973) (xy 394.348042 -292.292569) (xy 394.39009 -292.323119)
			(xy 394.426841 -292.35987) (xy 394.457391 -292.401918) (xy 394.480987 -292.448228) (xy 394.497048 -292.497658)
			(xy 394.505178 -292.548993) (xy 394.505688 -292.57498) (xy 394.505178 -292.600967) (xy 394.794742 -292.600967)
			(xy 394.794742 -292.548993) (xy 394.802872 -292.497658) (xy 394.818933 -292.448228) (xy 394.842529 -292.401918)
			(xy 394.873079 -292.35987) (xy 394.90983 -292.323119) (xy 394.951878 -292.292569) (xy 394.998188 -292.268973)
			(xy 395.047618 -292.252912) (xy 395.098953 -292.244782) (xy 395.150927 -292.244782) (xy 395.202262 -292.252912)
			(xy 395.251692 -292.268973) (xy 395.298002 -292.292569) (xy 395.34005 -292.323119) (xy 395.376801 -292.35987)
			(xy 395.407351 -292.401918) (xy 395.430947 -292.448228) (xy 395.447008 -292.497658) (xy 395.455138 -292.548993)
			(xy 395.455648 -292.57498) (xy 395.455138 -292.600967) (xy 395.744702 -292.600967) (xy 395.744702 -292.548993)
			(xy 395.752832 -292.497658) (xy 395.768893 -292.448228) (xy 395.792489 -292.401918) (xy 395.823039 -292.35987)
			(xy 395.85979 -292.323119) (xy 395.901838 -292.292569) (xy 395.948148 -292.268973) (xy 395.997578 -292.252912)
			(xy 396.048913 -292.244782) (xy 396.100887 -292.244782) (xy 396.152222 -292.252912) (xy 396.201652 -292.268973)
			(xy 396.247962 -292.292569) (xy 396.29001 -292.323119) (xy 396.326761 -292.35987) (xy 396.357311 -292.401918)
			(xy 396.380907 -292.448228) (xy 396.396968 -292.497658) (xy 396.405098 -292.548993) (xy 396.405608 -292.57498)
			(xy 396.405103 -292.600713) (xy 396.694662 -292.600713) (xy 396.694662 -292.548739) (xy 396.702792 -292.497404)
			(xy 396.718853 -292.447974) (xy 396.742449 -292.401664) (xy 396.772999 -292.359616) (xy 396.80975 -292.322865)
			(xy 396.851798 -292.292315) (xy 396.898108 -292.268719) (xy 396.947538 -292.252658) (xy 396.998873 -292.244528)
			(xy 397.050847 -292.244528) (xy 397.102182 -292.252658) (xy 397.151612 -292.268719) (xy 397.197922 -292.292315)
			(xy 397.23997 -292.322865) (xy 397.276721 -292.359616) (xy 397.307271 -292.401664) (xy 397.330867 -292.447974)
			(xy 397.346928 -292.497404) (xy 397.355058 -292.548739) (xy 397.355568 -292.574726) (xy 397.355058 -292.600713)
			(xy 397.644622 -292.600713) (xy 397.644622 -292.548739) (xy 397.652752 -292.497404) (xy 397.668813 -292.447974)
			(xy 397.692409 -292.401664) (xy 397.722959 -292.359616) (xy 397.75971 -292.322865) (xy 397.801758 -292.292315)
			(xy 397.848068 -292.268719) (xy 397.897498 -292.252658) (xy 397.948833 -292.244528) (xy 398.000807 -292.244528)
			(xy 398.052142 -292.252658) (xy 398.101572 -292.268719) (xy 398.147882 -292.292315) (xy 398.18993 -292.322865)
			(xy 398.226681 -292.359616) (xy 398.257231 -292.401664) (xy 398.280827 -292.447974) (xy 398.296888 -292.497404)
			(xy 398.305018 -292.548739) (xy 398.305528 -292.574726) (xy 398.305018 -292.600713) (xy 398.304978 -292.600967)
			(xy 398.594836 -292.600967) (xy 398.594836 -292.548993) (xy 398.602966 -292.497658) (xy 398.619027 -292.448228)
			(xy 398.642623 -292.401918) (xy 398.673173 -292.35987) (xy 398.709924 -292.323119) (xy 398.751972 -292.292569)
			(xy 398.798282 -292.268973) (xy 398.847712 -292.252912) (xy 398.899047 -292.244782) (xy 398.951021 -292.244782)
			(xy 399.002356 -292.252912) (xy 399.051786 -292.268973) (xy 399.098096 -292.292569) (xy 399.140144 -292.323119)
			(xy 399.176895 -292.35987) (xy 399.207445 -292.401918) (xy 399.231041 -292.448228) (xy 399.247102 -292.497658)
			(xy 399.255232 -292.548993) (xy 399.255742 -292.57498) (xy 399.255232 -292.600967) (xy 399.544796 -292.600967)
			(xy 399.544796 -292.548993) (xy 399.552926 -292.497658) (xy 399.568987 -292.448228) (xy 399.592583 -292.401918)
			(xy 399.623133 -292.35987) (xy 399.659884 -292.323119) (xy 399.701932 -292.292569) (xy 399.748242 -292.268973)
			(xy 399.797672 -292.252912) (xy 399.849007 -292.244782) (xy 399.900981 -292.244782) (xy 399.952316 -292.252912)
			(xy 400.001746 -292.268973) (xy 400.048056 -292.292569) (xy 400.090104 -292.323119) (xy 400.126855 -292.35987)
			(xy 400.157405 -292.401918) (xy 400.181001 -292.448228) (xy 400.197062 -292.497658) (xy 400.205192 -292.548993)
			(xy 400.205702 -292.57498) (xy 400.205192 -292.600967) (xy 400.494756 -292.600967) (xy 400.494756 -292.548993)
			(xy 400.502886 -292.497658) (xy 400.518947 -292.448228) (xy 400.542543 -292.401918) (xy 400.573093 -292.35987)
			(xy 400.609844 -292.323119) (xy 400.651892 -292.292569) (xy 400.698202 -292.268973) (xy 400.747632 -292.252912)
			(xy 400.798967 -292.244782) (xy 400.850941 -292.244782) (xy 400.902276 -292.252912) (xy 400.951706 -292.268973)
			(xy 400.998016 -292.292569) (xy 401.040064 -292.323119) (xy 401.076815 -292.35987) (xy 401.107365 -292.401918)
			(xy 401.130961 -292.448228) (xy 401.147022 -292.497658) (xy 401.155152 -292.548993) (xy 401.155662 -292.57498)
			(xy 401.155152 -292.600967) (xy 401.444716 -292.600967) (xy 401.444716 -292.548993) (xy 401.452846 -292.497658)
			(xy 401.468907 -292.448228) (xy 401.492503 -292.401918) (xy 401.523053 -292.35987) (xy 401.559804 -292.323119)
			(xy 401.601852 -292.292569) (xy 401.648162 -292.268973) (xy 401.697592 -292.252912) (xy 401.748927 -292.244782)
			(xy 401.800901 -292.244782) (xy 401.852236 -292.252912) (xy 401.901666 -292.268973) (xy 401.947976 -292.292569)
			(xy 401.990024 -292.323119) (xy 402.026775 -292.35987) (xy 402.057325 -292.401918) (xy 402.080921 -292.448228)
			(xy 402.096982 -292.497658) (xy 402.105112 -292.548993) (xy 402.105622 -292.57498) (xy 402.105112 -292.600967)
			(xy 402.394676 -292.600967) (xy 402.394676 -292.548993) (xy 402.402806 -292.497658) (xy 402.418867 -292.448228)
			(xy 402.442463 -292.401918) (xy 402.473013 -292.35987) (xy 402.509764 -292.323119) (xy 402.551812 -292.292569)
			(xy 402.598122 -292.268973) (xy 402.647552 -292.252912) (xy 402.698887 -292.244782) (xy 402.750861 -292.244782)
			(xy 402.802196 -292.252912) (xy 402.851626 -292.268973) (xy 402.897936 -292.292569) (xy 402.939984 -292.323119)
			(xy 402.976735 -292.35987) (xy 403.007285 -292.401918) (xy 403.030881 -292.448228) (xy 403.046942 -292.497658)
			(xy 403.055072 -292.548993) (xy 403.055582 -292.57498) (xy 403.055072 -292.600967) (xy 403.344636 -292.600967)
			(xy 403.344636 -292.548993) (xy 403.352766 -292.497658) (xy 403.368827 -292.448228) (xy 403.392423 -292.401918)
			(xy 403.422973 -292.35987) (xy 403.459724 -292.323119) (xy 403.501772 -292.292569) (xy 403.548082 -292.268973)
			(xy 403.597512 -292.252912) (xy 403.648847 -292.244782) (xy 403.700821 -292.244782) (xy 403.752156 -292.252912)
			(xy 403.801586 -292.268973) (xy 403.847896 -292.292569) (xy 403.889944 -292.323119) (xy 403.926695 -292.35987)
			(xy 403.957245 -292.401918) (xy 403.980841 -292.448228) (xy 403.996902 -292.497658) (xy 404.005032 -292.548993)
			(xy 404.005542 -292.57498) (xy 404.005032 -292.600967) (xy 404.29485 -292.600967) (xy 404.29485 -292.548993)
			(xy 404.30298 -292.497658) (xy 404.319041 -292.448228) (xy 404.342637 -292.401918) (xy 404.373187 -292.35987)
			(xy 404.409938 -292.323119) (xy 404.451986 -292.292569) (xy 404.498296 -292.268973) (xy 404.547726 -292.252912)
			(xy 404.599061 -292.244782) (xy 404.651035 -292.244782) (xy 404.70237 -292.252912) (xy 404.7518 -292.268973)
			(xy 404.79811 -292.292569) (xy 404.840158 -292.323119) (xy 404.876909 -292.35987) (xy 404.907459 -292.401918)
			(xy 404.931055 -292.448228) (xy 404.947116 -292.497658) (xy 404.955246 -292.548993) (xy 404.955756 -292.57498)
			(xy 404.955246 -292.600967) (xy 405.24481 -292.600967) (xy 405.24481 -292.548993) (xy 405.25294 -292.497658)
			(xy 405.269001 -292.448228) (xy 405.292597 -292.401918) (xy 405.323147 -292.35987) (xy 405.359898 -292.323119)
			(xy 405.401946 -292.292569) (xy 405.448256 -292.268973) (xy 405.497686 -292.252912) (xy 405.549021 -292.244782)
			(xy 405.600995 -292.244782) (xy 405.65233 -292.252912) (xy 405.70176 -292.268973) (xy 405.74807 -292.292569)
			(xy 405.790118 -292.323119) (xy 405.826869 -292.35987) (xy 405.857419 -292.401918) (xy 405.881015 -292.448228)
			(xy 405.897076 -292.497658) (xy 405.905206 -292.548993) (xy 405.905716 -292.57498) (xy 405.905206 -292.600967)
			(xy 406.19477 -292.600967) (xy 406.19477 -292.548993) (xy 406.2029 -292.497658) (xy 406.218961 -292.448228)
			(xy 406.242557 -292.401918) (xy 406.273107 -292.35987) (xy 406.309858 -292.323119) (xy 406.351906 -292.292569)
			(xy 406.398216 -292.268973) (xy 406.447646 -292.252912) (xy 406.498981 -292.244782) (xy 406.550955 -292.244782)
			(xy 406.60229 -292.252912) (xy 406.65172 -292.268973) (xy 406.69803 -292.292569) (xy 406.740078 -292.323119)
			(xy 406.776829 -292.35987) (xy 406.807379 -292.401918) (xy 406.830975 -292.448228) (xy 406.847036 -292.497658)
			(xy 406.855166 -292.548993) (xy 406.855676 -292.57498) (xy 406.855171 -292.600713) (xy 408.09469 -292.600713)
			(xy 408.09469 -292.548739) (xy 408.10282 -292.497404) (xy 408.118881 -292.447974) (xy 408.142477 -292.401664)
			(xy 408.173027 -292.359616) (xy 408.209778 -292.322865) (xy 408.251826 -292.292315) (xy 408.298136 -292.268719)
			(xy 408.347566 -292.252658) (xy 408.398901 -292.244528) (xy 408.450875 -292.244528) (xy 408.50221 -292.252658)
			(xy 408.55164 -292.268719) (xy 408.59795 -292.292315) (xy 408.639998 -292.322865) (xy 408.676749 -292.359616)
			(xy 408.707299 -292.401664) (xy 408.730895 -292.447974) (xy 408.746956 -292.497404) (xy 408.755086 -292.548739)
			(xy 408.755596 -292.574726) (xy 408.755086 -292.600713) (xy 409.04465 -292.600713) (xy 409.04465 -292.548739)
			(xy 409.05278 -292.497404) (xy 409.068841 -292.447974) (xy 409.092437 -292.401664) (xy 409.122987 -292.359616)
			(xy 409.159738 -292.322865) (xy 409.201786 -292.292315) (xy 409.248096 -292.268719) (xy 409.297526 -292.252658)
			(xy 409.348861 -292.244528) (xy 409.400835 -292.244528) (xy 409.45217 -292.252658) (xy 409.5016 -292.268719)
			(xy 409.54791 -292.292315) (xy 409.589958 -292.322865) (xy 409.626709 -292.359616) (xy 409.657259 -292.401664)
			(xy 409.680855 -292.447974) (xy 409.696916 -292.497404) (xy 409.705046 -292.548739) (xy 409.705556 -292.574726)
			(xy 409.705046 -292.600713) (xy 409.99461 -292.600713) (xy 409.99461 -292.548739) (xy 410.00274 -292.497404)
			(xy 410.018801 -292.447974) (xy 410.042397 -292.401664) (xy 410.072947 -292.359616) (xy 410.109698 -292.322865)
			(xy 410.151746 -292.292315) (xy 410.198056 -292.268719) (xy 410.247486 -292.252658) (xy 410.298821 -292.244528)
			(xy 410.350795 -292.244528) (xy 410.40213 -292.252658) (xy 410.45156 -292.268719) (xy 410.49787 -292.292315)
			(xy 410.539918 -292.322865) (xy 410.576669 -292.359616) (xy 410.607219 -292.401664) (xy 410.630815 -292.447974)
			(xy 410.646876 -292.497404) (xy 410.655006 -292.548739) (xy 410.655516 -292.574726) (xy 410.655006 -292.600713)
			(xy 410.944824 -292.600713) (xy 410.944824 -292.548739) (xy 410.952954 -292.497404) (xy 410.969015 -292.447974)
			(xy 410.992611 -292.401664) (xy 411.023161 -292.359616) (xy 411.059912 -292.322865) (xy 411.10196 -292.292315)
			(xy 411.14827 -292.268719) (xy 411.1977 -292.252658) (xy 411.249035 -292.244528) (xy 411.301009 -292.244528)
			(xy 411.352344 -292.252658) (xy 411.401774 -292.268719) (xy 411.448084 -292.292315) (xy 411.490132 -292.322865)
			(xy 411.526883 -292.359616) (xy 411.557433 -292.401664) (xy 411.581029 -292.447974) (xy 411.59709 -292.497404)
			(xy 411.60522 -292.548739) (xy 411.60573 -292.574726) (xy 411.60522 -292.600713) (xy 411.894784 -292.600713)
			(xy 411.894784 -292.548739) (xy 411.902914 -292.497404) (xy 411.918975 -292.447974) (xy 411.942571 -292.401664)
			(xy 411.973121 -292.359616) (xy 412.009872 -292.322865) (xy 412.05192 -292.292315) (xy 412.09823 -292.268719)
			(xy 412.14766 -292.252658) (xy 412.198995 -292.244528) (xy 412.250969 -292.244528) (xy 412.302304 -292.252658)
			(xy 412.351734 -292.268719) (xy 412.398044 -292.292315) (xy 412.440092 -292.322865) (xy 412.476843 -292.359616)
			(xy 412.507393 -292.401664) (xy 412.530989 -292.447974) (xy 412.54705 -292.497404) (xy 412.55518 -292.548739)
			(xy 412.55569 -292.574726) (xy 412.55518 -292.600713) (xy 412.844744 -292.600713) (xy 412.844744 -292.548739)
			(xy 412.852874 -292.497404) (xy 412.868935 -292.447974) (xy 412.892531 -292.401664) (xy 412.923081 -292.359616)
			(xy 412.959832 -292.322865) (xy 413.00188 -292.292315) (xy 413.04819 -292.268719) (xy 413.09762 -292.252658)
			(xy 413.148955 -292.244528) (xy 413.200929 -292.244528) (xy 413.252264 -292.252658) (xy 413.301694 -292.268719)
			(xy 413.348004 -292.292315) (xy 413.390052 -292.322865) (xy 413.426803 -292.359616) (xy 413.457353 -292.401664)
			(xy 413.480949 -292.447974) (xy 413.49701 -292.497404) (xy 413.50514 -292.548739) (xy 413.50565 -292.574726)
			(xy 413.50514 -292.600713) (xy 413.794704 -292.600713) (xy 413.794704 -292.548739) (xy 413.802834 -292.497404)
			(xy 413.818895 -292.447974) (xy 413.842491 -292.401664) (xy 413.873041 -292.359616) (xy 413.909792 -292.322865)
			(xy 413.95184 -292.292315) (xy 413.99815 -292.268719) (xy 414.04758 -292.252658) (xy 414.098915 -292.244528)
			(xy 414.150889 -292.244528) (xy 414.202224 -292.252658) (xy 414.251654 -292.268719) (xy 414.297964 -292.292315)
			(xy 414.340012 -292.322865) (xy 414.376763 -292.359616) (xy 414.407313 -292.401664) (xy 414.430909 -292.447974)
			(xy 414.44697 -292.497404) (xy 414.4551 -292.548739) (xy 414.45561 -292.574726) (xy 414.4551 -292.600713)
			(xy 414.744664 -292.600713) (xy 414.744664 -292.548739) (xy 414.752794 -292.497404) (xy 414.768855 -292.447974)
			(xy 414.792451 -292.401664) (xy 414.823001 -292.359616) (xy 414.859752 -292.322865) (xy 414.9018 -292.292315)
			(xy 414.94811 -292.268719) (xy 414.99754 -292.252658) (xy 415.048875 -292.244528) (xy 415.100849 -292.244528)
			(xy 415.152184 -292.252658) (xy 415.201614 -292.268719) (xy 415.247924 -292.292315) (xy 415.289972 -292.322865)
			(xy 415.326723 -292.359616) (xy 415.357273 -292.401664) (xy 415.380869 -292.447974) (xy 415.39693 -292.497404)
			(xy 415.40506 -292.548739) (xy 415.40557 -292.574726) (xy 415.40506 -292.600713) (xy 415.694624 -292.600713)
			(xy 415.694624 -292.548739) (xy 415.702754 -292.497404) (xy 415.718815 -292.447974) (xy 415.742411 -292.401664)
			(xy 415.772961 -292.359616) (xy 415.809712 -292.322865) (xy 415.85176 -292.292315) (xy 415.89807 -292.268719)
			(xy 415.9475 -292.252658) (xy 415.998835 -292.244528) (xy 416.050809 -292.244528) (xy 416.102144 -292.252658)
			(xy 416.151574 -292.268719) (xy 416.197884 -292.292315) (xy 416.239932 -292.322865) (xy 416.276683 -292.359616)
			(xy 416.307233 -292.401664) (xy 416.330829 -292.447974) (xy 416.34689 -292.497404) (xy 416.35502 -292.548739)
			(xy 416.35553 -292.574726) (xy 416.35502 -292.600713) (xy 416.644584 -292.600713) (xy 416.644584 -292.548739)
			(xy 416.652714 -292.497404) (xy 416.668775 -292.447974) (xy 416.692371 -292.401664) (xy 416.722921 -292.359616)
			(xy 416.759672 -292.322865) (xy 416.80172 -292.292315) (xy 416.84803 -292.268719) (xy 416.89746 -292.252658)
			(xy 416.948795 -292.244528) (xy 417.000769 -292.244528) (xy 417.052104 -292.252658) (xy 417.101534 -292.268719)
			(xy 417.147844 -292.292315) (xy 417.189892 -292.322865) (xy 417.226643 -292.359616) (xy 417.257193 -292.401664)
			(xy 417.280789 -292.447974) (xy 417.29685 -292.497404) (xy 417.30498 -292.548739) (xy 417.30549 -292.574726)
			(xy 417.30498 -292.600713) (xy 417.594798 -292.600713) (xy 417.594798 -292.548739) (xy 417.602928 -292.497404)
			(xy 417.618989 -292.447974) (xy 417.642585 -292.401664) (xy 417.673135 -292.359616) (xy 417.709886 -292.322865)
			(xy 417.751934 -292.292315) (xy 417.798244 -292.268719) (xy 417.847674 -292.252658) (xy 417.899009 -292.244528)
			(xy 417.950983 -292.244528) (xy 418.002318 -292.252658) (xy 418.051748 -292.268719) (xy 418.098058 -292.292315)
			(xy 418.140106 -292.322865) (xy 418.176857 -292.359616) (xy 418.207407 -292.401664) (xy 418.231003 -292.447974)
			(xy 418.247064 -292.497404) (xy 418.255194 -292.548739) (xy 418.255704 -292.574726) (xy 418.255194 -292.600713)
			(xy 418.247064 -292.652048) (xy 418.231003 -292.701478) (xy 418.207407 -292.747788) (xy 418.176857 -292.789836)
			(xy 418.140106 -292.826587) (xy 418.098058 -292.857137) (xy 418.051748 -292.880733) (xy 418.002318 -292.896794)
			(xy 417.950983 -292.904924) (xy 417.899009 -292.904924) (xy 417.847674 -292.896794) (xy 417.798244 -292.880733)
			(xy 417.751934 -292.857137) (xy 417.709886 -292.826587) (xy 417.673135 -292.789836) (xy 417.642585 -292.747788)
			(xy 417.618989 -292.701478) (xy 417.602928 -292.652048) (xy 417.594798 -292.600713) (xy 417.30498 -292.600713)
			(xy 417.29685 -292.652048) (xy 417.280789 -292.701478) (xy 417.257193 -292.747788) (xy 417.226643 -292.789836)
			(xy 417.189892 -292.826587) (xy 417.147844 -292.857137) (xy 417.101534 -292.880733) (xy 417.052104 -292.896794)
			(xy 417.000769 -292.904924) (xy 416.948795 -292.904924) (xy 416.89746 -292.896794) (xy 416.84803 -292.880733)
			(xy 416.80172 -292.857137) (xy 416.759672 -292.826587) (xy 416.722921 -292.789836) (xy 416.692371 -292.747788)
			(xy 416.668775 -292.701478) (xy 416.652714 -292.652048) (xy 416.644584 -292.600713) (xy 416.35502 -292.600713)
			(xy 416.34689 -292.652048) (xy 416.330829 -292.701478) (xy 416.307233 -292.747788) (xy 416.276683 -292.789836)
			(xy 416.239932 -292.826587) (xy 416.197884 -292.857137) (xy 416.151574 -292.880733) (xy 416.102144 -292.896794)
			(xy 416.050809 -292.904924) (xy 415.998835 -292.904924) (xy 415.9475 -292.896794) (xy 415.89807 -292.880733)
			(xy 415.85176 -292.857137) (xy 415.809712 -292.826587) (xy 415.772961 -292.789836) (xy 415.742411 -292.747788)
			(xy 415.718815 -292.701478) (xy 415.702754 -292.652048) (xy 415.694624 -292.600713) (xy 415.40506 -292.600713)
			(xy 415.39693 -292.652048) (xy 415.380869 -292.701478) (xy 415.357273 -292.747788) (xy 415.326723 -292.789836)
			(xy 415.289972 -292.826587) (xy 415.247924 -292.857137) (xy 415.201614 -292.880733) (xy 415.152184 -292.896794)
			(xy 415.100849 -292.904924) (xy 415.048875 -292.904924) (xy 414.99754 -292.896794) (xy 414.94811 -292.880733)
			(xy 414.9018 -292.857137) (xy 414.859752 -292.826587) (xy 414.823001 -292.789836) (xy 414.792451 -292.747788)
			(xy 414.768855 -292.701478) (xy 414.752794 -292.652048) (xy 414.744664 -292.600713) (xy 414.4551 -292.600713)
			(xy 414.44697 -292.652048) (xy 414.430909 -292.701478) (xy 414.407313 -292.747788) (xy 414.376763 -292.789836)
			(xy 414.340012 -292.826587) (xy 414.297964 -292.857137) (xy 414.251654 -292.880733) (xy 414.202224 -292.896794)
			(xy 414.150889 -292.904924) (xy 414.098915 -292.904924) (xy 414.04758 -292.896794) (xy 413.99815 -292.880733)
			(xy 413.95184 -292.857137) (xy 413.909792 -292.826587) (xy 413.873041 -292.789836) (xy 413.842491 -292.747788)
			(xy 413.818895 -292.701478) (xy 413.802834 -292.652048) (xy 413.794704 -292.600713) (xy 413.50514 -292.600713)
			(xy 413.49701 -292.652048) (xy 413.480949 -292.701478) (xy 413.457353 -292.747788) (xy 413.426803 -292.789836)
			(xy 413.390052 -292.826587) (xy 413.348004 -292.857137) (xy 413.301694 -292.880733) (xy 413.252264 -292.896794)
			(xy 413.200929 -292.904924) (xy 413.148955 -292.904924) (xy 413.09762 -292.896794) (xy 413.04819 -292.880733)
			(xy 413.00188 -292.857137) (xy 412.959832 -292.826587) (xy 412.923081 -292.789836) (xy 412.892531 -292.747788)
			(xy 412.868935 -292.701478) (xy 412.852874 -292.652048) (xy 412.844744 -292.600713) (xy 412.55518 -292.600713)
			(xy 412.54705 -292.652048) (xy 412.530989 -292.701478) (xy 412.507393 -292.747788) (xy 412.476843 -292.789836)
			(xy 412.440092 -292.826587) (xy 412.398044 -292.857137) (xy 412.351734 -292.880733) (xy 412.302304 -292.896794)
			(xy 412.250969 -292.904924) (xy 412.198995 -292.904924) (xy 412.14766 -292.896794) (xy 412.09823 -292.880733)
			(xy 412.05192 -292.857137) (xy 412.009872 -292.826587) (xy 411.973121 -292.789836) (xy 411.942571 -292.747788)
			(xy 411.918975 -292.701478) (xy 411.902914 -292.652048) (xy 411.894784 -292.600713) (xy 411.60522 -292.600713)
			(xy 411.59709 -292.652048) (xy 411.581029 -292.701478) (xy 411.557433 -292.747788) (xy 411.526883 -292.789836)
			(xy 411.490132 -292.826587) (xy 411.448084 -292.857137) (xy 411.401774 -292.880733) (xy 411.352344 -292.896794)
			(xy 411.301009 -292.904924) (xy 411.249035 -292.904924) (xy 411.1977 -292.896794) (xy 411.14827 -292.880733)
			(xy 411.10196 -292.857137) (xy 411.059912 -292.826587) (xy 411.023161 -292.789836) (xy 410.992611 -292.747788)
			(xy 410.969015 -292.701478) (xy 410.952954 -292.652048) (xy 410.944824 -292.600713) (xy 410.655006 -292.600713)
			(xy 410.646876 -292.652048) (xy 410.630815 -292.701478) (xy 410.607219 -292.747788) (xy 410.576669 -292.789836)
			(xy 410.539918 -292.826587) (xy 410.49787 -292.857137) (xy 410.45156 -292.880733) (xy 410.40213 -292.896794)
			(xy 410.350795 -292.904924) (xy 410.298821 -292.904924) (xy 410.247486 -292.896794) (xy 410.198056 -292.880733)
			(xy 410.151746 -292.857137) (xy 410.109698 -292.826587) (xy 410.072947 -292.789836) (xy 410.042397 -292.747788)
			(xy 410.018801 -292.701478) (xy 410.00274 -292.652048) (xy 409.99461 -292.600713) (xy 409.705046 -292.600713)
			(xy 409.696916 -292.652048) (xy 409.680855 -292.701478) (xy 409.657259 -292.747788) (xy 409.626709 -292.789836)
			(xy 409.589958 -292.826587) (xy 409.54791 -292.857137) (xy 409.5016 -292.880733) (xy 409.45217 -292.896794)
			(xy 409.400835 -292.904924) (xy 409.348861 -292.904924) (xy 409.297526 -292.896794) (xy 409.248096 -292.880733)
			(xy 409.201786 -292.857137) (xy 409.159738 -292.826587) (xy 409.122987 -292.789836) (xy 409.092437 -292.747788)
			(xy 409.068841 -292.701478) (xy 409.05278 -292.652048) (xy 409.04465 -292.600713) (xy 408.755086 -292.600713)
			(xy 408.746956 -292.652048) (xy 408.730895 -292.701478) (xy 408.707299 -292.747788) (xy 408.676749 -292.789836)
			(xy 408.639998 -292.826587) (xy 408.59795 -292.857137) (xy 408.55164 -292.880733) (xy 408.50221 -292.896794)
			(xy 408.450875 -292.904924) (xy 408.398901 -292.904924) (xy 408.347566 -292.896794) (xy 408.298136 -292.880733)
			(xy 408.251826 -292.857137) (xy 408.209778 -292.826587) (xy 408.173027 -292.789836) (xy 408.142477 -292.747788)
			(xy 408.118881 -292.701478) (xy 408.10282 -292.652048) (xy 408.09469 -292.600713) (xy 406.855171 -292.600713)
			(xy 406.855166 -292.600967) (xy 406.847036 -292.652302) (xy 406.830975 -292.701732) (xy 406.807379 -292.748042)
			(xy 406.776829 -292.79009) (xy 406.740078 -292.826841) (xy 406.69803 -292.857391) (xy 406.65172 -292.880987)
			(xy 406.60229 -292.897048) (xy 406.550955 -292.905178) (xy 406.498981 -292.905178) (xy 406.447646 -292.897048)
			(xy 406.398216 -292.880987) (xy 406.351906 -292.857391) (xy 406.309858 -292.826841) (xy 406.273107 -292.79009)
			(xy 406.242557 -292.748042) (xy 406.218961 -292.701732) (xy 406.2029 -292.652302) (xy 406.19477 -292.600967)
			(xy 405.905206 -292.600967) (xy 405.897076 -292.652302) (xy 405.881015 -292.701732) (xy 405.857419 -292.748042)
			(xy 405.826869 -292.79009) (xy 405.790118 -292.826841) (xy 405.74807 -292.857391) (xy 405.70176 -292.880987)
			(xy 405.65233 -292.897048) (xy 405.600995 -292.905178) (xy 405.549021 -292.905178) (xy 405.497686 -292.897048)
			(xy 405.448256 -292.880987) (xy 405.401946 -292.857391) (xy 405.359898 -292.826841) (xy 405.323147 -292.79009)
			(xy 405.292597 -292.748042) (xy 405.269001 -292.701732) (xy 405.25294 -292.652302) (xy 405.24481 -292.600967)
			(xy 404.955246 -292.600967) (xy 404.947116 -292.652302) (xy 404.931055 -292.701732) (xy 404.907459 -292.748042)
			(xy 404.876909 -292.79009) (xy 404.840158 -292.826841) (xy 404.79811 -292.857391) (xy 404.7518 -292.880987)
			(xy 404.70237 -292.897048) (xy 404.651035 -292.905178) (xy 404.599061 -292.905178) (xy 404.547726 -292.897048)
			(xy 404.498296 -292.880987) (xy 404.451986 -292.857391) (xy 404.409938 -292.826841) (xy 404.373187 -292.79009)
			(xy 404.342637 -292.748042) (xy 404.319041 -292.701732) (xy 404.30298 -292.652302) (xy 404.29485 -292.600967)
			(xy 404.005032 -292.600967) (xy 403.996902 -292.652302) (xy 403.980841 -292.701732) (xy 403.957245 -292.748042)
			(xy 403.926695 -292.79009) (xy 403.889944 -292.826841) (xy 403.847896 -292.857391) (xy 403.801586 -292.880987)
			(xy 403.752156 -292.897048) (xy 403.700821 -292.905178) (xy 403.648847 -292.905178) (xy 403.597512 -292.897048)
			(xy 403.548082 -292.880987) (xy 403.501772 -292.857391) (xy 403.459724 -292.826841) (xy 403.422973 -292.79009)
			(xy 403.392423 -292.748042) (xy 403.368827 -292.701732) (xy 403.352766 -292.652302) (xy 403.344636 -292.600967)
			(xy 403.055072 -292.600967) (xy 403.046942 -292.652302) (xy 403.030881 -292.701732) (xy 403.007285 -292.748042)
			(xy 402.976735 -292.79009) (xy 402.939984 -292.826841) (xy 402.897936 -292.857391) (xy 402.851626 -292.880987)
			(xy 402.802196 -292.897048) (xy 402.750861 -292.905178) (xy 402.698887 -292.905178) (xy 402.647552 -292.897048)
			(xy 402.598122 -292.880987) (xy 402.551812 -292.857391) (xy 402.509764 -292.826841) (xy 402.473013 -292.79009)
			(xy 402.442463 -292.748042) (xy 402.418867 -292.701732) (xy 402.402806 -292.652302) (xy 402.394676 -292.600967)
			(xy 402.105112 -292.600967) (xy 402.096982 -292.652302) (xy 402.080921 -292.701732) (xy 402.057325 -292.748042)
			(xy 402.026775 -292.79009) (xy 401.990024 -292.826841) (xy 401.947976 -292.857391) (xy 401.901666 -292.880987)
			(xy 401.852236 -292.897048) (xy 401.800901 -292.905178) (xy 401.748927 -292.905178) (xy 401.697592 -292.897048)
			(xy 401.648162 -292.880987) (xy 401.601852 -292.857391) (xy 401.559804 -292.826841) (xy 401.523053 -292.79009)
			(xy 401.492503 -292.748042) (xy 401.468907 -292.701732) (xy 401.452846 -292.652302) (xy 401.444716 -292.600967)
			(xy 401.155152 -292.600967) (xy 401.147022 -292.652302) (xy 401.130961 -292.701732) (xy 401.107365 -292.748042)
			(xy 401.076815 -292.79009) (xy 401.040064 -292.826841) (xy 400.998016 -292.857391) (xy 400.951706 -292.880987)
			(xy 400.902276 -292.897048) (xy 400.850941 -292.905178) (xy 400.798967 -292.905178) (xy 400.747632 -292.897048)
			(xy 400.698202 -292.880987) (xy 400.651892 -292.857391) (xy 400.609844 -292.826841) (xy 400.573093 -292.79009)
			(xy 400.542543 -292.748042) (xy 400.518947 -292.701732) (xy 400.502886 -292.652302) (xy 400.494756 -292.600967)
			(xy 400.205192 -292.600967) (xy 400.197062 -292.652302) (xy 400.181001 -292.701732) (xy 400.157405 -292.748042)
			(xy 400.126855 -292.79009) (xy 400.090104 -292.826841) (xy 400.048056 -292.857391) (xy 400.001746 -292.880987)
			(xy 399.952316 -292.897048) (xy 399.900981 -292.905178) (xy 399.849007 -292.905178) (xy 399.797672 -292.897048)
			(xy 399.748242 -292.880987) (xy 399.701932 -292.857391) (xy 399.659884 -292.826841) (xy 399.623133 -292.79009)
			(xy 399.592583 -292.748042) (xy 399.568987 -292.701732) (xy 399.552926 -292.652302) (xy 399.544796 -292.600967)
			(xy 399.255232 -292.600967) (xy 399.247102 -292.652302) (xy 399.231041 -292.701732) (xy 399.207445 -292.748042)
			(xy 399.176895 -292.79009) (xy 399.140144 -292.826841) (xy 399.098096 -292.857391) (xy 399.051786 -292.880987)
			(xy 399.002356 -292.897048) (xy 398.951021 -292.905178) (xy 398.899047 -292.905178) (xy 398.847712 -292.897048)
			(xy 398.798282 -292.880987) (xy 398.751972 -292.857391) (xy 398.709924 -292.826841) (xy 398.673173 -292.79009)
			(xy 398.642623 -292.748042) (xy 398.619027 -292.701732) (xy 398.602966 -292.652302) (xy 398.594836 -292.600967)
			(xy 398.304978 -292.600967) (xy 398.296888 -292.652048) (xy 398.280827 -292.701478) (xy 398.257231 -292.747788)
			(xy 398.226681 -292.789836) (xy 398.18993 -292.826587) (xy 398.147882 -292.857137) (xy 398.101572 -292.880733)
			(xy 398.052142 -292.896794) (xy 398.000807 -292.904924) (xy 397.948833 -292.904924) (xy 397.897498 -292.896794)
			(xy 397.848068 -292.880733) (xy 397.801758 -292.857137) (xy 397.75971 -292.826587) (xy 397.722959 -292.789836)
			(xy 397.692409 -292.747788) (xy 397.668813 -292.701478) (xy 397.652752 -292.652048) (xy 397.644622 -292.600713)
			(xy 397.355058 -292.600713) (xy 397.346928 -292.652048) (xy 397.330867 -292.701478) (xy 397.307271 -292.747788)
			(xy 397.276721 -292.789836) (xy 397.23997 -292.826587) (xy 397.197922 -292.857137) (xy 397.151612 -292.880733)
			(xy 397.102182 -292.896794) (xy 397.050847 -292.904924) (xy 396.998873 -292.904924) (xy 396.947538 -292.896794)
			(xy 396.898108 -292.880733) (xy 396.851798 -292.857137) (xy 396.80975 -292.826587) (xy 396.772999 -292.789836)
			(xy 396.742449 -292.747788) (xy 396.718853 -292.701478) (xy 396.702792 -292.652048) (xy 396.694662 -292.600713)
			(xy 396.405103 -292.600713) (xy 396.405098 -292.600967) (xy 396.396968 -292.652302) (xy 396.380907 -292.701732)
			(xy 396.357311 -292.748042) (xy 396.326761 -292.79009) (xy 396.29001 -292.826841) (xy 396.247962 -292.857391)
			(xy 396.201652 -292.880987) (xy 396.152222 -292.897048) (xy 396.100887 -292.905178) (xy 396.048913 -292.905178)
			(xy 395.997578 -292.897048) (xy 395.948148 -292.880987) (xy 395.901838 -292.857391) (xy 395.85979 -292.826841)
			(xy 395.823039 -292.79009) (xy 395.792489 -292.748042) (xy 395.768893 -292.701732) (xy 395.752832 -292.652302)
			(xy 395.744702 -292.600967) (xy 395.455138 -292.600967) (xy 395.447008 -292.652302) (xy 395.430947 -292.701732)
			(xy 395.407351 -292.748042) (xy 395.376801 -292.79009) (xy 395.34005 -292.826841) (xy 395.298002 -292.857391)
			(xy 395.251692 -292.880987) (xy 395.202262 -292.897048) (xy 395.150927 -292.905178) (xy 395.098953 -292.905178)
			(xy 395.047618 -292.897048) (xy 394.998188 -292.880987) (xy 394.951878 -292.857391) (xy 394.90983 -292.826841)
			(xy 394.873079 -292.79009) (xy 394.842529 -292.748042) (xy 394.818933 -292.701732) (xy 394.802872 -292.652302)
			(xy 394.794742 -292.600967) (xy 394.505178 -292.600967) (xy 394.497048 -292.652302) (xy 394.480987 -292.701732)
			(xy 394.457391 -292.748042) (xy 394.426841 -292.79009) (xy 394.39009 -292.826841) (xy 394.348042 -292.857391)
			(xy 394.301732 -292.880987) (xy 394.252302 -292.897048) (xy 394.200967 -292.905178) (xy 394.148993 -292.905178)
			(xy 394.097658 -292.897048) (xy 394.048228 -292.880987) (xy 394.001918 -292.857391) (xy 393.95987 -292.826841)
			(xy 393.923119 -292.79009) (xy 393.892569 -292.748042) (xy 393.868973 -292.701732) (xy 393.852912 -292.652302)
			(xy 393.844782 -292.600967) (xy 392.605004 -292.600967) (xy 392.596874 -292.652302) (xy 392.580813 -292.701732)
			(xy 392.557217 -292.748042) (xy 392.526667 -292.79009) (xy 392.489916 -292.826841) (xy 392.447868 -292.857391)
			(xy 392.401558 -292.880987) (xy 392.352128 -292.897048) (xy 392.300793 -292.905178) (xy 392.248819 -292.905178)
			(xy 392.197484 -292.897048) (xy 392.148054 -292.880987) (xy 392.101744 -292.857391) (xy 392.059696 -292.826841)
			(xy 392.022945 -292.79009) (xy 391.992395 -292.748042) (xy 391.968799 -292.701732) (xy 391.952738 -292.652302)
			(xy 391.944608 -292.600967) (xy 391.653948 -292.600967) (xy 391.651793 -292.62782) (xy 391.639183 -292.679295)
			(xy 391.618525 -292.728101) (xy 391.590348 -292.772987) (xy 391.555373 -292.812804) (xy 391.514495 -292.846533)
			(xy 391.46876 -292.873312) (xy 391.444226 -292.883336) (xy 391.43686 -292.88613) (xy 391.425176 -292.895528)
			(xy 391.420604 -292.902132) (xy 391.416488 -292.908582) (xy 391.411947 -292.923187) (xy 391.411714 -292.930834)
			(xy 391.411714 -293.131494) (xy 391.430764 -293.15791) (xy 391.446258 -293.163244) (xy 391.47264 -293.172623)
			(xy 391.522541 -293.198014) (xy 391.568195 -293.230427) (xy 391.608621 -293.269164) (xy 391.642952 -293.313393)
			(xy 391.670449 -293.362166) (xy 391.690522 -293.414433) (xy 391.70274 -293.469073) (xy 391.706841 -293.524913)
			(xy 391.704929 -293.550927) (xy 391.944608 -293.550927) (xy 391.944608 -293.498953) (xy 391.952738 -293.447618)
			(xy 391.968799 -293.398188) (xy 391.992395 -293.351878) (xy 392.022945 -293.30983) (xy 392.059696 -293.273079)
			(xy 392.101744 -293.242529) (xy 392.148054 -293.218933) (xy 392.197484 -293.202872) (xy 392.248819 -293.194742)
			(xy 392.300793 -293.194742) (xy 392.352128 -293.202872) (xy 392.401558 -293.218933) (xy 392.447868 -293.242529)
			(xy 392.489916 -293.273079) (xy 392.526667 -293.30983) (xy 392.557217 -293.351878) (xy 392.580813 -293.398188)
			(xy 392.596874 -293.447618) (xy 392.605004 -293.498953) (xy 392.605514 -293.52494) (xy 392.605004 -293.550927)
			(xy 393.844782 -293.550927) (xy 393.844782 -293.498953) (xy 393.852912 -293.447618) (xy 393.868973 -293.398188)
			(xy 393.892569 -293.351878) (xy 393.923119 -293.30983) (xy 393.95987 -293.273079) (xy 394.001918 -293.242529)
			(xy 394.048228 -293.218933) (xy 394.097658 -293.202872) (xy 394.148993 -293.194742) (xy 394.200967 -293.194742)
			(xy 394.252302 -293.202872) (xy 394.301732 -293.218933) (xy 394.348042 -293.242529) (xy 394.39009 -293.273079)
			(xy 394.426841 -293.30983) (xy 394.457391 -293.351878) (xy 394.480987 -293.398188) (xy 394.497048 -293.447618)
			(xy 394.505178 -293.498953) (xy 394.505688 -293.52494) (xy 394.505178 -293.550927) (xy 394.794742 -293.550927)
			(xy 394.794742 -293.498953) (xy 394.802872 -293.447618) (xy 394.818933 -293.398188) (xy 394.842529 -293.351878)
			(xy 394.873079 -293.30983) (xy 394.90983 -293.273079) (xy 394.951878 -293.242529) (xy 394.998188 -293.218933)
			(xy 395.047618 -293.202872) (xy 395.098953 -293.194742) (xy 395.150927 -293.194742) (xy 395.202262 -293.202872)
			(xy 395.251692 -293.218933) (xy 395.298002 -293.242529) (xy 395.34005 -293.273079) (xy 395.376801 -293.30983)
			(xy 395.407351 -293.351878) (xy 395.430947 -293.398188) (xy 395.447008 -293.447618) (xy 395.455138 -293.498953)
			(xy 395.455648 -293.52494) (xy 395.455138 -293.550927) (xy 395.744702 -293.550927) (xy 395.744702 -293.498953)
			(xy 395.752832 -293.447618) (xy 395.768893 -293.398188) (xy 395.792489 -293.351878) (xy 395.823039 -293.30983)
			(xy 395.85979 -293.273079) (xy 395.901838 -293.242529) (xy 395.948148 -293.218933) (xy 395.997578 -293.202872)
			(xy 396.048913 -293.194742) (xy 396.100887 -293.194742) (xy 396.152222 -293.202872) (xy 396.201652 -293.218933)
			(xy 396.247962 -293.242529) (xy 396.29001 -293.273079) (xy 396.326761 -293.30983) (xy 396.357311 -293.351878)
			(xy 396.380907 -293.398188) (xy 396.396968 -293.447618) (xy 396.405098 -293.498953) (xy 396.405608 -293.52494)
			(xy 396.405098 -293.550927) (xy 396.694662 -293.550927) (xy 396.694662 -293.498953) (xy 396.702792 -293.447618)
			(xy 396.718853 -293.398188) (xy 396.742449 -293.351878) (xy 396.772999 -293.30983) (xy 396.80975 -293.273079)
			(xy 396.851798 -293.242529) (xy 396.898108 -293.218933) (xy 396.947538 -293.202872) (xy 396.998873 -293.194742)
			(xy 397.050847 -293.194742) (xy 397.102182 -293.202872) (xy 397.151612 -293.218933) (xy 397.197922 -293.242529)
			(xy 397.23997 -293.273079) (xy 397.276721 -293.30983) (xy 397.307271 -293.351878) (xy 397.330867 -293.398188)
			(xy 397.346928 -293.447618) (xy 397.355058 -293.498953) (xy 397.355568 -293.52494) (xy 397.355058 -293.550927)
			(xy 397.644622 -293.550927) (xy 397.644622 -293.498953) (xy 397.652752 -293.447618) (xy 397.668813 -293.398188)
			(xy 397.692409 -293.351878) (xy 397.722959 -293.30983) (xy 397.75971 -293.273079) (xy 397.801758 -293.242529)
			(xy 397.848068 -293.218933) (xy 397.897498 -293.202872) (xy 397.948833 -293.194742) (xy 398.000807 -293.194742)
			(xy 398.052142 -293.202872) (xy 398.101572 -293.218933) (xy 398.147882 -293.242529) (xy 398.18993 -293.273079)
			(xy 398.226681 -293.30983) (xy 398.257231 -293.351878) (xy 398.280827 -293.398188) (xy 398.296888 -293.447618)
			(xy 398.305018 -293.498953) (xy 398.305528 -293.52494) (xy 398.305018 -293.550927) (xy 398.594836 -293.550927)
			(xy 398.594836 -293.498953) (xy 398.602966 -293.447618) (xy 398.619027 -293.398188) (xy 398.642623 -293.351878)
			(xy 398.673173 -293.30983) (xy 398.709924 -293.273079) (xy 398.751972 -293.242529) (xy 398.798282 -293.218933)
			(xy 398.847712 -293.202872) (xy 398.899047 -293.194742) (xy 398.951021 -293.194742) (xy 399.002356 -293.202872)
			(xy 399.051786 -293.218933) (xy 399.098096 -293.242529) (xy 399.140144 -293.273079) (xy 399.176895 -293.30983)
			(xy 399.207445 -293.351878) (xy 399.231041 -293.398188) (xy 399.247102 -293.447618) (xy 399.255232 -293.498953)
			(xy 399.255742 -293.52494) (xy 399.255232 -293.550927) (xy 399.544796 -293.550927) (xy 399.544796 -293.498953)
			(xy 399.552926 -293.447618) (xy 399.568987 -293.398188) (xy 399.592583 -293.351878) (xy 399.623133 -293.30983)
			(xy 399.659884 -293.273079) (xy 399.701932 -293.242529) (xy 399.748242 -293.218933) (xy 399.797672 -293.202872)
			(xy 399.849007 -293.194742) (xy 399.900981 -293.194742) (xy 399.952316 -293.202872) (xy 400.001746 -293.218933)
			(xy 400.048056 -293.242529) (xy 400.090104 -293.273079) (xy 400.126855 -293.30983) (xy 400.157405 -293.351878)
			(xy 400.181001 -293.398188) (xy 400.197062 -293.447618) (xy 400.205192 -293.498953) (xy 400.205702 -293.52494)
			(xy 400.205192 -293.550927) (xy 400.494756 -293.550927) (xy 400.494756 -293.498953) (xy 400.502886 -293.447618)
			(xy 400.518947 -293.398188) (xy 400.542543 -293.351878) (xy 400.573093 -293.30983) (xy 400.609844 -293.273079)
			(xy 400.651892 -293.242529) (xy 400.698202 -293.218933) (xy 400.747632 -293.202872) (xy 400.798967 -293.194742)
			(xy 400.850941 -293.194742) (xy 400.902276 -293.202872) (xy 400.951706 -293.218933) (xy 400.998016 -293.242529)
			(xy 401.040064 -293.273079) (xy 401.076815 -293.30983) (xy 401.107365 -293.351878) (xy 401.130961 -293.398188)
			(xy 401.147022 -293.447618) (xy 401.155152 -293.498953) (xy 401.155662 -293.52494) (xy 401.155152 -293.550927)
			(xy 401.444716 -293.550927) (xy 401.444716 -293.498953) (xy 401.452846 -293.447618) (xy 401.468907 -293.398188)
			(xy 401.492503 -293.351878) (xy 401.523053 -293.30983) (xy 401.559804 -293.273079) (xy 401.601852 -293.242529)
			(xy 401.648162 -293.218933) (xy 401.697592 -293.202872) (xy 401.748927 -293.194742) (xy 401.800901 -293.194742)
			(xy 401.852236 -293.202872) (xy 401.901666 -293.218933) (xy 401.947976 -293.242529) (xy 401.990024 -293.273079)
			(xy 402.026775 -293.30983) (xy 402.057325 -293.351878) (xy 402.080921 -293.398188) (xy 402.096982 -293.447618)
			(xy 402.105112 -293.498953) (xy 402.105622 -293.52494) (xy 402.105112 -293.550927) (xy 402.394676 -293.550927)
			(xy 402.394676 -293.498953) (xy 402.402806 -293.447618) (xy 402.418867 -293.398188) (xy 402.442463 -293.351878)
			(xy 402.473013 -293.30983) (xy 402.509764 -293.273079) (xy 402.551812 -293.242529) (xy 402.598122 -293.218933)
			(xy 402.647552 -293.202872) (xy 402.698887 -293.194742) (xy 402.750861 -293.194742) (xy 402.802196 -293.202872)
			(xy 402.851626 -293.218933) (xy 402.897936 -293.242529) (xy 402.939984 -293.273079) (xy 402.976735 -293.30983)
			(xy 403.007285 -293.351878) (xy 403.030881 -293.398188) (xy 403.046942 -293.447618) (xy 403.055072 -293.498953)
			(xy 403.055582 -293.52494) (xy 403.055072 -293.550927) (xy 403.344636 -293.550927) (xy 403.344636 -293.498953)
			(xy 403.352766 -293.447618) (xy 403.368827 -293.398188) (xy 403.392423 -293.351878) (xy 403.422973 -293.30983)
			(xy 403.459724 -293.273079) (xy 403.501772 -293.242529) (xy 403.548082 -293.218933) (xy 403.597512 -293.202872)
			(xy 403.648847 -293.194742) (xy 403.700821 -293.194742) (xy 403.752156 -293.202872) (xy 403.801586 -293.218933)
			(xy 403.847896 -293.242529) (xy 403.889944 -293.273079) (xy 403.926695 -293.30983) (xy 403.957245 -293.351878)
			(xy 403.980841 -293.398188) (xy 403.996902 -293.447618) (xy 404.005032 -293.498953) (xy 404.005542 -293.52494)
			(xy 404.005032 -293.550927) (xy 404.294596 -293.550927) (xy 404.294596 -293.498953) (xy 404.302726 -293.447618)
			(xy 404.318787 -293.398188) (xy 404.342383 -293.351878) (xy 404.372933 -293.30983) (xy 404.409684 -293.273079)
			(xy 404.451732 -293.242529) (xy 404.498042 -293.218933) (xy 404.547472 -293.202872) (xy 404.598807 -293.194742)
			(xy 404.650781 -293.194742) (xy 404.702116 -293.202872) (xy 404.751546 -293.218933) (xy 404.797856 -293.242529)
			(xy 404.839904 -293.273079) (xy 404.876655 -293.30983) (xy 404.907205 -293.351878) (xy 404.930801 -293.398188)
			(xy 404.946862 -293.447618) (xy 404.954992 -293.498953) (xy 404.955502 -293.52494) (xy 404.954992 -293.550927)
			(xy 405.24481 -293.550927) (xy 405.24481 -293.498953) (xy 405.25294 -293.447618) (xy 405.269001 -293.398188)
			(xy 405.292597 -293.351878) (xy 405.323147 -293.30983) (xy 405.359898 -293.273079) (xy 405.401946 -293.242529)
			(xy 405.448256 -293.218933) (xy 405.497686 -293.202872) (xy 405.549021 -293.194742) (xy 405.600995 -293.194742)
			(xy 405.65233 -293.202872) (xy 405.70176 -293.218933) (xy 405.74807 -293.242529) (xy 405.790118 -293.273079)
			(xy 405.826869 -293.30983) (xy 405.857419 -293.351878) (xy 405.881015 -293.398188) (xy 405.897076 -293.447618)
			(xy 405.905206 -293.498953) (xy 405.905716 -293.52494) (xy 405.905206 -293.550927) (xy 406.19477 -293.550927)
			(xy 406.19477 -293.498953) (xy 406.2029 -293.447618) (xy 406.218961 -293.398188) (xy 406.242557 -293.351878)
			(xy 406.273107 -293.30983) (xy 406.309858 -293.273079) (xy 406.351906 -293.242529) (xy 406.398216 -293.218933)
			(xy 406.447646 -293.202872) (xy 406.498981 -293.194742) (xy 406.550955 -293.194742) (xy 406.60229 -293.202872)
			(xy 406.65172 -293.218933) (xy 406.69803 -293.242529) (xy 406.740078 -293.273079) (xy 406.776829 -293.30983)
			(xy 406.807379 -293.351878) (xy 406.830975 -293.398188) (xy 406.847036 -293.447618) (xy 406.855166 -293.498953)
			(xy 406.855676 -293.52494) (xy 406.855166 -293.550927) (xy 408.09469 -293.550927) (xy 408.09469 -293.498953)
			(xy 408.10282 -293.447618) (xy 408.118881 -293.398188) (xy 408.142477 -293.351878) (xy 408.173027 -293.30983)
			(xy 408.209778 -293.273079) (xy 408.251826 -293.242529) (xy 408.298136 -293.218933) (xy 408.347566 -293.202872)
			(xy 408.398901 -293.194742) (xy 408.450875 -293.194742) (xy 408.50221 -293.202872) (xy 408.55164 -293.218933)
			(xy 408.59795 -293.242529) (xy 408.639998 -293.273079) (xy 408.676749 -293.30983) (xy 408.707299 -293.351878)
			(xy 408.730895 -293.398188) (xy 408.746956 -293.447618) (xy 408.755086 -293.498953) (xy 408.755596 -293.52494)
			(xy 408.755086 -293.550927) (xy 409.04465 -293.550927) (xy 409.04465 -293.498953) (xy 409.05278 -293.447618)
			(xy 409.068841 -293.398188) (xy 409.092437 -293.351878) (xy 409.122987 -293.30983) (xy 409.159738 -293.273079)
			(xy 409.201786 -293.242529) (xy 409.248096 -293.218933) (xy 409.297526 -293.202872) (xy 409.348861 -293.194742)
			(xy 409.400835 -293.194742) (xy 409.45217 -293.202872) (xy 409.5016 -293.218933) (xy 409.54791 -293.242529)
			(xy 409.589958 -293.273079) (xy 409.626709 -293.30983) (xy 409.657259 -293.351878) (xy 409.680855 -293.398188)
			(xy 409.696916 -293.447618) (xy 409.705046 -293.498953) (xy 409.705556 -293.52494) (xy 409.705046 -293.550927)
			(xy 409.99461 -293.550927) (xy 409.99461 -293.498953) (xy 410.00274 -293.447618) (xy 410.018801 -293.398188)
			(xy 410.042397 -293.351878) (xy 410.072947 -293.30983) (xy 410.109698 -293.273079) (xy 410.151746 -293.242529)
			(xy 410.198056 -293.218933) (xy 410.247486 -293.202872) (xy 410.298821 -293.194742) (xy 410.350795 -293.194742)
			(xy 410.40213 -293.202872) (xy 410.45156 -293.218933) (xy 410.49787 -293.242529) (xy 410.539918 -293.273079)
			(xy 410.576669 -293.30983) (xy 410.607219 -293.351878) (xy 410.630815 -293.398188) (xy 410.646876 -293.447618)
			(xy 410.655006 -293.498953) (xy 410.655516 -293.52494) (xy 410.655006 -293.550927) (xy 410.944824 -293.550927)
			(xy 410.944824 -293.498953) (xy 410.952954 -293.447618) (xy 410.969015 -293.398188) (xy 410.992611 -293.351878)
			(xy 411.023161 -293.30983) (xy 411.059912 -293.273079) (xy 411.10196 -293.242529) (xy 411.14827 -293.218933)
			(xy 411.1977 -293.202872) (xy 411.249035 -293.194742) (xy 411.301009 -293.194742) (xy 411.352344 -293.202872)
			(xy 411.401774 -293.218933) (xy 411.448084 -293.242529) (xy 411.490132 -293.273079) (xy 411.526883 -293.30983)
			(xy 411.557433 -293.351878) (xy 411.581029 -293.398188) (xy 411.59709 -293.447618) (xy 411.60522 -293.498953)
			(xy 411.60573 -293.52494) (xy 411.60522 -293.550927) (xy 411.894784 -293.550927) (xy 411.894784 -293.498953)
			(xy 411.902914 -293.447618) (xy 411.918975 -293.398188) (xy 411.942571 -293.351878) (xy 411.973121 -293.30983)
			(xy 412.009872 -293.273079) (xy 412.05192 -293.242529) (xy 412.09823 -293.218933) (xy 412.14766 -293.202872)
			(xy 412.198995 -293.194742) (xy 412.250969 -293.194742) (xy 412.302304 -293.202872) (xy 412.351734 -293.218933)
			(xy 412.398044 -293.242529) (xy 412.440092 -293.273079) (xy 412.476843 -293.30983) (xy 412.507393 -293.351878)
			(xy 412.530989 -293.398188) (xy 412.54705 -293.447618) (xy 412.55518 -293.498953) (xy 412.55569 -293.52494)
			(xy 412.55518 -293.550927) (xy 412.844744 -293.550927) (xy 412.844744 -293.498953) (xy 412.852874 -293.447618)
			(xy 412.868935 -293.398188) (xy 412.892531 -293.351878) (xy 412.923081 -293.30983) (xy 412.959832 -293.273079)
			(xy 413.00188 -293.242529) (xy 413.04819 -293.218933) (xy 413.09762 -293.202872) (xy 413.148955 -293.194742)
			(xy 413.200929 -293.194742) (xy 413.252264 -293.202872) (xy 413.301694 -293.218933) (xy 413.348004 -293.242529)
			(xy 413.390052 -293.273079) (xy 413.426803 -293.30983) (xy 413.457353 -293.351878) (xy 413.480949 -293.398188)
			(xy 413.49701 -293.447618) (xy 413.50514 -293.498953) (xy 413.50565 -293.52494) (xy 413.50514 -293.550927)
			(xy 413.794704 -293.550927) (xy 413.794704 -293.498953) (xy 413.802834 -293.447618) (xy 413.818895 -293.398188)
			(xy 413.842491 -293.351878) (xy 413.873041 -293.30983) (xy 413.909792 -293.273079) (xy 413.95184 -293.242529)
			(xy 413.99815 -293.218933) (xy 414.04758 -293.202872) (xy 414.098915 -293.194742) (xy 414.150889 -293.194742)
			(xy 414.202224 -293.202872) (xy 414.251654 -293.218933) (xy 414.297964 -293.242529) (xy 414.340012 -293.273079)
			(xy 414.376763 -293.30983) (xy 414.407313 -293.351878) (xy 414.430909 -293.398188) (xy 414.44697 -293.447618)
			(xy 414.4551 -293.498953) (xy 414.45561 -293.52494) (xy 414.4551 -293.550927) (xy 414.744664 -293.550927)
			(xy 414.744664 -293.498953) (xy 414.752794 -293.447618) (xy 414.768855 -293.398188) (xy 414.792451 -293.351878)
			(xy 414.823001 -293.30983) (xy 414.859752 -293.273079) (xy 414.9018 -293.242529) (xy 414.94811 -293.218933)
			(xy 414.99754 -293.202872) (xy 415.048875 -293.194742) (xy 415.100849 -293.194742) (xy 415.152184 -293.202872)
			(xy 415.201614 -293.218933) (xy 415.247924 -293.242529) (xy 415.289972 -293.273079) (xy 415.326723 -293.30983)
			(xy 415.357273 -293.351878) (xy 415.380869 -293.398188) (xy 415.39693 -293.447618) (xy 415.40506 -293.498953)
			(xy 415.40557 -293.52494) (xy 415.40506 -293.550927) (xy 415.694624 -293.550927) (xy 415.694624 -293.498953)
			(xy 415.702754 -293.447618) (xy 415.718815 -293.398188) (xy 415.742411 -293.351878) (xy 415.772961 -293.30983)
			(xy 415.809712 -293.273079) (xy 415.85176 -293.242529) (xy 415.89807 -293.218933) (xy 415.9475 -293.202872)
			(xy 415.998835 -293.194742) (xy 416.050809 -293.194742) (xy 416.102144 -293.202872) (xy 416.151574 -293.218933)
			(xy 416.197884 -293.242529) (xy 416.239932 -293.273079) (xy 416.276683 -293.30983) (xy 416.307233 -293.351878)
			(xy 416.330829 -293.398188) (xy 416.34689 -293.447618) (xy 416.35502 -293.498953) (xy 416.35553 -293.52494)
			(xy 416.35502 -293.550927) (xy 416.644584 -293.550927) (xy 416.644584 -293.498953) (xy 416.652714 -293.447618)
			(xy 416.668775 -293.398188) (xy 416.692371 -293.351878) (xy 416.722921 -293.30983) (xy 416.759672 -293.273079)
			(xy 416.80172 -293.242529) (xy 416.84803 -293.218933) (xy 416.89746 -293.202872) (xy 416.948795 -293.194742)
			(xy 417.000769 -293.194742) (xy 417.052104 -293.202872) (xy 417.101534 -293.218933) (xy 417.147844 -293.242529)
			(xy 417.189892 -293.273079) (xy 417.226643 -293.30983) (xy 417.257193 -293.351878) (xy 417.280789 -293.398188)
			(xy 417.29685 -293.447618) (xy 417.30498 -293.498953) (xy 417.30549 -293.52494) (xy 417.30498 -293.550927)
			(xy 417.594798 -293.550927) (xy 417.594798 -293.498953) (xy 417.602928 -293.447618) (xy 417.618989 -293.398188)
			(xy 417.642585 -293.351878) (xy 417.673135 -293.30983) (xy 417.709886 -293.273079) (xy 417.751934 -293.242529)
			(xy 417.798244 -293.218933) (xy 417.847674 -293.202872) (xy 417.899009 -293.194742) (xy 417.950983 -293.194742)
			(xy 418.002318 -293.202872) (xy 418.051748 -293.218933) (xy 418.098058 -293.242529) (xy 418.140106 -293.273079)
			(xy 418.176857 -293.30983) (xy 418.207407 -293.351878) (xy 418.231003 -293.398188) (xy 418.247064 -293.447618)
			(xy 418.255194 -293.498953) (xy 418.255704 -293.52494) (xy 418.255194 -293.550927) (xy 418.247064 -293.602262)
			(xy 418.231003 -293.651692) (xy 418.207407 -293.698002) (xy 418.176857 -293.74005) (xy 418.140106 -293.776801)
			(xy 418.098058 -293.807351) (xy 418.051748 -293.830947) (xy 418.002318 -293.847008) (xy 417.950983 -293.855138)
			(xy 417.899009 -293.855138) (xy 417.847674 -293.847008) (xy 417.798244 -293.830947) (xy 417.751934 -293.807351)
			(xy 417.709886 -293.776801) (xy 417.673135 -293.74005) (xy 417.642585 -293.698002) (xy 417.618989 -293.651692)
			(xy 417.602928 -293.602262) (xy 417.594798 -293.550927) (xy 417.30498 -293.550927) (xy 417.29685 -293.602262)
			(xy 417.280789 -293.651692) (xy 417.257193 -293.698002) (xy 417.226643 -293.74005) (xy 417.189892 -293.776801)
			(xy 417.147844 -293.807351) (xy 417.101534 -293.830947) (xy 417.052104 -293.847008) (xy 417.000769 -293.855138)
			(xy 416.948795 -293.855138) (xy 416.89746 -293.847008) (xy 416.84803 -293.830947) (xy 416.80172 -293.807351)
			(xy 416.759672 -293.776801) (xy 416.722921 -293.74005) (xy 416.692371 -293.698002) (xy 416.668775 -293.651692)
			(xy 416.652714 -293.602262) (xy 416.644584 -293.550927) (xy 416.35502 -293.550927) (xy 416.34689 -293.602262)
			(xy 416.330829 -293.651692) (xy 416.307233 -293.698002) (xy 416.276683 -293.74005) (xy 416.239932 -293.776801)
			(xy 416.197884 -293.807351) (xy 416.151574 -293.830947) (xy 416.102144 -293.847008) (xy 416.050809 -293.855138)
			(xy 415.998835 -293.855138) (xy 415.9475 -293.847008) (xy 415.89807 -293.830947) (xy 415.85176 -293.807351)
			(xy 415.809712 -293.776801) (xy 415.772961 -293.74005) (xy 415.742411 -293.698002) (xy 415.718815 -293.651692)
			(xy 415.702754 -293.602262) (xy 415.694624 -293.550927) (xy 415.40506 -293.550927) (xy 415.39693 -293.602262)
			(xy 415.380869 -293.651692) (xy 415.357273 -293.698002) (xy 415.326723 -293.74005) (xy 415.289972 -293.776801)
			(xy 415.247924 -293.807351) (xy 415.201614 -293.830947) (xy 415.152184 -293.847008) (xy 415.100849 -293.855138)
			(xy 415.048875 -293.855138) (xy 414.99754 -293.847008) (xy 414.94811 -293.830947) (xy 414.9018 -293.807351)
			(xy 414.859752 -293.776801) (xy 414.823001 -293.74005) (xy 414.792451 -293.698002) (xy 414.768855 -293.651692)
			(xy 414.752794 -293.602262) (xy 414.744664 -293.550927) (xy 414.4551 -293.550927) (xy 414.44697 -293.602262)
			(xy 414.430909 -293.651692) (xy 414.407313 -293.698002) (xy 414.376763 -293.74005) (xy 414.340012 -293.776801)
			(xy 414.297964 -293.807351) (xy 414.251654 -293.830947) (xy 414.202224 -293.847008) (xy 414.150889 -293.855138)
			(xy 414.098915 -293.855138) (xy 414.04758 -293.847008) (xy 413.99815 -293.830947) (xy 413.95184 -293.807351)
			(xy 413.909792 -293.776801) (xy 413.873041 -293.74005) (xy 413.842491 -293.698002) (xy 413.818895 -293.651692)
			(xy 413.802834 -293.602262) (xy 413.794704 -293.550927) (xy 413.50514 -293.550927) (xy 413.49701 -293.602262)
			(xy 413.480949 -293.651692) (xy 413.457353 -293.698002) (xy 413.426803 -293.74005) (xy 413.390052 -293.776801)
			(xy 413.348004 -293.807351) (xy 413.301694 -293.830947) (xy 413.252264 -293.847008) (xy 413.200929 -293.855138)
			(xy 413.148955 -293.855138) (xy 413.09762 -293.847008) (xy 413.04819 -293.830947) (xy 413.00188 -293.807351)
			(xy 412.959832 -293.776801) (xy 412.923081 -293.74005) (xy 412.892531 -293.698002) (xy 412.868935 -293.651692)
			(xy 412.852874 -293.602262) (xy 412.844744 -293.550927) (xy 412.55518 -293.550927) (xy 412.54705 -293.602262)
			(xy 412.530989 -293.651692) (xy 412.507393 -293.698002) (xy 412.476843 -293.74005) (xy 412.440092 -293.776801)
			(xy 412.398044 -293.807351) (xy 412.351734 -293.830947) (xy 412.302304 -293.847008) (xy 412.250969 -293.855138)
			(xy 412.198995 -293.855138) (xy 412.14766 -293.847008) (xy 412.09823 -293.830947) (xy 412.05192 -293.807351)
			(xy 412.009872 -293.776801) (xy 411.973121 -293.74005) (xy 411.942571 -293.698002) (xy 411.918975 -293.651692)
			(xy 411.902914 -293.602262) (xy 411.894784 -293.550927) (xy 411.60522 -293.550927) (xy 411.59709 -293.602262)
			(xy 411.581029 -293.651692) (xy 411.557433 -293.698002) (xy 411.526883 -293.74005) (xy 411.490132 -293.776801)
			(xy 411.448084 -293.807351) (xy 411.401774 -293.830947) (xy 411.352344 -293.847008) (xy 411.301009 -293.855138)
			(xy 411.249035 -293.855138) (xy 411.1977 -293.847008) (xy 411.14827 -293.830947) (xy 411.10196 -293.807351)
			(xy 411.059912 -293.776801) (xy 411.023161 -293.74005) (xy 410.992611 -293.698002) (xy 410.969015 -293.651692)
			(xy 410.952954 -293.602262) (xy 410.944824 -293.550927) (xy 410.655006 -293.550927) (xy 410.646876 -293.602262)
			(xy 410.630815 -293.651692) (xy 410.607219 -293.698002) (xy 410.576669 -293.74005) (xy 410.539918 -293.776801)
			(xy 410.49787 -293.807351) (xy 410.45156 -293.830947) (xy 410.40213 -293.847008) (xy 410.350795 -293.855138)
			(xy 410.298821 -293.855138) (xy 410.247486 -293.847008) (xy 410.198056 -293.830947) (xy 410.151746 -293.807351)
			(xy 410.109698 -293.776801) (xy 410.072947 -293.74005) (xy 410.042397 -293.698002) (xy 410.018801 -293.651692)
			(xy 410.00274 -293.602262) (xy 409.99461 -293.550927) (xy 409.705046 -293.550927) (xy 409.696916 -293.602262)
			(xy 409.680855 -293.651692) (xy 409.657259 -293.698002) (xy 409.626709 -293.74005) (xy 409.589958 -293.776801)
			(xy 409.54791 -293.807351) (xy 409.5016 -293.830947) (xy 409.45217 -293.847008) (xy 409.400835 -293.855138)
			(xy 409.348861 -293.855138) (xy 409.297526 -293.847008) (xy 409.248096 -293.830947) (xy 409.201786 -293.807351)
			(xy 409.159738 -293.776801) (xy 409.122987 -293.74005) (xy 409.092437 -293.698002) (xy 409.068841 -293.651692)
			(xy 409.05278 -293.602262) (xy 409.04465 -293.550927) (xy 408.755086 -293.550927) (xy 408.746956 -293.602262)
			(xy 408.730895 -293.651692) (xy 408.707299 -293.698002) (xy 408.676749 -293.74005) (xy 408.639998 -293.776801)
			(xy 408.59795 -293.807351) (xy 408.55164 -293.830947) (xy 408.50221 -293.847008) (xy 408.450875 -293.855138)
			(xy 408.398901 -293.855138) (xy 408.347566 -293.847008) (xy 408.298136 -293.830947) (xy 408.251826 -293.807351)
			(xy 408.209778 -293.776801) (xy 408.173027 -293.74005) (xy 408.142477 -293.698002) (xy 408.118881 -293.651692)
			(xy 408.10282 -293.602262) (xy 408.09469 -293.550927) (xy 406.855166 -293.550927) (xy 406.847036 -293.602262)
			(xy 406.830975 -293.651692) (xy 406.807379 -293.698002) (xy 406.776829 -293.74005) (xy 406.740078 -293.776801)
			(xy 406.69803 -293.807351) (xy 406.65172 -293.830947) (xy 406.60229 -293.847008) (xy 406.550955 -293.855138)
			(xy 406.498981 -293.855138) (xy 406.447646 -293.847008) (xy 406.398216 -293.830947) (xy 406.351906 -293.807351)
			(xy 406.309858 -293.776801) (xy 406.273107 -293.74005) (xy 406.242557 -293.698002) (xy 406.218961 -293.651692)
			(xy 406.2029 -293.602262) (xy 406.19477 -293.550927) (xy 405.905206 -293.550927) (xy 405.897076 -293.602262)
			(xy 405.881015 -293.651692) (xy 405.857419 -293.698002) (xy 405.826869 -293.74005) (xy 405.790118 -293.776801)
			(xy 405.74807 -293.807351) (xy 405.70176 -293.830947) (xy 405.65233 -293.847008) (xy 405.600995 -293.855138)
			(xy 405.549021 -293.855138) (xy 405.497686 -293.847008) (xy 405.448256 -293.830947) (xy 405.401946 -293.807351)
			(xy 405.359898 -293.776801) (xy 405.323147 -293.74005) (xy 405.292597 -293.698002) (xy 405.269001 -293.651692)
			(xy 405.25294 -293.602262) (xy 405.24481 -293.550927) (xy 404.954992 -293.550927) (xy 404.946862 -293.602262)
			(xy 404.930801 -293.651692) (xy 404.907205 -293.698002) (xy 404.876655 -293.74005) (xy 404.839904 -293.776801)
			(xy 404.797856 -293.807351) (xy 404.751546 -293.830947) (xy 404.702116 -293.847008) (xy 404.650781 -293.855138)
			(xy 404.598807 -293.855138) (xy 404.547472 -293.847008) (xy 404.498042 -293.830947) (xy 404.451732 -293.807351)
			(xy 404.409684 -293.776801) (xy 404.372933 -293.74005) (xy 404.342383 -293.698002) (xy 404.318787 -293.651692)
			(xy 404.302726 -293.602262) (xy 404.294596 -293.550927) (xy 404.005032 -293.550927) (xy 403.996902 -293.602262)
			(xy 403.980841 -293.651692) (xy 403.957245 -293.698002) (xy 403.926695 -293.74005) (xy 403.889944 -293.776801)
			(xy 403.847896 -293.807351) (xy 403.801586 -293.830947) (xy 403.752156 -293.847008) (xy 403.700821 -293.855138)
			(xy 403.648847 -293.855138) (xy 403.597512 -293.847008) (xy 403.548082 -293.830947) (xy 403.501772 -293.807351)
			(xy 403.459724 -293.776801) (xy 403.422973 -293.74005) (xy 403.392423 -293.698002) (xy 403.368827 -293.651692)
			(xy 403.352766 -293.602262) (xy 403.344636 -293.550927) (xy 403.055072 -293.550927) (xy 403.046942 -293.602262)
			(xy 403.030881 -293.651692) (xy 403.007285 -293.698002) (xy 402.976735 -293.74005) (xy 402.939984 -293.776801)
			(xy 402.897936 -293.807351) (xy 402.851626 -293.830947) (xy 402.802196 -293.847008) (xy 402.750861 -293.855138)
			(xy 402.698887 -293.855138) (xy 402.647552 -293.847008) (xy 402.598122 -293.830947) (xy 402.551812 -293.807351)
			(xy 402.509764 -293.776801) (xy 402.473013 -293.74005) (xy 402.442463 -293.698002) (xy 402.418867 -293.651692)
			(xy 402.402806 -293.602262) (xy 402.394676 -293.550927) (xy 402.105112 -293.550927) (xy 402.096982 -293.602262)
			(xy 402.080921 -293.651692) (xy 402.057325 -293.698002) (xy 402.026775 -293.74005) (xy 401.990024 -293.776801)
			(xy 401.947976 -293.807351) (xy 401.901666 -293.830947) (xy 401.852236 -293.847008) (xy 401.800901 -293.855138)
			(xy 401.748927 -293.855138) (xy 401.697592 -293.847008) (xy 401.648162 -293.830947) (xy 401.601852 -293.807351)
			(xy 401.559804 -293.776801) (xy 401.523053 -293.74005) (xy 401.492503 -293.698002) (xy 401.468907 -293.651692)
			(xy 401.452846 -293.602262) (xy 401.444716 -293.550927) (xy 401.155152 -293.550927) (xy 401.147022 -293.602262)
			(xy 401.130961 -293.651692) (xy 401.107365 -293.698002) (xy 401.076815 -293.74005) (xy 401.040064 -293.776801)
			(xy 400.998016 -293.807351) (xy 400.951706 -293.830947) (xy 400.902276 -293.847008) (xy 400.850941 -293.855138)
			(xy 400.798967 -293.855138) (xy 400.747632 -293.847008) (xy 400.698202 -293.830947) (xy 400.651892 -293.807351)
			(xy 400.609844 -293.776801) (xy 400.573093 -293.74005) (xy 400.542543 -293.698002) (xy 400.518947 -293.651692)
			(xy 400.502886 -293.602262) (xy 400.494756 -293.550927) (xy 400.205192 -293.550927) (xy 400.197062 -293.602262)
			(xy 400.181001 -293.651692) (xy 400.157405 -293.698002) (xy 400.126855 -293.74005) (xy 400.090104 -293.776801)
			(xy 400.048056 -293.807351) (xy 400.001746 -293.830947) (xy 399.952316 -293.847008) (xy 399.900981 -293.855138)
			(xy 399.849007 -293.855138) (xy 399.797672 -293.847008) (xy 399.748242 -293.830947) (xy 399.701932 -293.807351)
			(xy 399.659884 -293.776801) (xy 399.623133 -293.74005) (xy 399.592583 -293.698002) (xy 399.568987 -293.651692)
			(xy 399.552926 -293.602262) (xy 399.544796 -293.550927) (xy 399.255232 -293.550927) (xy 399.247102 -293.602262)
			(xy 399.231041 -293.651692) (xy 399.207445 -293.698002) (xy 399.176895 -293.74005) (xy 399.140144 -293.776801)
			(xy 399.098096 -293.807351) (xy 399.051786 -293.830947) (xy 399.002356 -293.847008) (xy 398.951021 -293.855138)
			(xy 398.899047 -293.855138) (xy 398.847712 -293.847008) (xy 398.798282 -293.830947) (xy 398.751972 -293.807351)
			(xy 398.709924 -293.776801) (xy 398.673173 -293.74005) (xy 398.642623 -293.698002) (xy 398.619027 -293.651692)
			(xy 398.602966 -293.602262) (xy 398.594836 -293.550927) (xy 398.305018 -293.550927) (xy 398.296888 -293.602262)
			(xy 398.280827 -293.651692) (xy 398.257231 -293.698002) (xy 398.226681 -293.74005) (xy 398.18993 -293.776801)
			(xy 398.147882 -293.807351) (xy 398.101572 -293.830947) (xy 398.052142 -293.847008) (xy 398.000807 -293.855138)
			(xy 397.948833 -293.855138) (xy 397.897498 -293.847008) (xy 397.848068 -293.830947) (xy 397.801758 -293.807351)
			(xy 397.75971 -293.776801) (xy 397.722959 -293.74005) (xy 397.692409 -293.698002) (xy 397.668813 -293.651692)
			(xy 397.652752 -293.602262) (xy 397.644622 -293.550927) (xy 397.355058 -293.550927) (xy 397.346928 -293.602262)
			(xy 397.330867 -293.651692) (xy 397.307271 -293.698002) (xy 397.276721 -293.74005) (xy 397.23997 -293.776801)
			(xy 397.197922 -293.807351) (xy 397.151612 -293.830947) (xy 397.102182 -293.847008) (xy 397.050847 -293.855138)
			(xy 396.998873 -293.855138) (xy 396.947538 -293.847008) (xy 396.898108 -293.830947) (xy 396.851798 -293.807351)
			(xy 396.80975 -293.776801) (xy 396.772999 -293.74005) (xy 396.742449 -293.698002) (xy 396.718853 -293.651692)
			(xy 396.702792 -293.602262) (xy 396.694662 -293.550927) (xy 396.405098 -293.550927) (xy 396.396968 -293.602262)
			(xy 396.380907 -293.651692) (xy 396.357311 -293.698002) (xy 396.326761 -293.74005) (xy 396.29001 -293.776801)
			(xy 396.247962 -293.807351) (xy 396.201652 -293.830947) (xy 396.152222 -293.847008) (xy 396.100887 -293.855138)
			(xy 396.048913 -293.855138) (xy 395.997578 -293.847008) (xy 395.948148 -293.830947) (xy 395.901838 -293.807351)
			(xy 395.85979 -293.776801) (xy 395.823039 -293.74005) (xy 395.792489 -293.698002) (xy 395.768893 -293.651692)
			(xy 395.752832 -293.602262) (xy 395.744702 -293.550927) (xy 395.455138 -293.550927) (xy 395.447008 -293.602262)
			(xy 395.430947 -293.651692) (xy 395.407351 -293.698002) (xy 395.376801 -293.74005) (xy 395.34005 -293.776801)
			(xy 395.298002 -293.807351) (xy 395.251692 -293.830947) (xy 395.202262 -293.847008) (xy 395.150927 -293.855138)
			(xy 395.098953 -293.855138) (xy 395.047618 -293.847008) (xy 394.998188 -293.830947) (xy 394.951878 -293.807351)
			(xy 394.90983 -293.776801) (xy 394.873079 -293.74005) (xy 394.842529 -293.698002) (xy 394.818933 -293.651692)
			(xy 394.802872 -293.602262) (xy 394.794742 -293.550927) (xy 394.505178 -293.550927) (xy 394.497048 -293.602262)
			(xy 394.480987 -293.651692) (xy 394.457391 -293.698002) (xy 394.426841 -293.74005) (xy 394.39009 -293.776801)
			(xy 394.348042 -293.807351) (xy 394.301732 -293.830947) (xy 394.252302 -293.847008) (xy 394.200967 -293.855138)
			(xy 394.148993 -293.855138) (xy 394.097658 -293.847008) (xy 394.048228 -293.830947) (xy 394.001918 -293.807351)
			(xy 393.95987 -293.776801) (xy 393.923119 -293.74005) (xy 393.892569 -293.698002) (xy 393.868973 -293.651692)
			(xy 393.852912 -293.602262) (xy 393.844782 -293.550927) (xy 392.605004 -293.550927) (xy 392.596874 -293.602262)
			(xy 392.580813 -293.651692) (xy 392.557217 -293.698002) (xy 392.526667 -293.74005) (xy 392.489916 -293.776801)
			(xy 392.447868 -293.807351) (xy 392.401558 -293.830947) (xy 392.352128 -293.847008) (xy 392.300793 -293.855138)
			(xy 392.248819 -293.855138) (xy 392.197484 -293.847008) (xy 392.148054 -293.830947) (xy 392.101744 -293.807351)
			(xy 392.059696 -293.776801) (xy 392.022945 -293.74005) (xy 391.992395 -293.698002) (xy 391.968799 -293.651692)
			(xy 391.952738 -293.602262) (xy 391.944608 -293.550927) (xy 391.704929 -293.550927) (xy 391.702737 -293.580752)
			(xy 391.690515 -293.635391) (xy 391.670438 -293.687657) (xy 391.642938 -293.736428) (xy 391.608604 -293.780655)
			(xy 391.568175 -293.81939) (xy 391.522519 -293.851799) (xy 391.472616 -293.877187) (xy 391.446258 -293.886636)
			(xy 391.430764 -293.89197) (xy 391.411714 -293.918386) (xy 391.411714 -294.119046) (xy 391.411979 -294.126689)
			(xy 391.416513 -294.141286) (xy 391.420604 -294.147748) (xy 391.425176 -294.154352) (xy 391.43686 -294.16375)
			(xy 391.444226 -294.166544) (xy 391.468746 -294.176602) (xy 391.514478 -294.203378) (xy 391.555354 -294.237104)
			(xy 391.590329 -294.276919) (xy 391.618506 -294.321802) (xy 391.639163 -294.370604) (xy 391.651774 -294.422076)
			(xy 391.656013 -294.4749) (xy 391.653928 -294.500887) (xy 391.944608 -294.500887) (xy 391.944608 -294.448913)
			(xy 391.952738 -294.397578) (xy 391.968799 -294.348148) (xy 391.992395 -294.301838) (xy 392.022945 -294.25979)
			(xy 392.059696 -294.223039) (xy 392.101744 -294.192489) (xy 392.148054 -294.168893) (xy 392.197484 -294.152832)
			(xy 392.248819 -294.144702) (xy 392.300793 -294.144702) (xy 392.352128 -294.152832) (xy 392.401558 -294.168893)
			(xy 392.447868 -294.192489) (xy 392.489916 -294.223039) (xy 392.526667 -294.25979) (xy 392.557217 -294.301838)
			(xy 392.580813 -294.348148) (xy 392.596874 -294.397578) (xy 392.605004 -294.448913) (xy 392.605514 -294.4749)
			(xy 392.605004 -294.500887) (xy 393.844782 -294.500887) (xy 393.844782 -294.448913) (xy 393.852912 -294.397578)
			(xy 393.868973 -294.348148) (xy 393.892569 -294.301838) (xy 393.923119 -294.25979) (xy 393.95987 -294.223039)
			(xy 394.001918 -294.192489) (xy 394.048228 -294.168893) (xy 394.097658 -294.152832) (xy 394.148993 -294.144702)
			(xy 394.200967 -294.144702) (xy 394.252302 -294.152832) (xy 394.301732 -294.168893) (xy 394.348042 -294.192489)
			(xy 394.39009 -294.223039) (xy 394.426841 -294.25979) (xy 394.457391 -294.301838) (xy 394.480987 -294.348148)
			(xy 394.497048 -294.397578) (xy 394.505178 -294.448913) (xy 394.505688 -294.4749) (xy 394.505178 -294.500887)
			(xy 394.794742 -294.500887) (xy 394.794742 -294.448913) (xy 394.802872 -294.397578) (xy 394.818933 -294.348148)
			(xy 394.842529 -294.301838) (xy 394.873079 -294.25979) (xy 394.90983 -294.223039) (xy 394.951878 -294.192489)
			(xy 394.998188 -294.168893) (xy 395.047618 -294.152832) (xy 395.098953 -294.144702) (xy 395.150927 -294.144702)
			(xy 395.202262 -294.152832) (xy 395.251692 -294.168893) (xy 395.298002 -294.192489) (xy 395.34005 -294.223039)
			(xy 395.376801 -294.25979) (xy 395.407351 -294.301838) (xy 395.430947 -294.348148) (xy 395.447008 -294.397578)
			(xy 395.455138 -294.448913) (xy 395.455648 -294.4749) (xy 395.455138 -294.500887) (xy 395.744702 -294.500887)
			(xy 395.744702 -294.448913) (xy 395.752832 -294.397578) (xy 395.768893 -294.348148) (xy 395.792489 -294.301838)
			(xy 395.823039 -294.25979) (xy 395.85979 -294.223039) (xy 395.901838 -294.192489) (xy 395.948148 -294.168893)
			(xy 395.997578 -294.152832) (xy 396.048913 -294.144702) (xy 396.100887 -294.144702) (xy 396.152222 -294.152832)
			(xy 396.201652 -294.168893) (xy 396.247962 -294.192489) (xy 396.29001 -294.223039) (xy 396.326761 -294.25979)
			(xy 396.357311 -294.301838) (xy 396.380907 -294.348148) (xy 396.396968 -294.397578) (xy 396.405098 -294.448913)
			(xy 396.405608 -294.4749) (xy 396.405098 -294.500887) (xy 396.694662 -294.500887) (xy 396.694662 -294.448913)
			(xy 396.702792 -294.397578) (xy 396.718853 -294.348148) (xy 396.742449 -294.301838) (xy 396.772999 -294.25979)
			(xy 396.80975 -294.223039) (xy 396.851798 -294.192489) (xy 396.898108 -294.168893) (xy 396.947538 -294.152832)
			(xy 396.998873 -294.144702) (xy 397.050847 -294.144702) (xy 397.102182 -294.152832) (xy 397.151612 -294.168893)
			(xy 397.197922 -294.192489) (xy 397.23997 -294.223039) (xy 397.276721 -294.25979) (xy 397.307271 -294.301838)
			(xy 397.330867 -294.348148) (xy 397.346928 -294.397578) (xy 397.355058 -294.448913) (xy 397.355568 -294.4749)
			(xy 397.355058 -294.500887) (xy 397.644622 -294.500887) (xy 397.644622 -294.448913) (xy 397.652752 -294.397578)
			(xy 397.668813 -294.348148) (xy 397.692409 -294.301838) (xy 397.722959 -294.25979) (xy 397.75971 -294.223039)
			(xy 397.801758 -294.192489) (xy 397.848068 -294.168893) (xy 397.897498 -294.152832) (xy 397.948833 -294.144702)
			(xy 398.000807 -294.144702) (xy 398.052142 -294.152832) (xy 398.101572 -294.168893) (xy 398.147882 -294.192489)
			(xy 398.18993 -294.223039) (xy 398.226681 -294.25979) (xy 398.257231 -294.301838) (xy 398.280827 -294.348148)
			(xy 398.296888 -294.397578) (xy 398.305018 -294.448913) (xy 398.305528 -294.4749) (xy 398.305018 -294.500887)
			(xy 398.594836 -294.500887) (xy 398.594836 -294.448913) (xy 398.602966 -294.397578) (xy 398.619027 -294.348148)
			(xy 398.642623 -294.301838) (xy 398.673173 -294.25979) (xy 398.709924 -294.223039) (xy 398.751972 -294.192489)
			(xy 398.798282 -294.168893) (xy 398.847712 -294.152832) (xy 398.899047 -294.144702) (xy 398.951021 -294.144702)
			(xy 399.002356 -294.152832) (xy 399.051786 -294.168893) (xy 399.098096 -294.192489) (xy 399.140144 -294.223039)
			(xy 399.176895 -294.25979) (xy 399.207445 -294.301838) (xy 399.231041 -294.348148) (xy 399.247102 -294.397578)
			(xy 399.255232 -294.448913) (xy 399.255742 -294.4749) (xy 399.255232 -294.500887) (xy 399.544796 -294.500887)
			(xy 399.544796 -294.448913) (xy 399.552926 -294.397578) (xy 399.568987 -294.348148) (xy 399.592583 -294.301838)
			(xy 399.623133 -294.25979) (xy 399.659884 -294.223039) (xy 399.701932 -294.192489) (xy 399.748242 -294.168893)
			(xy 399.797672 -294.152832) (xy 399.849007 -294.144702) (xy 399.900981 -294.144702) (xy 399.952316 -294.152832)
			(xy 400.001746 -294.168893) (xy 400.048056 -294.192489) (xy 400.090104 -294.223039) (xy 400.126855 -294.25979)
			(xy 400.157405 -294.301838) (xy 400.181001 -294.348148) (xy 400.197062 -294.397578) (xy 400.205192 -294.448913)
			(xy 400.205702 -294.4749) (xy 400.205192 -294.500887) (xy 400.494756 -294.500887) (xy 400.494756 -294.448913)
			(xy 400.502886 -294.397578) (xy 400.518947 -294.348148) (xy 400.542543 -294.301838) (xy 400.573093 -294.25979)
			(xy 400.609844 -294.223039) (xy 400.651892 -294.192489) (xy 400.698202 -294.168893) (xy 400.747632 -294.152832)
			(xy 400.798967 -294.144702) (xy 400.850941 -294.144702) (xy 400.902276 -294.152832) (xy 400.951706 -294.168893)
			(xy 400.998016 -294.192489) (xy 401.040064 -294.223039) (xy 401.076815 -294.25979) (xy 401.107365 -294.301838)
			(xy 401.130961 -294.348148) (xy 401.147022 -294.397578) (xy 401.155152 -294.448913) (xy 401.155662 -294.4749)
			(xy 401.155152 -294.500887) (xy 401.444716 -294.500887) (xy 401.444716 -294.448913) (xy 401.452846 -294.397578)
			(xy 401.468907 -294.348148) (xy 401.492503 -294.301838) (xy 401.523053 -294.25979) (xy 401.559804 -294.223039)
			(xy 401.601852 -294.192489) (xy 401.648162 -294.168893) (xy 401.697592 -294.152832) (xy 401.748927 -294.144702)
			(xy 401.800901 -294.144702) (xy 401.852236 -294.152832) (xy 401.901666 -294.168893) (xy 401.947976 -294.192489)
			(xy 401.990024 -294.223039) (xy 402.026775 -294.25979) (xy 402.057325 -294.301838) (xy 402.080921 -294.348148)
			(xy 402.096982 -294.397578) (xy 402.105112 -294.448913) (xy 402.105622 -294.4749) (xy 402.105112 -294.500887)
			(xy 402.394676 -294.500887) (xy 402.394676 -294.448913) (xy 402.402806 -294.397578) (xy 402.418867 -294.348148)
			(xy 402.442463 -294.301838) (xy 402.473013 -294.25979) (xy 402.509764 -294.223039) (xy 402.551812 -294.192489)
			(xy 402.598122 -294.168893) (xy 402.647552 -294.152832) (xy 402.698887 -294.144702) (xy 402.750861 -294.144702)
			(xy 402.802196 -294.152832) (xy 402.851626 -294.168893) (xy 402.897936 -294.192489) (xy 402.939984 -294.223039)
			(xy 402.976735 -294.25979) (xy 403.007285 -294.301838) (xy 403.030881 -294.348148) (xy 403.046942 -294.397578)
			(xy 403.055072 -294.448913) (xy 403.055582 -294.4749) (xy 403.055072 -294.500887) (xy 403.344636 -294.500887)
			(xy 403.344636 -294.448913) (xy 403.352766 -294.397578) (xy 403.368827 -294.348148) (xy 403.392423 -294.301838)
			(xy 403.422973 -294.25979) (xy 403.459724 -294.223039) (xy 403.501772 -294.192489) (xy 403.548082 -294.168893)
			(xy 403.597512 -294.152832) (xy 403.648847 -294.144702) (xy 403.700821 -294.144702) (xy 403.752156 -294.152832)
			(xy 403.801586 -294.168893) (xy 403.847896 -294.192489) (xy 403.889944 -294.223039) (xy 403.926695 -294.25979)
			(xy 403.957245 -294.301838) (xy 403.980841 -294.348148) (xy 403.996902 -294.397578) (xy 404.005032 -294.448913)
			(xy 404.005542 -294.4749) (xy 404.005032 -294.500887) (xy 404.294596 -294.500887) (xy 404.294596 -294.448913)
			(xy 404.302726 -294.397578) (xy 404.318787 -294.348148) (xy 404.342383 -294.301838) (xy 404.372933 -294.25979)
			(xy 404.409684 -294.223039) (xy 404.451732 -294.192489) (xy 404.498042 -294.168893) (xy 404.547472 -294.152832)
			(xy 404.598807 -294.144702) (xy 404.650781 -294.144702) (xy 404.702116 -294.152832) (xy 404.751546 -294.168893)
			(xy 404.797856 -294.192489) (xy 404.839904 -294.223039) (xy 404.876655 -294.25979) (xy 404.907205 -294.301838)
			(xy 404.930801 -294.348148) (xy 404.946862 -294.397578) (xy 404.954992 -294.448913) (xy 404.955502 -294.4749)
			(xy 404.954992 -294.500887) (xy 405.24481 -294.500887) (xy 405.24481 -294.448913) (xy 405.25294 -294.397578)
			(xy 405.269001 -294.348148) (xy 405.292597 -294.301838) (xy 405.323147 -294.25979) (xy 405.359898 -294.223039)
			(xy 405.401946 -294.192489) (xy 405.448256 -294.168893) (xy 405.497686 -294.152832) (xy 405.549021 -294.144702)
			(xy 405.600995 -294.144702) (xy 405.65233 -294.152832) (xy 405.70176 -294.168893) (xy 405.74807 -294.192489)
			(xy 405.790118 -294.223039) (xy 405.826869 -294.25979) (xy 405.857419 -294.301838) (xy 405.881015 -294.348148)
			(xy 405.897076 -294.397578) (xy 405.905206 -294.448913) (xy 405.905716 -294.4749) (xy 405.905206 -294.500887)
			(xy 406.19477 -294.500887) (xy 406.19477 -294.448913) (xy 406.2029 -294.397578) (xy 406.218961 -294.348148)
			(xy 406.242557 -294.301838) (xy 406.273107 -294.25979) (xy 406.309858 -294.223039) (xy 406.351906 -294.192489)
			(xy 406.398216 -294.168893) (xy 406.447646 -294.152832) (xy 406.498981 -294.144702) (xy 406.550955 -294.144702)
			(xy 406.60229 -294.152832) (xy 406.65172 -294.168893) (xy 406.69803 -294.192489) (xy 406.740078 -294.223039)
			(xy 406.776829 -294.25979) (xy 406.807379 -294.301838) (xy 406.830975 -294.348148) (xy 406.847036 -294.397578)
			(xy 406.855166 -294.448913) (xy 406.855676 -294.4749) (xy 406.855166 -294.500887) (xy 408.09469 -294.500887)
			(xy 408.09469 -294.448913) (xy 408.10282 -294.397578) (xy 408.118881 -294.348148) (xy 408.142477 -294.301838)
			(xy 408.173027 -294.25979) (xy 408.209778 -294.223039) (xy 408.251826 -294.192489) (xy 408.298136 -294.168893)
			(xy 408.347566 -294.152832) (xy 408.398901 -294.144702) (xy 408.450875 -294.144702) (xy 408.50221 -294.152832)
			(xy 408.55164 -294.168893) (xy 408.59795 -294.192489) (xy 408.639998 -294.223039) (xy 408.676749 -294.25979)
			(xy 408.707299 -294.301838) (xy 408.730895 -294.348148) (xy 408.746956 -294.397578) (xy 408.755086 -294.448913)
			(xy 408.755596 -294.4749) (xy 408.755086 -294.500887) (xy 409.04465 -294.500887) (xy 409.04465 -294.448913)
			(xy 409.05278 -294.397578) (xy 409.068841 -294.348148) (xy 409.092437 -294.301838) (xy 409.122987 -294.25979)
			(xy 409.159738 -294.223039) (xy 409.201786 -294.192489) (xy 409.248096 -294.168893) (xy 409.297526 -294.152832)
			(xy 409.348861 -294.144702) (xy 409.400835 -294.144702) (xy 409.45217 -294.152832) (xy 409.5016 -294.168893)
			(xy 409.54791 -294.192489) (xy 409.589958 -294.223039) (xy 409.626709 -294.25979) (xy 409.657259 -294.301838)
			(xy 409.680855 -294.348148) (xy 409.696916 -294.397578) (xy 409.705046 -294.448913) (xy 409.705556 -294.4749)
			(xy 409.705046 -294.500887) (xy 409.99461 -294.500887) (xy 409.99461 -294.448913) (xy 410.00274 -294.397578)
			(xy 410.018801 -294.348148) (xy 410.042397 -294.301838) (xy 410.072947 -294.25979) (xy 410.109698 -294.223039)
			(xy 410.151746 -294.192489) (xy 410.198056 -294.168893) (xy 410.247486 -294.152832) (xy 410.298821 -294.144702)
			(xy 410.350795 -294.144702) (xy 410.40213 -294.152832) (xy 410.45156 -294.168893) (xy 410.49787 -294.192489)
			(xy 410.539918 -294.223039) (xy 410.576669 -294.25979) (xy 410.607219 -294.301838) (xy 410.630815 -294.348148)
			(xy 410.646876 -294.397578) (xy 410.655006 -294.448913) (xy 410.655516 -294.4749) (xy 410.655006 -294.500887)
			(xy 410.944824 -294.500887) (xy 410.944824 -294.448913) (xy 410.952954 -294.397578) (xy 410.969015 -294.348148)
			(xy 410.992611 -294.301838) (xy 411.023161 -294.25979) (xy 411.059912 -294.223039) (xy 411.10196 -294.192489)
			(xy 411.14827 -294.168893) (xy 411.1977 -294.152832) (xy 411.249035 -294.144702) (xy 411.301009 -294.144702)
			(xy 411.352344 -294.152832) (xy 411.401774 -294.168893) (xy 411.448084 -294.192489) (xy 411.490132 -294.223039)
			(xy 411.526883 -294.25979) (xy 411.557433 -294.301838) (xy 411.581029 -294.348148) (xy 411.59709 -294.397578)
			(xy 411.60522 -294.448913) (xy 411.60573 -294.4749) (xy 411.60522 -294.500887) (xy 411.894784 -294.500887)
			(xy 411.894784 -294.448913) (xy 411.902914 -294.397578) (xy 411.918975 -294.348148) (xy 411.942571 -294.301838)
			(xy 411.973121 -294.25979) (xy 412.009872 -294.223039) (xy 412.05192 -294.192489) (xy 412.09823 -294.168893)
			(xy 412.14766 -294.152832) (xy 412.198995 -294.144702) (xy 412.250969 -294.144702) (xy 412.302304 -294.152832)
			(xy 412.351734 -294.168893) (xy 412.398044 -294.192489) (xy 412.440092 -294.223039) (xy 412.476843 -294.25979)
			(xy 412.507393 -294.301838) (xy 412.530989 -294.348148) (xy 412.54705 -294.397578) (xy 412.55518 -294.448913)
			(xy 412.55569 -294.4749) (xy 412.55518 -294.500887) (xy 412.844744 -294.500887) (xy 412.844744 -294.448913)
			(xy 412.852874 -294.397578) (xy 412.868935 -294.348148) (xy 412.892531 -294.301838) (xy 412.923081 -294.25979)
			(xy 412.959832 -294.223039) (xy 413.00188 -294.192489) (xy 413.04819 -294.168893) (xy 413.09762 -294.152832)
			(xy 413.148955 -294.144702) (xy 413.200929 -294.144702) (xy 413.252264 -294.152832) (xy 413.301694 -294.168893)
			(xy 413.348004 -294.192489) (xy 413.390052 -294.223039) (xy 413.426803 -294.25979) (xy 413.457353 -294.301838)
			(xy 413.480949 -294.348148) (xy 413.49701 -294.397578) (xy 413.50514 -294.448913) (xy 413.50565 -294.4749)
			(xy 413.50514 -294.500887) (xy 413.794704 -294.500887) (xy 413.794704 -294.448913) (xy 413.802834 -294.397578)
			(xy 413.818895 -294.348148) (xy 413.842491 -294.301838) (xy 413.873041 -294.25979) (xy 413.909792 -294.223039)
			(xy 413.95184 -294.192489) (xy 413.99815 -294.168893) (xy 414.04758 -294.152832) (xy 414.098915 -294.144702)
			(xy 414.150889 -294.144702) (xy 414.202224 -294.152832) (xy 414.251654 -294.168893) (xy 414.297964 -294.192489)
			(xy 414.340012 -294.223039) (xy 414.376763 -294.25979) (xy 414.407313 -294.301838) (xy 414.430909 -294.348148)
			(xy 414.44697 -294.397578) (xy 414.4551 -294.448913) (xy 414.45561 -294.4749) (xy 414.4551 -294.500887)
			(xy 414.744664 -294.500887) (xy 414.744664 -294.448913) (xy 414.752794 -294.397578) (xy 414.768855 -294.348148)
			(xy 414.792451 -294.301838) (xy 414.823001 -294.25979) (xy 414.859752 -294.223039) (xy 414.9018 -294.192489)
			(xy 414.94811 -294.168893) (xy 414.99754 -294.152832) (xy 415.048875 -294.144702) (xy 415.100849 -294.144702)
			(xy 415.152184 -294.152832) (xy 415.201614 -294.168893) (xy 415.247924 -294.192489) (xy 415.289972 -294.223039)
			(xy 415.326723 -294.25979) (xy 415.357273 -294.301838) (xy 415.380869 -294.348148) (xy 415.39693 -294.397578)
			(xy 415.40506 -294.448913) (xy 415.40557 -294.4749) (xy 415.40506 -294.500887) (xy 415.694624 -294.500887)
			(xy 415.694624 -294.448913) (xy 415.702754 -294.397578) (xy 415.718815 -294.348148) (xy 415.742411 -294.301838)
			(xy 415.772961 -294.25979) (xy 415.809712 -294.223039) (xy 415.85176 -294.192489) (xy 415.89807 -294.168893)
			(xy 415.9475 -294.152832) (xy 415.998835 -294.144702) (xy 416.050809 -294.144702) (xy 416.102144 -294.152832)
			(xy 416.151574 -294.168893) (xy 416.197884 -294.192489) (xy 416.239932 -294.223039) (xy 416.276683 -294.25979)
			(xy 416.307233 -294.301838) (xy 416.330829 -294.348148) (xy 416.34689 -294.397578) (xy 416.35502 -294.448913)
			(xy 416.35553 -294.4749) (xy 416.35502 -294.500887) (xy 416.644584 -294.500887) (xy 416.644584 -294.448913)
			(xy 416.652714 -294.397578) (xy 416.668775 -294.348148) (xy 416.692371 -294.301838) (xy 416.722921 -294.25979)
			(xy 416.759672 -294.223039) (xy 416.80172 -294.192489) (xy 416.84803 -294.168893) (xy 416.89746 -294.152832)
			(xy 416.948795 -294.144702) (xy 417.000769 -294.144702) (xy 417.052104 -294.152832) (xy 417.101534 -294.168893)
			(xy 417.147844 -294.192489) (xy 417.189892 -294.223039) (xy 417.226643 -294.25979) (xy 417.257193 -294.301838)
			(xy 417.280789 -294.348148) (xy 417.29685 -294.397578) (xy 417.30498 -294.448913) (xy 417.30549 -294.4749)
			(xy 417.30498 -294.500887) (xy 417.594798 -294.500887) (xy 417.594798 -294.448913) (xy 417.602928 -294.397578)
			(xy 417.618989 -294.348148) (xy 417.642585 -294.301838) (xy 417.673135 -294.25979) (xy 417.709886 -294.223039)
			(xy 417.751934 -294.192489) (xy 417.798244 -294.168893) (xy 417.847674 -294.152832) (xy 417.899009 -294.144702)
			(xy 417.950983 -294.144702) (xy 418.002318 -294.152832) (xy 418.051748 -294.168893) (xy 418.098058 -294.192489)
			(xy 418.140106 -294.223039) (xy 418.176857 -294.25979) (xy 418.207407 -294.301838) (xy 418.231003 -294.348148)
			(xy 418.247064 -294.397578) (xy 418.255194 -294.448913) (xy 418.255704 -294.4749) (xy 418.255194 -294.500887)
			(xy 418.247064 -294.552222) (xy 418.231003 -294.601652) (xy 418.207407 -294.647962) (xy 418.176857 -294.69001)
			(xy 418.140106 -294.726761) (xy 418.098058 -294.757311) (xy 418.051748 -294.780907) (xy 418.002318 -294.796968)
			(xy 417.950983 -294.805098) (xy 417.899009 -294.805098) (xy 417.847674 -294.796968) (xy 417.798244 -294.780907)
			(xy 417.751934 -294.757311) (xy 417.709886 -294.726761) (xy 417.673135 -294.69001) (xy 417.642585 -294.647962)
			(xy 417.618989 -294.601652) (xy 417.602928 -294.552222) (xy 417.594798 -294.500887) (xy 417.30498 -294.500887)
			(xy 417.29685 -294.552222) (xy 417.280789 -294.601652) (xy 417.257193 -294.647962) (xy 417.226643 -294.69001)
			(xy 417.189892 -294.726761) (xy 417.147844 -294.757311) (xy 417.101534 -294.780907) (xy 417.052104 -294.796968)
			(xy 417.000769 -294.805098) (xy 416.948795 -294.805098) (xy 416.89746 -294.796968) (xy 416.84803 -294.780907)
			(xy 416.80172 -294.757311) (xy 416.759672 -294.726761) (xy 416.722921 -294.69001) (xy 416.692371 -294.647962)
			(xy 416.668775 -294.601652) (xy 416.652714 -294.552222) (xy 416.644584 -294.500887) (xy 416.35502 -294.500887)
			(xy 416.34689 -294.552222) (xy 416.330829 -294.601652) (xy 416.307233 -294.647962) (xy 416.276683 -294.69001)
			(xy 416.239932 -294.726761) (xy 416.197884 -294.757311) (xy 416.151574 -294.780907) (xy 416.102144 -294.796968)
			(xy 416.050809 -294.805098) (xy 415.998835 -294.805098) (xy 415.9475 -294.796968) (xy 415.89807 -294.780907)
			(xy 415.85176 -294.757311) (xy 415.809712 -294.726761) (xy 415.772961 -294.69001) (xy 415.742411 -294.647962)
			(xy 415.718815 -294.601652) (xy 415.702754 -294.552222) (xy 415.694624 -294.500887) (xy 415.40506 -294.500887)
			(xy 415.39693 -294.552222) (xy 415.380869 -294.601652) (xy 415.357273 -294.647962) (xy 415.326723 -294.69001)
			(xy 415.289972 -294.726761) (xy 415.247924 -294.757311) (xy 415.201614 -294.780907) (xy 415.152184 -294.796968)
			(xy 415.100849 -294.805098) (xy 415.048875 -294.805098) (xy 414.99754 -294.796968) (xy 414.94811 -294.780907)
			(xy 414.9018 -294.757311) (xy 414.859752 -294.726761) (xy 414.823001 -294.69001) (xy 414.792451 -294.647962)
			(xy 414.768855 -294.601652) (xy 414.752794 -294.552222) (xy 414.744664 -294.500887) (xy 414.4551 -294.500887)
			(xy 414.44697 -294.552222) (xy 414.430909 -294.601652) (xy 414.407313 -294.647962) (xy 414.376763 -294.69001)
			(xy 414.340012 -294.726761) (xy 414.297964 -294.757311) (xy 414.251654 -294.780907) (xy 414.202224 -294.796968)
			(xy 414.150889 -294.805098) (xy 414.098915 -294.805098) (xy 414.04758 -294.796968) (xy 413.99815 -294.780907)
			(xy 413.95184 -294.757311) (xy 413.909792 -294.726761) (xy 413.873041 -294.69001) (xy 413.842491 -294.647962)
			(xy 413.818895 -294.601652) (xy 413.802834 -294.552222) (xy 413.794704 -294.500887) (xy 413.50514 -294.500887)
			(xy 413.49701 -294.552222) (xy 413.480949 -294.601652) (xy 413.457353 -294.647962) (xy 413.426803 -294.69001)
			(xy 413.390052 -294.726761) (xy 413.348004 -294.757311) (xy 413.301694 -294.780907) (xy 413.252264 -294.796968)
			(xy 413.200929 -294.805098) (xy 413.148955 -294.805098) (xy 413.09762 -294.796968) (xy 413.04819 -294.780907)
			(xy 413.00188 -294.757311) (xy 412.959832 -294.726761) (xy 412.923081 -294.69001) (xy 412.892531 -294.647962)
			(xy 412.868935 -294.601652) (xy 412.852874 -294.552222) (xy 412.844744 -294.500887) (xy 412.55518 -294.500887)
			(xy 412.54705 -294.552222) (xy 412.530989 -294.601652) (xy 412.507393 -294.647962) (xy 412.476843 -294.69001)
			(xy 412.440092 -294.726761) (xy 412.398044 -294.757311) (xy 412.351734 -294.780907) (xy 412.302304 -294.796968)
			(xy 412.250969 -294.805098) (xy 412.198995 -294.805098) (xy 412.14766 -294.796968) (xy 412.09823 -294.780907)
			(xy 412.05192 -294.757311) (xy 412.009872 -294.726761) (xy 411.973121 -294.69001) (xy 411.942571 -294.647962)
			(xy 411.918975 -294.601652) (xy 411.902914 -294.552222) (xy 411.894784 -294.500887) (xy 411.60522 -294.500887)
			(xy 411.59709 -294.552222) (xy 411.581029 -294.601652) (xy 411.557433 -294.647962) (xy 411.526883 -294.69001)
			(xy 411.490132 -294.726761) (xy 411.448084 -294.757311) (xy 411.401774 -294.780907) (xy 411.352344 -294.796968)
			(xy 411.301009 -294.805098) (xy 411.249035 -294.805098) (xy 411.1977 -294.796968) (xy 411.14827 -294.780907)
			(xy 411.10196 -294.757311) (xy 411.059912 -294.726761) (xy 411.023161 -294.69001) (xy 410.992611 -294.647962)
			(xy 410.969015 -294.601652) (xy 410.952954 -294.552222) (xy 410.944824 -294.500887) (xy 410.655006 -294.500887)
			(xy 410.646876 -294.552222) (xy 410.630815 -294.601652) (xy 410.607219 -294.647962) (xy 410.576669 -294.69001)
			(xy 410.539918 -294.726761) (xy 410.49787 -294.757311) (xy 410.45156 -294.780907) (xy 410.40213 -294.796968)
			(xy 410.350795 -294.805098) (xy 410.298821 -294.805098) (xy 410.247486 -294.796968) (xy 410.198056 -294.780907)
			(xy 410.151746 -294.757311) (xy 410.109698 -294.726761) (xy 410.072947 -294.69001) (xy 410.042397 -294.647962)
			(xy 410.018801 -294.601652) (xy 410.00274 -294.552222) (xy 409.99461 -294.500887) (xy 409.705046 -294.500887)
			(xy 409.696916 -294.552222) (xy 409.680855 -294.601652) (xy 409.657259 -294.647962) (xy 409.626709 -294.69001)
			(xy 409.589958 -294.726761) (xy 409.54791 -294.757311) (xy 409.5016 -294.780907) (xy 409.45217 -294.796968)
			(xy 409.400835 -294.805098) (xy 409.348861 -294.805098) (xy 409.297526 -294.796968) (xy 409.248096 -294.780907)
			(xy 409.201786 -294.757311) (xy 409.159738 -294.726761) (xy 409.122987 -294.69001) (xy 409.092437 -294.647962)
			(xy 409.068841 -294.601652) (xy 409.05278 -294.552222) (xy 409.04465 -294.500887) (xy 408.755086 -294.500887)
			(xy 408.746956 -294.552222) (xy 408.730895 -294.601652) (xy 408.707299 -294.647962) (xy 408.676749 -294.69001)
			(xy 408.639998 -294.726761) (xy 408.59795 -294.757311) (xy 408.55164 -294.780907) (xy 408.50221 -294.796968)
			(xy 408.450875 -294.805098) (xy 408.398901 -294.805098) (xy 408.347566 -294.796968) (xy 408.298136 -294.780907)
			(xy 408.251826 -294.757311) (xy 408.209778 -294.726761) (xy 408.173027 -294.69001) (xy 408.142477 -294.647962)
			(xy 408.118881 -294.601652) (xy 408.10282 -294.552222) (xy 408.09469 -294.500887) (xy 406.855166 -294.500887)
			(xy 406.847036 -294.552222) (xy 406.830975 -294.601652) (xy 406.807379 -294.647962) (xy 406.776829 -294.69001)
			(xy 406.740078 -294.726761) (xy 406.69803 -294.757311) (xy 406.65172 -294.780907) (xy 406.60229 -294.796968)
			(xy 406.550955 -294.805098) (xy 406.498981 -294.805098) (xy 406.447646 -294.796968) (xy 406.398216 -294.780907)
			(xy 406.351906 -294.757311) (xy 406.309858 -294.726761) (xy 406.273107 -294.69001) (xy 406.242557 -294.647962)
			(xy 406.218961 -294.601652) (xy 406.2029 -294.552222) (xy 406.19477 -294.500887) (xy 405.905206 -294.500887)
			(xy 405.897076 -294.552222) (xy 405.881015 -294.601652) (xy 405.857419 -294.647962) (xy 405.826869 -294.69001)
			(xy 405.790118 -294.726761) (xy 405.74807 -294.757311) (xy 405.70176 -294.780907) (xy 405.65233 -294.796968)
			(xy 405.600995 -294.805098) (xy 405.549021 -294.805098) (xy 405.497686 -294.796968) (xy 405.448256 -294.780907)
			(xy 405.401946 -294.757311) (xy 405.359898 -294.726761) (xy 405.323147 -294.69001) (xy 405.292597 -294.647962)
			(xy 405.269001 -294.601652) (xy 405.25294 -294.552222) (xy 405.24481 -294.500887) (xy 404.954992 -294.500887)
			(xy 404.946862 -294.552222) (xy 404.930801 -294.601652) (xy 404.907205 -294.647962) (xy 404.876655 -294.69001)
			(xy 404.839904 -294.726761) (xy 404.797856 -294.757311) (xy 404.751546 -294.780907) (xy 404.702116 -294.796968)
			(xy 404.650781 -294.805098) (xy 404.598807 -294.805098) (xy 404.547472 -294.796968) (xy 404.498042 -294.780907)
			(xy 404.451732 -294.757311) (xy 404.409684 -294.726761) (xy 404.372933 -294.69001) (xy 404.342383 -294.647962)
			(xy 404.318787 -294.601652) (xy 404.302726 -294.552222) (xy 404.294596 -294.500887) (xy 404.005032 -294.500887)
			(xy 403.996902 -294.552222) (xy 403.980841 -294.601652) (xy 403.957245 -294.647962) (xy 403.926695 -294.69001)
			(xy 403.889944 -294.726761) (xy 403.847896 -294.757311) (xy 403.801586 -294.780907) (xy 403.752156 -294.796968)
			(xy 403.700821 -294.805098) (xy 403.648847 -294.805098) (xy 403.597512 -294.796968) (xy 403.548082 -294.780907)
			(xy 403.501772 -294.757311) (xy 403.459724 -294.726761) (xy 403.422973 -294.69001) (xy 403.392423 -294.647962)
			(xy 403.368827 -294.601652) (xy 403.352766 -294.552222) (xy 403.344636 -294.500887) (xy 403.055072 -294.500887)
			(xy 403.046942 -294.552222) (xy 403.030881 -294.601652) (xy 403.007285 -294.647962) (xy 402.976735 -294.69001)
			(xy 402.939984 -294.726761) (xy 402.897936 -294.757311) (xy 402.851626 -294.780907) (xy 402.802196 -294.796968)
			(xy 402.750861 -294.805098) (xy 402.698887 -294.805098) (xy 402.647552 -294.796968) (xy 402.598122 -294.780907)
			(xy 402.551812 -294.757311) (xy 402.509764 -294.726761) (xy 402.473013 -294.69001) (xy 402.442463 -294.647962)
			(xy 402.418867 -294.601652) (xy 402.402806 -294.552222) (xy 402.394676 -294.500887) (xy 402.105112 -294.500887)
			(xy 402.096982 -294.552222) (xy 402.080921 -294.601652) (xy 402.057325 -294.647962) (xy 402.026775 -294.69001)
			(xy 401.990024 -294.726761) (xy 401.947976 -294.757311) (xy 401.901666 -294.780907) (xy 401.852236 -294.796968)
			(xy 401.800901 -294.805098) (xy 401.748927 -294.805098) (xy 401.697592 -294.796968) (xy 401.648162 -294.780907)
			(xy 401.601852 -294.757311) (xy 401.559804 -294.726761) (xy 401.523053 -294.69001) (xy 401.492503 -294.647962)
			(xy 401.468907 -294.601652) (xy 401.452846 -294.552222) (xy 401.444716 -294.500887) (xy 401.155152 -294.500887)
			(xy 401.147022 -294.552222) (xy 401.130961 -294.601652) (xy 401.107365 -294.647962) (xy 401.076815 -294.69001)
			(xy 401.040064 -294.726761) (xy 400.998016 -294.757311) (xy 400.951706 -294.780907) (xy 400.902276 -294.796968)
			(xy 400.850941 -294.805098) (xy 400.798967 -294.805098) (xy 400.747632 -294.796968) (xy 400.698202 -294.780907)
			(xy 400.651892 -294.757311) (xy 400.609844 -294.726761) (xy 400.573093 -294.69001) (xy 400.542543 -294.647962)
			(xy 400.518947 -294.601652) (xy 400.502886 -294.552222) (xy 400.494756 -294.500887) (xy 400.205192 -294.500887)
			(xy 400.197062 -294.552222) (xy 400.181001 -294.601652) (xy 400.157405 -294.647962) (xy 400.126855 -294.69001)
			(xy 400.090104 -294.726761) (xy 400.048056 -294.757311) (xy 400.001746 -294.780907) (xy 399.952316 -294.796968)
			(xy 399.900981 -294.805098) (xy 399.849007 -294.805098) (xy 399.797672 -294.796968) (xy 399.748242 -294.780907)
			(xy 399.701932 -294.757311) (xy 399.659884 -294.726761) (xy 399.623133 -294.69001) (xy 399.592583 -294.647962)
			(xy 399.568987 -294.601652) (xy 399.552926 -294.552222) (xy 399.544796 -294.500887) (xy 399.255232 -294.500887)
			(xy 399.247102 -294.552222) (xy 399.231041 -294.601652) (xy 399.207445 -294.647962) (xy 399.176895 -294.69001)
			(xy 399.140144 -294.726761) (xy 399.098096 -294.757311) (xy 399.051786 -294.780907) (xy 399.002356 -294.796968)
			(xy 398.951021 -294.805098) (xy 398.899047 -294.805098) (xy 398.847712 -294.796968) (xy 398.798282 -294.780907)
			(xy 398.751972 -294.757311) (xy 398.709924 -294.726761) (xy 398.673173 -294.69001) (xy 398.642623 -294.647962)
			(xy 398.619027 -294.601652) (xy 398.602966 -294.552222) (xy 398.594836 -294.500887) (xy 398.305018 -294.500887)
			(xy 398.296888 -294.552222) (xy 398.280827 -294.601652) (xy 398.257231 -294.647962) (xy 398.226681 -294.69001)
			(xy 398.18993 -294.726761) (xy 398.147882 -294.757311) (xy 398.101572 -294.780907) (xy 398.052142 -294.796968)
			(xy 398.000807 -294.805098) (xy 397.948833 -294.805098) (xy 397.897498 -294.796968) (xy 397.848068 -294.780907)
			(xy 397.801758 -294.757311) (xy 397.75971 -294.726761) (xy 397.722959 -294.69001) (xy 397.692409 -294.647962)
			(xy 397.668813 -294.601652) (xy 397.652752 -294.552222) (xy 397.644622 -294.500887) (xy 397.355058 -294.500887)
			(xy 397.346928 -294.552222) (xy 397.330867 -294.601652) (xy 397.307271 -294.647962) (xy 397.276721 -294.69001)
			(xy 397.23997 -294.726761) (xy 397.197922 -294.757311) (xy 397.151612 -294.780907) (xy 397.102182 -294.796968)
			(xy 397.050847 -294.805098) (xy 396.998873 -294.805098) (xy 396.947538 -294.796968) (xy 396.898108 -294.780907)
			(xy 396.851798 -294.757311) (xy 396.80975 -294.726761) (xy 396.772999 -294.69001) (xy 396.742449 -294.647962)
			(xy 396.718853 -294.601652) (xy 396.702792 -294.552222) (xy 396.694662 -294.500887) (xy 396.405098 -294.500887)
			(xy 396.396968 -294.552222) (xy 396.380907 -294.601652) (xy 396.357311 -294.647962) (xy 396.326761 -294.69001)
			(xy 396.29001 -294.726761) (xy 396.247962 -294.757311) (xy 396.201652 -294.780907) (xy 396.152222 -294.796968)
			(xy 396.100887 -294.805098) (xy 396.048913 -294.805098) (xy 395.997578 -294.796968) (xy 395.948148 -294.780907)
			(xy 395.901838 -294.757311) (xy 395.85979 -294.726761) (xy 395.823039 -294.69001) (xy 395.792489 -294.647962)
			(xy 395.768893 -294.601652) (xy 395.752832 -294.552222) (xy 395.744702 -294.500887) (xy 395.455138 -294.500887)
			(xy 395.447008 -294.552222) (xy 395.430947 -294.601652) (xy 395.407351 -294.647962) (xy 395.376801 -294.69001)
			(xy 395.34005 -294.726761) (xy 395.298002 -294.757311) (xy 395.251692 -294.780907) (xy 395.202262 -294.796968)
			(xy 395.150927 -294.805098) (xy 395.098953 -294.805098) (xy 395.047618 -294.796968) (xy 394.998188 -294.780907)
			(xy 394.951878 -294.757311) (xy 394.90983 -294.726761) (xy 394.873079 -294.69001) (xy 394.842529 -294.647962)
			(xy 394.818933 -294.601652) (xy 394.802872 -294.552222) (xy 394.794742 -294.500887) (xy 394.505178 -294.500887)
			(xy 394.497048 -294.552222) (xy 394.480987 -294.601652) (xy 394.457391 -294.647962) (xy 394.426841 -294.69001)
			(xy 394.39009 -294.726761) (xy 394.348042 -294.757311) (xy 394.301732 -294.780907) (xy 394.252302 -294.796968)
			(xy 394.200967 -294.805098) (xy 394.148993 -294.805098) (xy 394.097658 -294.796968) (xy 394.048228 -294.780907)
			(xy 394.001918 -294.757311) (xy 393.95987 -294.726761) (xy 393.923119 -294.69001) (xy 393.892569 -294.647962)
			(xy 393.868973 -294.601652) (xy 393.852912 -294.552222) (xy 393.844782 -294.500887) (xy 392.605004 -294.500887)
			(xy 392.596874 -294.552222) (xy 392.580813 -294.601652) (xy 392.557217 -294.647962) (xy 392.526667 -294.69001)
			(xy 392.489916 -294.726761) (xy 392.447868 -294.757311) (xy 392.401558 -294.780907) (xy 392.352128 -294.796968)
			(xy 392.300793 -294.805098) (xy 392.248819 -294.805098) (xy 392.197484 -294.796968) (xy 392.148054 -294.780907)
			(xy 392.101744 -294.757311) (xy 392.059696 -294.726761) (xy 392.022945 -294.69001) (xy 391.992395 -294.647962)
			(xy 391.968799 -294.601652) (xy 391.952738 -294.552222) (xy 391.944608 -294.500887) (xy 391.653928 -294.500887)
			(xy 391.651774 -294.527724) (xy 391.639163 -294.579196) (xy 391.618506 -294.627998) (xy 391.590329 -294.672881)
			(xy 391.555354 -294.712696) (xy 391.514478 -294.746422) (xy 391.468746 -294.773198) (xy 391.444226 -294.783256)
			(xy 391.43686 -294.78605) (xy 391.425176 -294.795448) (xy 391.420604 -294.802052) (xy 391.416491 -294.808503)
			(xy 391.411955 -294.823108) (xy 391.411714 -294.830754) (xy 391.411714 -296.400807) (xy 391.944608 -296.400807)
			(xy 391.944608 -296.348833) (xy 391.952738 -296.297498) (xy 391.968799 -296.248068) (xy 391.992395 -296.201758)
			(xy 392.022945 -296.15971) (xy 392.059696 -296.122959) (xy 392.101744 -296.092409) (xy 392.148054 -296.068813)
			(xy 392.197484 -296.052752) (xy 392.248819 -296.044622) (xy 392.300793 -296.044622) (xy 392.352128 -296.052752)
			(xy 392.401558 -296.068813) (xy 392.447868 -296.092409) (xy 392.489916 -296.122959) (xy 392.526667 -296.15971)
			(xy 392.557217 -296.201758) (xy 392.580813 -296.248068) (xy 392.596874 -296.297498) (xy 392.605004 -296.348833)
			(xy 392.605514 -296.37482) (xy 392.605004 -296.400807) (xy 393.844782 -296.400807) (xy 393.844782 -296.348833)
			(xy 393.852912 -296.297498) (xy 393.868973 -296.248068) (xy 393.892569 -296.201758) (xy 393.923119 -296.15971)
			(xy 393.95987 -296.122959) (xy 394.001918 -296.092409) (xy 394.048228 -296.068813) (xy 394.097658 -296.052752)
			(xy 394.148993 -296.044622) (xy 394.200967 -296.044622) (xy 394.252302 -296.052752) (xy 394.301732 -296.068813)
			(xy 394.348042 -296.092409) (xy 394.39009 -296.122959) (xy 394.426841 -296.15971) (xy 394.457391 -296.201758)
			(xy 394.480987 -296.248068) (xy 394.497048 -296.297498) (xy 394.505178 -296.348833) (xy 394.505688 -296.37482)
			(xy 394.505178 -296.400807) (xy 394.794742 -296.400807) (xy 394.794742 -296.348833) (xy 394.802872 -296.297498)
			(xy 394.818933 -296.248068) (xy 394.842529 -296.201758) (xy 394.873079 -296.15971) (xy 394.90983 -296.122959)
			(xy 394.951878 -296.092409) (xy 394.998188 -296.068813) (xy 395.047618 -296.052752) (xy 395.098953 -296.044622)
			(xy 395.150927 -296.044622) (xy 395.202262 -296.052752) (xy 395.251692 -296.068813) (xy 395.298002 -296.092409)
			(xy 395.34005 -296.122959) (xy 395.376801 -296.15971) (xy 395.407351 -296.201758) (xy 395.430947 -296.248068)
			(xy 395.447008 -296.297498) (xy 395.455138 -296.348833) (xy 395.455648 -296.37482) (xy 395.455138 -296.400807)
			(xy 395.744702 -296.400807) (xy 395.744702 -296.348833) (xy 395.752832 -296.297498) (xy 395.768893 -296.248068)
			(xy 395.792489 -296.201758) (xy 395.823039 -296.15971) (xy 395.85979 -296.122959) (xy 395.901838 -296.092409)
			(xy 395.948148 -296.068813) (xy 395.997578 -296.052752) (xy 396.048913 -296.044622) (xy 396.100887 -296.044622)
			(xy 396.152222 -296.052752) (xy 396.201652 -296.068813) (xy 396.247962 -296.092409) (xy 396.29001 -296.122959)
			(xy 396.326761 -296.15971) (xy 396.357311 -296.201758) (xy 396.380907 -296.248068) (xy 396.396968 -296.297498)
			(xy 396.405098 -296.348833) (xy 396.405608 -296.37482) (xy 396.405098 -296.400807) (xy 396.694662 -296.400807)
			(xy 396.694662 -296.348833) (xy 396.702792 -296.297498) (xy 396.718853 -296.248068) (xy 396.742449 -296.201758)
			(xy 396.772999 -296.15971) (xy 396.80975 -296.122959) (xy 396.851798 -296.092409) (xy 396.898108 -296.068813)
			(xy 396.947538 -296.052752) (xy 396.998873 -296.044622) (xy 397.050847 -296.044622) (xy 397.102182 -296.052752)
			(xy 397.151612 -296.068813) (xy 397.197922 -296.092409) (xy 397.23997 -296.122959) (xy 397.276721 -296.15971)
			(xy 397.307271 -296.201758) (xy 397.330867 -296.248068) (xy 397.346928 -296.297498) (xy 397.355058 -296.348833)
			(xy 397.355568 -296.37482) (xy 397.355058 -296.400807) (xy 397.644622 -296.400807) (xy 397.644622 -296.348833)
			(xy 397.652752 -296.297498) (xy 397.668813 -296.248068) (xy 397.692409 -296.201758) (xy 397.722959 -296.15971)
			(xy 397.75971 -296.122959) (xy 397.801758 -296.092409) (xy 397.848068 -296.068813) (xy 397.897498 -296.052752)
			(xy 397.948833 -296.044622) (xy 398.000807 -296.044622) (xy 398.052142 -296.052752) (xy 398.101572 -296.068813)
			(xy 398.147882 -296.092409) (xy 398.18993 -296.122959) (xy 398.226681 -296.15971) (xy 398.257231 -296.201758)
			(xy 398.280827 -296.248068) (xy 398.296888 -296.297498) (xy 398.305018 -296.348833) (xy 398.305528 -296.37482)
			(xy 398.305018 -296.400807) (xy 398.594836 -296.400807) (xy 398.594836 -296.348833) (xy 398.602966 -296.297498)
			(xy 398.619027 -296.248068) (xy 398.642623 -296.201758) (xy 398.673173 -296.15971) (xy 398.709924 -296.122959)
			(xy 398.751972 -296.092409) (xy 398.798282 -296.068813) (xy 398.847712 -296.052752) (xy 398.899047 -296.044622)
			(xy 398.951021 -296.044622) (xy 399.002356 -296.052752) (xy 399.051786 -296.068813) (xy 399.098096 -296.092409)
			(xy 399.140144 -296.122959) (xy 399.176895 -296.15971) (xy 399.207445 -296.201758) (xy 399.231041 -296.248068)
			(xy 399.247102 -296.297498) (xy 399.255232 -296.348833) (xy 399.255742 -296.37482) (xy 399.255232 -296.400807)
			(xy 399.544796 -296.400807) (xy 399.544796 -296.348833) (xy 399.552926 -296.297498) (xy 399.568987 -296.248068)
			(xy 399.592583 -296.201758) (xy 399.623133 -296.15971) (xy 399.659884 -296.122959) (xy 399.701932 -296.092409)
			(xy 399.748242 -296.068813) (xy 399.797672 -296.052752) (xy 399.849007 -296.044622) (xy 399.900981 -296.044622)
			(xy 399.952316 -296.052752) (xy 400.001746 -296.068813) (xy 400.048056 -296.092409) (xy 400.090104 -296.122959)
			(xy 400.126855 -296.15971) (xy 400.157405 -296.201758) (xy 400.181001 -296.248068) (xy 400.197062 -296.297498)
			(xy 400.205192 -296.348833) (xy 400.205702 -296.37482) (xy 400.205192 -296.400807) (xy 400.494756 -296.400807)
			(xy 400.494756 -296.348833) (xy 400.502886 -296.297498) (xy 400.518947 -296.248068) (xy 400.542543 -296.201758)
			(xy 400.573093 -296.15971) (xy 400.609844 -296.122959) (xy 400.651892 -296.092409) (xy 400.698202 -296.068813)
			(xy 400.747632 -296.052752) (xy 400.798967 -296.044622) (xy 400.850941 -296.044622) (xy 400.902276 -296.052752)
			(xy 400.951706 -296.068813) (xy 400.998016 -296.092409) (xy 401.040064 -296.122959) (xy 401.076815 -296.15971)
			(xy 401.107365 -296.201758) (xy 401.130961 -296.248068) (xy 401.147022 -296.297498) (xy 401.155152 -296.348833)
			(xy 401.155662 -296.37482) (xy 401.155152 -296.400807) (xy 401.444716 -296.400807) (xy 401.444716 -296.348833)
			(xy 401.452846 -296.297498) (xy 401.468907 -296.248068) (xy 401.492503 -296.201758) (xy 401.523053 -296.15971)
			(xy 401.559804 -296.122959) (xy 401.601852 -296.092409) (xy 401.648162 -296.068813) (xy 401.697592 -296.052752)
			(xy 401.748927 -296.044622) (xy 401.800901 -296.044622) (xy 401.852236 -296.052752) (xy 401.901666 -296.068813)
			(xy 401.947976 -296.092409) (xy 401.990024 -296.122959) (xy 402.026775 -296.15971) (xy 402.057325 -296.201758)
			(xy 402.080921 -296.248068) (xy 402.096982 -296.297498) (xy 402.105112 -296.348833) (xy 402.105622 -296.37482)
			(xy 402.105112 -296.400807) (xy 402.394676 -296.400807) (xy 402.394676 -296.348833) (xy 402.402806 -296.297498)
			(xy 402.418867 -296.248068) (xy 402.442463 -296.201758) (xy 402.473013 -296.15971) (xy 402.509764 -296.122959)
			(xy 402.551812 -296.092409) (xy 402.598122 -296.068813) (xy 402.647552 -296.052752) (xy 402.698887 -296.044622)
			(xy 402.750861 -296.044622) (xy 402.802196 -296.052752) (xy 402.851626 -296.068813) (xy 402.897936 -296.092409)
			(xy 402.939984 -296.122959) (xy 402.976735 -296.15971) (xy 403.007285 -296.201758) (xy 403.030881 -296.248068)
			(xy 403.046942 -296.297498) (xy 403.055072 -296.348833) (xy 403.055582 -296.37482) (xy 403.055072 -296.400807)
			(xy 403.344636 -296.400807) (xy 403.344636 -296.348833) (xy 403.352766 -296.297498) (xy 403.368827 -296.248068)
			(xy 403.392423 -296.201758) (xy 403.422973 -296.15971) (xy 403.459724 -296.122959) (xy 403.501772 -296.092409)
			(xy 403.548082 -296.068813) (xy 403.597512 -296.052752) (xy 403.648847 -296.044622) (xy 403.700821 -296.044622)
			(xy 403.752156 -296.052752) (xy 403.801586 -296.068813) (xy 403.847896 -296.092409) (xy 403.889944 -296.122959)
			(xy 403.926695 -296.15971) (xy 403.957245 -296.201758) (xy 403.980841 -296.248068) (xy 403.996902 -296.297498)
			(xy 404.005032 -296.348833) (xy 404.005542 -296.37482) (xy 404.005032 -296.400807) (xy 404.29485 -296.400807)
			(xy 404.29485 -296.348833) (xy 404.30298 -296.297498) (xy 404.319041 -296.248068) (xy 404.342637 -296.201758)
			(xy 404.373187 -296.15971) (xy 404.409938 -296.122959) (xy 404.451986 -296.092409) (xy 404.498296 -296.068813)
			(xy 404.547726 -296.052752) (xy 404.599061 -296.044622) (xy 404.651035 -296.044622) (xy 404.70237 -296.052752)
			(xy 404.7518 -296.068813) (xy 404.79811 -296.092409) (xy 404.840158 -296.122959) (xy 404.876909 -296.15971)
			(xy 404.907459 -296.201758) (xy 404.931055 -296.248068) (xy 404.947116 -296.297498) (xy 404.955246 -296.348833)
			(xy 404.955756 -296.37482) (xy 404.955246 -296.400807) (xy 405.24481 -296.400807) (xy 405.24481 -296.348833)
			(xy 405.25294 -296.297498) (xy 405.269001 -296.248068) (xy 405.292597 -296.201758) (xy 405.323147 -296.15971)
			(xy 405.359898 -296.122959) (xy 405.401946 -296.092409) (xy 405.448256 -296.068813) (xy 405.497686 -296.052752)
			(xy 405.549021 -296.044622) (xy 405.600995 -296.044622) (xy 405.65233 -296.052752) (xy 405.70176 -296.068813)
			(xy 405.74807 -296.092409) (xy 405.790118 -296.122959) (xy 405.826869 -296.15971) (xy 405.857419 -296.201758)
			(xy 405.881015 -296.248068) (xy 405.897076 -296.297498) (xy 405.905206 -296.348833) (xy 405.905716 -296.37482)
			(xy 405.905206 -296.400807) (xy 406.19477 -296.400807) (xy 406.19477 -296.348833) (xy 406.2029 -296.297498)
			(xy 406.218961 -296.248068) (xy 406.242557 -296.201758) (xy 406.273107 -296.15971) (xy 406.309858 -296.122959)
			(xy 406.351906 -296.092409) (xy 406.398216 -296.068813) (xy 406.447646 -296.052752) (xy 406.498981 -296.044622)
			(xy 406.550955 -296.044622) (xy 406.60229 -296.052752) (xy 406.65172 -296.068813) (xy 406.69803 -296.092409)
			(xy 406.740078 -296.122959) (xy 406.776829 -296.15971) (xy 406.807379 -296.201758) (xy 406.830975 -296.248068)
			(xy 406.847036 -296.297498) (xy 406.855166 -296.348833) (xy 406.855676 -296.37482) (xy 406.855166 -296.400807)
			(xy 408.09469 -296.400807) (xy 408.09469 -296.348833) (xy 408.10282 -296.297498) (xy 408.118881 -296.248068)
			(xy 408.142477 -296.201758) (xy 408.173027 -296.15971) (xy 408.209778 -296.122959) (xy 408.251826 -296.092409)
			(xy 408.298136 -296.068813) (xy 408.347566 -296.052752) (xy 408.398901 -296.044622) (xy 408.450875 -296.044622)
			(xy 408.50221 -296.052752) (xy 408.55164 -296.068813) (xy 408.59795 -296.092409) (xy 408.639998 -296.122959)
			(xy 408.676749 -296.15971) (xy 408.707299 -296.201758) (xy 408.730895 -296.248068) (xy 408.746956 -296.297498)
			(xy 408.755086 -296.348833) (xy 408.755596 -296.37482) (xy 408.755086 -296.400807) (xy 409.04465 -296.400807)
			(xy 409.04465 -296.348833) (xy 409.05278 -296.297498) (xy 409.068841 -296.248068) (xy 409.092437 -296.201758)
			(xy 409.122987 -296.15971) (xy 409.159738 -296.122959) (xy 409.201786 -296.092409) (xy 409.248096 -296.068813)
			(xy 409.297526 -296.052752) (xy 409.348861 -296.044622) (xy 409.400835 -296.044622) (xy 409.45217 -296.052752)
			(xy 409.5016 -296.068813) (xy 409.54791 -296.092409) (xy 409.589958 -296.122959) (xy 409.626709 -296.15971)
			(xy 409.657259 -296.201758) (xy 409.680855 -296.248068) (xy 409.696916 -296.297498) (xy 409.705046 -296.348833)
			(xy 409.705556 -296.37482) (xy 409.705046 -296.400807) (xy 409.99461 -296.400807) (xy 409.99461 -296.348833)
			(xy 410.00274 -296.297498) (xy 410.018801 -296.248068) (xy 410.042397 -296.201758) (xy 410.072947 -296.15971)
			(xy 410.109698 -296.122959) (xy 410.151746 -296.092409) (xy 410.198056 -296.068813) (xy 410.247486 -296.052752)
			(xy 410.298821 -296.044622) (xy 410.350795 -296.044622) (xy 410.40213 -296.052752) (xy 410.45156 -296.068813)
			(xy 410.49787 -296.092409) (xy 410.539918 -296.122959) (xy 410.576669 -296.15971) (xy 410.607219 -296.201758)
			(xy 410.630815 -296.248068) (xy 410.646876 -296.297498) (xy 410.655006 -296.348833) (xy 410.655516 -296.37482)
			(xy 410.655006 -296.400807) (xy 410.944824 -296.400807) (xy 410.944824 -296.348833) (xy 410.952954 -296.297498)
			(xy 410.969015 -296.248068) (xy 410.992611 -296.201758) (xy 411.023161 -296.15971) (xy 411.059912 -296.122959)
			(xy 411.10196 -296.092409) (xy 411.14827 -296.068813) (xy 411.1977 -296.052752) (xy 411.249035 -296.044622)
			(xy 411.301009 -296.044622) (xy 411.352344 -296.052752) (xy 411.401774 -296.068813) (xy 411.448084 -296.092409)
			(xy 411.490132 -296.122959) (xy 411.526883 -296.15971) (xy 411.557433 -296.201758) (xy 411.581029 -296.248068)
			(xy 411.59709 -296.297498) (xy 411.60522 -296.348833) (xy 411.60573 -296.37482) (xy 411.60522 -296.400807)
			(xy 411.894784 -296.400807) (xy 411.894784 -296.348833) (xy 411.902914 -296.297498) (xy 411.918975 -296.248068)
			(xy 411.942571 -296.201758) (xy 411.973121 -296.15971) (xy 412.009872 -296.122959) (xy 412.05192 -296.092409)
			(xy 412.09823 -296.068813) (xy 412.14766 -296.052752) (xy 412.198995 -296.044622) (xy 412.250969 -296.044622)
			(xy 412.302304 -296.052752) (xy 412.351734 -296.068813) (xy 412.398044 -296.092409) (xy 412.440092 -296.122959)
			(xy 412.476843 -296.15971) (xy 412.507393 -296.201758) (xy 412.530989 -296.248068) (xy 412.54705 -296.297498)
			(xy 412.55518 -296.348833) (xy 412.55569 -296.37482) (xy 412.55518 -296.400807) (xy 412.844744 -296.400807)
			(xy 412.844744 -296.348833) (xy 412.852874 -296.297498) (xy 412.868935 -296.248068) (xy 412.892531 -296.201758)
			(xy 412.923081 -296.15971) (xy 412.959832 -296.122959) (xy 413.00188 -296.092409) (xy 413.04819 -296.068813)
			(xy 413.09762 -296.052752) (xy 413.148955 -296.044622) (xy 413.200929 -296.044622) (xy 413.252264 -296.052752)
			(xy 413.301694 -296.068813) (xy 413.348004 -296.092409) (xy 413.390052 -296.122959) (xy 413.426803 -296.15971)
			(xy 413.457353 -296.201758) (xy 413.480949 -296.248068) (xy 413.49701 -296.297498) (xy 413.50514 -296.348833)
			(xy 413.50565 -296.37482) (xy 413.50514 -296.400807) (xy 413.794704 -296.400807) (xy 413.794704 -296.348833)
			(xy 413.802834 -296.297498) (xy 413.818895 -296.248068) (xy 413.842491 -296.201758) (xy 413.873041 -296.15971)
			(xy 413.909792 -296.122959) (xy 413.95184 -296.092409) (xy 413.99815 -296.068813) (xy 414.04758 -296.052752)
			(xy 414.098915 -296.044622) (xy 414.150889 -296.044622) (xy 414.202224 -296.052752) (xy 414.251654 -296.068813)
			(xy 414.297964 -296.092409) (xy 414.340012 -296.122959) (xy 414.376763 -296.15971) (xy 414.407313 -296.201758)
			(xy 414.430909 -296.248068) (xy 414.44697 -296.297498) (xy 414.4551 -296.348833) (xy 414.45561 -296.37482)
			(xy 414.4551 -296.400807) (xy 414.744664 -296.400807) (xy 414.744664 -296.348833) (xy 414.752794 -296.297498)
			(xy 414.768855 -296.248068) (xy 414.792451 -296.201758) (xy 414.823001 -296.15971) (xy 414.859752 -296.122959)
			(xy 414.9018 -296.092409) (xy 414.94811 -296.068813) (xy 414.99754 -296.052752) (xy 415.048875 -296.044622)
			(xy 415.100849 -296.044622) (xy 415.152184 -296.052752) (xy 415.201614 -296.068813) (xy 415.247924 -296.092409)
			(xy 415.289972 -296.122959) (xy 415.326723 -296.15971) (xy 415.357273 -296.201758) (xy 415.380869 -296.248068)
			(xy 415.39693 -296.297498) (xy 415.40506 -296.348833) (xy 415.40557 -296.37482) (xy 415.40506 -296.400807)
			(xy 415.694624 -296.400807) (xy 415.694624 -296.348833) (xy 415.702754 -296.297498) (xy 415.718815 -296.248068)
			(xy 415.742411 -296.201758) (xy 415.772961 -296.15971) (xy 415.809712 -296.122959) (xy 415.85176 -296.092409)
			(xy 415.89807 -296.068813) (xy 415.9475 -296.052752) (xy 415.998835 -296.044622) (xy 416.050809 -296.044622)
			(xy 416.102144 -296.052752) (xy 416.151574 -296.068813) (xy 416.197884 -296.092409) (xy 416.239932 -296.122959)
			(xy 416.276683 -296.15971) (xy 416.307233 -296.201758) (xy 416.330829 -296.248068) (xy 416.34689 -296.297498)
			(xy 416.35502 -296.348833) (xy 416.35553 -296.37482) (xy 416.35502 -296.400807) (xy 416.644584 -296.400807)
			(xy 416.644584 -296.348833) (xy 416.652714 -296.297498) (xy 416.668775 -296.248068) (xy 416.692371 -296.201758)
			(xy 416.722921 -296.15971) (xy 416.759672 -296.122959) (xy 416.80172 -296.092409) (xy 416.84803 -296.068813)
			(xy 416.89746 -296.052752) (xy 416.948795 -296.044622) (xy 417.000769 -296.044622) (xy 417.052104 -296.052752)
			(xy 417.101534 -296.068813) (xy 417.147844 -296.092409) (xy 417.189892 -296.122959) (xy 417.226643 -296.15971)
			(xy 417.257193 -296.201758) (xy 417.280789 -296.248068) (xy 417.29685 -296.297498) (xy 417.30498 -296.348833)
			(xy 417.30549 -296.37482) (xy 417.30498 -296.400807) (xy 417.594798 -296.400807) (xy 417.594798 -296.348833)
			(xy 417.602928 -296.297498) (xy 417.618989 -296.248068) (xy 417.642585 -296.201758) (xy 417.673135 -296.15971)
			(xy 417.709886 -296.122959) (xy 417.751934 -296.092409) (xy 417.798244 -296.068813) (xy 417.847674 -296.052752)
			(xy 417.899009 -296.044622) (xy 417.950983 -296.044622) (xy 418.002318 -296.052752) (xy 418.051748 -296.068813)
			(xy 418.098058 -296.092409) (xy 418.140106 -296.122959) (xy 418.176857 -296.15971) (xy 418.207407 -296.201758)
			(xy 418.231003 -296.248068) (xy 418.247064 -296.297498) (xy 418.255194 -296.348833) (xy 418.255704 -296.37482)
			(xy 418.255194 -296.400807) (xy 418.247064 -296.452142) (xy 418.231003 -296.501572) (xy 418.207407 -296.547882)
			(xy 418.176857 -296.58993) (xy 418.140106 -296.626681) (xy 418.098058 -296.657231) (xy 418.051748 -296.680827)
			(xy 418.002318 -296.696888) (xy 417.950983 -296.705018) (xy 417.899009 -296.705018) (xy 417.847674 -296.696888)
			(xy 417.798244 -296.680827) (xy 417.751934 -296.657231) (xy 417.709886 -296.626681) (xy 417.673135 -296.58993)
			(xy 417.642585 -296.547882) (xy 417.618989 -296.501572) (xy 417.602928 -296.452142) (xy 417.594798 -296.400807)
			(xy 417.30498 -296.400807) (xy 417.29685 -296.452142) (xy 417.280789 -296.501572) (xy 417.257193 -296.547882)
			(xy 417.226643 -296.58993) (xy 417.189892 -296.626681) (xy 417.147844 -296.657231) (xy 417.101534 -296.680827)
			(xy 417.052104 -296.696888) (xy 417.000769 -296.705018) (xy 416.948795 -296.705018) (xy 416.89746 -296.696888)
			(xy 416.84803 -296.680827) (xy 416.80172 -296.657231) (xy 416.759672 -296.626681) (xy 416.722921 -296.58993)
			(xy 416.692371 -296.547882) (xy 416.668775 -296.501572) (xy 416.652714 -296.452142) (xy 416.644584 -296.400807)
			(xy 416.35502 -296.400807) (xy 416.34689 -296.452142) (xy 416.330829 -296.501572) (xy 416.307233 -296.547882)
			(xy 416.276683 -296.58993) (xy 416.239932 -296.626681) (xy 416.197884 -296.657231) (xy 416.151574 -296.680827)
			(xy 416.102144 -296.696888) (xy 416.050809 -296.705018) (xy 415.998835 -296.705018) (xy 415.9475 -296.696888)
			(xy 415.89807 -296.680827) (xy 415.85176 -296.657231) (xy 415.809712 -296.626681) (xy 415.772961 -296.58993)
			(xy 415.742411 -296.547882) (xy 415.718815 -296.501572) (xy 415.702754 -296.452142) (xy 415.694624 -296.400807)
			(xy 415.40506 -296.400807) (xy 415.39693 -296.452142) (xy 415.380869 -296.501572) (xy 415.357273 -296.547882)
			(xy 415.326723 -296.58993) (xy 415.289972 -296.626681) (xy 415.247924 -296.657231) (xy 415.201614 -296.680827)
			(xy 415.152184 -296.696888) (xy 415.100849 -296.705018) (xy 415.048875 -296.705018) (xy 414.99754 -296.696888)
			(xy 414.94811 -296.680827) (xy 414.9018 -296.657231) (xy 414.859752 -296.626681) (xy 414.823001 -296.58993)
			(xy 414.792451 -296.547882) (xy 414.768855 -296.501572) (xy 414.752794 -296.452142) (xy 414.744664 -296.400807)
			(xy 414.4551 -296.400807) (xy 414.44697 -296.452142) (xy 414.430909 -296.501572) (xy 414.407313 -296.547882)
			(xy 414.376763 -296.58993) (xy 414.340012 -296.626681) (xy 414.297964 -296.657231) (xy 414.251654 -296.680827)
			(xy 414.202224 -296.696888) (xy 414.150889 -296.705018) (xy 414.098915 -296.705018) (xy 414.04758 -296.696888)
			(xy 413.99815 -296.680827) (xy 413.95184 -296.657231) (xy 413.909792 -296.626681) (xy 413.873041 -296.58993)
			(xy 413.842491 -296.547882) (xy 413.818895 -296.501572) (xy 413.802834 -296.452142) (xy 413.794704 -296.400807)
			(xy 413.50514 -296.400807) (xy 413.49701 -296.452142) (xy 413.480949 -296.501572) (xy 413.457353 -296.547882)
			(xy 413.426803 -296.58993) (xy 413.390052 -296.626681) (xy 413.348004 -296.657231) (xy 413.301694 -296.680827)
			(xy 413.252264 -296.696888) (xy 413.200929 -296.705018) (xy 413.148955 -296.705018) (xy 413.09762 -296.696888)
			(xy 413.04819 -296.680827) (xy 413.00188 -296.657231) (xy 412.959832 -296.626681) (xy 412.923081 -296.58993)
			(xy 412.892531 -296.547882) (xy 412.868935 -296.501572) (xy 412.852874 -296.452142) (xy 412.844744 -296.400807)
			(xy 412.55518 -296.400807) (xy 412.54705 -296.452142) (xy 412.530989 -296.501572) (xy 412.507393 -296.547882)
			(xy 412.476843 -296.58993) (xy 412.440092 -296.626681) (xy 412.398044 -296.657231) (xy 412.351734 -296.680827)
			(xy 412.302304 -296.696888) (xy 412.250969 -296.705018) (xy 412.198995 -296.705018) (xy 412.14766 -296.696888)
			(xy 412.09823 -296.680827) (xy 412.05192 -296.657231) (xy 412.009872 -296.626681) (xy 411.973121 -296.58993)
			(xy 411.942571 -296.547882) (xy 411.918975 -296.501572) (xy 411.902914 -296.452142) (xy 411.894784 -296.400807)
			(xy 411.60522 -296.400807) (xy 411.59709 -296.452142) (xy 411.581029 -296.501572) (xy 411.557433 -296.547882)
			(xy 411.526883 -296.58993) (xy 411.490132 -296.626681) (xy 411.448084 -296.657231) (xy 411.401774 -296.680827)
			(xy 411.352344 -296.696888) (xy 411.301009 -296.705018) (xy 411.249035 -296.705018) (xy 411.1977 -296.696888)
			(xy 411.14827 -296.680827) (xy 411.10196 -296.657231) (xy 411.059912 -296.626681) (xy 411.023161 -296.58993)
			(xy 410.992611 -296.547882) (xy 410.969015 -296.501572) (xy 410.952954 -296.452142) (xy 410.944824 -296.400807)
			(xy 410.655006 -296.400807) (xy 410.646876 -296.452142) (xy 410.630815 -296.501572) (xy 410.607219 -296.547882)
			(xy 410.576669 -296.58993) (xy 410.539918 -296.626681) (xy 410.49787 -296.657231) (xy 410.45156 -296.680827)
			(xy 410.40213 -296.696888) (xy 410.350795 -296.705018) (xy 410.298821 -296.705018) (xy 410.247486 -296.696888)
			(xy 410.198056 -296.680827) (xy 410.151746 -296.657231) (xy 410.109698 -296.626681) (xy 410.072947 -296.58993)
			(xy 410.042397 -296.547882) (xy 410.018801 -296.501572) (xy 410.00274 -296.452142) (xy 409.99461 -296.400807)
			(xy 409.705046 -296.400807) (xy 409.696916 -296.452142) (xy 409.680855 -296.501572) (xy 409.657259 -296.547882)
			(xy 409.626709 -296.58993) (xy 409.589958 -296.626681) (xy 409.54791 -296.657231) (xy 409.5016 -296.680827)
			(xy 409.45217 -296.696888) (xy 409.400835 -296.705018) (xy 409.348861 -296.705018) (xy 409.297526 -296.696888)
			(xy 409.248096 -296.680827) (xy 409.201786 -296.657231) (xy 409.159738 -296.626681) (xy 409.122987 -296.58993)
			(xy 409.092437 -296.547882) (xy 409.068841 -296.501572) (xy 409.05278 -296.452142) (xy 409.04465 -296.400807)
			(xy 408.755086 -296.400807) (xy 408.746956 -296.452142) (xy 408.730895 -296.501572) (xy 408.707299 -296.547882)
			(xy 408.676749 -296.58993) (xy 408.639998 -296.626681) (xy 408.59795 -296.657231) (xy 408.55164 -296.680827)
			(xy 408.50221 -296.696888) (xy 408.450875 -296.705018) (xy 408.398901 -296.705018) (xy 408.347566 -296.696888)
			(xy 408.298136 -296.680827) (xy 408.251826 -296.657231) (xy 408.209778 -296.626681) (xy 408.173027 -296.58993)
			(xy 408.142477 -296.547882) (xy 408.118881 -296.501572) (xy 408.10282 -296.452142) (xy 408.09469 -296.400807)
			(xy 406.855166 -296.400807) (xy 406.847036 -296.452142) (xy 406.830975 -296.501572) (xy 406.807379 -296.547882)
			(xy 406.776829 -296.58993) (xy 406.740078 -296.626681) (xy 406.69803 -296.657231) (xy 406.65172 -296.680827)
			(xy 406.60229 -296.696888) (xy 406.550955 -296.705018) (xy 406.498981 -296.705018) (xy 406.447646 -296.696888)
			(xy 406.398216 -296.680827) (xy 406.351906 -296.657231) (xy 406.309858 -296.626681) (xy 406.273107 -296.58993)
			(xy 406.242557 -296.547882) (xy 406.218961 -296.501572) (xy 406.2029 -296.452142) (xy 406.19477 -296.400807)
			(xy 405.905206 -296.400807) (xy 405.897076 -296.452142) (xy 405.881015 -296.501572) (xy 405.857419 -296.547882)
			(xy 405.826869 -296.58993) (xy 405.790118 -296.626681) (xy 405.74807 -296.657231) (xy 405.70176 -296.680827)
			(xy 405.65233 -296.696888) (xy 405.600995 -296.705018) (xy 405.549021 -296.705018) (xy 405.497686 -296.696888)
			(xy 405.448256 -296.680827) (xy 405.401946 -296.657231) (xy 405.359898 -296.626681) (xy 405.323147 -296.58993)
			(xy 405.292597 -296.547882) (xy 405.269001 -296.501572) (xy 405.25294 -296.452142) (xy 405.24481 -296.400807)
			(xy 404.955246 -296.400807) (xy 404.947116 -296.452142) (xy 404.931055 -296.501572) (xy 404.907459 -296.547882)
			(xy 404.876909 -296.58993) (xy 404.840158 -296.626681) (xy 404.79811 -296.657231) (xy 404.7518 -296.680827)
			(xy 404.70237 -296.696888) (xy 404.651035 -296.705018) (xy 404.599061 -296.705018) (xy 404.547726 -296.696888)
			(xy 404.498296 -296.680827) (xy 404.451986 -296.657231) (xy 404.409938 -296.626681) (xy 404.373187 -296.58993)
			(xy 404.342637 -296.547882) (xy 404.319041 -296.501572) (xy 404.30298 -296.452142) (xy 404.29485 -296.400807)
			(xy 404.005032 -296.400807) (xy 403.996902 -296.452142) (xy 403.980841 -296.501572) (xy 403.957245 -296.547882)
			(xy 403.926695 -296.58993) (xy 403.889944 -296.626681) (xy 403.847896 -296.657231) (xy 403.801586 -296.680827)
			(xy 403.752156 -296.696888) (xy 403.700821 -296.705018) (xy 403.648847 -296.705018) (xy 403.597512 -296.696888)
			(xy 403.548082 -296.680827) (xy 403.501772 -296.657231) (xy 403.459724 -296.626681) (xy 403.422973 -296.58993)
			(xy 403.392423 -296.547882) (xy 403.368827 -296.501572) (xy 403.352766 -296.452142) (xy 403.344636 -296.400807)
			(xy 403.055072 -296.400807) (xy 403.046942 -296.452142) (xy 403.030881 -296.501572) (xy 403.007285 -296.547882)
			(xy 402.976735 -296.58993) (xy 402.939984 -296.626681) (xy 402.897936 -296.657231) (xy 402.851626 -296.680827)
			(xy 402.802196 -296.696888) (xy 402.750861 -296.705018) (xy 402.698887 -296.705018) (xy 402.647552 -296.696888)
			(xy 402.598122 -296.680827) (xy 402.551812 -296.657231) (xy 402.509764 -296.626681) (xy 402.473013 -296.58993)
			(xy 402.442463 -296.547882) (xy 402.418867 -296.501572) (xy 402.402806 -296.452142) (xy 402.394676 -296.400807)
			(xy 402.105112 -296.400807) (xy 402.096982 -296.452142) (xy 402.080921 -296.501572) (xy 402.057325 -296.547882)
			(xy 402.026775 -296.58993) (xy 401.990024 -296.626681) (xy 401.947976 -296.657231) (xy 401.901666 -296.680827)
			(xy 401.852236 -296.696888) (xy 401.800901 -296.705018) (xy 401.748927 -296.705018) (xy 401.697592 -296.696888)
			(xy 401.648162 -296.680827) (xy 401.601852 -296.657231) (xy 401.559804 -296.626681) (xy 401.523053 -296.58993)
			(xy 401.492503 -296.547882) (xy 401.468907 -296.501572) (xy 401.452846 -296.452142) (xy 401.444716 -296.400807)
			(xy 401.155152 -296.400807) (xy 401.147022 -296.452142) (xy 401.130961 -296.501572) (xy 401.107365 -296.547882)
			(xy 401.076815 -296.58993) (xy 401.040064 -296.626681) (xy 400.998016 -296.657231) (xy 400.951706 -296.680827)
			(xy 400.902276 -296.696888) (xy 400.850941 -296.705018) (xy 400.798967 -296.705018) (xy 400.747632 -296.696888)
			(xy 400.698202 -296.680827) (xy 400.651892 -296.657231) (xy 400.609844 -296.626681) (xy 400.573093 -296.58993)
			(xy 400.542543 -296.547882) (xy 400.518947 -296.501572) (xy 400.502886 -296.452142) (xy 400.494756 -296.400807)
			(xy 400.205192 -296.400807) (xy 400.197062 -296.452142) (xy 400.181001 -296.501572) (xy 400.157405 -296.547882)
			(xy 400.126855 -296.58993) (xy 400.090104 -296.626681) (xy 400.048056 -296.657231) (xy 400.001746 -296.680827)
			(xy 399.952316 -296.696888) (xy 399.900981 -296.705018) (xy 399.849007 -296.705018) (xy 399.797672 -296.696888)
			(xy 399.748242 -296.680827) (xy 399.701932 -296.657231) (xy 399.659884 -296.626681) (xy 399.623133 -296.58993)
			(xy 399.592583 -296.547882) (xy 399.568987 -296.501572) (xy 399.552926 -296.452142) (xy 399.544796 -296.400807)
			(xy 399.255232 -296.400807) (xy 399.247102 -296.452142) (xy 399.231041 -296.501572) (xy 399.207445 -296.547882)
			(xy 399.176895 -296.58993) (xy 399.140144 -296.626681) (xy 399.098096 -296.657231) (xy 399.051786 -296.680827)
			(xy 399.002356 -296.696888) (xy 398.951021 -296.705018) (xy 398.899047 -296.705018) (xy 398.847712 -296.696888)
			(xy 398.798282 -296.680827) (xy 398.751972 -296.657231) (xy 398.709924 -296.626681) (xy 398.673173 -296.58993)
			(xy 398.642623 -296.547882) (xy 398.619027 -296.501572) (xy 398.602966 -296.452142) (xy 398.594836 -296.400807)
			(xy 398.305018 -296.400807) (xy 398.296888 -296.452142) (xy 398.280827 -296.501572) (xy 398.257231 -296.547882)
			(xy 398.226681 -296.58993) (xy 398.18993 -296.626681) (xy 398.147882 -296.657231) (xy 398.101572 -296.680827)
			(xy 398.052142 -296.696888) (xy 398.000807 -296.705018) (xy 397.948833 -296.705018) (xy 397.897498 -296.696888)
			(xy 397.848068 -296.680827) (xy 397.801758 -296.657231) (xy 397.75971 -296.626681) (xy 397.722959 -296.58993)
			(xy 397.692409 -296.547882) (xy 397.668813 -296.501572) (xy 397.652752 -296.452142) (xy 397.644622 -296.400807)
			(xy 397.355058 -296.400807) (xy 397.346928 -296.452142) (xy 397.330867 -296.501572) (xy 397.307271 -296.547882)
			(xy 397.276721 -296.58993) (xy 397.23997 -296.626681) (xy 397.197922 -296.657231) (xy 397.151612 -296.680827)
			(xy 397.102182 -296.696888) (xy 397.050847 -296.705018) (xy 396.998873 -296.705018) (xy 396.947538 -296.696888)
			(xy 396.898108 -296.680827) (xy 396.851798 -296.657231) (xy 396.80975 -296.626681) (xy 396.772999 -296.58993)
			(xy 396.742449 -296.547882) (xy 396.718853 -296.501572) (xy 396.702792 -296.452142) (xy 396.694662 -296.400807)
			(xy 396.405098 -296.400807) (xy 396.396968 -296.452142) (xy 396.380907 -296.501572) (xy 396.357311 -296.547882)
			(xy 396.326761 -296.58993) (xy 396.29001 -296.626681) (xy 396.247962 -296.657231) (xy 396.201652 -296.680827)
			(xy 396.152222 -296.696888) (xy 396.100887 -296.705018) (xy 396.048913 -296.705018) (xy 395.997578 -296.696888)
			(xy 395.948148 -296.680827) (xy 395.901838 -296.657231) (xy 395.85979 -296.626681) (xy 395.823039 -296.58993)
			(xy 395.792489 -296.547882) (xy 395.768893 -296.501572) (xy 395.752832 -296.452142) (xy 395.744702 -296.400807)
			(xy 395.455138 -296.400807) (xy 395.447008 -296.452142) (xy 395.430947 -296.501572) (xy 395.407351 -296.547882)
			(xy 395.376801 -296.58993) (xy 395.34005 -296.626681) (xy 395.298002 -296.657231) (xy 395.251692 -296.680827)
			(xy 395.202262 -296.696888) (xy 395.150927 -296.705018) (xy 395.098953 -296.705018) (xy 395.047618 -296.696888)
			(xy 394.998188 -296.680827) (xy 394.951878 -296.657231) (xy 394.90983 -296.626681) (xy 394.873079 -296.58993)
			(xy 394.842529 -296.547882) (xy 394.818933 -296.501572) (xy 394.802872 -296.452142) (xy 394.794742 -296.400807)
			(xy 394.505178 -296.400807) (xy 394.497048 -296.452142) (xy 394.480987 -296.501572) (xy 394.457391 -296.547882)
			(xy 394.426841 -296.58993) (xy 394.39009 -296.626681) (xy 394.348042 -296.657231) (xy 394.301732 -296.680827)
			(xy 394.252302 -296.696888) (xy 394.200967 -296.705018) (xy 394.148993 -296.705018) (xy 394.097658 -296.696888)
			(xy 394.048228 -296.680827) (xy 394.001918 -296.657231) (xy 393.95987 -296.626681) (xy 393.923119 -296.58993)
			(xy 393.892569 -296.547882) (xy 393.868973 -296.501572) (xy 393.852912 -296.452142) (xy 393.844782 -296.400807)
			(xy 392.605004 -296.400807) (xy 392.596874 -296.452142) (xy 392.580813 -296.501572) (xy 392.557217 -296.547882)
			(xy 392.526667 -296.58993) (xy 392.489916 -296.626681) (xy 392.447868 -296.657231) (xy 392.401558 -296.680827)
			(xy 392.352128 -296.696888) (xy 392.300793 -296.705018) (xy 392.248819 -296.705018) (xy 392.197484 -296.696888)
			(xy 392.148054 -296.680827) (xy 392.101744 -296.657231) (xy 392.059696 -296.626681) (xy 392.022945 -296.58993)
			(xy 391.992395 -296.547882) (xy 391.968799 -296.501572) (xy 391.952738 -296.452142) (xy 391.944608 -296.400807)
			(xy 391.411714 -296.400807) (xy 391.411714 -296.950384) (xy 391.412186 -296.960256) (xy 391.419648 -296.978536)
			(xy 391.426192 -296.985944) (xy 391.426446 -296.986198) (xy 391.808462 -297.368214) (xy 391.813478 -297.372949)
			(xy 391.825452 -297.379783) (xy 391.832084 -297.381676) (xy 391.845038 -297.384724) (xy 391.869168 -297.378628)
			(xy 391.87882 -297.369992) (xy 391.936478 -297.317922) (xy 391.94486 -297.301412) (xy 391.945622 -297.29176)
			(xy 391.948675 -297.266325) (xy 391.961621 -297.216761) (xy 391.982051 -297.169785) (xy 392.009477 -297.126519)
			(xy 392.043243 -297.087996) (xy 392.082544 -297.055139) (xy 392.126439 -297.028731) (xy 392.17388 -297.009405)
			(xy 392.223733 -296.997621) (xy 392.274806 -296.993661) (xy 392.325879 -296.997621) (xy 392.375732 -297.009405)
			(xy 392.423173 -297.028731) (xy 392.467068 -297.055139) (xy 392.506369 -297.087996) (xy 392.540135 -297.126519)
			(xy 392.567561 -297.169785) (xy 392.587991 -297.216761) (xy 392.600937 -297.266325) (xy 392.60399 -297.29176)
			(xy 392.604752 -297.301412) (xy 392.613134 -297.317922) (xy 392.670792 -297.369992) (xy 392.678017 -297.376085)
			(xy 392.695637 -297.382883) (xy 392.705082 -297.3832) (xy 392.804396 -297.3832) (xy 392.821922 -297.376342)
			(xy 392.829034 -297.369992) (xy 392.886692 -297.317922) (xy 392.895074 -297.301412) (xy 392.895836 -297.29176)
			(xy 392.898889 -297.266325) (xy 392.911835 -297.216761) (xy 392.932265 -297.169785) (xy 392.959691 -297.126519)
			(xy 392.993457 -297.087996) (xy 393.032758 -297.055139) (xy 393.076653 -297.028731) (xy 393.124094 -297.009405)
			(xy 393.173947 -296.997621) (xy 393.22502 -296.993661) (xy 393.276093 -296.997621) (xy 393.325946 -297.009405)
			(xy 393.373387 -297.028731) (xy 393.417282 -297.055139) (xy 393.456583 -297.087996) (xy 393.490349 -297.126519)
			(xy 393.517775 -297.169785) (xy 393.538205 -297.216761) (xy 393.551151 -297.266325) (xy 393.554204 -297.29176)
			(xy 393.554966 -297.301412) (xy 393.563348 -297.317922) (xy 393.621006 -297.369992) (xy 393.628232 -297.376082)
			(xy 393.645852 -297.382876) (xy 393.655296 -297.3832) (xy 393.754356 -297.3832) (xy 393.771882 -297.376342)
			(xy 393.778994 -297.369992) (xy 393.836652 -297.317922) (xy 393.845034 -297.301412) (xy 393.845796 -297.29176)
			(xy 393.849053 -297.26491) (xy 393.863172 -297.212703) (xy 393.885588 -297.163484) (xy 393.915706 -297.118563)
			(xy 393.952724 -297.079134) (xy 393.995658 -297.046246) (xy 394.043367 -297.020773) (xy 394.094581 -297.003393)
			(xy 394.147939 -296.994568) (xy 394.17498 -296.994072) (xy 394.200969 -296.99458) (xy 394.252307 -297.002708)
			(xy 394.301741 -297.018767) (xy 394.348055 -297.042361) (xy 394.390108 -297.07291) (xy 394.426863 -297.109662)
			(xy 394.457418 -297.151711) (xy 394.481018 -297.198022) (xy 394.497083 -297.247454) (xy 394.505217 -297.298791)
			(xy 394.505688 -297.32478) (xy 394.505241 -297.349642) (xy 394.505071 -297.350767) (xy 394.794742 -297.350767)
			(xy 394.794742 -297.298793) (xy 394.802872 -297.247458) (xy 394.818933 -297.198028) (xy 394.842529 -297.151718)
			(xy 394.873079 -297.10967) (xy 394.90983 -297.072919) (xy 394.951878 -297.042369) (xy 394.998188 -297.018773)
			(xy 395.047618 -297.002712) (xy 395.098953 -296.994582) (xy 395.150927 -296.994582) (xy 395.202262 -297.002712)
			(xy 395.251692 -297.018773) (xy 395.298002 -297.042369) (xy 395.34005 -297.072919) (xy 395.376801 -297.10967)
			(xy 395.407351 -297.151718) (xy 395.430947 -297.198028) (xy 395.447008 -297.247458) (xy 395.455138 -297.298793)
			(xy 395.455648 -297.32478) (xy 395.455138 -297.350767) (xy 395.744702 -297.350767) (xy 395.744702 -297.298793)
			(xy 395.752832 -297.247458) (xy 395.768893 -297.198028) (xy 395.792489 -297.151718) (xy 395.823039 -297.10967)
			(xy 395.85979 -297.072919) (xy 395.901838 -297.042369) (xy 395.948148 -297.018773) (xy 395.997578 -297.002712)
			(xy 396.048913 -296.994582) (xy 396.100887 -296.994582) (xy 396.152222 -297.002712) (xy 396.201652 -297.018773)
			(xy 396.247962 -297.042369) (xy 396.29001 -297.072919) (xy 396.326761 -297.10967) (xy 396.357311 -297.151718)
			(xy 396.380907 -297.198028) (xy 396.396968 -297.247458) (xy 396.405098 -297.298793) (xy 396.405608 -297.32478)
			(xy 396.405098 -297.350767) (xy 396.694662 -297.350767) (xy 396.694662 -297.298793) (xy 396.702792 -297.247458)
			(xy 396.718853 -297.198028) (xy 396.742449 -297.151718) (xy 396.772999 -297.10967) (xy 396.80975 -297.072919)
			(xy 396.851798 -297.042369) (xy 396.898108 -297.018773) (xy 396.947538 -297.002712) (xy 396.998873 -296.994582)
			(xy 397.050847 -296.994582) (xy 397.102182 -297.002712) (xy 397.151612 -297.018773) (xy 397.197922 -297.042369)
			(xy 397.23997 -297.072919) (xy 397.276721 -297.10967) (xy 397.307271 -297.151718) (xy 397.330867 -297.198028)
			(xy 397.346928 -297.247458) (xy 397.355058 -297.298793) (xy 397.355568 -297.32478) (xy 397.355058 -297.350767)
			(xy 397.644622 -297.350767) (xy 397.644622 -297.298793) (xy 397.652752 -297.247458) (xy 397.668813 -297.198028)
			(xy 397.692409 -297.151718) (xy 397.722959 -297.10967) (xy 397.75971 -297.072919) (xy 397.801758 -297.042369)
			(xy 397.848068 -297.018773) (xy 397.897498 -297.002712) (xy 397.948833 -296.994582) (xy 398.000807 -296.994582)
			(xy 398.052142 -297.002712) (xy 398.101572 -297.018773) (xy 398.147882 -297.042369) (xy 398.18993 -297.072919)
			(xy 398.226681 -297.10967) (xy 398.257231 -297.151718) (xy 398.280827 -297.198028) (xy 398.296888 -297.247458)
			(xy 398.305018 -297.298793) (xy 398.305528 -297.32478) (xy 398.305018 -297.350767) (xy 398.594836 -297.350767)
			(xy 398.594836 -297.298793) (xy 398.602966 -297.247458) (xy 398.619027 -297.198028) (xy 398.642623 -297.151718)
			(xy 398.673173 -297.10967) (xy 398.709924 -297.072919) (xy 398.751972 -297.042369) (xy 398.798282 -297.018773)
			(xy 398.847712 -297.002712) (xy 398.899047 -296.994582) (xy 398.951021 -296.994582) (xy 399.002356 -297.002712)
			(xy 399.051786 -297.018773) (xy 399.098096 -297.042369) (xy 399.140144 -297.072919) (xy 399.176895 -297.10967)
			(xy 399.207445 -297.151718) (xy 399.231041 -297.198028) (xy 399.247102 -297.247458) (xy 399.255232 -297.298793)
			(xy 399.255742 -297.32478) (xy 399.255232 -297.350767) (xy 399.544796 -297.350767) (xy 399.544796 -297.298793)
			(xy 399.552926 -297.247458) (xy 399.568987 -297.198028) (xy 399.592583 -297.151718) (xy 399.623133 -297.10967)
			(xy 399.659884 -297.072919) (xy 399.701932 -297.042369) (xy 399.748242 -297.018773) (xy 399.797672 -297.002712)
			(xy 399.849007 -296.994582) (xy 399.900981 -296.994582) (xy 399.952316 -297.002712) (xy 400.001746 -297.018773)
			(xy 400.048056 -297.042369) (xy 400.090104 -297.072919) (xy 400.126855 -297.10967) (xy 400.157405 -297.151718)
			(xy 400.181001 -297.198028) (xy 400.197062 -297.247458) (xy 400.205192 -297.298793) (xy 400.205702 -297.32478)
			(xy 400.205192 -297.350767) (xy 400.494756 -297.350767) (xy 400.494756 -297.298793) (xy 400.502886 -297.247458)
			(xy 400.518947 -297.198028) (xy 400.542543 -297.151718) (xy 400.573093 -297.10967) (xy 400.609844 -297.072919)
			(xy 400.651892 -297.042369) (xy 400.698202 -297.018773) (xy 400.747632 -297.002712) (xy 400.798967 -296.994582)
			(xy 400.850941 -296.994582) (xy 400.902276 -297.002712) (xy 400.951706 -297.018773) (xy 400.998016 -297.042369)
			(xy 401.040064 -297.072919) (xy 401.076815 -297.10967) (xy 401.107365 -297.151718) (xy 401.130961 -297.198028)
			(xy 401.147022 -297.247458) (xy 401.155152 -297.298793) (xy 401.155662 -297.32478) (xy 401.155152 -297.350767)
			(xy 401.444716 -297.350767) (xy 401.444716 -297.298793) (xy 401.452846 -297.247458) (xy 401.468907 -297.198028)
			(xy 401.492503 -297.151718) (xy 401.523053 -297.10967) (xy 401.559804 -297.072919) (xy 401.601852 -297.042369)
			(xy 401.648162 -297.018773) (xy 401.697592 -297.002712) (xy 401.748927 -296.994582) (xy 401.800901 -296.994582)
			(xy 401.852236 -297.002712) (xy 401.901666 -297.018773) (xy 401.947976 -297.042369) (xy 401.990024 -297.072919)
			(xy 402.026775 -297.10967) (xy 402.057325 -297.151718) (xy 402.080921 -297.198028) (xy 402.096982 -297.247458)
			(xy 402.105112 -297.298793) (xy 402.105622 -297.32478) (xy 402.105112 -297.350767) (xy 402.394676 -297.350767)
			(xy 402.394676 -297.298793) (xy 402.402806 -297.247458) (xy 402.418867 -297.198028) (xy 402.442463 -297.151718)
			(xy 402.473013 -297.10967) (xy 402.509764 -297.072919) (xy 402.551812 -297.042369) (xy 402.598122 -297.018773)
			(xy 402.647552 -297.002712) (xy 402.698887 -296.994582) (xy 402.750861 -296.994582) (xy 402.802196 -297.002712)
			(xy 402.851626 -297.018773) (xy 402.897936 -297.042369) (xy 402.939984 -297.072919) (xy 402.976735 -297.10967)
			(xy 403.007285 -297.151718) (xy 403.030881 -297.198028) (xy 403.046942 -297.247458) (xy 403.055072 -297.298793)
			(xy 403.055582 -297.32478) (xy 403.055072 -297.350767) (xy 403.344636 -297.350767) (xy 403.344636 -297.298793)
			(xy 403.352766 -297.247458) (xy 403.368827 -297.198028) (xy 403.392423 -297.151718) (xy 403.422973 -297.10967)
			(xy 403.459724 -297.072919) (xy 403.501772 -297.042369) (xy 403.548082 -297.018773) (xy 403.597512 -297.002712)
			(xy 403.648847 -296.994582) (xy 403.700821 -296.994582) (xy 403.752156 -297.002712) (xy 403.801586 -297.018773)
			(xy 403.847896 -297.042369) (xy 403.889944 -297.072919) (xy 403.926695 -297.10967) (xy 403.957245 -297.151718)
			(xy 403.980841 -297.198028) (xy 403.996902 -297.247458) (xy 404.005032 -297.298793) (xy 404.005542 -297.32478)
			(xy 404.005032 -297.350767) (xy 404.294596 -297.350767) (xy 404.294596 -297.298793) (xy 404.302726 -297.247458)
			(xy 404.318787 -297.198028) (xy 404.342383 -297.151718) (xy 404.372933 -297.10967) (xy 404.409684 -297.072919)
			(xy 404.451732 -297.042369) (xy 404.498042 -297.018773) (xy 404.547472 -297.002712) (xy 404.598807 -296.994582)
			(xy 404.650781 -296.994582) (xy 404.702116 -297.002712) (xy 404.751546 -297.018773) (xy 404.797856 -297.042369)
			(xy 404.839904 -297.072919) (xy 404.876655 -297.10967) (xy 404.907205 -297.151718) (xy 404.930801 -297.198028)
			(xy 404.946862 -297.247458) (xy 404.954992 -297.298793) (xy 404.955502 -297.32478) (xy 404.954992 -297.350767)
			(xy 405.24481 -297.350767) (xy 405.24481 -297.298793) (xy 405.25294 -297.247458) (xy 405.269001 -297.198028)
			(xy 405.292597 -297.151718) (xy 405.323147 -297.10967) (xy 405.359898 -297.072919) (xy 405.401946 -297.042369)
			(xy 405.448256 -297.018773) (xy 405.497686 -297.002712) (xy 405.549021 -296.994582) (xy 405.600995 -296.994582)
			(xy 405.65233 -297.002712) (xy 405.70176 -297.018773) (xy 405.74807 -297.042369) (xy 405.790118 -297.072919)
			(xy 405.826869 -297.10967) (xy 405.857419 -297.151718) (xy 405.881015 -297.198028) (xy 405.897076 -297.247458)
			(xy 405.905206 -297.298793) (xy 405.905716 -297.32478) (xy 405.905206 -297.350767) (xy 406.19477 -297.350767)
			(xy 406.19477 -297.298793) (xy 406.2029 -297.247458) (xy 406.218961 -297.198028) (xy 406.242557 -297.151718)
			(xy 406.273107 -297.10967) (xy 406.309858 -297.072919) (xy 406.351906 -297.042369) (xy 406.398216 -297.018773)
			(xy 406.447646 -297.002712) (xy 406.498981 -296.994582) (xy 406.550955 -296.994582) (xy 406.60229 -297.002712)
			(xy 406.65172 -297.018773) (xy 406.69803 -297.042369) (xy 406.740078 -297.072919) (xy 406.776829 -297.10967)
			(xy 406.807379 -297.151718) (xy 406.830975 -297.198028) (xy 406.847036 -297.247458) (xy 406.855166 -297.298793)
			(xy 406.855676 -297.32478) (xy 406.855166 -297.350767) (xy 408.09469 -297.350767) (xy 408.09469 -297.298793)
			(xy 408.10282 -297.247458) (xy 408.118881 -297.198028) (xy 408.142477 -297.151718) (xy 408.173027 -297.10967)
			(xy 408.209778 -297.072919) (xy 408.251826 -297.042369) (xy 408.298136 -297.018773) (xy 408.347566 -297.002712)
			(xy 408.398901 -296.994582) (xy 408.450875 -296.994582) (xy 408.50221 -297.002712) (xy 408.55164 -297.018773)
			(xy 408.59795 -297.042369) (xy 408.639998 -297.072919) (xy 408.676749 -297.10967) (xy 408.707299 -297.151718)
			(xy 408.730895 -297.198028) (xy 408.746956 -297.247458) (xy 408.755086 -297.298793) (xy 408.755596 -297.32478)
			(xy 408.755086 -297.350767) (xy 409.04465 -297.350767) (xy 409.04465 -297.298793) (xy 409.05278 -297.247458)
			(xy 409.068841 -297.198028) (xy 409.092437 -297.151718) (xy 409.122987 -297.10967) (xy 409.159738 -297.072919)
			(xy 409.201786 -297.042369) (xy 409.248096 -297.018773) (xy 409.297526 -297.002712) (xy 409.348861 -296.994582)
			(xy 409.400835 -296.994582) (xy 409.45217 -297.002712) (xy 409.5016 -297.018773) (xy 409.54791 -297.042369)
			(xy 409.589958 -297.072919) (xy 409.626709 -297.10967) (xy 409.657259 -297.151718) (xy 409.680855 -297.198028)
			(xy 409.696916 -297.247458) (xy 409.705046 -297.298793) (xy 409.705556 -297.32478) (xy 409.705046 -297.350767)
			(xy 409.99461 -297.350767) (xy 409.99461 -297.298793) (xy 410.00274 -297.247458) (xy 410.018801 -297.198028)
			(xy 410.042397 -297.151718) (xy 410.072947 -297.10967) (xy 410.109698 -297.072919) (xy 410.151746 -297.042369)
			(xy 410.198056 -297.018773) (xy 410.247486 -297.002712) (xy 410.298821 -296.994582) (xy 410.350795 -296.994582)
			(xy 410.40213 -297.002712) (xy 410.45156 -297.018773) (xy 410.49787 -297.042369) (xy 410.539918 -297.072919)
			(xy 410.576669 -297.10967) (xy 410.607219 -297.151718) (xy 410.630815 -297.198028) (xy 410.646876 -297.247458)
			(xy 410.655006 -297.298793) (xy 410.655516 -297.32478) (xy 410.655006 -297.350767) (xy 410.944824 -297.350767)
			(xy 410.944824 -297.298793) (xy 410.952954 -297.247458) (xy 410.969015 -297.198028) (xy 410.992611 -297.151718)
			(xy 411.023161 -297.10967) (xy 411.059912 -297.072919) (xy 411.10196 -297.042369) (xy 411.14827 -297.018773)
			(xy 411.1977 -297.002712) (xy 411.249035 -296.994582) (xy 411.301009 -296.994582) (xy 411.352344 -297.002712)
			(xy 411.401774 -297.018773) (xy 411.448084 -297.042369) (xy 411.490132 -297.072919) (xy 411.526883 -297.10967)
			(xy 411.557433 -297.151718) (xy 411.581029 -297.198028) (xy 411.59709 -297.247458) (xy 411.60522 -297.298793)
			(xy 411.60573 -297.32478) (xy 411.60522 -297.350767) (xy 411.894784 -297.350767) (xy 411.894784 -297.298793)
			(xy 411.902914 -297.247458) (xy 411.918975 -297.198028) (xy 411.942571 -297.151718) (xy 411.973121 -297.10967)
			(xy 412.009872 -297.072919) (xy 412.05192 -297.042369) (xy 412.09823 -297.018773) (xy 412.14766 -297.002712)
			(xy 412.198995 -296.994582) (xy 412.250969 -296.994582) (xy 412.302304 -297.002712) (xy 412.351734 -297.018773)
			(xy 412.398044 -297.042369) (xy 412.440092 -297.072919) (xy 412.476843 -297.10967) (xy 412.507393 -297.151718)
			(xy 412.530989 -297.198028) (xy 412.54705 -297.247458) (xy 412.55518 -297.298793) (xy 412.55569 -297.32478)
			(xy 412.55518 -297.350767) (xy 412.844744 -297.350767) (xy 412.844744 -297.298793) (xy 412.852874 -297.247458)
			(xy 412.868935 -297.198028) (xy 412.892531 -297.151718) (xy 412.923081 -297.10967) (xy 412.959832 -297.072919)
			(xy 413.00188 -297.042369) (xy 413.04819 -297.018773) (xy 413.09762 -297.002712) (xy 413.148955 -296.994582)
			(xy 413.200929 -296.994582) (xy 413.252264 -297.002712) (xy 413.301694 -297.018773) (xy 413.348004 -297.042369)
			(xy 413.390052 -297.072919) (xy 413.426803 -297.10967) (xy 413.457353 -297.151718) (xy 413.480949 -297.198028)
			(xy 413.49701 -297.247458) (xy 413.50514 -297.298793) (xy 413.50565 -297.32478) (xy 413.50514 -297.350767)
			(xy 413.794704 -297.350767) (xy 413.794704 -297.298793) (xy 413.802834 -297.247458) (xy 413.818895 -297.198028)
			(xy 413.842491 -297.151718) (xy 413.873041 -297.10967) (xy 413.909792 -297.072919) (xy 413.95184 -297.042369)
			(xy 413.99815 -297.018773) (xy 414.04758 -297.002712) (xy 414.098915 -296.994582) (xy 414.150889 -296.994582)
			(xy 414.202224 -297.002712) (xy 414.251654 -297.018773) (xy 414.297964 -297.042369) (xy 414.340012 -297.072919)
			(xy 414.376763 -297.10967) (xy 414.407313 -297.151718) (xy 414.430909 -297.198028) (xy 414.44697 -297.247458)
			(xy 414.4551 -297.298793) (xy 414.45561 -297.32478) (xy 414.4551 -297.350767) (xy 414.744664 -297.350767)
			(xy 414.744664 -297.298793) (xy 414.752794 -297.247458) (xy 414.768855 -297.198028) (xy 414.792451 -297.151718)
			(xy 414.823001 -297.10967) (xy 414.859752 -297.072919) (xy 414.9018 -297.042369) (xy 414.94811 -297.018773)
			(xy 414.99754 -297.002712) (xy 415.048875 -296.994582) (xy 415.100849 -296.994582) (xy 415.152184 -297.002712)
			(xy 415.201614 -297.018773) (xy 415.247924 -297.042369) (xy 415.289972 -297.072919) (xy 415.326723 -297.10967)
			(xy 415.357273 -297.151718) (xy 415.380869 -297.198028) (xy 415.39693 -297.247458) (xy 415.40506 -297.298793)
			(xy 415.40557 -297.32478) (xy 415.40506 -297.350767) (xy 415.694624 -297.350767) (xy 415.694624 -297.298793)
			(xy 415.702754 -297.247458) (xy 415.718815 -297.198028) (xy 415.742411 -297.151718) (xy 415.772961 -297.10967)
			(xy 415.809712 -297.072919) (xy 415.85176 -297.042369) (xy 415.89807 -297.018773) (xy 415.9475 -297.002712)
			(xy 415.998835 -296.994582) (xy 416.050809 -296.994582) (xy 416.102144 -297.002712) (xy 416.151574 -297.018773)
			(xy 416.197884 -297.042369) (xy 416.239932 -297.072919) (xy 416.276683 -297.10967) (xy 416.307233 -297.151718)
			(xy 416.330829 -297.198028) (xy 416.34689 -297.247458) (xy 416.35502 -297.298793) (xy 416.35553 -297.32478)
			(xy 416.35502 -297.350767) (xy 416.34689 -297.402102) (xy 416.330829 -297.451532) (xy 416.307233 -297.497842)
			(xy 416.276683 -297.53989) (xy 416.239932 -297.576641) (xy 416.197884 -297.607191) (xy 416.151574 -297.630787)
			(xy 416.102144 -297.646848) (xy 416.050809 -297.654978) (xy 415.998835 -297.654978) (xy 415.9475 -297.646848)
			(xy 415.89807 -297.630787) (xy 415.85176 -297.607191) (xy 415.809712 -297.576641) (xy 415.772961 -297.53989)
			(xy 415.742411 -297.497842) (xy 415.718815 -297.451532) (xy 415.702754 -297.402102) (xy 415.694624 -297.350767)
			(xy 415.40506 -297.350767) (xy 415.39693 -297.402102) (xy 415.380869 -297.451532) (xy 415.357273 -297.497842)
			(xy 415.326723 -297.53989) (xy 415.289972 -297.576641) (xy 415.247924 -297.607191) (xy 415.201614 -297.630787)
			(xy 415.152184 -297.646848) (xy 415.100849 -297.654978) (xy 415.048875 -297.654978) (xy 414.99754 -297.646848)
			(xy 414.94811 -297.630787) (xy 414.9018 -297.607191) (xy 414.859752 -297.576641) (xy 414.823001 -297.53989)
			(xy 414.792451 -297.497842) (xy 414.768855 -297.451532) (xy 414.752794 -297.402102) (xy 414.744664 -297.350767)
			(xy 414.4551 -297.350767) (xy 414.44697 -297.402102) (xy 414.430909 -297.451532) (xy 414.407313 -297.497842)
			(xy 414.376763 -297.53989) (xy 414.340012 -297.576641) (xy 414.297964 -297.607191) (xy 414.251654 -297.630787)
			(xy 414.202224 -297.646848) (xy 414.150889 -297.654978) (xy 414.098915 -297.654978) (xy 414.04758 -297.646848)
			(xy 413.99815 -297.630787) (xy 413.95184 -297.607191) (xy 413.909792 -297.576641) (xy 413.873041 -297.53989)
			(xy 413.842491 -297.497842) (xy 413.818895 -297.451532) (xy 413.802834 -297.402102) (xy 413.794704 -297.350767)
			(xy 413.50514 -297.350767) (xy 413.49701 -297.402102) (xy 413.480949 -297.451532) (xy 413.457353 -297.497842)
			(xy 413.426803 -297.53989) (xy 413.390052 -297.576641) (xy 413.348004 -297.607191) (xy 413.301694 -297.630787)
			(xy 413.252264 -297.646848) (xy 413.200929 -297.654978) (xy 413.148955 -297.654978) (xy 413.09762 -297.646848)
			(xy 413.04819 -297.630787) (xy 413.00188 -297.607191) (xy 412.959832 -297.576641) (xy 412.923081 -297.53989)
			(xy 412.892531 -297.497842) (xy 412.868935 -297.451532) (xy 412.852874 -297.402102) (xy 412.844744 -297.350767)
			(xy 412.55518 -297.350767) (xy 412.54705 -297.402102) (xy 412.530989 -297.451532) (xy 412.507393 -297.497842)
			(xy 412.476843 -297.53989) (xy 412.440092 -297.576641) (xy 412.398044 -297.607191) (xy 412.351734 -297.630787)
			(xy 412.302304 -297.646848) (xy 412.250969 -297.654978) (xy 412.198995 -297.654978) (xy 412.14766 -297.646848)
			(xy 412.09823 -297.630787) (xy 412.05192 -297.607191) (xy 412.009872 -297.576641) (xy 411.973121 -297.53989)
			(xy 411.942571 -297.497842) (xy 411.918975 -297.451532) (xy 411.902914 -297.402102) (xy 411.894784 -297.350767)
			(xy 411.60522 -297.350767) (xy 411.59709 -297.402102) (xy 411.581029 -297.451532) (xy 411.557433 -297.497842)
			(xy 411.526883 -297.53989) (xy 411.490132 -297.576641) (xy 411.448084 -297.607191) (xy 411.401774 -297.630787)
			(xy 411.352344 -297.646848) (xy 411.301009 -297.654978) (xy 411.249035 -297.654978) (xy 411.1977 -297.646848)
			(xy 411.14827 -297.630787) (xy 411.10196 -297.607191) (xy 411.059912 -297.576641) (xy 411.023161 -297.53989)
			(xy 410.992611 -297.497842) (xy 410.969015 -297.451532) (xy 410.952954 -297.402102) (xy 410.944824 -297.350767)
			(xy 410.655006 -297.350767) (xy 410.646876 -297.402102) (xy 410.630815 -297.451532) (xy 410.607219 -297.497842)
			(xy 410.576669 -297.53989) (xy 410.539918 -297.576641) (xy 410.49787 -297.607191) (xy 410.45156 -297.630787)
			(xy 410.40213 -297.646848) (xy 410.350795 -297.654978) (xy 410.298821 -297.654978) (xy 410.247486 -297.646848)
			(xy 410.198056 -297.630787) (xy 410.151746 -297.607191) (xy 410.109698 -297.576641) (xy 410.072947 -297.53989)
			(xy 410.042397 -297.497842) (xy 410.018801 -297.451532) (xy 410.00274 -297.402102) (xy 409.99461 -297.350767)
			(xy 409.705046 -297.350767) (xy 409.696916 -297.402102) (xy 409.680855 -297.451532) (xy 409.657259 -297.497842)
			(xy 409.626709 -297.53989) (xy 409.589958 -297.576641) (xy 409.54791 -297.607191) (xy 409.5016 -297.630787)
			(xy 409.45217 -297.646848) (xy 409.400835 -297.654978) (xy 409.348861 -297.654978) (xy 409.297526 -297.646848)
			(xy 409.248096 -297.630787) (xy 409.201786 -297.607191) (xy 409.159738 -297.576641) (xy 409.122987 -297.53989)
			(xy 409.092437 -297.497842) (xy 409.068841 -297.451532) (xy 409.05278 -297.402102) (xy 409.04465 -297.350767)
			(xy 408.755086 -297.350767) (xy 408.746956 -297.402102) (xy 408.730895 -297.451532) (xy 408.707299 -297.497842)
			(xy 408.676749 -297.53989) (xy 408.639998 -297.576641) (xy 408.59795 -297.607191) (xy 408.55164 -297.630787)
			(xy 408.50221 -297.646848) (xy 408.450875 -297.654978) (xy 408.398901 -297.654978) (xy 408.347566 -297.646848)
			(xy 408.298136 -297.630787) (xy 408.251826 -297.607191) (xy 408.209778 -297.576641) (xy 408.173027 -297.53989)
			(xy 408.142477 -297.497842) (xy 408.118881 -297.451532) (xy 408.10282 -297.402102) (xy 408.09469 -297.350767)
			(xy 406.855166 -297.350767) (xy 406.847036 -297.402102) (xy 406.830975 -297.451532) (xy 406.807379 -297.497842)
			(xy 406.776829 -297.53989) (xy 406.740078 -297.576641) (xy 406.69803 -297.607191) (xy 406.65172 -297.630787)
			(xy 406.60229 -297.646848) (xy 406.550955 -297.654978) (xy 406.498981 -297.654978) (xy 406.447646 -297.646848)
			(xy 406.398216 -297.630787) (xy 406.351906 -297.607191) (xy 406.309858 -297.576641) (xy 406.273107 -297.53989)
			(xy 406.242557 -297.497842) (xy 406.218961 -297.451532) (xy 406.2029 -297.402102) (xy 406.19477 -297.350767)
			(xy 405.905206 -297.350767) (xy 405.897076 -297.402102) (xy 405.881015 -297.451532) (xy 405.857419 -297.497842)
			(xy 405.826869 -297.53989) (xy 405.790118 -297.576641) (xy 405.74807 -297.607191) (xy 405.70176 -297.630787)
			(xy 405.65233 -297.646848) (xy 405.600995 -297.654978) (xy 405.549021 -297.654978) (xy 405.497686 -297.646848)
			(xy 405.448256 -297.630787) (xy 405.401946 -297.607191) (xy 405.359898 -297.576641) (xy 405.323147 -297.53989)
			(xy 405.292597 -297.497842) (xy 405.269001 -297.451532) (xy 405.25294 -297.402102) (xy 405.24481 -297.350767)
			(xy 404.954992 -297.350767) (xy 404.946862 -297.402102) (xy 404.930801 -297.451532) (xy 404.907205 -297.497842)
			(xy 404.876655 -297.53989) (xy 404.839904 -297.576641) (xy 404.797856 -297.607191) (xy 404.751546 -297.630787)
			(xy 404.702116 -297.646848) (xy 404.650781 -297.654978) (xy 404.598807 -297.654978) (xy 404.547472 -297.646848)
			(xy 404.498042 -297.630787) (xy 404.451732 -297.607191) (xy 404.409684 -297.576641) (xy 404.372933 -297.53989)
			(xy 404.342383 -297.497842) (xy 404.318787 -297.451532) (xy 404.302726 -297.402102) (xy 404.294596 -297.350767)
			(xy 404.005032 -297.350767) (xy 403.996902 -297.402102) (xy 403.980841 -297.451532) (xy 403.957245 -297.497842)
			(xy 403.926695 -297.53989) (xy 403.889944 -297.576641) (xy 403.847896 -297.607191) (xy 403.801586 -297.630787)
			(xy 403.752156 -297.646848) (xy 403.700821 -297.654978) (xy 403.648847 -297.654978) (xy 403.597512 -297.646848)
			(xy 403.548082 -297.630787) (xy 403.501772 -297.607191) (xy 403.459724 -297.576641) (xy 403.422973 -297.53989)
			(xy 403.392423 -297.497842) (xy 403.368827 -297.451532) (xy 403.352766 -297.402102) (xy 403.344636 -297.350767)
			(xy 403.055072 -297.350767) (xy 403.046942 -297.402102) (xy 403.030881 -297.451532) (xy 403.007285 -297.497842)
			(xy 402.976735 -297.53989) (xy 402.939984 -297.576641) (xy 402.897936 -297.607191) (xy 402.851626 -297.630787)
			(xy 402.802196 -297.646848) (xy 402.750861 -297.654978) (xy 402.698887 -297.654978) (xy 402.647552 -297.646848)
			(xy 402.598122 -297.630787) (xy 402.551812 -297.607191) (xy 402.509764 -297.576641) (xy 402.473013 -297.53989)
			(xy 402.442463 -297.497842) (xy 402.418867 -297.451532) (xy 402.402806 -297.402102) (xy 402.394676 -297.350767)
			(xy 402.105112 -297.350767) (xy 402.096982 -297.402102) (xy 402.080921 -297.451532) (xy 402.057325 -297.497842)
			(xy 402.026775 -297.53989) (xy 401.990024 -297.576641) (xy 401.947976 -297.607191) (xy 401.901666 -297.630787)
			(xy 401.852236 -297.646848) (xy 401.800901 -297.654978) (xy 401.748927 -297.654978) (xy 401.697592 -297.646848)
			(xy 401.648162 -297.630787) (xy 401.601852 -297.607191) (xy 401.559804 -297.576641) (xy 401.523053 -297.53989)
			(xy 401.492503 -297.497842) (xy 401.468907 -297.451532) (xy 401.452846 -297.402102) (xy 401.444716 -297.350767)
			(xy 401.155152 -297.350767) (xy 401.147022 -297.402102) (xy 401.130961 -297.451532) (xy 401.107365 -297.497842)
			(xy 401.076815 -297.53989) (xy 401.040064 -297.576641) (xy 400.998016 -297.607191) (xy 400.951706 -297.630787)
			(xy 400.902276 -297.646848) (xy 400.850941 -297.654978) (xy 400.798967 -297.654978) (xy 400.747632 -297.646848)
			(xy 400.698202 -297.630787) (xy 400.651892 -297.607191) (xy 400.609844 -297.576641) (xy 400.573093 -297.53989)
			(xy 400.542543 -297.497842) (xy 400.518947 -297.451532) (xy 400.502886 -297.402102) (xy 400.494756 -297.350767)
			(xy 400.205192 -297.350767) (xy 400.197062 -297.402102) (xy 400.181001 -297.451532) (xy 400.157405 -297.497842)
			(xy 400.126855 -297.53989) (xy 400.090104 -297.576641) (xy 400.048056 -297.607191) (xy 400.001746 -297.630787)
			(xy 399.952316 -297.646848) (xy 399.900981 -297.654978) (xy 399.849007 -297.654978) (xy 399.797672 -297.646848)
			(xy 399.748242 -297.630787) (xy 399.701932 -297.607191) (xy 399.659884 -297.576641) (xy 399.623133 -297.53989)
			(xy 399.592583 -297.497842) (xy 399.568987 -297.451532) (xy 399.552926 -297.402102) (xy 399.544796 -297.350767)
			(xy 399.255232 -297.350767) (xy 399.247102 -297.402102) (xy 399.231041 -297.451532) (xy 399.207445 -297.497842)
			(xy 399.176895 -297.53989) (xy 399.140144 -297.576641) (xy 399.098096 -297.607191) (xy 399.051786 -297.630787)
			(xy 399.002356 -297.646848) (xy 398.951021 -297.654978) (xy 398.899047 -297.654978) (xy 398.847712 -297.646848)
			(xy 398.798282 -297.630787) (xy 398.751972 -297.607191) (xy 398.709924 -297.576641) (xy 398.673173 -297.53989)
			(xy 398.642623 -297.497842) (xy 398.619027 -297.451532) (xy 398.602966 -297.402102) (xy 398.594836 -297.350767)
			(xy 398.305018 -297.350767) (xy 398.296888 -297.402102) (xy 398.280827 -297.451532) (xy 398.257231 -297.497842)
			(xy 398.226681 -297.53989) (xy 398.18993 -297.576641) (xy 398.147882 -297.607191) (xy 398.101572 -297.630787)
			(xy 398.052142 -297.646848) (xy 398.000807 -297.654978) (xy 397.948833 -297.654978) (xy 397.897498 -297.646848)
			(xy 397.848068 -297.630787) (xy 397.801758 -297.607191) (xy 397.75971 -297.576641) (xy 397.722959 -297.53989)
			(xy 397.692409 -297.497842) (xy 397.668813 -297.451532) (xy 397.652752 -297.402102) (xy 397.644622 -297.350767)
			(xy 397.355058 -297.350767) (xy 397.346928 -297.402102) (xy 397.330867 -297.451532) (xy 397.307271 -297.497842)
			(xy 397.276721 -297.53989) (xy 397.23997 -297.576641) (xy 397.197922 -297.607191) (xy 397.151612 -297.630787)
			(xy 397.102182 -297.646848) (xy 397.050847 -297.654978) (xy 396.998873 -297.654978) (xy 396.947538 -297.646848)
			(xy 396.898108 -297.630787) (xy 396.851798 -297.607191) (xy 396.80975 -297.576641) (xy 396.772999 -297.53989)
			(xy 396.742449 -297.497842) (xy 396.718853 -297.451532) (xy 396.702792 -297.402102) (xy 396.694662 -297.350767)
			(xy 396.405098 -297.350767) (xy 396.396968 -297.402102) (xy 396.380907 -297.451532) (xy 396.357311 -297.497842)
			(xy 396.326761 -297.53989) (xy 396.29001 -297.576641) (xy 396.247962 -297.607191) (xy 396.201652 -297.630787)
			(xy 396.152222 -297.646848) (xy 396.100887 -297.654978) (xy 396.048913 -297.654978) (xy 395.997578 -297.646848)
			(xy 395.948148 -297.630787) (xy 395.901838 -297.607191) (xy 395.85979 -297.576641) (xy 395.823039 -297.53989)
			(xy 395.792489 -297.497842) (xy 395.768893 -297.451532) (xy 395.752832 -297.402102) (xy 395.744702 -297.350767)
			(xy 395.455138 -297.350767) (xy 395.447008 -297.402102) (xy 395.430947 -297.451532) (xy 395.407351 -297.497842)
			(xy 395.376801 -297.53989) (xy 395.34005 -297.576641) (xy 395.298002 -297.607191) (xy 395.251692 -297.630787)
			(xy 395.202262 -297.646848) (xy 395.150927 -297.654978) (xy 395.098953 -297.654978) (xy 395.047618 -297.646848)
			(xy 394.998188 -297.630787) (xy 394.951878 -297.607191) (xy 394.90983 -297.576641) (xy 394.873079 -297.53989)
			(xy 394.842529 -297.497842) (xy 394.818933 -297.451532) (xy 394.802872 -297.402102) (xy 394.794742 -297.350767)
			(xy 394.505071 -297.350767) (xy 394.4978 -297.398806) (xy 394.483081 -297.446301) (xy 394.461417 -297.491058)
			(xy 394.433297 -297.532066) (xy 394.399354 -297.568402) (xy 394.360353 -297.599247) (xy 394.317173 -297.623904)
			(xy 394.270789 -297.641819) (xy 394.246608 -297.647614) (xy 394.229082 -297.651424) (xy 394.20673 -297.679364)
			(xy 394.20673 -297.920156) (xy 394.229082 -297.948096) (xy 394.246608 -297.951906) (xy 394.272194 -297.958104)
			(xy 394.32113 -297.977504) (xy 394.366375 -298.004412) (xy 394.406784 -298.03815) (xy 394.441337 -298.077865)
			(xy 394.469161 -298.122552) (xy 394.489553 -298.171084) (xy 394.501997 -298.222233) (xy 394.506179 -298.274709)
			(xy 394.504104 -298.300727) (xy 394.794742 -298.300727) (xy 394.794742 -298.248753) (xy 394.802872 -298.197418)
			(xy 394.818933 -298.147988) (xy 394.842529 -298.101678) (xy 394.873079 -298.05963) (xy 394.90983 -298.022879)
			(xy 394.951878 -297.992329) (xy 394.998188 -297.968733) (xy 395.047618 -297.952672) (xy 395.098953 -297.944542)
			(xy 395.150927 -297.944542) (xy 395.202262 -297.952672) (xy 395.251692 -297.968733) (xy 395.298002 -297.992329)
			(xy 395.34005 -298.022879) (xy 395.376801 -298.05963) (xy 395.407351 -298.101678) (xy 395.430947 -298.147988)
			(xy 395.447008 -298.197418) (xy 395.455138 -298.248753) (xy 395.455648 -298.27474) (xy 395.455138 -298.300727)
			(xy 395.744702 -298.300727) (xy 395.744702 -298.248753) (xy 395.752832 -298.197418) (xy 395.768893 -298.147988)
			(xy 395.792489 -298.101678) (xy 395.823039 -298.05963) (xy 395.85979 -298.022879) (xy 395.901838 -297.992329)
			(xy 395.948148 -297.968733) (xy 395.997578 -297.952672) (xy 396.048913 -297.944542) (xy 396.100887 -297.944542)
			(xy 396.152222 -297.952672) (xy 396.201652 -297.968733) (xy 396.247962 -297.992329) (xy 396.29001 -298.022879)
			(xy 396.326761 -298.05963) (xy 396.357311 -298.101678) (xy 396.380907 -298.147988) (xy 396.396968 -298.197418)
			(xy 396.405098 -298.248753) (xy 396.405608 -298.27474) (xy 396.405098 -298.300727) (xy 396.694662 -298.300727)
			(xy 396.694662 -298.248753) (xy 396.702792 -298.197418) (xy 396.718853 -298.147988) (xy 396.742449 -298.101678)
			(xy 396.772999 -298.05963) (xy 396.80975 -298.022879) (xy 396.851798 -297.992329) (xy 396.898108 -297.968733)
			(xy 396.947538 -297.952672) (xy 396.998873 -297.944542) (xy 397.050847 -297.944542) (xy 397.102182 -297.952672)
			(xy 397.151612 -297.968733) (xy 397.197922 -297.992329) (xy 397.23997 -298.022879) (xy 397.276721 -298.05963)
			(xy 397.307271 -298.101678) (xy 397.330867 -298.147988) (xy 397.346928 -298.197418) (xy 397.355058 -298.248753)
			(xy 397.355568 -298.27474) (xy 397.355058 -298.300727) (xy 397.644622 -298.300727) (xy 397.644622 -298.248753)
			(xy 397.652752 -298.197418) (xy 397.668813 -298.147988) (xy 397.692409 -298.101678) (xy 397.722959 -298.05963)
			(xy 397.75971 -298.022879) (xy 397.801758 -297.992329) (xy 397.848068 -297.968733) (xy 397.897498 -297.952672)
			(xy 397.948833 -297.944542) (xy 398.000807 -297.944542) (xy 398.052142 -297.952672) (xy 398.101572 -297.968733)
			(xy 398.147882 -297.992329) (xy 398.18993 -298.022879) (xy 398.226681 -298.05963) (xy 398.257231 -298.101678)
			(xy 398.280827 -298.147988) (xy 398.296888 -298.197418) (xy 398.305018 -298.248753) (xy 398.305528 -298.27474)
			(xy 398.305018 -298.300727) (xy 398.594836 -298.300727) (xy 398.594836 -298.248753) (xy 398.602966 -298.197418)
			(xy 398.619027 -298.147988) (xy 398.642623 -298.101678) (xy 398.673173 -298.05963) (xy 398.709924 -298.022879)
			(xy 398.751972 -297.992329) (xy 398.798282 -297.968733) (xy 398.847712 -297.952672) (xy 398.899047 -297.944542)
			(xy 398.951021 -297.944542) (xy 399.002356 -297.952672) (xy 399.051786 -297.968733) (xy 399.098096 -297.992329)
			(xy 399.140144 -298.022879) (xy 399.176895 -298.05963) (xy 399.207445 -298.101678) (xy 399.231041 -298.147988)
			(xy 399.247102 -298.197418) (xy 399.255232 -298.248753) (xy 399.255742 -298.27474) (xy 399.255232 -298.300727)
			(xy 399.544796 -298.300727) (xy 399.544796 -298.248753) (xy 399.552926 -298.197418) (xy 399.568987 -298.147988)
			(xy 399.592583 -298.101678) (xy 399.623133 -298.05963) (xy 399.659884 -298.022879) (xy 399.701932 -297.992329)
			(xy 399.748242 -297.968733) (xy 399.797672 -297.952672) (xy 399.849007 -297.944542) (xy 399.900981 -297.944542)
			(xy 399.952316 -297.952672) (xy 400.001746 -297.968733) (xy 400.048056 -297.992329) (xy 400.090104 -298.022879)
			(xy 400.126855 -298.05963) (xy 400.157405 -298.101678) (xy 400.181001 -298.147988) (xy 400.197062 -298.197418)
			(xy 400.205192 -298.248753) (xy 400.205702 -298.27474) (xy 400.205192 -298.300727) (xy 400.494756 -298.300727)
			(xy 400.494756 -298.248753) (xy 400.502886 -298.197418) (xy 400.518947 -298.147988) (xy 400.542543 -298.101678)
			(xy 400.573093 -298.05963) (xy 400.609844 -298.022879) (xy 400.651892 -297.992329) (xy 400.698202 -297.968733)
			(xy 400.747632 -297.952672) (xy 400.798967 -297.944542) (xy 400.850941 -297.944542) (xy 400.902276 -297.952672)
			(xy 400.951706 -297.968733) (xy 400.998016 -297.992329) (xy 401.040064 -298.022879) (xy 401.076815 -298.05963)
			(xy 401.107365 -298.101678) (xy 401.130961 -298.147988) (xy 401.147022 -298.197418) (xy 401.155152 -298.248753)
			(xy 401.155662 -298.27474) (xy 401.155152 -298.300727) (xy 401.444716 -298.300727) (xy 401.444716 -298.248753)
			(xy 401.452846 -298.197418) (xy 401.468907 -298.147988) (xy 401.492503 -298.101678) (xy 401.523053 -298.05963)
			(xy 401.559804 -298.022879) (xy 401.601852 -297.992329) (xy 401.648162 -297.968733) (xy 401.697592 -297.952672)
			(xy 401.748927 -297.944542) (xy 401.800901 -297.944542) (xy 401.852236 -297.952672) (xy 401.901666 -297.968733)
			(xy 401.947976 -297.992329) (xy 401.990024 -298.022879) (xy 402.026775 -298.05963) (xy 402.057325 -298.101678)
			(xy 402.080921 -298.147988) (xy 402.096982 -298.197418) (xy 402.105112 -298.248753) (xy 402.105622 -298.27474)
			(xy 402.105112 -298.300727) (xy 402.394676 -298.300727) (xy 402.394676 -298.248753) (xy 402.402806 -298.197418)
			(xy 402.418867 -298.147988) (xy 402.442463 -298.101678) (xy 402.473013 -298.05963) (xy 402.509764 -298.022879)
			(xy 402.551812 -297.992329) (xy 402.598122 -297.968733) (xy 402.647552 -297.952672) (xy 402.698887 -297.944542)
			(xy 402.750861 -297.944542) (xy 402.802196 -297.952672) (xy 402.851626 -297.968733) (xy 402.897936 -297.992329)
			(xy 402.939984 -298.022879) (xy 402.976735 -298.05963) (xy 403.007285 -298.101678) (xy 403.030881 -298.147988)
			(xy 403.046942 -298.197418) (xy 403.055072 -298.248753) (xy 403.055582 -298.27474) (xy 403.055072 -298.300727)
			(xy 403.344636 -298.300727) (xy 403.344636 -298.248753) (xy 403.352766 -298.197418) (xy 403.368827 -298.147988)
			(xy 403.392423 -298.101678) (xy 403.422973 -298.05963) (xy 403.459724 -298.022879) (xy 403.501772 -297.992329)
			(xy 403.548082 -297.968733) (xy 403.597512 -297.952672) (xy 403.648847 -297.944542) (xy 403.700821 -297.944542)
			(xy 403.752156 -297.952672) (xy 403.801586 -297.968733) (xy 403.847896 -297.992329) (xy 403.889944 -298.022879)
			(xy 403.926695 -298.05963) (xy 403.957245 -298.101678) (xy 403.980841 -298.147988) (xy 403.996902 -298.197418)
			(xy 404.005032 -298.248753) (xy 404.005542 -298.27474) (xy 404.005032 -298.300727) (xy 404.294596 -298.300727)
			(xy 404.294596 -298.248753) (xy 404.302726 -298.197418) (xy 404.318787 -298.147988) (xy 404.342383 -298.101678)
			(xy 404.372933 -298.05963) (xy 404.409684 -298.022879) (xy 404.451732 -297.992329) (xy 404.498042 -297.968733)
			(xy 404.547472 -297.952672) (xy 404.598807 -297.944542) (xy 404.650781 -297.944542) (xy 404.702116 -297.952672)
			(xy 404.751546 -297.968733) (xy 404.797856 -297.992329) (xy 404.839904 -298.022879) (xy 404.876655 -298.05963)
			(xy 404.907205 -298.101678) (xy 404.930801 -298.147988) (xy 404.946862 -298.197418) (xy 404.954992 -298.248753)
			(xy 404.955502 -298.27474) (xy 404.954992 -298.300727) (xy 405.24481 -298.300727) (xy 405.24481 -298.248753)
			(xy 405.25294 -298.197418) (xy 405.269001 -298.147988) (xy 405.292597 -298.101678) (xy 405.323147 -298.05963)
			(xy 405.359898 -298.022879) (xy 405.401946 -297.992329) (xy 405.448256 -297.968733) (xy 405.497686 -297.952672)
			(xy 405.549021 -297.944542) (xy 405.600995 -297.944542) (xy 405.65233 -297.952672) (xy 405.70176 -297.968733)
			(xy 405.74807 -297.992329) (xy 405.790118 -298.022879) (xy 405.826869 -298.05963) (xy 405.857419 -298.101678)
			(xy 405.881015 -298.147988) (xy 405.897076 -298.197418) (xy 405.905206 -298.248753) (xy 405.905716 -298.27474)
			(xy 405.905206 -298.300727) (xy 406.19477 -298.300727) (xy 406.19477 -298.248753) (xy 406.2029 -298.197418)
			(xy 406.218961 -298.147988) (xy 406.242557 -298.101678) (xy 406.273107 -298.05963) (xy 406.309858 -298.022879)
			(xy 406.351906 -297.992329) (xy 406.398216 -297.968733) (xy 406.447646 -297.952672) (xy 406.498981 -297.944542)
			(xy 406.550955 -297.944542) (xy 406.60229 -297.952672) (xy 406.65172 -297.968733) (xy 406.69803 -297.992329)
			(xy 406.740078 -298.022879) (xy 406.776829 -298.05963) (xy 406.807379 -298.101678) (xy 406.830975 -298.147988)
			(xy 406.847036 -298.197418) (xy 406.855166 -298.248753) (xy 406.855676 -298.27474) (xy 406.855166 -298.300727)
			(xy 408.09469 -298.300727) (xy 408.09469 -298.248753) (xy 408.10282 -298.197418) (xy 408.118881 -298.147988)
			(xy 408.142477 -298.101678) (xy 408.173027 -298.05963) (xy 408.209778 -298.022879) (xy 408.251826 -297.992329)
			(xy 408.298136 -297.968733) (xy 408.347566 -297.952672) (xy 408.398901 -297.944542) (xy 408.450875 -297.944542)
			(xy 408.50221 -297.952672) (xy 408.55164 -297.968733) (xy 408.59795 -297.992329) (xy 408.639998 -298.022879)
			(xy 408.676749 -298.05963) (xy 408.707299 -298.101678) (xy 408.730895 -298.147988) (xy 408.746956 -298.197418)
			(xy 408.755086 -298.248753) (xy 408.755596 -298.27474) (xy 408.755086 -298.300727) (xy 409.04465 -298.300727)
			(xy 409.04465 -298.248753) (xy 409.05278 -298.197418) (xy 409.068841 -298.147988) (xy 409.092437 -298.101678)
			(xy 409.122987 -298.05963) (xy 409.159738 -298.022879) (xy 409.201786 -297.992329) (xy 409.248096 -297.968733)
			(xy 409.297526 -297.952672) (xy 409.348861 -297.944542) (xy 409.400835 -297.944542) (xy 409.45217 -297.952672)
			(xy 409.5016 -297.968733) (xy 409.54791 -297.992329) (xy 409.589958 -298.022879) (xy 409.626709 -298.05963)
			(xy 409.657259 -298.101678) (xy 409.680855 -298.147988) (xy 409.696916 -298.197418) (xy 409.705046 -298.248753)
			(xy 409.705556 -298.27474) (xy 409.705046 -298.300727) (xy 409.99461 -298.300727) (xy 409.99461 -298.248753)
			(xy 410.00274 -298.197418) (xy 410.018801 -298.147988) (xy 410.042397 -298.101678) (xy 410.072947 -298.05963)
			(xy 410.109698 -298.022879) (xy 410.151746 -297.992329) (xy 410.198056 -297.968733) (xy 410.247486 -297.952672)
			(xy 410.298821 -297.944542) (xy 410.350795 -297.944542) (xy 410.40213 -297.952672) (xy 410.45156 -297.968733)
			(xy 410.49787 -297.992329) (xy 410.539918 -298.022879) (xy 410.576669 -298.05963) (xy 410.607219 -298.101678)
			(xy 410.630815 -298.147988) (xy 410.646876 -298.197418) (xy 410.655006 -298.248753) (xy 410.655516 -298.27474)
			(xy 410.655006 -298.300727) (xy 410.944824 -298.300727) (xy 410.944824 -298.248753) (xy 410.952954 -298.197418)
			(xy 410.969015 -298.147988) (xy 410.992611 -298.101678) (xy 411.023161 -298.05963) (xy 411.059912 -298.022879)
			(xy 411.10196 -297.992329) (xy 411.14827 -297.968733) (xy 411.1977 -297.952672) (xy 411.249035 -297.944542)
			(xy 411.301009 -297.944542) (xy 411.352344 -297.952672) (xy 411.401774 -297.968733) (xy 411.448084 -297.992329)
			(xy 411.490132 -298.022879) (xy 411.526883 -298.05963) (xy 411.557433 -298.101678) (xy 411.581029 -298.147988)
			(xy 411.59709 -298.197418) (xy 411.60522 -298.248753) (xy 411.60573 -298.27474) (xy 411.60522 -298.300727)
			(xy 411.894784 -298.300727) (xy 411.894784 -298.248753) (xy 411.902914 -298.197418) (xy 411.918975 -298.147988)
			(xy 411.942571 -298.101678) (xy 411.973121 -298.05963) (xy 412.009872 -298.022879) (xy 412.05192 -297.992329)
			(xy 412.09823 -297.968733) (xy 412.14766 -297.952672) (xy 412.198995 -297.944542) (xy 412.250969 -297.944542)
			(xy 412.302304 -297.952672) (xy 412.351734 -297.968733) (xy 412.398044 -297.992329) (xy 412.440092 -298.022879)
			(xy 412.476843 -298.05963) (xy 412.507393 -298.101678) (xy 412.530989 -298.147988) (xy 412.54705 -298.197418)
			(xy 412.55518 -298.248753) (xy 412.55569 -298.27474) (xy 412.55518 -298.300727) (xy 412.844744 -298.300727)
			(xy 412.844744 -298.248753) (xy 412.852874 -298.197418) (xy 412.868935 -298.147988) (xy 412.892531 -298.101678)
			(xy 412.923081 -298.05963) (xy 412.959832 -298.022879) (xy 413.00188 -297.992329) (xy 413.04819 -297.968733)
			(xy 413.09762 -297.952672) (xy 413.148955 -297.944542) (xy 413.200929 -297.944542) (xy 413.252264 -297.952672)
			(xy 413.301694 -297.968733) (xy 413.348004 -297.992329) (xy 413.390052 -298.022879) (xy 413.426803 -298.05963)
			(xy 413.457353 -298.101678) (xy 413.480949 -298.147988) (xy 413.49701 -298.197418) (xy 413.50514 -298.248753)
			(xy 413.50565 -298.27474) (xy 413.50514 -298.300727) (xy 413.794704 -298.300727) (xy 413.794704 -298.248753)
			(xy 413.802834 -298.197418) (xy 413.818895 -298.147988) (xy 413.842491 -298.101678) (xy 413.873041 -298.05963)
			(xy 413.909792 -298.022879) (xy 413.95184 -297.992329) (xy 413.99815 -297.968733) (xy 414.04758 -297.952672)
			(xy 414.098915 -297.944542) (xy 414.150889 -297.944542) (xy 414.202224 -297.952672) (xy 414.251654 -297.968733)
			(xy 414.297964 -297.992329) (xy 414.340012 -298.022879) (xy 414.376763 -298.05963) (xy 414.407313 -298.101678)
			(xy 414.430909 -298.147988) (xy 414.44697 -298.197418) (xy 414.4551 -298.248753) (xy 414.45561 -298.27474)
			(xy 414.4551 -298.300727) (xy 414.744664 -298.300727) (xy 414.744664 -298.248753) (xy 414.752794 -298.197418)
			(xy 414.768855 -298.147988) (xy 414.792451 -298.101678) (xy 414.823001 -298.05963) (xy 414.859752 -298.022879)
			(xy 414.9018 -297.992329) (xy 414.94811 -297.968733) (xy 414.99754 -297.952672) (xy 415.048875 -297.944542)
			(xy 415.100849 -297.944542) (xy 415.152184 -297.952672) (xy 415.201614 -297.968733) (xy 415.247924 -297.992329)
			(xy 415.289972 -298.022879) (xy 415.326723 -298.05963) (xy 415.357273 -298.101678) (xy 415.380869 -298.147988)
			(xy 415.39693 -298.197418) (xy 415.40506 -298.248753) (xy 415.40557 -298.27474) (xy 415.40506 -298.300727)
			(xy 415.694624 -298.300727) (xy 415.694624 -298.248753) (xy 415.702754 -298.197418) (xy 415.718815 -298.147988)
			(xy 415.742411 -298.101678) (xy 415.772961 -298.05963) (xy 415.809712 -298.022879) (xy 415.85176 -297.992329)
			(xy 415.89807 -297.968733) (xy 415.9475 -297.952672) (xy 415.998835 -297.944542) (xy 416.050809 -297.944542)
			(xy 416.102144 -297.952672) (xy 416.151574 -297.968733) (xy 416.197884 -297.992329) (xy 416.239932 -298.022879)
			(xy 416.276683 -298.05963) (xy 416.307233 -298.101678) (xy 416.330829 -298.147988) (xy 416.34689 -298.197418)
			(xy 416.35502 -298.248753) (xy 416.35553 -298.27474) (xy 416.35502 -298.300727) (xy 416.34689 -298.352062)
			(xy 416.330829 -298.401492) (xy 416.307233 -298.447802) (xy 416.276683 -298.48985) (xy 416.239932 -298.526601)
			(xy 416.197884 -298.557151) (xy 416.151574 -298.580747) (xy 416.102144 -298.596808) (xy 416.050809 -298.604938)
			(xy 415.998835 -298.604938) (xy 415.9475 -298.596808) (xy 415.89807 -298.580747) (xy 415.85176 -298.557151)
			(xy 415.809712 -298.526601) (xy 415.772961 -298.48985) (xy 415.742411 -298.447802) (xy 415.718815 -298.401492)
			(xy 415.702754 -298.352062) (xy 415.694624 -298.300727) (xy 415.40506 -298.300727) (xy 415.39693 -298.352062)
			(xy 415.380869 -298.401492) (xy 415.357273 -298.447802) (xy 415.326723 -298.48985) (xy 415.289972 -298.526601)
			(xy 415.247924 -298.557151) (xy 415.201614 -298.580747) (xy 415.152184 -298.596808) (xy 415.100849 -298.604938)
			(xy 415.048875 -298.604938) (xy 414.99754 -298.596808) (xy 414.94811 -298.580747) (xy 414.9018 -298.557151)
			(xy 414.859752 -298.526601) (xy 414.823001 -298.48985) (xy 414.792451 -298.447802) (xy 414.768855 -298.401492)
			(xy 414.752794 -298.352062) (xy 414.744664 -298.300727) (xy 414.4551 -298.300727) (xy 414.44697 -298.352062)
			(xy 414.430909 -298.401492) (xy 414.407313 -298.447802) (xy 414.376763 -298.48985) (xy 414.340012 -298.526601)
			(xy 414.297964 -298.557151) (xy 414.251654 -298.580747) (xy 414.202224 -298.596808) (xy 414.150889 -298.604938)
			(xy 414.098915 -298.604938) (xy 414.04758 -298.596808) (xy 413.99815 -298.580747) (xy 413.95184 -298.557151)
			(xy 413.909792 -298.526601) (xy 413.873041 -298.48985) (xy 413.842491 -298.447802) (xy 413.818895 -298.401492)
			(xy 413.802834 -298.352062) (xy 413.794704 -298.300727) (xy 413.50514 -298.300727) (xy 413.49701 -298.352062)
			(xy 413.480949 -298.401492) (xy 413.457353 -298.447802) (xy 413.426803 -298.48985) (xy 413.390052 -298.526601)
			(xy 413.348004 -298.557151) (xy 413.301694 -298.580747) (xy 413.252264 -298.596808) (xy 413.200929 -298.604938)
			(xy 413.148955 -298.604938) (xy 413.09762 -298.596808) (xy 413.04819 -298.580747) (xy 413.00188 -298.557151)
			(xy 412.959832 -298.526601) (xy 412.923081 -298.48985) (xy 412.892531 -298.447802) (xy 412.868935 -298.401492)
			(xy 412.852874 -298.352062) (xy 412.844744 -298.300727) (xy 412.55518 -298.300727) (xy 412.54705 -298.352062)
			(xy 412.530989 -298.401492) (xy 412.507393 -298.447802) (xy 412.476843 -298.48985) (xy 412.440092 -298.526601)
			(xy 412.398044 -298.557151) (xy 412.351734 -298.580747) (xy 412.302304 -298.596808) (xy 412.250969 -298.604938)
			(xy 412.198995 -298.604938) (xy 412.14766 -298.596808) (xy 412.09823 -298.580747) (xy 412.05192 -298.557151)
			(xy 412.009872 -298.526601) (xy 411.973121 -298.48985) (xy 411.942571 -298.447802) (xy 411.918975 -298.401492)
			(xy 411.902914 -298.352062) (xy 411.894784 -298.300727) (xy 411.60522 -298.300727) (xy 411.59709 -298.352062)
			(xy 411.581029 -298.401492) (xy 411.557433 -298.447802) (xy 411.526883 -298.48985) (xy 411.490132 -298.526601)
			(xy 411.448084 -298.557151) (xy 411.401774 -298.580747) (xy 411.352344 -298.596808) (xy 411.301009 -298.604938)
			(xy 411.249035 -298.604938) (xy 411.1977 -298.596808) (xy 411.14827 -298.580747) (xy 411.10196 -298.557151)
			(xy 411.059912 -298.526601) (xy 411.023161 -298.48985) (xy 410.992611 -298.447802) (xy 410.969015 -298.401492)
			(xy 410.952954 -298.352062) (xy 410.944824 -298.300727) (xy 410.655006 -298.300727) (xy 410.646876 -298.352062)
			(xy 410.630815 -298.401492) (xy 410.607219 -298.447802) (xy 410.576669 -298.48985) (xy 410.539918 -298.526601)
			(xy 410.49787 -298.557151) (xy 410.45156 -298.580747) (xy 410.40213 -298.596808) (xy 410.350795 -298.604938)
			(xy 410.298821 -298.604938) (xy 410.247486 -298.596808) (xy 410.198056 -298.580747) (xy 410.151746 -298.557151)
			(xy 410.109698 -298.526601) (xy 410.072947 -298.48985) (xy 410.042397 -298.447802) (xy 410.018801 -298.401492)
			(xy 410.00274 -298.352062) (xy 409.99461 -298.300727) (xy 409.705046 -298.300727) (xy 409.696916 -298.352062)
			(xy 409.680855 -298.401492) (xy 409.657259 -298.447802) (xy 409.626709 -298.48985) (xy 409.589958 -298.526601)
			(xy 409.54791 -298.557151) (xy 409.5016 -298.580747) (xy 409.45217 -298.596808) (xy 409.400835 -298.604938)
			(xy 409.348861 -298.604938) (xy 409.297526 -298.596808) (xy 409.248096 -298.580747) (xy 409.201786 -298.557151)
			(xy 409.159738 -298.526601) (xy 409.122987 -298.48985) (xy 409.092437 -298.447802) (xy 409.068841 -298.401492)
			(xy 409.05278 -298.352062) (xy 409.04465 -298.300727) (xy 408.755086 -298.300727) (xy 408.746956 -298.352062)
			(xy 408.730895 -298.401492) (xy 408.707299 -298.447802) (xy 408.676749 -298.48985) (xy 408.639998 -298.526601)
			(xy 408.59795 -298.557151) (xy 408.55164 -298.580747) (xy 408.50221 -298.596808) (xy 408.450875 -298.604938)
			(xy 408.398901 -298.604938) (xy 408.347566 -298.596808) (xy 408.298136 -298.580747) (xy 408.251826 -298.557151)
			(xy 408.209778 -298.526601) (xy 408.173027 -298.48985) (xy 408.142477 -298.447802) (xy 408.118881 -298.401492)
			(xy 408.10282 -298.352062) (xy 408.09469 -298.300727) (xy 406.855166 -298.300727) (xy 406.847036 -298.352062)
			(xy 406.830975 -298.401492) (xy 406.807379 -298.447802) (xy 406.776829 -298.48985) (xy 406.740078 -298.526601)
			(xy 406.69803 -298.557151) (xy 406.65172 -298.580747) (xy 406.60229 -298.596808) (xy 406.550955 -298.604938)
			(xy 406.498981 -298.604938) (xy 406.447646 -298.596808) (xy 406.398216 -298.580747) (xy 406.351906 -298.557151)
			(xy 406.309858 -298.526601) (xy 406.273107 -298.48985) (xy 406.242557 -298.447802) (xy 406.218961 -298.401492)
			(xy 406.2029 -298.352062) (xy 406.19477 -298.300727) (xy 405.905206 -298.300727) (xy 405.897076 -298.352062)
			(xy 405.881015 -298.401492) (xy 405.857419 -298.447802) (xy 405.826869 -298.48985) (xy 405.790118 -298.526601)
			(xy 405.74807 -298.557151) (xy 405.70176 -298.580747) (xy 405.65233 -298.596808) (xy 405.600995 -298.604938)
			(xy 405.549021 -298.604938) (xy 405.497686 -298.596808) (xy 405.448256 -298.580747) (xy 405.401946 -298.557151)
			(xy 405.359898 -298.526601) (xy 405.323147 -298.48985) (xy 405.292597 -298.447802) (xy 405.269001 -298.401492)
			(xy 405.25294 -298.352062) (xy 405.24481 -298.300727) (xy 404.954992 -298.300727) (xy 404.946862 -298.352062)
			(xy 404.930801 -298.401492) (xy 404.907205 -298.447802) (xy 404.876655 -298.48985) (xy 404.839904 -298.526601)
			(xy 404.797856 -298.557151) (xy 404.751546 -298.580747) (xy 404.702116 -298.596808) (xy 404.650781 -298.604938)
			(xy 404.598807 -298.604938) (xy 404.547472 -298.596808) (xy 404.498042 -298.580747) (xy 404.451732 -298.557151)
			(xy 404.409684 -298.526601) (xy 404.372933 -298.48985) (xy 404.342383 -298.447802) (xy 404.318787 -298.401492)
			(xy 404.302726 -298.352062) (xy 404.294596 -298.300727) (xy 404.005032 -298.300727) (xy 403.996902 -298.352062)
			(xy 403.980841 -298.401492) (xy 403.957245 -298.447802) (xy 403.926695 -298.48985) (xy 403.889944 -298.526601)
			(xy 403.847896 -298.557151) (xy 403.801586 -298.580747) (xy 403.752156 -298.596808) (xy 403.700821 -298.604938)
			(xy 403.648847 -298.604938) (xy 403.597512 -298.596808) (xy 403.548082 -298.580747) (xy 403.501772 -298.557151)
			(xy 403.459724 -298.526601) (xy 403.422973 -298.48985) (xy 403.392423 -298.447802) (xy 403.368827 -298.401492)
			(xy 403.352766 -298.352062) (xy 403.344636 -298.300727) (xy 403.055072 -298.300727) (xy 403.046942 -298.352062)
			(xy 403.030881 -298.401492) (xy 403.007285 -298.447802) (xy 402.976735 -298.48985) (xy 402.939984 -298.526601)
			(xy 402.897936 -298.557151) (xy 402.851626 -298.580747) (xy 402.802196 -298.596808) (xy 402.750861 -298.604938)
			(xy 402.698887 -298.604938) (xy 402.647552 -298.596808) (xy 402.598122 -298.580747) (xy 402.551812 -298.557151)
			(xy 402.509764 -298.526601) (xy 402.473013 -298.48985) (xy 402.442463 -298.447802) (xy 402.418867 -298.401492)
			(xy 402.402806 -298.352062) (xy 402.394676 -298.300727) (xy 402.105112 -298.300727) (xy 402.096982 -298.352062)
			(xy 402.080921 -298.401492) (xy 402.057325 -298.447802) (xy 402.026775 -298.48985) (xy 401.990024 -298.526601)
			(xy 401.947976 -298.557151) (xy 401.901666 -298.580747) (xy 401.852236 -298.596808) (xy 401.800901 -298.604938)
			(xy 401.748927 -298.604938) (xy 401.697592 -298.596808) (xy 401.648162 -298.580747) (xy 401.601852 -298.557151)
			(xy 401.559804 -298.526601) (xy 401.523053 -298.48985) (xy 401.492503 -298.447802) (xy 401.468907 -298.401492)
			(xy 401.452846 -298.352062) (xy 401.444716 -298.300727) (xy 401.155152 -298.300727) (xy 401.147022 -298.352062)
			(xy 401.130961 -298.401492) (xy 401.107365 -298.447802) (xy 401.076815 -298.48985) (xy 401.040064 -298.526601)
			(xy 400.998016 -298.557151) (xy 400.951706 -298.580747) (xy 400.902276 -298.596808) (xy 400.850941 -298.604938)
			(xy 400.798967 -298.604938) (xy 400.747632 -298.596808) (xy 400.698202 -298.580747) (xy 400.651892 -298.557151)
			(xy 400.609844 -298.526601) (xy 400.573093 -298.48985) (xy 400.542543 -298.447802) (xy 400.518947 -298.401492)
			(xy 400.502886 -298.352062) (xy 400.494756 -298.300727) (xy 400.205192 -298.300727) (xy 400.197062 -298.352062)
			(xy 400.181001 -298.401492) (xy 400.157405 -298.447802) (xy 400.126855 -298.48985) (xy 400.090104 -298.526601)
			(xy 400.048056 -298.557151) (xy 400.001746 -298.580747) (xy 399.952316 -298.596808) (xy 399.900981 -298.604938)
			(xy 399.849007 -298.604938) (xy 399.797672 -298.596808) (xy 399.748242 -298.580747) (xy 399.701932 -298.557151)
			(xy 399.659884 -298.526601) (xy 399.623133 -298.48985) (xy 399.592583 -298.447802) (xy 399.568987 -298.401492)
			(xy 399.552926 -298.352062) (xy 399.544796 -298.300727) (xy 399.255232 -298.300727) (xy 399.247102 -298.352062)
			(xy 399.231041 -298.401492) (xy 399.207445 -298.447802) (xy 399.176895 -298.48985) (xy 399.140144 -298.526601)
			(xy 399.098096 -298.557151) (xy 399.051786 -298.580747) (xy 399.002356 -298.596808) (xy 398.951021 -298.604938)
			(xy 398.899047 -298.604938) (xy 398.847712 -298.596808) (xy 398.798282 -298.580747) (xy 398.751972 -298.557151)
			(xy 398.709924 -298.526601) (xy 398.673173 -298.48985) (xy 398.642623 -298.447802) (xy 398.619027 -298.401492)
			(xy 398.602966 -298.352062) (xy 398.594836 -298.300727) (xy 398.305018 -298.300727) (xy 398.296888 -298.352062)
			(xy 398.280827 -298.401492) (xy 398.257231 -298.447802) (xy 398.226681 -298.48985) (xy 398.18993 -298.526601)
			(xy 398.147882 -298.557151) (xy 398.101572 -298.580747) (xy 398.052142 -298.596808) (xy 398.000807 -298.604938)
			(xy 397.948833 -298.604938) (xy 397.897498 -298.596808) (xy 397.848068 -298.580747) (xy 397.801758 -298.557151)
			(xy 397.75971 -298.526601) (xy 397.722959 -298.48985) (xy 397.692409 -298.447802) (xy 397.668813 -298.401492)
			(xy 397.652752 -298.352062) (xy 397.644622 -298.300727) (xy 397.355058 -298.300727) (xy 397.346928 -298.352062)
			(xy 397.330867 -298.401492) (xy 397.307271 -298.447802) (xy 397.276721 -298.48985) (xy 397.23997 -298.526601)
			(xy 397.197922 -298.557151) (xy 397.151612 -298.580747) (xy 397.102182 -298.596808) (xy 397.050847 -298.604938)
			(xy 396.998873 -298.604938) (xy 396.947538 -298.596808) (xy 396.898108 -298.580747) (xy 396.851798 -298.557151)
			(xy 396.80975 -298.526601) (xy 396.772999 -298.48985) (xy 396.742449 -298.447802) (xy 396.718853 -298.401492)
			(xy 396.702792 -298.352062) (xy 396.694662 -298.300727) (xy 396.405098 -298.300727) (xy 396.396968 -298.352062)
			(xy 396.380907 -298.401492) (xy 396.357311 -298.447802) (xy 396.326761 -298.48985) (xy 396.29001 -298.526601)
			(xy 396.247962 -298.557151) (xy 396.201652 -298.580747) (xy 396.152222 -298.596808) (xy 396.100887 -298.604938)
			(xy 396.048913 -298.604938) (xy 395.997578 -298.596808) (xy 395.948148 -298.580747) (xy 395.901838 -298.557151)
			(xy 395.85979 -298.526601) (xy 395.823039 -298.48985) (xy 395.792489 -298.447802) (xy 395.768893 -298.401492)
			(xy 395.752832 -298.352062) (xy 395.744702 -298.300727) (xy 395.455138 -298.300727) (xy 395.447008 -298.352062)
			(xy 395.430947 -298.401492) (xy 395.407351 -298.447802) (xy 395.376801 -298.48985) (xy 395.34005 -298.526601)
			(xy 395.298002 -298.557151) (xy 395.251692 -298.580747) (xy 395.202262 -298.596808) (xy 395.150927 -298.604938)
			(xy 395.098953 -298.604938) (xy 395.047618 -298.596808) (xy 394.998188 -298.580747) (xy 394.951878 -298.557151)
			(xy 394.90983 -298.526601) (xy 394.873079 -298.48985) (xy 394.842529 -298.447802) (xy 394.818933 -298.401492)
			(xy 394.802872 -298.352062) (xy 394.794742 -298.300727) (xy 394.504104 -298.300727) (xy 394.501994 -298.327184)
			(xy 394.489547 -298.378333) (xy 394.469153 -298.426863) (xy 394.441327 -298.471549) (xy 394.406772 -298.511262)
			(xy 394.366361 -298.544998) (xy 394.321115 -298.571904) (xy 394.272177 -298.591301) (xy 394.246608 -298.597574)
			(xy 394.229082 -298.601384) (xy 394.20673 -298.629324) (xy 394.20673 -298.87037) (xy 394.229082 -298.89831)
			(xy 394.246608 -298.90212) (xy 394.272201 -298.908318) (xy 394.321151 -298.92772) (xy 394.366408 -298.954633)
			(xy 394.40683 -298.988377) (xy 394.441394 -299.0281) (xy 394.469227 -299.072797) (xy 394.489627 -299.12134)
			(xy 394.502077 -299.172502) (xy 394.506263 -299.22499) (xy 394.504195 -299.250941) (xy 394.794742 -299.250941)
			(xy 394.794742 -299.198967) (xy 394.802872 -299.147632) (xy 394.818933 -299.098202) (xy 394.842529 -299.051892)
			(xy 394.873079 -299.009844) (xy 394.90983 -298.973093) (xy 394.951878 -298.942543) (xy 394.998188 -298.918947)
			(xy 395.047618 -298.902886) (xy 395.098953 -298.894756) (xy 395.150927 -298.894756) (xy 395.202262 -298.902886)
			(xy 395.251692 -298.918947) (xy 395.298002 -298.942543) (xy 395.34005 -298.973093) (xy 395.376801 -299.009844)
			(xy 395.407351 -299.051892) (xy 395.430947 -299.098202) (xy 395.447008 -299.147632) (xy 395.455138 -299.198967)
			(xy 395.455648 -299.224954) (xy 395.455138 -299.250941) (xy 395.744702 -299.250941) (xy 395.744702 -299.198967)
			(xy 395.752832 -299.147632) (xy 395.768893 -299.098202) (xy 395.792489 -299.051892) (xy 395.823039 -299.009844)
			(xy 395.85979 -298.973093) (xy 395.901838 -298.942543) (xy 395.948148 -298.918947) (xy 395.997578 -298.902886)
			(xy 396.048913 -298.894756) (xy 396.100887 -298.894756) (xy 396.152222 -298.902886) (xy 396.201652 -298.918947)
			(xy 396.247962 -298.942543) (xy 396.29001 -298.973093) (xy 396.326761 -299.009844) (xy 396.357311 -299.051892)
			(xy 396.380907 -299.098202) (xy 396.396968 -299.147632) (xy 396.405098 -299.198967) (xy 396.405608 -299.224954)
			(xy 396.405098 -299.250941) (xy 396.694662 -299.250941) (xy 396.694662 -299.198967) (xy 396.702792 -299.147632)
			(xy 396.718853 -299.098202) (xy 396.742449 -299.051892) (xy 396.772999 -299.009844) (xy 396.80975 -298.973093)
			(xy 396.851798 -298.942543) (xy 396.898108 -298.918947) (xy 396.947538 -298.902886) (xy 396.998873 -298.894756)
			(xy 397.050847 -298.894756) (xy 397.102182 -298.902886) (xy 397.151612 -298.918947) (xy 397.197922 -298.942543)
			(xy 397.23997 -298.973093) (xy 397.276721 -299.009844) (xy 397.307271 -299.051892) (xy 397.330867 -299.098202)
			(xy 397.346928 -299.147632) (xy 397.355058 -299.198967) (xy 397.355568 -299.224954) (xy 397.355058 -299.250941)
			(xy 397.644622 -299.250941) (xy 397.644622 -299.198967) (xy 397.652752 -299.147632) (xy 397.668813 -299.098202)
			(xy 397.692409 -299.051892) (xy 397.722959 -299.009844) (xy 397.75971 -298.973093) (xy 397.801758 -298.942543)
			(xy 397.848068 -298.918947) (xy 397.897498 -298.902886) (xy 397.948833 -298.894756) (xy 398.000807 -298.894756)
			(xy 398.052142 -298.902886) (xy 398.101572 -298.918947) (xy 398.147882 -298.942543) (xy 398.18993 -298.973093)
			(xy 398.226681 -299.009844) (xy 398.257231 -299.051892) (xy 398.280827 -299.098202) (xy 398.296888 -299.147632)
			(xy 398.305018 -299.198967) (xy 398.305528 -299.224954) (xy 398.305018 -299.250941) (xy 398.594836 -299.250941)
			(xy 398.594836 -299.198967) (xy 398.602966 -299.147632) (xy 398.619027 -299.098202) (xy 398.642623 -299.051892)
			(xy 398.673173 -299.009844) (xy 398.709924 -298.973093) (xy 398.751972 -298.942543) (xy 398.798282 -298.918947)
			(xy 398.847712 -298.902886) (xy 398.899047 -298.894756) (xy 398.951021 -298.894756) (xy 399.002356 -298.902886)
			(xy 399.051786 -298.918947) (xy 399.098096 -298.942543) (xy 399.140144 -298.973093) (xy 399.176895 -299.009844)
			(xy 399.207445 -299.051892) (xy 399.231041 -299.098202) (xy 399.247102 -299.147632) (xy 399.255232 -299.198967)
			(xy 399.255742 -299.224954) (xy 399.255232 -299.250941) (xy 399.544796 -299.250941) (xy 399.544796 -299.198967)
			(xy 399.552926 -299.147632) (xy 399.568987 -299.098202) (xy 399.592583 -299.051892) (xy 399.623133 -299.009844)
			(xy 399.659884 -298.973093) (xy 399.701932 -298.942543) (xy 399.748242 -298.918947) (xy 399.797672 -298.902886)
			(xy 399.849007 -298.894756) (xy 399.900981 -298.894756) (xy 399.952316 -298.902886) (xy 400.001746 -298.918947)
			(xy 400.048056 -298.942543) (xy 400.090104 -298.973093) (xy 400.126855 -299.009844) (xy 400.157405 -299.051892)
			(xy 400.181001 -299.098202) (xy 400.197062 -299.147632) (xy 400.205192 -299.198967) (xy 400.205702 -299.224954)
			(xy 400.205192 -299.250941) (xy 400.494756 -299.250941) (xy 400.494756 -299.198967) (xy 400.502886 -299.147632)
			(xy 400.518947 -299.098202) (xy 400.542543 -299.051892) (xy 400.573093 -299.009844) (xy 400.609844 -298.973093)
			(xy 400.651892 -298.942543) (xy 400.698202 -298.918947) (xy 400.747632 -298.902886) (xy 400.798967 -298.894756)
			(xy 400.850941 -298.894756) (xy 400.902276 -298.902886) (xy 400.951706 -298.918947) (xy 400.998016 -298.942543)
			(xy 401.040064 -298.973093) (xy 401.076815 -299.009844) (xy 401.107365 -299.051892) (xy 401.130961 -299.098202)
			(xy 401.147022 -299.147632) (xy 401.155152 -299.198967) (xy 401.155662 -299.224954) (xy 401.155152 -299.250941)
			(xy 401.444716 -299.250941) (xy 401.444716 -299.198967) (xy 401.452846 -299.147632) (xy 401.468907 -299.098202)
			(xy 401.492503 -299.051892) (xy 401.523053 -299.009844) (xy 401.559804 -298.973093) (xy 401.601852 -298.942543)
			(xy 401.648162 -298.918947) (xy 401.697592 -298.902886) (xy 401.748927 -298.894756) (xy 401.800901 -298.894756)
			(xy 401.852236 -298.902886) (xy 401.901666 -298.918947) (xy 401.947976 -298.942543) (xy 401.990024 -298.973093)
			(xy 402.026775 -299.009844) (xy 402.057325 -299.051892) (xy 402.080921 -299.098202) (xy 402.096982 -299.147632)
			(xy 402.105112 -299.198967) (xy 402.105622 -299.224954) (xy 402.105112 -299.250941) (xy 402.394676 -299.250941)
			(xy 402.394676 -299.198967) (xy 402.402806 -299.147632) (xy 402.418867 -299.098202) (xy 402.442463 -299.051892)
			(xy 402.473013 -299.009844) (xy 402.509764 -298.973093) (xy 402.551812 -298.942543) (xy 402.598122 -298.918947)
			(xy 402.647552 -298.902886) (xy 402.698887 -298.894756) (xy 402.750861 -298.894756) (xy 402.802196 -298.902886)
			(xy 402.851626 -298.918947) (xy 402.897936 -298.942543) (xy 402.939984 -298.973093) (xy 402.976735 -299.009844)
			(xy 403.007285 -299.051892) (xy 403.030881 -299.098202) (xy 403.046942 -299.147632) (xy 403.055072 -299.198967)
			(xy 403.055582 -299.224954) (xy 403.055072 -299.250941) (xy 403.344636 -299.250941) (xy 403.344636 -299.198967)
			(xy 403.352766 -299.147632) (xy 403.368827 -299.098202) (xy 403.392423 -299.051892) (xy 403.422973 -299.009844)
			(xy 403.459724 -298.973093) (xy 403.501772 -298.942543) (xy 403.548082 -298.918947) (xy 403.597512 -298.902886)
			(xy 403.648847 -298.894756) (xy 403.700821 -298.894756) (xy 403.752156 -298.902886) (xy 403.801586 -298.918947)
			(xy 403.847896 -298.942543) (xy 403.889944 -298.973093) (xy 403.926695 -299.009844) (xy 403.957245 -299.051892)
			(xy 403.980841 -299.098202) (xy 403.996902 -299.147632) (xy 404.005032 -299.198967) (xy 404.005542 -299.224954)
			(xy 404.005032 -299.250941) (xy 404.294596 -299.250941) (xy 404.294596 -299.198967) (xy 404.302726 -299.147632)
			(xy 404.318787 -299.098202) (xy 404.342383 -299.051892) (xy 404.372933 -299.009844) (xy 404.409684 -298.973093)
			(xy 404.451732 -298.942543) (xy 404.498042 -298.918947) (xy 404.547472 -298.902886) (xy 404.598807 -298.894756)
			(xy 404.650781 -298.894756) (xy 404.702116 -298.902886) (xy 404.751546 -298.918947) (xy 404.797856 -298.942543)
			(xy 404.839904 -298.973093) (xy 404.876655 -299.009844) (xy 404.907205 -299.051892) (xy 404.930801 -299.098202)
			(xy 404.946862 -299.147632) (xy 404.954992 -299.198967) (xy 404.955502 -299.224954) (xy 404.954992 -299.250941)
			(xy 405.24481 -299.250941) (xy 405.24481 -299.198967) (xy 405.25294 -299.147632) (xy 405.269001 -299.098202)
			(xy 405.292597 -299.051892) (xy 405.323147 -299.009844) (xy 405.359898 -298.973093) (xy 405.401946 -298.942543)
			(xy 405.448256 -298.918947) (xy 405.497686 -298.902886) (xy 405.549021 -298.894756) (xy 405.600995 -298.894756)
			(xy 405.65233 -298.902886) (xy 405.70176 -298.918947) (xy 405.74807 -298.942543) (xy 405.790118 -298.973093)
			(xy 405.826869 -299.009844) (xy 405.857419 -299.051892) (xy 405.881015 -299.098202) (xy 405.897076 -299.147632)
			(xy 405.905206 -299.198967) (xy 405.905716 -299.224954) (xy 405.905206 -299.250941) (xy 406.19477 -299.250941)
			(xy 406.19477 -299.198967) (xy 406.2029 -299.147632) (xy 406.218961 -299.098202) (xy 406.242557 -299.051892)
			(xy 406.273107 -299.009844) (xy 406.309858 -298.973093) (xy 406.351906 -298.942543) (xy 406.398216 -298.918947)
			(xy 406.447646 -298.902886) (xy 406.498981 -298.894756) (xy 406.550955 -298.894756) (xy 406.60229 -298.902886)
			(xy 406.65172 -298.918947) (xy 406.69803 -298.942543) (xy 406.740078 -298.973093) (xy 406.776829 -299.009844)
			(xy 406.807379 -299.051892) (xy 406.830975 -299.098202) (xy 406.847036 -299.147632) (xy 406.855166 -299.198967)
			(xy 406.855676 -299.224954) (xy 406.855166 -299.250941) (xy 408.09469 -299.250941) (xy 408.09469 -299.198967)
			(xy 408.10282 -299.147632) (xy 408.118881 -299.098202) (xy 408.142477 -299.051892) (xy 408.173027 -299.009844)
			(xy 408.209778 -298.973093) (xy 408.251826 -298.942543) (xy 408.298136 -298.918947) (xy 408.347566 -298.902886)
			(xy 408.398901 -298.894756) (xy 408.450875 -298.894756) (xy 408.50221 -298.902886) (xy 408.55164 -298.918947)
			(xy 408.59795 -298.942543) (xy 408.639998 -298.973093) (xy 408.676749 -299.009844) (xy 408.707299 -299.051892)
			(xy 408.730895 -299.098202) (xy 408.746956 -299.147632) (xy 408.755086 -299.198967) (xy 408.755596 -299.224954)
			(xy 408.755086 -299.250941) (xy 409.04465 -299.250941) (xy 409.04465 -299.198967) (xy 409.05278 -299.147632)
			(xy 409.068841 -299.098202) (xy 409.092437 -299.051892) (xy 409.122987 -299.009844) (xy 409.159738 -298.973093)
			(xy 409.201786 -298.942543) (xy 409.248096 -298.918947) (xy 409.297526 -298.902886) (xy 409.348861 -298.894756)
			(xy 409.400835 -298.894756) (xy 409.45217 -298.902886) (xy 409.5016 -298.918947) (xy 409.54791 -298.942543)
			(xy 409.589958 -298.973093) (xy 409.626709 -299.009844) (xy 409.657259 -299.051892) (xy 409.680855 -299.098202)
			(xy 409.696916 -299.147632) (xy 409.705046 -299.198967) (xy 409.705556 -299.224954) (xy 409.705046 -299.250941)
			(xy 409.99461 -299.250941) (xy 409.99461 -299.198967) (xy 410.00274 -299.147632) (xy 410.018801 -299.098202)
			(xy 410.042397 -299.051892) (xy 410.072947 -299.009844) (xy 410.109698 -298.973093) (xy 410.151746 -298.942543)
			(xy 410.198056 -298.918947) (xy 410.247486 -298.902886) (xy 410.298821 -298.894756) (xy 410.350795 -298.894756)
			(xy 410.40213 -298.902886) (xy 410.45156 -298.918947) (xy 410.49787 -298.942543) (xy 410.539918 -298.973093)
			(xy 410.576669 -299.009844) (xy 410.607219 -299.051892) (xy 410.630815 -299.098202) (xy 410.646876 -299.147632)
			(xy 410.655006 -299.198967) (xy 410.655516 -299.224954) (xy 410.655006 -299.250941) (xy 410.944824 -299.250941)
			(xy 410.944824 -299.198967) (xy 410.952954 -299.147632) (xy 410.969015 -299.098202) (xy 410.992611 -299.051892)
			(xy 411.023161 -299.009844) (xy 411.059912 -298.973093) (xy 411.10196 -298.942543) (xy 411.14827 -298.918947)
			(xy 411.1977 -298.902886) (xy 411.249035 -298.894756) (xy 411.301009 -298.894756) (xy 411.352344 -298.902886)
			(xy 411.401774 -298.918947) (xy 411.448084 -298.942543) (xy 411.490132 -298.973093) (xy 411.526883 -299.009844)
			(xy 411.557433 -299.051892) (xy 411.581029 -299.098202) (xy 411.59709 -299.147632) (xy 411.60522 -299.198967)
			(xy 411.60573 -299.224954) (xy 411.60522 -299.250941) (xy 411.894784 -299.250941) (xy 411.894784 -299.198967)
			(xy 411.902914 -299.147632) (xy 411.918975 -299.098202) (xy 411.942571 -299.051892) (xy 411.973121 -299.009844)
			(xy 412.009872 -298.973093) (xy 412.05192 -298.942543) (xy 412.09823 -298.918947) (xy 412.14766 -298.902886)
			(xy 412.198995 -298.894756) (xy 412.250969 -298.894756) (xy 412.302304 -298.902886) (xy 412.351734 -298.918947)
			(xy 412.398044 -298.942543) (xy 412.440092 -298.973093) (xy 412.476843 -299.009844) (xy 412.507393 -299.051892)
			(xy 412.530989 -299.098202) (xy 412.54705 -299.147632) (xy 412.55518 -299.198967) (xy 412.55569 -299.224954)
			(xy 412.55518 -299.250941) (xy 412.844744 -299.250941) (xy 412.844744 -299.198967) (xy 412.852874 -299.147632)
			(xy 412.868935 -299.098202) (xy 412.892531 -299.051892) (xy 412.923081 -299.009844) (xy 412.959832 -298.973093)
			(xy 413.00188 -298.942543) (xy 413.04819 -298.918947) (xy 413.09762 -298.902886) (xy 413.148955 -298.894756)
			(xy 413.200929 -298.894756) (xy 413.252264 -298.902886) (xy 413.301694 -298.918947) (xy 413.348004 -298.942543)
			(xy 413.390052 -298.973093) (xy 413.426803 -299.009844) (xy 413.457353 -299.051892) (xy 413.480949 -299.098202)
			(xy 413.49701 -299.147632) (xy 413.50514 -299.198967) (xy 413.50565 -299.224954) (xy 413.50514 -299.250941)
			(xy 413.794704 -299.250941) (xy 413.794704 -299.198967) (xy 413.802834 -299.147632) (xy 413.818895 -299.098202)
			(xy 413.842491 -299.051892) (xy 413.873041 -299.009844) (xy 413.909792 -298.973093) (xy 413.95184 -298.942543)
			(xy 413.99815 -298.918947) (xy 414.04758 -298.902886) (xy 414.098915 -298.894756) (xy 414.150889 -298.894756)
			(xy 414.202224 -298.902886) (xy 414.251654 -298.918947) (xy 414.297964 -298.942543) (xy 414.340012 -298.973093)
			(xy 414.376763 -299.009844) (xy 414.407313 -299.051892) (xy 414.430909 -299.098202) (xy 414.44697 -299.147632)
			(xy 414.4551 -299.198967) (xy 414.45561 -299.224954) (xy 414.4551 -299.250941) (xy 414.744664 -299.250941)
			(xy 414.744664 -299.198967) (xy 414.752794 -299.147632) (xy 414.768855 -299.098202) (xy 414.792451 -299.051892)
			(xy 414.823001 -299.009844) (xy 414.859752 -298.973093) (xy 414.9018 -298.942543) (xy 414.94811 -298.918947)
			(xy 414.99754 -298.902886) (xy 415.048875 -298.894756) (xy 415.100849 -298.894756) (xy 415.152184 -298.902886)
			(xy 415.201614 -298.918947) (xy 415.247924 -298.942543) (xy 415.289972 -298.973093) (xy 415.326723 -299.009844)
			(xy 415.357273 -299.051892) (xy 415.380869 -299.098202) (xy 415.39693 -299.147632) (xy 415.40506 -299.198967)
			(xy 415.40557 -299.224954) (xy 415.40506 -299.250941) (xy 415.694624 -299.250941) (xy 415.694624 -299.198967)
			(xy 415.702754 -299.147632) (xy 415.718815 -299.098202) (xy 415.742411 -299.051892) (xy 415.772961 -299.009844)
			(xy 415.809712 -298.973093) (xy 415.85176 -298.942543) (xy 415.89807 -298.918947) (xy 415.9475 -298.902886)
			(xy 415.998835 -298.894756) (xy 416.050809 -298.894756) (xy 416.102144 -298.902886) (xy 416.151574 -298.918947)
			(xy 416.197884 -298.942543) (xy 416.239932 -298.973093) (xy 416.276683 -299.009844) (xy 416.307233 -299.051892)
			(xy 416.330829 -299.098202) (xy 416.34689 -299.147632) (xy 416.35502 -299.198967) (xy 416.35553 -299.224954)
			(xy 416.35502 -299.250941) (xy 416.34689 -299.302276) (xy 416.330829 -299.351706) (xy 416.307233 -299.398016)
			(xy 416.276683 -299.440064) (xy 416.239932 -299.476815) (xy 416.197884 -299.507365) (xy 416.151574 -299.530961)
			(xy 416.102144 -299.547022) (xy 416.050809 -299.555152) (xy 415.998835 -299.555152) (xy 415.9475 -299.547022)
			(xy 415.89807 -299.530961) (xy 415.85176 -299.507365) (xy 415.809712 -299.476815) (xy 415.772961 -299.440064)
			(xy 415.742411 -299.398016) (xy 415.718815 -299.351706) (xy 415.702754 -299.302276) (xy 415.694624 -299.250941)
			(xy 415.40506 -299.250941) (xy 415.39693 -299.302276) (xy 415.380869 -299.351706) (xy 415.357273 -299.398016)
			(xy 415.326723 -299.440064) (xy 415.289972 -299.476815) (xy 415.247924 -299.507365) (xy 415.201614 -299.530961)
			(xy 415.152184 -299.547022) (xy 415.100849 -299.555152) (xy 415.048875 -299.555152) (xy 414.99754 -299.547022)
			(xy 414.94811 -299.530961) (xy 414.9018 -299.507365) (xy 414.859752 -299.476815) (xy 414.823001 -299.440064)
			(xy 414.792451 -299.398016) (xy 414.768855 -299.351706) (xy 414.752794 -299.302276) (xy 414.744664 -299.250941)
			(xy 414.4551 -299.250941) (xy 414.44697 -299.302276) (xy 414.430909 -299.351706) (xy 414.407313 -299.398016)
			(xy 414.376763 -299.440064) (xy 414.340012 -299.476815) (xy 414.297964 -299.507365) (xy 414.251654 -299.530961)
			(xy 414.202224 -299.547022) (xy 414.150889 -299.555152) (xy 414.098915 -299.555152) (xy 414.04758 -299.547022)
			(xy 413.99815 -299.530961) (xy 413.95184 -299.507365) (xy 413.909792 -299.476815) (xy 413.873041 -299.440064)
			(xy 413.842491 -299.398016) (xy 413.818895 -299.351706) (xy 413.802834 -299.302276) (xy 413.794704 -299.250941)
			(xy 413.50514 -299.250941) (xy 413.49701 -299.302276) (xy 413.480949 -299.351706) (xy 413.457353 -299.398016)
			(xy 413.426803 -299.440064) (xy 413.390052 -299.476815) (xy 413.348004 -299.507365) (xy 413.301694 -299.530961)
			(xy 413.252264 -299.547022) (xy 413.200929 -299.555152) (xy 413.148955 -299.555152) (xy 413.09762 -299.547022)
			(xy 413.04819 -299.530961) (xy 413.00188 -299.507365) (xy 412.959832 -299.476815) (xy 412.923081 -299.440064)
			(xy 412.892531 -299.398016) (xy 412.868935 -299.351706) (xy 412.852874 -299.302276) (xy 412.844744 -299.250941)
			(xy 412.55518 -299.250941) (xy 412.54705 -299.302276) (xy 412.530989 -299.351706) (xy 412.507393 -299.398016)
			(xy 412.476843 -299.440064) (xy 412.440092 -299.476815) (xy 412.398044 -299.507365) (xy 412.351734 -299.530961)
			(xy 412.302304 -299.547022) (xy 412.250969 -299.555152) (xy 412.198995 -299.555152) (xy 412.14766 -299.547022)
			(xy 412.09823 -299.530961) (xy 412.05192 -299.507365) (xy 412.009872 -299.476815) (xy 411.973121 -299.440064)
			(xy 411.942571 -299.398016) (xy 411.918975 -299.351706) (xy 411.902914 -299.302276) (xy 411.894784 -299.250941)
			(xy 411.60522 -299.250941) (xy 411.59709 -299.302276) (xy 411.581029 -299.351706) (xy 411.557433 -299.398016)
			(xy 411.526883 -299.440064) (xy 411.490132 -299.476815) (xy 411.448084 -299.507365) (xy 411.401774 -299.530961)
			(xy 411.352344 -299.547022) (xy 411.301009 -299.555152) (xy 411.249035 -299.555152) (xy 411.1977 -299.547022)
			(xy 411.14827 -299.530961) (xy 411.10196 -299.507365) (xy 411.059912 -299.476815) (xy 411.023161 -299.440064)
			(xy 410.992611 -299.398016) (xy 410.969015 -299.351706) (xy 410.952954 -299.302276) (xy 410.944824 -299.250941)
			(xy 410.655006 -299.250941) (xy 410.646876 -299.302276) (xy 410.630815 -299.351706) (xy 410.607219 -299.398016)
			(xy 410.576669 -299.440064) (xy 410.539918 -299.476815) (xy 410.49787 -299.507365) (xy 410.45156 -299.530961)
			(xy 410.40213 -299.547022) (xy 410.350795 -299.555152) (xy 410.298821 -299.555152) (xy 410.247486 -299.547022)
			(xy 410.198056 -299.530961) (xy 410.151746 -299.507365) (xy 410.109698 -299.476815) (xy 410.072947 -299.440064)
			(xy 410.042397 -299.398016) (xy 410.018801 -299.351706) (xy 410.00274 -299.302276) (xy 409.99461 -299.250941)
			(xy 409.705046 -299.250941) (xy 409.696916 -299.302276) (xy 409.680855 -299.351706) (xy 409.657259 -299.398016)
			(xy 409.626709 -299.440064) (xy 409.589958 -299.476815) (xy 409.54791 -299.507365) (xy 409.5016 -299.530961)
			(xy 409.45217 -299.547022) (xy 409.400835 -299.555152) (xy 409.348861 -299.555152) (xy 409.297526 -299.547022)
			(xy 409.248096 -299.530961) (xy 409.201786 -299.507365) (xy 409.159738 -299.476815) (xy 409.122987 -299.440064)
			(xy 409.092437 -299.398016) (xy 409.068841 -299.351706) (xy 409.05278 -299.302276) (xy 409.04465 -299.250941)
			(xy 408.755086 -299.250941) (xy 408.746956 -299.302276) (xy 408.730895 -299.351706) (xy 408.707299 -299.398016)
			(xy 408.676749 -299.440064) (xy 408.639998 -299.476815) (xy 408.59795 -299.507365) (xy 408.55164 -299.530961)
			(xy 408.50221 -299.547022) (xy 408.450875 -299.555152) (xy 408.398901 -299.555152) (xy 408.347566 -299.547022)
			(xy 408.298136 -299.530961) (xy 408.251826 -299.507365) (xy 408.209778 -299.476815) (xy 408.173027 -299.440064)
			(xy 408.142477 -299.398016) (xy 408.118881 -299.351706) (xy 408.10282 -299.302276) (xy 408.09469 -299.250941)
			(xy 406.855166 -299.250941) (xy 406.847036 -299.302276) (xy 406.830975 -299.351706) (xy 406.807379 -299.398016)
			(xy 406.776829 -299.440064) (xy 406.740078 -299.476815) (xy 406.69803 -299.507365) (xy 406.65172 -299.530961)
			(xy 406.60229 -299.547022) (xy 406.550955 -299.555152) (xy 406.498981 -299.555152) (xy 406.447646 -299.547022)
			(xy 406.398216 -299.530961) (xy 406.351906 -299.507365) (xy 406.309858 -299.476815) (xy 406.273107 -299.440064)
			(xy 406.242557 -299.398016) (xy 406.218961 -299.351706) (xy 406.2029 -299.302276) (xy 406.19477 -299.250941)
			(xy 405.905206 -299.250941) (xy 405.897076 -299.302276) (xy 405.881015 -299.351706) (xy 405.857419 -299.398016)
			(xy 405.826869 -299.440064) (xy 405.790118 -299.476815) (xy 405.74807 -299.507365) (xy 405.70176 -299.530961)
			(xy 405.65233 -299.547022) (xy 405.600995 -299.555152) (xy 405.549021 -299.555152) (xy 405.497686 -299.547022)
			(xy 405.448256 -299.530961) (xy 405.401946 -299.507365) (xy 405.359898 -299.476815) (xy 405.323147 -299.440064)
			(xy 405.292597 -299.398016) (xy 405.269001 -299.351706) (xy 405.25294 -299.302276) (xy 405.24481 -299.250941)
			(xy 404.954992 -299.250941) (xy 404.946862 -299.302276) (xy 404.930801 -299.351706) (xy 404.907205 -299.398016)
			(xy 404.876655 -299.440064) (xy 404.839904 -299.476815) (xy 404.797856 -299.507365) (xy 404.751546 -299.530961)
			(xy 404.702116 -299.547022) (xy 404.650781 -299.555152) (xy 404.598807 -299.555152) (xy 404.547472 -299.547022)
			(xy 404.498042 -299.530961) (xy 404.451732 -299.507365) (xy 404.409684 -299.476815) (xy 404.372933 -299.440064)
			(xy 404.342383 -299.398016) (xy 404.318787 -299.351706) (xy 404.302726 -299.302276) (xy 404.294596 -299.250941)
			(xy 404.005032 -299.250941) (xy 403.996902 -299.302276) (xy 403.980841 -299.351706) (xy 403.957245 -299.398016)
			(xy 403.926695 -299.440064) (xy 403.889944 -299.476815) (xy 403.847896 -299.507365) (xy 403.801586 -299.530961)
			(xy 403.752156 -299.547022) (xy 403.700821 -299.555152) (xy 403.648847 -299.555152) (xy 403.597512 -299.547022)
			(xy 403.548082 -299.530961) (xy 403.501772 -299.507365) (xy 403.459724 -299.476815) (xy 403.422973 -299.440064)
			(xy 403.392423 -299.398016) (xy 403.368827 -299.351706) (xy 403.352766 -299.302276) (xy 403.344636 -299.250941)
			(xy 403.055072 -299.250941) (xy 403.046942 -299.302276) (xy 403.030881 -299.351706) (xy 403.007285 -299.398016)
			(xy 402.976735 -299.440064) (xy 402.939984 -299.476815) (xy 402.897936 -299.507365) (xy 402.851626 -299.530961)
			(xy 402.802196 -299.547022) (xy 402.750861 -299.555152) (xy 402.698887 -299.555152) (xy 402.647552 -299.547022)
			(xy 402.598122 -299.530961) (xy 402.551812 -299.507365) (xy 402.509764 -299.476815) (xy 402.473013 -299.440064)
			(xy 402.442463 -299.398016) (xy 402.418867 -299.351706) (xy 402.402806 -299.302276) (xy 402.394676 -299.250941)
			(xy 402.105112 -299.250941) (xy 402.096982 -299.302276) (xy 402.080921 -299.351706) (xy 402.057325 -299.398016)
			(xy 402.026775 -299.440064) (xy 401.990024 -299.476815) (xy 401.947976 -299.507365) (xy 401.901666 -299.530961)
			(xy 401.852236 -299.547022) (xy 401.800901 -299.555152) (xy 401.748927 -299.555152) (xy 401.697592 -299.547022)
			(xy 401.648162 -299.530961) (xy 401.601852 -299.507365) (xy 401.559804 -299.476815) (xy 401.523053 -299.440064)
			(xy 401.492503 -299.398016) (xy 401.468907 -299.351706) (xy 401.452846 -299.302276) (xy 401.444716 -299.250941)
			(xy 401.155152 -299.250941) (xy 401.147022 -299.302276) (xy 401.130961 -299.351706) (xy 401.107365 -299.398016)
			(xy 401.076815 -299.440064) (xy 401.040064 -299.476815) (xy 400.998016 -299.507365) (xy 400.951706 -299.530961)
			(xy 400.902276 -299.547022) (xy 400.850941 -299.555152) (xy 400.798967 -299.555152) (xy 400.747632 -299.547022)
			(xy 400.698202 -299.530961) (xy 400.651892 -299.507365) (xy 400.609844 -299.476815) (xy 400.573093 -299.440064)
			(xy 400.542543 -299.398016) (xy 400.518947 -299.351706) (xy 400.502886 -299.302276) (xy 400.494756 -299.250941)
			(xy 400.205192 -299.250941) (xy 400.197062 -299.302276) (xy 400.181001 -299.351706) (xy 400.157405 -299.398016)
			(xy 400.126855 -299.440064) (xy 400.090104 -299.476815) (xy 400.048056 -299.507365) (xy 400.001746 -299.530961)
			(xy 399.952316 -299.547022) (xy 399.900981 -299.555152) (xy 399.849007 -299.555152) (xy 399.797672 -299.547022)
			(xy 399.748242 -299.530961) (xy 399.701932 -299.507365) (xy 399.659884 -299.476815) (xy 399.623133 -299.440064)
			(xy 399.592583 -299.398016) (xy 399.568987 -299.351706) (xy 399.552926 -299.302276) (xy 399.544796 -299.250941)
			(xy 399.255232 -299.250941) (xy 399.247102 -299.302276) (xy 399.231041 -299.351706) (xy 399.207445 -299.398016)
			(xy 399.176895 -299.440064) (xy 399.140144 -299.476815) (xy 399.098096 -299.507365) (xy 399.051786 -299.530961)
			(xy 399.002356 -299.547022) (xy 398.951021 -299.555152) (xy 398.899047 -299.555152) (xy 398.847712 -299.547022)
			(xy 398.798282 -299.530961) (xy 398.751972 -299.507365) (xy 398.709924 -299.476815) (xy 398.673173 -299.440064)
			(xy 398.642623 -299.398016) (xy 398.619027 -299.351706) (xy 398.602966 -299.302276) (xy 398.594836 -299.250941)
			(xy 398.305018 -299.250941) (xy 398.296888 -299.302276) (xy 398.280827 -299.351706) (xy 398.257231 -299.398016)
			(xy 398.226681 -299.440064) (xy 398.18993 -299.476815) (xy 398.147882 -299.507365) (xy 398.101572 -299.530961)
			(xy 398.052142 -299.547022) (xy 398.000807 -299.555152) (xy 397.948833 -299.555152) (xy 397.897498 -299.547022)
			(xy 397.848068 -299.530961) (xy 397.801758 -299.507365) (xy 397.75971 -299.476815) (xy 397.722959 -299.440064)
			(xy 397.692409 -299.398016) (xy 397.668813 -299.351706) (xy 397.652752 -299.302276) (xy 397.644622 -299.250941)
			(xy 397.355058 -299.250941) (xy 397.346928 -299.302276) (xy 397.330867 -299.351706) (xy 397.307271 -299.398016)
			(xy 397.276721 -299.440064) (xy 397.23997 -299.476815) (xy 397.197922 -299.507365) (xy 397.151612 -299.530961)
			(xy 397.102182 -299.547022) (xy 397.050847 -299.555152) (xy 396.998873 -299.555152) (xy 396.947538 -299.547022)
			(xy 396.898108 -299.530961) (xy 396.851798 -299.507365) (xy 396.80975 -299.476815) (xy 396.772999 -299.440064)
			(xy 396.742449 -299.398016) (xy 396.718853 -299.351706) (xy 396.702792 -299.302276) (xy 396.694662 -299.250941)
			(xy 396.405098 -299.250941) (xy 396.396968 -299.302276) (xy 396.380907 -299.351706) (xy 396.357311 -299.398016)
			(xy 396.326761 -299.440064) (xy 396.29001 -299.476815) (xy 396.247962 -299.507365) (xy 396.201652 -299.530961)
			(xy 396.152222 -299.547022) (xy 396.100887 -299.555152) (xy 396.048913 -299.555152) (xy 395.997578 -299.547022)
			(xy 395.948148 -299.530961) (xy 395.901838 -299.507365) (xy 395.85979 -299.476815) (xy 395.823039 -299.440064)
			(xy 395.792489 -299.398016) (xy 395.768893 -299.351706) (xy 395.752832 -299.302276) (xy 395.744702 -299.250941)
			(xy 395.455138 -299.250941) (xy 395.447008 -299.302276) (xy 395.430947 -299.351706) (xy 395.407351 -299.398016)
			(xy 395.376801 -299.440064) (xy 395.34005 -299.476815) (xy 395.298002 -299.507365) (xy 395.251692 -299.530961)
			(xy 395.202262 -299.547022) (xy 395.150927 -299.555152) (xy 395.098953 -299.555152) (xy 395.047618 -299.547022)
			(xy 394.998188 -299.530961) (xy 394.951878 -299.507365) (xy 394.90983 -299.476815) (xy 394.873079 -299.440064)
			(xy 394.842529 -299.398016) (xy 394.818933 -299.351706) (xy 394.802872 -299.302276) (xy 394.794742 -299.250941)
			(xy 394.504195 -299.250941) (xy 394.50208 -299.277479) (xy 394.489633 -299.328641) (xy 394.469236 -299.377185)
			(xy 394.441406 -299.421884) (xy 394.406844 -299.461609) (xy 394.366424 -299.495355) (xy 394.321169 -299.522271)
			(xy 394.27222 -299.541676) (xy 394.246608 -299.547788) (xy 394.229082 -299.551598) (xy 394.20673 -299.579538)
			(xy 394.20673 -299.82033) (xy 394.229082 -299.84827) (xy 394.246608 -299.85208) (xy 394.272196 -299.858278)
			(xy 394.321137 -299.877678) (xy 394.366385 -299.904588) (xy 394.406798 -299.938328) (xy 394.441354 -299.978045)
			(xy 394.469181 -300.022735) (xy 394.489575 -300.07127) (xy 394.502021 -300.122424) (xy 394.506205 -300.174903)
			(xy 394.504132 -300.200901) (xy 394.794742 -300.200901) (xy 394.794742 -300.148927) (xy 394.802872 -300.097592)
			(xy 394.818933 -300.048162) (xy 394.842529 -300.001852) (xy 394.873079 -299.959804) (xy 394.90983 -299.923053)
			(xy 394.951878 -299.892503) (xy 394.998188 -299.868907) (xy 395.047618 -299.852846) (xy 395.098953 -299.844716)
			(xy 395.150927 -299.844716) (xy 395.202262 -299.852846) (xy 395.251692 -299.868907) (xy 395.298002 -299.892503)
			(xy 395.34005 -299.923053) (xy 395.376801 -299.959804) (xy 395.407351 -300.001852) (xy 395.430947 -300.048162)
			(xy 395.447008 -300.097592) (xy 395.455138 -300.148927) (xy 395.455648 -300.174914) (xy 395.455138 -300.200901)
			(xy 395.744702 -300.200901) (xy 395.744702 -300.148927) (xy 395.752832 -300.097592) (xy 395.768893 -300.048162)
			(xy 395.792489 -300.001852) (xy 395.823039 -299.959804) (xy 395.85979 -299.923053) (xy 395.901838 -299.892503)
			(xy 395.948148 -299.868907) (xy 395.997578 -299.852846) (xy 396.048913 -299.844716) (xy 396.100887 -299.844716)
			(xy 396.152222 -299.852846) (xy 396.201652 -299.868907) (xy 396.247962 -299.892503) (xy 396.29001 -299.923053)
			(xy 396.326761 -299.959804) (xy 396.357311 -300.001852) (xy 396.380907 -300.048162) (xy 396.396968 -300.097592)
			(xy 396.405098 -300.148927) (xy 396.405608 -300.174914) (xy 396.405098 -300.200901) (xy 396.694662 -300.200901)
			(xy 396.694662 -300.148927) (xy 396.702792 -300.097592) (xy 396.718853 -300.048162) (xy 396.742449 -300.001852)
			(xy 396.772999 -299.959804) (xy 396.80975 -299.923053) (xy 396.851798 -299.892503) (xy 396.898108 -299.868907)
			(xy 396.947538 -299.852846) (xy 396.998873 -299.844716) (xy 397.050847 -299.844716) (xy 397.102182 -299.852846)
			(xy 397.151612 -299.868907) (xy 397.197922 -299.892503) (xy 397.23997 -299.923053) (xy 397.276721 -299.959804)
			(xy 397.307271 -300.001852) (xy 397.330867 -300.048162) (xy 397.346928 -300.097592) (xy 397.355058 -300.148927)
			(xy 397.355568 -300.174914) (xy 397.355058 -300.200901) (xy 397.644622 -300.200901) (xy 397.644622 -300.148927)
			(xy 397.652752 -300.097592) (xy 397.668813 -300.048162) (xy 397.692409 -300.001852) (xy 397.722959 -299.959804)
			(xy 397.75971 -299.923053) (xy 397.801758 -299.892503) (xy 397.848068 -299.868907) (xy 397.897498 -299.852846)
			(xy 397.948833 -299.844716) (xy 398.000807 -299.844716) (xy 398.052142 -299.852846) (xy 398.101572 -299.868907)
			(xy 398.147882 -299.892503) (xy 398.18993 -299.923053) (xy 398.226681 -299.959804) (xy 398.257231 -300.001852)
			(xy 398.280827 -300.048162) (xy 398.296888 -300.097592) (xy 398.305018 -300.148927) (xy 398.305528 -300.174914)
			(xy 398.305018 -300.200901) (xy 398.594836 -300.200901) (xy 398.594836 -300.148927) (xy 398.602966 -300.097592)
			(xy 398.619027 -300.048162) (xy 398.642623 -300.001852) (xy 398.673173 -299.959804) (xy 398.709924 -299.923053)
			(xy 398.751972 -299.892503) (xy 398.798282 -299.868907) (xy 398.847712 -299.852846) (xy 398.899047 -299.844716)
			(xy 398.951021 -299.844716) (xy 399.002356 -299.852846) (xy 399.051786 -299.868907) (xy 399.098096 -299.892503)
			(xy 399.140144 -299.923053) (xy 399.176895 -299.959804) (xy 399.207445 -300.001852) (xy 399.231041 -300.048162)
			(xy 399.247102 -300.097592) (xy 399.255232 -300.148927) (xy 399.255742 -300.174914) (xy 399.255232 -300.200901)
			(xy 399.544796 -300.200901) (xy 399.544796 -300.148927) (xy 399.552926 -300.097592) (xy 399.568987 -300.048162)
			(xy 399.592583 -300.001852) (xy 399.623133 -299.959804) (xy 399.659884 -299.923053) (xy 399.701932 -299.892503)
			(xy 399.748242 -299.868907) (xy 399.797672 -299.852846) (xy 399.849007 -299.844716) (xy 399.900981 -299.844716)
			(xy 399.952316 -299.852846) (xy 400.001746 -299.868907) (xy 400.048056 -299.892503) (xy 400.090104 -299.923053)
			(xy 400.126855 -299.959804) (xy 400.157405 -300.001852) (xy 400.181001 -300.048162) (xy 400.197062 -300.097592)
			(xy 400.205192 -300.148927) (xy 400.205702 -300.174914) (xy 400.205192 -300.200901) (xy 400.494756 -300.200901)
			(xy 400.494756 -300.148927) (xy 400.502886 -300.097592) (xy 400.518947 -300.048162) (xy 400.542543 -300.001852)
			(xy 400.573093 -299.959804) (xy 400.609844 -299.923053) (xy 400.651892 -299.892503) (xy 400.698202 -299.868907)
			(xy 400.747632 -299.852846) (xy 400.798967 -299.844716) (xy 400.850941 -299.844716) (xy 400.902276 -299.852846)
			(xy 400.951706 -299.868907) (xy 400.998016 -299.892503) (xy 401.040064 -299.923053) (xy 401.076815 -299.959804)
			(xy 401.107365 -300.001852) (xy 401.130961 -300.048162) (xy 401.147022 -300.097592) (xy 401.155152 -300.148927)
			(xy 401.155662 -300.174914) (xy 401.155152 -300.200901) (xy 401.444716 -300.200901) (xy 401.444716 -300.148927)
			(xy 401.452846 -300.097592) (xy 401.468907 -300.048162) (xy 401.492503 -300.001852) (xy 401.523053 -299.959804)
			(xy 401.559804 -299.923053) (xy 401.601852 -299.892503) (xy 401.648162 -299.868907) (xy 401.697592 -299.852846)
			(xy 401.748927 -299.844716) (xy 401.800901 -299.844716) (xy 401.852236 -299.852846) (xy 401.901666 -299.868907)
			(xy 401.947976 -299.892503) (xy 401.990024 -299.923053) (xy 402.026775 -299.959804) (xy 402.057325 -300.001852)
			(xy 402.080921 -300.048162) (xy 402.096982 -300.097592) (xy 402.105112 -300.148927) (xy 402.105622 -300.174914)
			(xy 402.105112 -300.200901) (xy 402.394676 -300.200901) (xy 402.394676 -300.148927) (xy 402.402806 -300.097592)
			(xy 402.418867 -300.048162) (xy 402.442463 -300.001852) (xy 402.473013 -299.959804) (xy 402.509764 -299.923053)
			(xy 402.551812 -299.892503) (xy 402.598122 -299.868907) (xy 402.647552 -299.852846) (xy 402.698887 -299.844716)
			(xy 402.750861 -299.844716) (xy 402.802196 -299.852846) (xy 402.851626 -299.868907) (xy 402.897936 -299.892503)
			(xy 402.939984 -299.923053) (xy 402.976735 -299.959804) (xy 403.007285 -300.001852) (xy 403.030881 -300.048162)
			(xy 403.046942 -300.097592) (xy 403.055072 -300.148927) (xy 403.055582 -300.174914) (xy 403.055072 -300.200901)
			(xy 403.344636 -300.200901) (xy 403.344636 -300.148927) (xy 403.352766 -300.097592) (xy 403.368827 -300.048162)
			(xy 403.392423 -300.001852) (xy 403.422973 -299.959804) (xy 403.459724 -299.923053) (xy 403.501772 -299.892503)
			(xy 403.548082 -299.868907) (xy 403.597512 -299.852846) (xy 403.648847 -299.844716) (xy 403.700821 -299.844716)
			(xy 403.752156 -299.852846) (xy 403.801586 -299.868907) (xy 403.847896 -299.892503) (xy 403.889944 -299.923053)
			(xy 403.926695 -299.959804) (xy 403.957245 -300.001852) (xy 403.980841 -300.048162) (xy 403.996902 -300.097592)
			(xy 404.005032 -300.148927) (xy 404.005542 -300.174914) (xy 404.005032 -300.200901) (xy 404.294596 -300.200901)
			(xy 404.294596 -300.148927) (xy 404.302726 -300.097592) (xy 404.318787 -300.048162) (xy 404.342383 -300.001852)
			(xy 404.372933 -299.959804) (xy 404.409684 -299.923053) (xy 404.451732 -299.892503) (xy 404.498042 -299.868907)
			(xy 404.547472 -299.852846) (xy 404.598807 -299.844716) (xy 404.650781 -299.844716) (xy 404.702116 -299.852846)
			(xy 404.751546 -299.868907) (xy 404.797856 -299.892503) (xy 404.839904 -299.923053) (xy 404.876655 -299.959804)
			(xy 404.907205 -300.001852) (xy 404.930801 -300.048162) (xy 404.946862 -300.097592) (xy 404.954992 -300.148927)
			(xy 404.955502 -300.174914) (xy 404.954992 -300.200901) (xy 405.24481 -300.200901) (xy 405.24481 -300.148927)
			(xy 405.25294 -300.097592) (xy 405.269001 -300.048162) (xy 405.292597 -300.001852) (xy 405.323147 -299.959804)
			(xy 405.359898 -299.923053) (xy 405.401946 -299.892503) (xy 405.448256 -299.868907) (xy 405.497686 -299.852846)
			(xy 405.549021 -299.844716) (xy 405.600995 -299.844716) (xy 405.65233 -299.852846) (xy 405.70176 -299.868907)
			(xy 405.74807 -299.892503) (xy 405.790118 -299.923053) (xy 405.826869 -299.959804) (xy 405.857419 -300.001852)
			(xy 405.881015 -300.048162) (xy 405.897076 -300.097592) (xy 405.905206 -300.148927) (xy 405.905716 -300.174914)
			(xy 405.905206 -300.200901) (xy 406.19477 -300.200901) (xy 406.19477 -300.148927) (xy 406.2029 -300.097592)
			(xy 406.218961 -300.048162) (xy 406.242557 -300.001852) (xy 406.273107 -299.959804) (xy 406.309858 -299.923053)
			(xy 406.351906 -299.892503) (xy 406.398216 -299.868907) (xy 406.447646 -299.852846) (xy 406.498981 -299.844716)
			(xy 406.550955 -299.844716) (xy 406.60229 -299.852846) (xy 406.65172 -299.868907) (xy 406.69803 -299.892503)
			(xy 406.740078 -299.923053) (xy 406.776829 -299.959804) (xy 406.807379 -300.001852) (xy 406.830975 -300.048162)
			(xy 406.847036 -300.097592) (xy 406.855166 -300.148927) (xy 406.855676 -300.174914) (xy 406.855166 -300.200901)
			(xy 408.09469 -300.200901) (xy 408.09469 -300.148927) (xy 408.10282 -300.097592) (xy 408.118881 -300.048162)
			(xy 408.142477 -300.001852) (xy 408.173027 -299.959804) (xy 408.209778 -299.923053) (xy 408.251826 -299.892503)
			(xy 408.298136 -299.868907) (xy 408.347566 -299.852846) (xy 408.398901 -299.844716) (xy 408.450875 -299.844716)
			(xy 408.50221 -299.852846) (xy 408.55164 -299.868907) (xy 408.59795 -299.892503) (xy 408.639998 -299.923053)
			(xy 408.676749 -299.959804) (xy 408.707299 -300.001852) (xy 408.730895 -300.048162) (xy 408.746956 -300.097592)
			(xy 408.755086 -300.148927) (xy 408.755596 -300.174914) (xy 408.755086 -300.200901) (xy 409.04465 -300.200901)
			(xy 409.04465 -300.148927) (xy 409.05278 -300.097592) (xy 409.068841 -300.048162) (xy 409.092437 -300.001852)
			(xy 409.122987 -299.959804) (xy 409.159738 -299.923053) (xy 409.201786 -299.892503) (xy 409.248096 -299.868907)
			(xy 409.297526 -299.852846) (xy 409.348861 -299.844716) (xy 409.400835 -299.844716) (xy 409.45217 -299.852846)
			(xy 409.5016 -299.868907) (xy 409.54791 -299.892503) (xy 409.589958 -299.923053) (xy 409.626709 -299.959804)
			(xy 409.657259 -300.001852) (xy 409.680855 -300.048162) (xy 409.696916 -300.097592) (xy 409.705046 -300.148927)
			(xy 409.705556 -300.174914) (xy 409.705046 -300.200901) (xy 409.99461 -300.200901) (xy 409.99461 -300.148927)
			(xy 410.00274 -300.097592) (xy 410.018801 -300.048162) (xy 410.042397 -300.001852) (xy 410.072947 -299.959804)
			(xy 410.109698 -299.923053) (xy 410.151746 -299.892503) (xy 410.198056 -299.868907) (xy 410.247486 -299.852846)
			(xy 410.298821 -299.844716) (xy 410.350795 -299.844716) (xy 410.40213 -299.852846) (xy 410.45156 -299.868907)
			(xy 410.49787 -299.892503) (xy 410.539918 -299.923053) (xy 410.576669 -299.959804) (xy 410.607219 -300.001852)
			(xy 410.630815 -300.048162) (xy 410.646876 -300.097592) (xy 410.655006 -300.148927) (xy 410.655516 -300.174914)
			(xy 410.655006 -300.200901) (xy 410.944824 -300.200901) (xy 410.944824 -300.148927) (xy 410.952954 -300.097592)
			(xy 410.969015 -300.048162) (xy 410.992611 -300.001852) (xy 411.023161 -299.959804) (xy 411.059912 -299.923053)
			(xy 411.10196 -299.892503) (xy 411.14827 -299.868907) (xy 411.1977 -299.852846) (xy 411.249035 -299.844716)
			(xy 411.301009 -299.844716) (xy 411.352344 -299.852846) (xy 411.401774 -299.868907) (xy 411.448084 -299.892503)
			(xy 411.490132 -299.923053) (xy 411.526883 -299.959804) (xy 411.557433 -300.001852) (xy 411.581029 -300.048162)
			(xy 411.59709 -300.097592) (xy 411.60522 -300.148927) (xy 411.60573 -300.174914) (xy 411.60522 -300.200901)
			(xy 411.894784 -300.200901) (xy 411.894784 -300.148927) (xy 411.902914 -300.097592) (xy 411.918975 -300.048162)
			(xy 411.942571 -300.001852) (xy 411.973121 -299.959804) (xy 412.009872 -299.923053) (xy 412.05192 -299.892503)
			(xy 412.09823 -299.868907) (xy 412.14766 -299.852846) (xy 412.198995 -299.844716) (xy 412.250969 -299.844716)
			(xy 412.302304 -299.852846) (xy 412.351734 -299.868907) (xy 412.398044 -299.892503) (xy 412.440092 -299.923053)
			(xy 412.476843 -299.959804) (xy 412.507393 -300.001852) (xy 412.530989 -300.048162) (xy 412.54705 -300.097592)
			(xy 412.55518 -300.148927) (xy 412.55569 -300.174914) (xy 412.55518 -300.200901) (xy 412.844744 -300.200901)
			(xy 412.844744 -300.148927) (xy 412.852874 -300.097592) (xy 412.868935 -300.048162) (xy 412.892531 -300.001852)
			(xy 412.923081 -299.959804) (xy 412.959832 -299.923053) (xy 413.00188 -299.892503) (xy 413.04819 -299.868907)
			(xy 413.09762 -299.852846) (xy 413.148955 -299.844716) (xy 413.200929 -299.844716) (xy 413.252264 -299.852846)
			(xy 413.301694 -299.868907) (xy 413.348004 -299.892503) (xy 413.390052 -299.923053) (xy 413.426803 -299.959804)
			(xy 413.457353 -300.001852) (xy 413.480949 -300.048162) (xy 413.49701 -300.097592) (xy 413.50514 -300.148927)
			(xy 413.50565 -300.174914) (xy 413.50514 -300.200901) (xy 413.794704 -300.200901) (xy 413.794704 -300.148927)
			(xy 413.802834 -300.097592) (xy 413.818895 -300.048162) (xy 413.842491 -300.001852) (xy 413.873041 -299.959804)
			(xy 413.909792 -299.923053) (xy 413.95184 -299.892503) (xy 413.99815 -299.868907) (xy 414.04758 -299.852846)
			(xy 414.098915 -299.844716) (xy 414.150889 -299.844716) (xy 414.202224 -299.852846) (xy 414.251654 -299.868907)
			(xy 414.297964 -299.892503) (xy 414.340012 -299.923053) (xy 414.376763 -299.959804) (xy 414.407313 -300.001852)
			(xy 414.430909 -300.048162) (xy 414.44697 -300.097592) (xy 414.4551 -300.148927) (xy 414.45561 -300.174914)
			(xy 414.4551 -300.200901) (xy 414.744664 -300.200901) (xy 414.744664 -300.148927) (xy 414.752794 -300.097592)
			(xy 414.768855 -300.048162) (xy 414.792451 -300.001852) (xy 414.823001 -299.959804) (xy 414.859752 -299.923053)
			(xy 414.9018 -299.892503) (xy 414.94811 -299.868907) (xy 414.99754 -299.852846) (xy 415.048875 -299.844716)
			(xy 415.100849 -299.844716) (xy 415.152184 -299.852846) (xy 415.201614 -299.868907) (xy 415.247924 -299.892503)
			(xy 415.289972 -299.923053) (xy 415.326723 -299.959804) (xy 415.357273 -300.001852) (xy 415.380869 -300.048162)
			(xy 415.39693 -300.097592) (xy 415.40506 -300.148927) (xy 415.40557 -300.174914) (xy 415.40506 -300.200901)
			(xy 415.694624 -300.200901) (xy 415.694624 -300.148927) (xy 415.702754 -300.097592) (xy 415.718815 -300.048162)
			(xy 415.742411 -300.001852) (xy 415.772961 -299.959804) (xy 415.809712 -299.923053) (xy 415.85176 -299.892503)
			(xy 415.89807 -299.868907) (xy 415.9475 -299.852846) (xy 415.998835 -299.844716) (xy 416.050809 -299.844716)
			(xy 416.102144 -299.852846) (xy 416.151574 -299.868907) (xy 416.197884 -299.892503) (xy 416.239932 -299.923053)
			(xy 416.276683 -299.959804) (xy 416.307233 -300.001852) (xy 416.330829 -300.048162) (xy 416.34689 -300.097592)
			(xy 416.35502 -300.148927) (xy 416.35553 -300.174914) (xy 416.35502 -300.200901) (xy 416.34689 -300.252236)
			(xy 416.330829 -300.301666) (xy 416.307233 -300.347976) (xy 416.276683 -300.390024) (xy 416.239932 -300.426775)
			(xy 416.197884 -300.457325) (xy 416.151574 -300.480921) (xy 416.102144 -300.496982) (xy 416.050809 -300.505112)
			(xy 415.998835 -300.505112) (xy 415.9475 -300.496982) (xy 415.89807 -300.480921) (xy 415.85176 -300.457325)
			(xy 415.809712 -300.426775) (xy 415.772961 -300.390024) (xy 415.742411 -300.347976) (xy 415.718815 -300.301666)
			(xy 415.702754 -300.252236) (xy 415.694624 -300.200901) (xy 415.40506 -300.200901) (xy 415.39693 -300.252236)
			(xy 415.380869 -300.301666) (xy 415.357273 -300.347976) (xy 415.326723 -300.390024) (xy 415.289972 -300.426775)
			(xy 415.247924 -300.457325) (xy 415.201614 -300.480921) (xy 415.152184 -300.496982) (xy 415.100849 -300.505112)
			(xy 415.048875 -300.505112) (xy 414.99754 -300.496982) (xy 414.94811 -300.480921) (xy 414.9018 -300.457325)
			(xy 414.859752 -300.426775) (xy 414.823001 -300.390024) (xy 414.792451 -300.347976) (xy 414.768855 -300.301666)
			(xy 414.752794 -300.252236) (xy 414.744664 -300.200901) (xy 414.4551 -300.200901) (xy 414.44697 -300.252236)
			(xy 414.430909 -300.301666) (xy 414.407313 -300.347976) (xy 414.376763 -300.390024) (xy 414.340012 -300.426775)
			(xy 414.297964 -300.457325) (xy 414.251654 -300.480921) (xy 414.202224 -300.496982) (xy 414.150889 -300.505112)
			(xy 414.098915 -300.505112) (xy 414.04758 -300.496982) (xy 413.99815 -300.480921) (xy 413.95184 -300.457325)
			(xy 413.909792 -300.426775) (xy 413.873041 -300.390024) (xy 413.842491 -300.347976) (xy 413.818895 -300.301666)
			(xy 413.802834 -300.252236) (xy 413.794704 -300.200901) (xy 413.50514 -300.200901) (xy 413.49701 -300.252236)
			(xy 413.480949 -300.301666) (xy 413.457353 -300.347976) (xy 413.426803 -300.390024) (xy 413.390052 -300.426775)
			(xy 413.348004 -300.457325) (xy 413.301694 -300.480921) (xy 413.252264 -300.496982) (xy 413.200929 -300.505112)
			(xy 413.148955 -300.505112) (xy 413.09762 -300.496982) (xy 413.04819 -300.480921) (xy 413.00188 -300.457325)
			(xy 412.959832 -300.426775) (xy 412.923081 -300.390024) (xy 412.892531 -300.347976) (xy 412.868935 -300.301666)
			(xy 412.852874 -300.252236) (xy 412.844744 -300.200901) (xy 412.55518 -300.200901) (xy 412.54705 -300.252236)
			(xy 412.530989 -300.301666) (xy 412.507393 -300.347976) (xy 412.476843 -300.390024) (xy 412.440092 -300.426775)
			(xy 412.398044 -300.457325) (xy 412.351734 -300.480921) (xy 412.302304 -300.496982) (xy 412.250969 -300.505112)
			(xy 412.198995 -300.505112) (xy 412.14766 -300.496982) (xy 412.09823 -300.480921) (xy 412.05192 -300.457325)
			(xy 412.009872 -300.426775) (xy 411.973121 -300.390024) (xy 411.942571 -300.347976) (xy 411.918975 -300.301666)
			(xy 411.902914 -300.252236) (xy 411.894784 -300.200901) (xy 411.60522 -300.200901) (xy 411.59709 -300.252236)
			(xy 411.581029 -300.301666) (xy 411.557433 -300.347976) (xy 411.526883 -300.390024) (xy 411.490132 -300.426775)
			(xy 411.448084 -300.457325) (xy 411.401774 -300.480921) (xy 411.352344 -300.496982) (xy 411.301009 -300.505112)
			(xy 411.249035 -300.505112) (xy 411.1977 -300.496982) (xy 411.14827 -300.480921) (xy 411.10196 -300.457325)
			(xy 411.059912 -300.426775) (xy 411.023161 -300.390024) (xy 410.992611 -300.347976) (xy 410.969015 -300.301666)
			(xy 410.952954 -300.252236) (xy 410.944824 -300.200901) (xy 410.655006 -300.200901) (xy 410.646876 -300.252236)
			(xy 410.630815 -300.301666) (xy 410.607219 -300.347976) (xy 410.576669 -300.390024) (xy 410.539918 -300.426775)
			(xy 410.49787 -300.457325) (xy 410.45156 -300.480921) (xy 410.40213 -300.496982) (xy 410.350795 -300.505112)
			(xy 410.298821 -300.505112) (xy 410.247486 -300.496982) (xy 410.198056 -300.480921) (xy 410.151746 -300.457325)
			(xy 410.109698 -300.426775) (xy 410.072947 -300.390024) (xy 410.042397 -300.347976) (xy 410.018801 -300.301666)
			(xy 410.00274 -300.252236) (xy 409.99461 -300.200901) (xy 409.705046 -300.200901) (xy 409.696916 -300.252236)
			(xy 409.680855 -300.301666) (xy 409.657259 -300.347976) (xy 409.626709 -300.390024) (xy 409.589958 -300.426775)
			(xy 409.54791 -300.457325) (xy 409.5016 -300.480921) (xy 409.45217 -300.496982) (xy 409.400835 -300.505112)
			(xy 409.348861 -300.505112) (xy 409.297526 -300.496982) (xy 409.248096 -300.480921) (xy 409.201786 -300.457325)
			(xy 409.159738 -300.426775) (xy 409.122987 -300.390024) (xy 409.092437 -300.347976) (xy 409.068841 -300.301666)
			(xy 409.05278 -300.252236) (xy 409.04465 -300.200901) (xy 408.755086 -300.200901) (xy 408.746956 -300.252236)
			(xy 408.730895 -300.301666) (xy 408.707299 -300.347976) (xy 408.676749 -300.390024) (xy 408.639998 -300.426775)
			(xy 408.59795 -300.457325) (xy 408.55164 -300.480921) (xy 408.50221 -300.496982) (xy 408.450875 -300.505112)
			(xy 408.398901 -300.505112) (xy 408.347566 -300.496982) (xy 408.298136 -300.480921) (xy 408.251826 -300.457325)
			(xy 408.209778 -300.426775) (xy 408.173027 -300.390024) (xy 408.142477 -300.347976) (xy 408.118881 -300.301666)
			(xy 408.10282 -300.252236) (xy 408.09469 -300.200901) (xy 406.855166 -300.200901) (xy 406.847036 -300.252236)
			(xy 406.830975 -300.301666) (xy 406.807379 -300.347976) (xy 406.776829 -300.390024) (xy 406.740078 -300.426775)
			(xy 406.69803 -300.457325) (xy 406.65172 -300.480921) (xy 406.60229 -300.496982) (xy 406.550955 -300.505112)
			(xy 406.498981 -300.505112) (xy 406.447646 -300.496982) (xy 406.398216 -300.480921) (xy 406.351906 -300.457325)
			(xy 406.309858 -300.426775) (xy 406.273107 -300.390024) (xy 406.242557 -300.347976) (xy 406.218961 -300.301666)
			(xy 406.2029 -300.252236) (xy 406.19477 -300.200901) (xy 405.905206 -300.200901) (xy 405.897076 -300.252236)
			(xy 405.881015 -300.301666) (xy 405.857419 -300.347976) (xy 405.826869 -300.390024) (xy 405.790118 -300.426775)
			(xy 405.74807 -300.457325) (xy 405.70176 -300.480921) (xy 405.65233 -300.496982) (xy 405.600995 -300.505112)
			(xy 405.549021 -300.505112) (xy 405.497686 -300.496982) (xy 405.448256 -300.480921) (xy 405.401946 -300.457325)
			(xy 405.359898 -300.426775) (xy 405.323147 -300.390024) (xy 405.292597 -300.347976) (xy 405.269001 -300.301666)
			(xy 405.25294 -300.252236) (xy 405.24481 -300.200901) (xy 404.954992 -300.200901) (xy 404.946862 -300.252236)
			(xy 404.930801 -300.301666) (xy 404.907205 -300.347976) (xy 404.876655 -300.390024) (xy 404.839904 -300.426775)
			(xy 404.797856 -300.457325) (xy 404.751546 -300.480921) (xy 404.702116 -300.496982) (xy 404.650781 -300.505112)
			(xy 404.598807 -300.505112) (xy 404.547472 -300.496982) (xy 404.498042 -300.480921) (xy 404.451732 -300.457325)
			(xy 404.409684 -300.426775) (xy 404.372933 -300.390024) (xy 404.342383 -300.347976) (xy 404.318787 -300.301666)
			(xy 404.302726 -300.252236) (xy 404.294596 -300.200901) (xy 404.005032 -300.200901) (xy 403.996902 -300.252236)
			(xy 403.980841 -300.301666) (xy 403.957245 -300.347976) (xy 403.926695 -300.390024) (xy 403.889944 -300.426775)
			(xy 403.847896 -300.457325) (xy 403.801586 -300.480921) (xy 403.752156 -300.496982) (xy 403.700821 -300.505112)
			(xy 403.648847 -300.505112) (xy 403.597512 -300.496982) (xy 403.548082 -300.480921) (xy 403.501772 -300.457325)
			(xy 403.459724 -300.426775) (xy 403.422973 -300.390024) (xy 403.392423 -300.347976) (xy 403.368827 -300.301666)
			(xy 403.352766 -300.252236) (xy 403.344636 -300.200901) (xy 403.055072 -300.200901) (xy 403.046942 -300.252236)
			(xy 403.030881 -300.301666) (xy 403.007285 -300.347976) (xy 402.976735 -300.390024) (xy 402.939984 -300.426775)
			(xy 402.897936 -300.457325) (xy 402.851626 -300.480921) (xy 402.802196 -300.496982) (xy 402.750861 -300.505112)
			(xy 402.698887 -300.505112) (xy 402.647552 -300.496982) (xy 402.598122 -300.480921) (xy 402.551812 -300.457325)
			(xy 402.509764 -300.426775) (xy 402.473013 -300.390024) (xy 402.442463 -300.347976) (xy 402.418867 -300.301666)
			(xy 402.402806 -300.252236) (xy 402.394676 -300.200901) (xy 402.105112 -300.200901) (xy 402.096982 -300.252236)
			(xy 402.080921 -300.301666) (xy 402.057325 -300.347976) (xy 402.026775 -300.390024) (xy 401.990024 -300.426775)
			(xy 401.947976 -300.457325) (xy 401.901666 -300.480921) (xy 401.852236 -300.496982) (xy 401.800901 -300.505112)
			(xy 401.748927 -300.505112) (xy 401.697592 -300.496982) (xy 401.648162 -300.480921) (xy 401.601852 -300.457325)
			(xy 401.559804 -300.426775) (xy 401.523053 -300.390024) (xy 401.492503 -300.347976) (xy 401.468907 -300.301666)
			(xy 401.452846 -300.252236) (xy 401.444716 -300.200901) (xy 401.155152 -300.200901) (xy 401.147022 -300.252236)
			(xy 401.130961 -300.301666) (xy 401.107365 -300.347976) (xy 401.076815 -300.390024) (xy 401.040064 -300.426775)
			(xy 400.998016 -300.457325) (xy 400.951706 -300.480921) (xy 400.902276 -300.496982) (xy 400.850941 -300.505112)
			(xy 400.798967 -300.505112) (xy 400.747632 -300.496982) (xy 400.698202 -300.480921) (xy 400.651892 -300.457325)
			(xy 400.609844 -300.426775) (xy 400.573093 -300.390024) (xy 400.542543 -300.347976) (xy 400.518947 -300.301666)
			(xy 400.502886 -300.252236) (xy 400.494756 -300.200901) (xy 400.205192 -300.200901) (xy 400.197062 -300.252236)
			(xy 400.181001 -300.301666) (xy 400.157405 -300.347976) (xy 400.126855 -300.390024) (xy 400.090104 -300.426775)
			(xy 400.048056 -300.457325) (xy 400.001746 -300.480921) (xy 399.952316 -300.496982) (xy 399.900981 -300.505112)
			(xy 399.849007 -300.505112) (xy 399.797672 -300.496982) (xy 399.748242 -300.480921) (xy 399.701932 -300.457325)
			(xy 399.659884 -300.426775) (xy 399.623133 -300.390024) (xy 399.592583 -300.347976) (xy 399.568987 -300.301666)
			(xy 399.552926 -300.252236) (xy 399.544796 -300.200901) (xy 399.255232 -300.200901) (xy 399.247102 -300.252236)
			(xy 399.231041 -300.301666) (xy 399.207445 -300.347976) (xy 399.176895 -300.390024) (xy 399.140144 -300.426775)
			(xy 399.098096 -300.457325) (xy 399.051786 -300.480921) (xy 399.002356 -300.496982) (xy 398.951021 -300.505112)
			(xy 398.899047 -300.505112) (xy 398.847712 -300.496982) (xy 398.798282 -300.480921) (xy 398.751972 -300.457325)
			(xy 398.709924 -300.426775) (xy 398.673173 -300.390024) (xy 398.642623 -300.347976) (xy 398.619027 -300.301666)
			(xy 398.602966 -300.252236) (xy 398.594836 -300.200901) (xy 398.305018 -300.200901) (xy 398.296888 -300.252236)
			(xy 398.280827 -300.301666) (xy 398.257231 -300.347976) (xy 398.226681 -300.390024) (xy 398.18993 -300.426775)
			(xy 398.147882 -300.457325) (xy 398.101572 -300.480921) (xy 398.052142 -300.496982) (xy 398.000807 -300.505112)
			(xy 397.948833 -300.505112) (xy 397.897498 -300.496982) (xy 397.848068 -300.480921) (xy 397.801758 -300.457325)
			(xy 397.75971 -300.426775) (xy 397.722959 -300.390024) (xy 397.692409 -300.347976) (xy 397.668813 -300.301666)
			(xy 397.652752 -300.252236) (xy 397.644622 -300.200901) (xy 397.355058 -300.200901) (xy 397.346928 -300.252236)
			(xy 397.330867 -300.301666) (xy 397.307271 -300.347976) (xy 397.276721 -300.390024) (xy 397.23997 -300.426775)
			(xy 397.197922 -300.457325) (xy 397.151612 -300.480921) (xy 397.102182 -300.496982) (xy 397.050847 -300.505112)
			(xy 396.998873 -300.505112) (xy 396.947538 -300.496982) (xy 396.898108 -300.480921) (xy 396.851798 -300.457325)
			(xy 396.80975 -300.426775) (xy 396.772999 -300.390024) (xy 396.742449 -300.347976) (xy 396.718853 -300.301666)
			(xy 396.702792 -300.252236) (xy 396.694662 -300.200901) (xy 396.405098 -300.200901) (xy 396.396968 -300.252236)
			(xy 396.380907 -300.301666) (xy 396.357311 -300.347976) (xy 396.326761 -300.390024) (xy 396.29001 -300.426775)
			(xy 396.247962 -300.457325) (xy 396.201652 -300.480921) (xy 396.152222 -300.496982) (xy 396.100887 -300.505112)
			(xy 396.048913 -300.505112) (xy 395.997578 -300.496982) (xy 395.948148 -300.480921) (xy 395.901838 -300.457325)
			(xy 395.85979 -300.426775) (xy 395.823039 -300.390024) (xy 395.792489 -300.347976) (xy 395.768893 -300.301666)
			(xy 395.752832 -300.252236) (xy 395.744702 -300.200901) (xy 395.455138 -300.200901) (xy 395.447008 -300.252236)
			(xy 395.430947 -300.301666) (xy 395.407351 -300.347976) (xy 395.376801 -300.390024) (xy 395.34005 -300.426775)
			(xy 395.298002 -300.457325) (xy 395.251692 -300.480921) (xy 395.202262 -300.496982) (xy 395.150927 -300.505112)
			(xy 395.098953 -300.505112) (xy 395.047618 -300.496982) (xy 394.998188 -300.480921) (xy 394.951878 -300.457325)
			(xy 394.90983 -300.426775) (xy 394.873079 -300.390024) (xy 394.842529 -300.347976) (xy 394.818933 -300.301666)
			(xy 394.802872 -300.252236) (xy 394.794742 -300.200901) (xy 394.504132 -300.200901) (xy 394.50202 -300.227382)
			(xy 394.489573 -300.278535) (xy 394.469178 -300.32707) (xy 394.441351 -300.37176) (xy 394.406794 -300.411476)
			(xy 394.36638 -300.445215) (xy 394.321131 -300.472124) (xy 394.27219 -300.491524) (xy 394.246608 -300.497748)
			(xy 394.229082 -300.501558) (xy 394.20673 -300.529498) (xy 394.20673 -300.77029) (xy 394.229082 -300.79823)
			(xy 394.246608 -300.80204) (xy 394.272199 -300.808238) (xy 394.321146 -300.82764) (xy 394.3664 -300.854552)
			(xy 394.406819 -300.888294) (xy 394.441381 -300.928015) (xy 394.469212 -300.97271) (xy 394.489609 -301.02125)
			(xy 394.502058 -301.072409) (xy 394.506244 -301.124894) (xy 394.504174 -301.150861) (xy 395.744702 -301.150861)
			(xy 395.744702 -301.098887) (xy 395.752832 -301.047552) (xy 395.768893 -300.998122) (xy 395.792489 -300.951812)
			(xy 395.823039 -300.909764) (xy 395.85979 -300.873013) (xy 395.901838 -300.842463) (xy 395.948148 -300.818867)
			(xy 395.997578 -300.802806) (xy 396.048913 -300.794676) (xy 396.100887 -300.794676) (xy 396.152222 -300.802806)
			(xy 396.201652 -300.818867) (xy 396.247962 -300.842463) (xy 396.29001 -300.873013) (xy 396.326761 -300.909764)
			(xy 396.357311 -300.951812) (xy 396.380907 -300.998122) (xy 396.396968 -301.047552) (xy 396.405098 -301.098887)
			(xy 396.405608 -301.124874) (xy 396.405098 -301.150861) (xy 396.694662 -301.150861) (xy 396.694662 -301.098887)
			(xy 396.702792 -301.047552) (xy 396.718853 -300.998122) (xy 396.742449 -300.951812) (xy 396.772999 -300.909764)
			(xy 396.80975 -300.873013) (xy 396.851798 -300.842463) (xy 396.898108 -300.818867) (xy 396.947538 -300.802806)
			(xy 396.998873 -300.794676) (xy 397.050847 -300.794676) (xy 397.102182 -300.802806) (xy 397.151612 -300.818867)
			(xy 397.197922 -300.842463) (xy 397.23997 -300.873013) (xy 397.276721 -300.909764) (xy 397.307271 -300.951812)
			(xy 397.330867 -300.998122) (xy 397.346928 -301.047552) (xy 397.355058 -301.098887) (xy 397.355568 -301.124874)
			(xy 397.355058 -301.150861) (xy 397.644622 -301.150861) (xy 397.644622 -301.098887) (xy 397.652752 -301.047552)
			(xy 397.668813 -300.998122) (xy 397.692409 -300.951812) (xy 397.722959 -300.909764) (xy 397.75971 -300.873013)
			(xy 397.801758 -300.842463) (xy 397.848068 -300.818867) (xy 397.897498 -300.802806) (xy 397.948833 -300.794676)
			(xy 398.000807 -300.794676) (xy 398.052142 -300.802806) (xy 398.101572 -300.818867) (xy 398.147882 -300.842463)
			(xy 398.18993 -300.873013) (xy 398.226681 -300.909764) (xy 398.257231 -300.951812) (xy 398.280827 -300.998122)
			(xy 398.296888 -301.047552) (xy 398.305018 -301.098887) (xy 398.305528 -301.124874) (xy 398.305018 -301.150861)
			(xy 398.594836 -301.150861) (xy 398.594836 -301.098887) (xy 398.602966 -301.047552) (xy 398.619027 -300.998122)
			(xy 398.642623 -300.951812) (xy 398.673173 -300.909764) (xy 398.709924 -300.873013) (xy 398.751972 -300.842463)
			(xy 398.798282 -300.818867) (xy 398.847712 -300.802806) (xy 398.899047 -300.794676) (xy 398.951021 -300.794676)
			(xy 399.002356 -300.802806) (xy 399.051786 -300.818867) (xy 399.098096 -300.842463) (xy 399.140144 -300.873013)
			(xy 399.176895 -300.909764) (xy 399.207445 -300.951812) (xy 399.231041 -300.998122) (xy 399.247102 -301.047552)
			(xy 399.255232 -301.098887) (xy 399.255742 -301.124874) (xy 399.255232 -301.150861) (xy 399.544796 -301.150861)
			(xy 399.544796 -301.098887) (xy 399.552926 -301.047552) (xy 399.568987 -300.998122) (xy 399.592583 -300.951812)
			(xy 399.623133 -300.909764) (xy 399.659884 -300.873013) (xy 399.701932 -300.842463) (xy 399.748242 -300.818867)
			(xy 399.797672 -300.802806) (xy 399.849007 -300.794676) (xy 399.900981 -300.794676) (xy 399.952316 -300.802806)
			(xy 400.001746 -300.818867) (xy 400.048056 -300.842463) (xy 400.090104 -300.873013) (xy 400.126855 -300.909764)
			(xy 400.157405 -300.951812) (xy 400.181001 -300.998122) (xy 400.197062 -301.047552) (xy 400.205192 -301.098887)
			(xy 400.205702 -301.124874) (xy 400.205192 -301.150861) (xy 400.494756 -301.150861) (xy 400.494756 -301.098887)
			(xy 400.502886 -301.047552) (xy 400.518947 -300.998122) (xy 400.542543 -300.951812) (xy 400.573093 -300.909764)
			(xy 400.609844 -300.873013) (xy 400.651892 -300.842463) (xy 400.698202 -300.818867) (xy 400.747632 -300.802806)
			(xy 400.798967 -300.794676) (xy 400.850941 -300.794676) (xy 400.902276 -300.802806) (xy 400.951706 -300.818867)
			(xy 400.998016 -300.842463) (xy 401.040064 -300.873013) (xy 401.076815 -300.909764) (xy 401.107365 -300.951812)
			(xy 401.130961 -300.998122) (xy 401.147022 -301.047552) (xy 401.155152 -301.098887) (xy 401.155662 -301.124874)
			(xy 401.155152 -301.150861) (xy 401.444716 -301.150861) (xy 401.444716 -301.098887) (xy 401.452846 -301.047552)
			(xy 401.468907 -300.998122) (xy 401.492503 -300.951812) (xy 401.523053 -300.909764) (xy 401.559804 -300.873013)
			(xy 401.601852 -300.842463) (xy 401.648162 -300.818867) (xy 401.697592 -300.802806) (xy 401.748927 -300.794676)
			(xy 401.800901 -300.794676) (xy 401.852236 -300.802806) (xy 401.901666 -300.818867) (xy 401.947976 -300.842463)
			(xy 401.990024 -300.873013) (xy 402.026775 -300.909764) (xy 402.057325 -300.951812) (xy 402.080921 -300.998122)
			(xy 402.096982 -301.047552) (xy 402.105112 -301.098887) (xy 402.105622 -301.124874) (xy 402.105112 -301.150861)
			(xy 402.394676 -301.150861) (xy 402.394676 -301.098887) (xy 402.402806 -301.047552) (xy 402.418867 -300.998122)
			(xy 402.442463 -300.951812) (xy 402.473013 -300.909764) (xy 402.509764 -300.873013) (xy 402.551812 -300.842463)
			(xy 402.598122 -300.818867) (xy 402.647552 -300.802806) (xy 402.698887 -300.794676) (xy 402.750861 -300.794676)
			(xy 402.802196 -300.802806) (xy 402.851626 -300.818867) (xy 402.897936 -300.842463) (xy 402.939984 -300.873013)
			(xy 402.976735 -300.909764) (xy 403.007285 -300.951812) (xy 403.030881 -300.998122) (xy 403.046942 -301.047552)
			(xy 403.055072 -301.098887) (xy 403.055582 -301.124874) (xy 403.055072 -301.150861) (xy 403.344636 -301.150861)
			(xy 403.344636 -301.098887) (xy 403.352766 -301.047552) (xy 403.368827 -300.998122) (xy 403.392423 -300.951812)
			(xy 403.422973 -300.909764) (xy 403.459724 -300.873013) (xy 403.501772 -300.842463) (xy 403.548082 -300.818867)
			(xy 403.597512 -300.802806) (xy 403.648847 -300.794676) (xy 403.700821 -300.794676) (xy 403.752156 -300.802806)
			(xy 403.801586 -300.818867) (xy 403.847896 -300.842463) (xy 403.889944 -300.873013) (xy 403.926695 -300.909764)
			(xy 403.957245 -300.951812) (xy 403.980841 -300.998122) (xy 403.996902 -301.047552) (xy 404.005032 -301.098887)
			(xy 404.005542 -301.124874) (xy 404.005032 -301.150861) (xy 404.294596 -301.150861) (xy 404.294596 -301.098887)
			(xy 404.302726 -301.047552) (xy 404.318787 -300.998122) (xy 404.342383 -300.951812) (xy 404.372933 -300.909764)
			(xy 404.409684 -300.873013) (xy 404.451732 -300.842463) (xy 404.498042 -300.818867) (xy 404.547472 -300.802806)
			(xy 404.598807 -300.794676) (xy 404.650781 -300.794676) (xy 404.702116 -300.802806) (xy 404.751546 -300.818867)
			(xy 404.797856 -300.842463) (xy 404.839904 -300.873013) (xy 404.876655 -300.909764) (xy 404.907205 -300.951812)
			(xy 404.930801 -300.998122) (xy 404.946862 -301.047552) (xy 404.954992 -301.098887) (xy 404.955502 -301.124874)
			(xy 404.954992 -301.150861) (xy 405.24481 -301.150861) (xy 405.24481 -301.098887) (xy 405.25294 -301.047552)
			(xy 405.269001 -300.998122) (xy 405.292597 -300.951812) (xy 405.323147 -300.909764) (xy 405.359898 -300.873013)
			(xy 405.401946 -300.842463) (xy 405.448256 -300.818867) (xy 405.497686 -300.802806) (xy 405.549021 -300.794676)
			(xy 405.600995 -300.794676) (xy 405.65233 -300.802806) (xy 405.70176 -300.818867) (xy 405.74807 -300.842463)
			(xy 405.790118 -300.873013) (xy 405.826869 -300.909764) (xy 405.857419 -300.951812) (xy 405.881015 -300.998122)
			(xy 405.897076 -301.047552) (xy 405.905206 -301.098887) (xy 405.905716 -301.124874) (xy 405.905206 -301.150861)
			(xy 406.19477 -301.150861) (xy 406.19477 -301.098887) (xy 406.2029 -301.047552) (xy 406.218961 -300.998122)
			(xy 406.242557 -300.951812) (xy 406.273107 -300.909764) (xy 406.309858 -300.873013) (xy 406.351906 -300.842463)
			(xy 406.398216 -300.818867) (xy 406.447646 -300.802806) (xy 406.498981 -300.794676) (xy 406.550955 -300.794676)
			(xy 406.60229 -300.802806) (xy 406.65172 -300.818867) (xy 406.69803 -300.842463) (xy 406.740078 -300.873013)
			(xy 406.776829 -300.909764) (xy 406.807379 -300.951812) (xy 406.830975 -300.998122) (xy 406.847036 -301.047552)
			(xy 406.855166 -301.098887) (xy 406.855676 -301.124874) (xy 406.855166 -301.150861) (xy 408.09469 -301.150861)
			(xy 408.09469 -301.098887) (xy 408.10282 -301.047552) (xy 408.118881 -300.998122) (xy 408.142477 -300.951812)
			(xy 408.173027 -300.909764) (xy 408.209778 -300.873013) (xy 408.251826 -300.842463) (xy 408.298136 -300.818867)
			(xy 408.347566 -300.802806) (xy 408.398901 -300.794676) (xy 408.450875 -300.794676) (xy 408.50221 -300.802806)
			(xy 408.55164 -300.818867) (xy 408.59795 -300.842463) (xy 408.639998 -300.873013) (xy 408.676749 -300.909764)
			(xy 408.707299 -300.951812) (xy 408.730895 -300.998122) (xy 408.746956 -301.047552) (xy 408.755086 -301.098887)
			(xy 408.755596 -301.124874) (xy 408.755086 -301.150861) (xy 409.04465 -301.150861) (xy 409.04465 -301.098887)
			(xy 409.05278 -301.047552) (xy 409.068841 -300.998122) (xy 409.092437 -300.951812) (xy 409.122987 -300.909764)
			(xy 409.159738 -300.873013) (xy 409.201786 -300.842463) (xy 409.248096 -300.818867) (xy 409.297526 -300.802806)
			(xy 409.348861 -300.794676) (xy 409.400835 -300.794676) (xy 409.45217 -300.802806) (xy 409.5016 -300.818867)
			(xy 409.54791 -300.842463) (xy 409.589958 -300.873013) (xy 409.626709 -300.909764) (xy 409.657259 -300.951812)
			(xy 409.680855 -300.998122) (xy 409.696916 -301.047552) (xy 409.705046 -301.098887) (xy 409.705556 -301.124874)
			(xy 409.705046 -301.150861) (xy 409.99461 -301.150861) (xy 409.99461 -301.098887) (xy 410.00274 -301.047552)
			(xy 410.018801 -300.998122) (xy 410.042397 -300.951812) (xy 410.072947 -300.909764) (xy 410.109698 -300.873013)
			(xy 410.151746 -300.842463) (xy 410.198056 -300.818867) (xy 410.247486 -300.802806) (xy 410.298821 -300.794676)
			(xy 410.350795 -300.794676) (xy 410.40213 -300.802806) (xy 410.45156 -300.818867) (xy 410.49787 -300.842463)
			(xy 410.539918 -300.873013) (xy 410.576669 -300.909764) (xy 410.607219 -300.951812) (xy 410.630815 -300.998122)
			(xy 410.646876 -301.047552) (xy 410.655006 -301.098887) (xy 410.655516 -301.124874) (xy 410.655006 -301.150861)
			(xy 410.944824 -301.150861) (xy 410.944824 -301.098887) (xy 410.952954 -301.047552) (xy 410.969015 -300.998122)
			(xy 410.992611 -300.951812) (xy 411.023161 -300.909764) (xy 411.059912 -300.873013) (xy 411.10196 -300.842463)
			(xy 411.14827 -300.818867) (xy 411.1977 -300.802806) (xy 411.249035 -300.794676) (xy 411.301009 -300.794676)
			(xy 411.352344 -300.802806) (xy 411.401774 -300.818867) (xy 411.448084 -300.842463) (xy 411.490132 -300.873013)
			(xy 411.526883 -300.909764) (xy 411.557433 -300.951812) (xy 411.581029 -300.998122) (xy 411.59709 -301.047552)
			(xy 411.60522 -301.098887) (xy 411.60573 -301.124874) (xy 411.60522 -301.150861) (xy 411.894784 -301.150861)
			(xy 411.894784 -301.098887) (xy 411.902914 -301.047552) (xy 411.918975 -300.998122) (xy 411.942571 -300.951812)
			(xy 411.973121 -300.909764) (xy 412.009872 -300.873013) (xy 412.05192 -300.842463) (xy 412.09823 -300.818867)
			(xy 412.14766 -300.802806) (xy 412.198995 -300.794676) (xy 412.250969 -300.794676) (xy 412.302304 -300.802806)
			(xy 412.351734 -300.818867) (xy 412.398044 -300.842463) (xy 412.440092 -300.873013) (xy 412.476843 -300.909764)
			(xy 412.507393 -300.951812) (xy 412.530989 -300.998122) (xy 412.54705 -301.047552) (xy 412.55518 -301.098887)
			(xy 412.55569 -301.124874) (xy 412.55518 -301.150861) (xy 412.844744 -301.150861) (xy 412.844744 -301.098887)
			(xy 412.852874 -301.047552) (xy 412.868935 -300.998122) (xy 412.892531 -300.951812) (xy 412.923081 -300.909764)
			(xy 412.959832 -300.873013) (xy 413.00188 -300.842463) (xy 413.04819 -300.818867) (xy 413.09762 -300.802806)
			(xy 413.148955 -300.794676) (xy 413.200929 -300.794676) (xy 413.252264 -300.802806) (xy 413.301694 -300.818867)
			(xy 413.348004 -300.842463) (xy 413.390052 -300.873013) (xy 413.426803 -300.909764) (xy 413.457353 -300.951812)
			(xy 413.480949 -300.998122) (xy 413.49701 -301.047552) (xy 413.50514 -301.098887) (xy 413.50565 -301.124874)
			(xy 413.50514 -301.150861) (xy 413.794704 -301.150861) (xy 413.794704 -301.098887) (xy 413.802834 -301.047552)
			(xy 413.818895 -300.998122) (xy 413.842491 -300.951812) (xy 413.873041 -300.909764) (xy 413.909792 -300.873013)
			(xy 413.95184 -300.842463) (xy 413.99815 -300.818867) (xy 414.04758 -300.802806) (xy 414.098915 -300.794676)
			(xy 414.150889 -300.794676) (xy 414.202224 -300.802806) (xy 414.251654 -300.818867) (xy 414.297964 -300.842463)
			(xy 414.340012 -300.873013) (xy 414.376763 -300.909764) (xy 414.407313 -300.951812) (xy 414.430909 -300.998122)
			(xy 414.44697 -301.047552) (xy 414.4551 -301.098887) (xy 414.45561 -301.124874) (xy 414.4551 -301.150861)
			(xy 414.744664 -301.150861) (xy 414.744664 -301.098887) (xy 414.752794 -301.047552) (xy 414.768855 -300.998122)
			(xy 414.792451 -300.951812) (xy 414.823001 -300.909764) (xy 414.859752 -300.873013) (xy 414.9018 -300.842463)
			(xy 414.94811 -300.818867) (xy 414.99754 -300.802806) (xy 415.048875 -300.794676) (xy 415.100849 -300.794676)
			(xy 415.152184 -300.802806) (xy 415.201614 -300.818867) (xy 415.247924 -300.842463) (xy 415.289972 -300.873013)
			(xy 415.326723 -300.909764) (xy 415.357273 -300.951812) (xy 415.380869 -300.998122) (xy 415.39693 -301.047552)
			(xy 415.40506 -301.098887) (xy 415.40557 -301.124874) (xy 415.40506 -301.150861) (xy 415.694624 -301.150861)
			(xy 415.694624 -301.098887) (xy 415.702754 -301.047552) (xy 415.718815 -300.998122) (xy 415.742411 -300.951812)
			(xy 415.772961 -300.909764) (xy 415.809712 -300.873013) (xy 415.85176 -300.842463) (xy 415.89807 -300.818867)
			(xy 415.9475 -300.802806) (xy 415.998835 -300.794676) (xy 416.050809 -300.794676) (xy 416.102144 -300.802806)
			(xy 416.151574 -300.818867) (xy 416.197884 -300.842463) (xy 416.239932 -300.873013) (xy 416.276683 -300.909764)
			(xy 416.307233 -300.951812) (xy 416.330829 -300.998122) (xy 416.34689 -301.047552) (xy 416.35502 -301.098887)
			(xy 416.35553 -301.124874) (xy 416.35502 -301.150861) (xy 416.644584 -301.150861) (xy 416.644584 -301.098887)
			(xy 416.652714 -301.047552) (xy 416.668775 -300.998122) (xy 416.692371 -300.951812) (xy 416.722921 -300.909764)
			(xy 416.759672 -300.873013) (xy 416.80172 -300.842463) (xy 416.84803 -300.818867) (xy 416.89746 -300.802806)
			(xy 416.948795 -300.794676) (xy 417.000769 -300.794676) (xy 417.052104 -300.802806) (xy 417.101534 -300.818867)
			(xy 417.147844 -300.842463) (xy 417.189892 -300.873013) (xy 417.226643 -300.909764) (xy 417.257193 -300.951812)
			(xy 417.280789 -300.998122) (xy 417.29685 -301.047552) (xy 417.30498 -301.098887) (xy 417.30549 -301.124874)
			(xy 417.30498 -301.150861) (xy 417.29685 -301.202196) (xy 417.280789 -301.251626) (xy 417.257193 -301.297936)
			(xy 417.226643 -301.339984) (xy 417.189892 -301.376735) (xy 417.147844 -301.407285) (xy 417.101534 -301.430881)
			(xy 417.052104 -301.446942) (xy 417.000769 -301.455072) (xy 416.948795 -301.455072) (xy 416.89746 -301.446942)
			(xy 416.84803 -301.430881) (xy 416.80172 -301.407285) (xy 416.759672 -301.376735) (xy 416.722921 -301.339984)
			(xy 416.692371 -301.297936) (xy 416.668775 -301.251626) (xy 416.652714 -301.202196) (xy 416.644584 -301.150861)
			(xy 416.35502 -301.150861) (xy 416.34689 -301.202196) (xy 416.330829 -301.251626) (xy 416.307233 -301.297936)
			(xy 416.276683 -301.339984) (xy 416.239932 -301.376735) (xy 416.197884 -301.407285) (xy 416.151574 -301.430881)
			(xy 416.102144 -301.446942) (xy 416.050809 -301.455072) (xy 415.998835 -301.455072) (xy 415.9475 -301.446942)
			(xy 415.89807 -301.430881) (xy 415.85176 -301.407285) (xy 415.809712 -301.376735) (xy 415.772961 -301.339984)
			(xy 415.742411 -301.297936) (xy 415.718815 -301.251626) (xy 415.702754 -301.202196) (xy 415.694624 -301.150861)
			(xy 415.40506 -301.150861) (xy 415.39693 -301.202196) (xy 415.380869 -301.251626) (xy 415.357273 -301.297936)
			(xy 415.326723 -301.339984) (xy 415.289972 -301.376735) (xy 415.247924 -301.407285) (xy 415.201614 -301.430881)
			(xy 415.152184 -301.446942) (xy 415.100849 -301.455072) (xy 415.048875 -301.455072) (xy 414.99754 -301.446942)
			(xy 414.94811 -301.430881) (xy 414.9018 -301.407285) (xy 414.859752 -301.376735) (xy 414.823001 -301.339984)
			(xy 414.792451 -301.297936) (xy 414.768855 -301.251626) (xy 414.752794 -301.202196) (xy 414.744664 -301.150861)
			(xy 414.4551 -301.150861) (xy 414.44697 -301.202196) (xy 414.430909 -301.251626) (xy 414.407313 -301.297936)
			(xy 414.376763 -301.339984) (xy 414.340012 -301.376735) (xy 414.297964 -301.407285) (xy 414.251654 -301.430881)
			(xy 414.202224 -301.446942) (xy 414.150889 -301.455072) (xy 414.098915 -301.455072) (xy 414.04758 -301.446942)
			(xy 413.99815 -301.430881) (xy 413.95184 -301.407285) (xy 413.909792 -301.376735) (xy 413.873041 -301.339984)
			(xy 413.842491 -301.297936) (xy 413.818895 -301.251626) (xy 413.802834 -301.202196) (xy 413.794704 -301.150861)
			(xy 413.50514 -301.150861) (xy 413.49701 -301.202196) (xy 413.480949 -301.251626) (xy 413.457353 -301.297936)
			(xy 413.426803 -301.339984) (xy 413.390052 -301.376735) (xy 413.348004 -301.407285) (xy 413.301694 -301.430881)
			(xy 413.252264 -301.446942) (xy 413.200929 -301.455072) (xy 413.148955 -301.455072) (xy 413.09762 -301.446942)
			(xy 413.04819 -301.430881) (xy 413.00188 -301.407285) (xy 412.959832 -301.376735) (xy 412.923081 -301.339984)
			(xy 412.892531 -301.297936) (xy 412.868935 -301.251626) (xy 412.852874 -301.202196) (xy 412.844744 -301.150861)
			(xy 412.55518 -301.150861) (xy 412.54705 -301.202196) (xy 412.530989 -301.251626) (xy 412.507393 -301.297936)
			(xy 412.476843 -301.339984) (xy 412.440092 -301.376735) (xy 412.398044 -301.407285) (xy 412.351734 -301.430881)
			(xy 412.302304 -301.446942) (xy 412.250969 -301.455072) (xy 412.198995 -301.455072) (xy 412.14766 -301.446942)
			(xy 412.09823 -301.430881) (xy 412.05192 -301.407285) (xy 412.009872 -301.376735) (xy 411.973121 -301.339984)
			(xy 411.942571 -301.297936) (xy 411.918975 -301.251626) (xy 411.902914 -301.202196) (xy 411.894784 -301.150861)
			(xy 411.60522 -301.150861) (xy 411.59709 -301.202196) (xy 411.581029 -301.251626) (xy 411.557433 -301.297936)
			(xy 411.526883 -301.339984) (xy 411.490132 -301.376735) (xy 411.448084 -301.407285) (xy 411.401774 -301.430881)
			(xy 411.352344 -301.446942) (xy 411.301009 -301.455072) (xy 411.249035 -301.455072) (xy 411.1977 -301.446942)
			(xy 411.14827 -301.430881) (xy 411.10196 -301.407285) (xy 411.059912 -301.376735) (xy 411.023161 -301.339984)
			(xy 410.992611 -301.297936) (xy 410.969015 -301.251626) (xy 410.952954 -301.202196) (xy 410.944824 -301.150861)
			(xy 410.655006 -301.150861) (xy 410.646876 -301.202196) (xy 410.630815 -301.251626) (xy 410.607219 -301.297936)
			(xy 410.576669 -301.339984) (xy 410.539918 -301.376735) (xy 410.49787 -301.407285) (xy 410.45156 -301.430881)
			(xy 410.40213 -301.446942) (xy 410.350795 -301.455072) (xy 410.298821 -301.455072) (xy 410.247486 -301.446942)
			(xy 410.198056 -301.430881) (xy 410.151746 -301.407285) (xy 410.109698 -301.376735) (xy 410.072947 -301.339984)
			(xy 410.042397 -301.297936) (xy 410.018801 -301.251626) (xy 410.00274 -301.202196) (xy 409.99461 -301.150861)
			(xy 409.705046 -301.150861) (xy 409.696916 -301.202196) (xy 409.680855 -301.251626) (xy 409.657259 -301.297936)
			(xy 409.626709 -301.339984) (xy 409.589958 -301.376735) (xy 409.54791 -301.407285) (xy 409.5016 -301.430881)
			(xy 409.45217 -301.446942) (xy 409.400835 -301.455072) (xy 409.348861 -301.455072) (xy 409.297526 -301.446942)
			(xy 409.248096 -301.430881) (xy 409.201786 -301.407285) (xy 409.159738 -301.376735) (xy 409.122987 -301.339984)
			(xy 409.092437 -301.297936) (xy 409.068841 -301.251626) (xy 409.05278 -301.202196) (xy 409.04465 -301.150861)
			(xy 408.755086 -301.150861) (xy 408.746956 -301.202196) (xy 408.730895 -301.251626) (xy 408.707299 -301.297936)
			(xy 408.676749 -301.339984) (xy 408.639998 -301.376735) (xy 408.59795 -301.407285) (xy 408.55164 -301.430881)
			(xy 408.50221 -301.446942) (xy 408.450875 -301.455072) (xy 408.398901 -301.455072) (xy 408.347566 -301.446942)
			(xy 408.298136 -301.430881) (xy 408.251826 -301.407285) (xy 408.209778 -301.376735) (xy 408.173027 -301.339984)
			(xy 408.142477 -301.297936) (xy 408.118881 -301.251626) (xy 408.10282 -301.202196) (xy 408.09469 -301.150861)
			(xy 406.855166 -301.150861) (xy 406.847036 -301.202196) (xy 406.830975 -301.251626) (xy 406.807379 -301.297936)
			(xy 406.776829 -301.339984) (xy 406.740078 -301.376735) (xy 406.69803 -301.407285) (xy 406.65172 -301.430881)
			(xy 406.60229 -301.446942) (xy 406.550955 -301.455072) (xy 406.498981 -301.455072) (xy 406.447646 -301.446942)
			(xy 406.398216 -301.430881) (xy 406.351906 -301.407285) (xy 406.309858 -301.376735) (xy 406.273107 -301.339984)
			(xy 406.242557 -301.297936) (xy 406.218961 -301.251626) (xy 406.2029 -301.202196) (xy 406.19477 -301.150861)
			(xy 405.905206 -301.150861) (xy 405.897076 -301.202196) (xy 405.881015 -301.251626) (xy 405.857419 -301.297936)
			(xy 405.826869 -301.339984) (xy 405.790118 -301.376735) (xy 405.74807 -301.407285) (xy 405.70176 -301.430881)
			(xy 405.65233 -301.446942) (xy 405.600995 -301.455072) (xy 405.549021 -301.455072) (xy 405.497686 -301.446942)
			(xy 405.448256 -301.430881) (xy 405.401946 -301.407285) (xy 405.359898 -301.376735) (xy 405.323147 -301.339984)
			(xy 405.292597 -301.297936) (xy 405.269001 -301.251626) (xy 405.25294 -301.202196) (xy 405.24481 -301.150861)
			(xy 404.954992 -301.150861) (xy 404.946862 -301.202196) (xy 404.930801 -301.251626) (xy 404.907205 -301.297936)
			(xy 404.876655 -301.339984) (xy 404.839904 -301.376735) (xy 404.797856 -301.407285) (xy 404.751546 -301.430881)
			(xy 404.702116 -301.446942) (xy 404.650781 -301.455072) (xy 404.598807 -301.455072) (xy 404.547472 -301.446942)
			(xy 404.498042 -301.430881) (xy 404.451732 -301.407285) (xy 404.409684 -301.376735) (xy 404.372933 -301.339984)
			(xy 404.342383 -301.297936) (xy 404.318787 -301.251626) (xy 404.302726 -301.202196) (xy 404.294596 -301.150861)
			(xy 404.005032 -301.150861) (xy 403.996902 -301.202196) (xy 403.980841 -301.251626) (xy 403.957245 -301.297936)
			(xy 403.926695 -301.339984) (xy 403.889944 -301.376735) (xy 403.847896 -301.407285) (xy 403.801586 -301.430881)
			(xy 403.752156 -301.446942) (xy 403.700821 -301.455072) (xy 403.648847 -301.455072) (xy 403.597512 -301.446942)
			(xy 403.548082 -301.430881) (xy 403.501772 -301.407285) (xy 403.459724 -301.376735) (xy 403.422973 -301.339984)
			(xy 403.392423 -301.297936) (xy 403.368827 -301.251626) (xy 403.352766 -301.202196) (xy 403.344636 -301.150861)
			(xy 403.055072 -301.150861) (xy 403.046942 -301.202196) (xy 403.030881 -301.251626) (xy 403.007285 -301.297936)
			(xy 402.976735 -301.339984) (xy 402.939984 -301.376735) (xy 402.897936 -301.407285) (xy 402.851626 -301.430881)
			(xy 402.802196 -301.446942) (xy 402.750861 -301.455072) (xy 402.698887 -301.455072) (xy 402.647552 -301.446942)
			(xy 402.598122 -301.430881) (xy 402.551812 -301.407285) (xy 402.509764 -301.376735) (xy 402.473013 -301.339984)
			(xy 402.442463 -301.297936) (xy 402.418867 -301.251626) (xy 402.402806 -301.202196) (xy 402.394676 -301.150861)
			(xy 402.105112 -301.150861) (xy 402.096982 -301.202196) (xy 402.080921 -301.251626) (xy 402.057325 -301.297936)
			(xy 402.026775 -301.339984) (xy 401.990024 -301.376735) (xy 401.947976 -301.407285) (xy 401.901666 -301.430881)
			(xy 401.852236 -301.446942) (xy 401.800901 -301.455072) (xy 401.748927 -301.455072) (xy 401.697592 -301.446942)
			(xy 401.648162 -301.430881) (xy 401.601852 -301.407285) (xy 401.559804 -301.376735) (xy 401.523053 -301.339984)
			(xy 401.492503 -301.297936) (xy 401.468907 -301.251626) (xy 401.452846 -301.202196) (xy 401.444716 -301.150861)
			(xy 401.155152 -301.150861) (xy 401.147022 -301.202196) (xy 401.130961 -301.251626) (xy 401.107365 -301.297936)
			(xy 401.076815 -301.339984) (xy 401.040064 -301.376735) (xy 400.998016 -301.407285) (xy 400.951706 -301.430881)
			(xy 400.902276 -301.446942) (xy 400.850941 -301.455072) (xy 400.798967 -301.455072) (xy 400.747632 -301.446942)
			(xy 400.698202 -301.430881) (xy 400.651892 -301.407285) (xy 400.609844 -301.376735) (xy 400.573093 -301.339984)
			(xy 400.542543 -301.297936) (xy 400.518947 -301.251626) (xy 400.502886 -301.202196) (xy 400.494756 -301.150861)
			(xy 400.205192 -301.150861) (xy 400.197062 -301.202196) (xy 400.181001 -301.251626) (xy 400.157405 -301.297936)
			(xy 400.126855 -301.339984) (xy 400.090104 -301.376735) (xy 400.048056 -301.407285) (xy 400.001746 -301.430881)
			(xy 399.952316 -301.446942) (xy 399.900981 -301.455072) (xy 399.849007 -301.455072) (xy 399.797672 -301.446942)
			(xy 399.748242 -301.430881) (xy 399.701932 -301.407285) (xy 399.659884 -301.376735) (xy 399.623133 -301.339984)
			(xy 399.592583 -301.297936) (xy 399.568987 -301.251626) (xy 399.552926 -301.202196) (xy 399.544796 -301.150861)
			(xy 399.255232 -301.150861) (xy 399.247102 -301.202196) (xy 399.231041 -301.251626) (xy 399.207445 -301.297936)
			(xy 399.176895 -301.339984) (xy 399.140144 -301.376735) (xy 399.098096 -301.407285) (xy 399.051786 -301.430881)
			(xy 399.002356 -301.446942) (xy 398.951021 -301.455072) (xy 398.899047 -301.455072) (xy 398.847712 -301.446942)
			(xy 398.798282 -301.430881) (xy 398.751972 -301.407285) (xy 398.709924 -301.376735) (xy 398.673173 -301.339984)
			(xy 398.642623 -301.297936) (xy 398.619027 -301.251626) (xy 398.602966 -301.202196) (xy 398.594836 -301.150861)
			(xy 398.305018 -301.150861) (xy 398.296888 -301.202196) (xy 398.280827 -301.251626) (xy 398.257231 -301.297936)
			(xy 398.226681 -301.339984) (xy 398.18993 -301.376735) (xy 398.147882 -301.407285) (xy 398.101572 -301.430881)
			(xy 398.052142 -301.446942) (xy 398.000807 -301.455072) (xy 397.948833 -301.455072) (xy 397.897498 -301.446942)
			(xy 397.848068 -301.430881) (xy 397.801758 -301.407285) (xy 397.75971 -301.376735) (xy 397.722959 -301.339984)
			(xy 397.692409 -301.297936) (xy 397.668813 -301.251626) (xy 397.652752 -301.202196) (xy 397.644622 -301.150861)
			(xy 397.355058 -301.150861) (xy 397.346928 -301.202196) (xy 397.330867 -301.251626) (xy 397.307271 -301.297936)
			(xy 397.276721 -301.339984) (xy 397.23997 -301.376735) (xy 397.197922 -301.407285) (xy 397.151612 -301.430881)
			(xy 397.102182 -301.446942) (xy 397.050847 -301.455072) (xy 396.998873 -301.455072) (xy 396.947538 -301.446942)
			(xy 396.898108 -301.430881) (xy 396.851798 -301.407285) (xy 396.80975 -301.376735) (xy 396.772999 -301.339984)
			(xy 396.742449 -301.297936) (xy 396.718853 -301.251626) (xy 396.702792 -301.202196) (xy 396.694662 -301.150861)
			(xy 396.405098 -301.150861) (xy 396.396968 -301.202196) (xy 396.380907 -301.251626) (xy 396.357311 -301.297936)
			(xy 396.326761 -301.339984) (xy 396.29001 -301.376735) (xy 396.247962 -301.407285) (xy 396.201652 -301.430881)
			(xy 396.152222 -301.446942) (xy 396.100887 -301.455072) (xy 396.048913 -301.455072) (xy 395.997578 -301.446942)
			(xy 395.948148 -301.430881) (xy 395.901838 -301.407285) (xy 395.85979 -301.376735) (xy 395.823039 -301.339984)
			(xy 395.792489 -301.297936) (xy 395.768893 -301.251626) (xy 395.752832 -301.202196) (xy 395.744702 -301.150861)
			(xy 394.504174 -301.150861) (xy 394.50206 -301.17738) (xy 394.489613 -301.228539) (xy 394.469217 -301.27708)
			(xy 394.441387 -301.321776) (xy 394.406827 -301.361498) (xy 394.36641 -301.395242) (xy 394.321156 -301.422155)
			(xy 394.27221 -301.441559) (xy 394.246608 -301.447708) (xy 394.229082 -301.451518) (xy 394.20673 -301.479458)
			(xy 394.20673 -301.72025) (xy 394.229082 -301.74819) (xy 394.246608 -301.752) (xy 394.27045 -301.757749)
			(xy 394.316235 -301.775329) (xy 394.358922 -301.799475) (xy 394.397578 -301.829658) (xy 394.431354 -301.865216)
			(xy 394.459512 -301.905371) (xy 394.481434 -301.949242) (xy 394.49664 -301.995868) (xy 394.504796 -302.044229)
			(xy 394.505688 -302.068738) (xy 394.505688 -302.0695) (xy 394.506377 -302.079076) (xy 394.513943 -302.096704)
			(xy 394.517706 -302.100821) (xy 397.644622 -302.100821) (xy 397.644622 -302.048847) (xy 397.652752 -301.997512)
			(xy 397.668813 -301.948082) (xy 397.692409 -301.901772) (xy 397.722959 -301.859724) (xy 397.75971 -301.822973)
			(xy 397.801758 -301.792423) (xy 397.848068 -301.768827) (xy 397.897498 -301.752766) (xy 397.948833 -301.744636)
			(xy 398.000807 -301.744636) (xy 398.052142 -301.752766) (xy 398.101572 -301.768827) (xy 398.147882 -301.792423)
			(xy 398.18993 -301.822973) (xy 398.226681 -301.859724) (xy 398.257231 -301.901772) (xy 398.280827 -301.948082)
			(xy 398.296888 -301.997512) (xy 398.305018 -302.048847) (xy 398.305528 -302.074834) (xy 398.305018 -302.100821)
			(xy 398.594836 -302.100821) (xy 398.594836 -302.048847) (xy 398.602966 -301.997512) (xy 398.619027 -301.948082)
			(xy 398.642623 -301.901772) (xy 398.673173 -301.859724) (xy 398.709924 -301.822973) (xy 398.751972 -301.792423)
			(xy 398.798282 -301.768827) (xy 398.847712 -301.752766) (xy 398.899047 -301.744636) (xy 398.951021 -301.744636)
			(xy 399.002356 -301.752766) (xy 399.051786 -301.768827) (xy 399.098096 -301.792423) (xy 399.140144 -301.822973)
			(xy 399.176895 -301.859724) (xy 399.207445 -301.901772) (xy 399.231041 -301.948082) (xy 399.247102 -301.997512)
			(xy 399.255232 -302.048847) (xy 399.255742 -302.074834) (xy 399.255232 -302.100821) (xy 399.544796 -302.100821)
			(xy 399.544796 -302.048847) (xy 399.552926 -301.997512) (xy 399.568987 -301.948082) (xy 399.592583 -301.901772)
			(xy 399.623133 -301.859724) (xy 399.659884 -301.822973) (xy 399.701932 -301.792423) (xy 399.748242 -301.768827)
			(xy 399.797672 -301.752766) (xy 399.849007 -301.744636) (xy 399.900981 -301.744636) (xy 399.952316 -301.752766)
			(xy 400.001746 -301.768827) (xy 400.048056 -301.792423) (xy 400.090104 -301.822973) (xy 400.126855 -301.859724)
			(xy 400.157405 -301.901772) (xy 400.181001 -301.948082) (xy 400.197062 -301.997512) (xy 400.205192 -302.048847)
			(xy 400.205702 -302.074834) (xy 400.205192 -302.100821) (xy 400.494756 -302.100821) (xy 400.494756 -302.048847)
			(xy 400.502886 -301.997512) (xy 400.518947 -301.948082) (xy 400.542543 -301.901772) (xy 400.573093 -301.859724)
			(xy 400.609844 -301.822973) (xy 400.651892 -301.792423) (xy 400.698202 -301.768827) (xy 400.747632 -301.752766)
			(xy 400.798967 -301.744636) (xy 400.850941 -301.744636) (xy 400.902276 -301.752766) (xy 400.951706 -301.768827)
			(xy 400.998016 -301.792423) (xy 401.040064 -301.822973) (xy 401.076815 -301.859724) (xy 401.107365 -301.901772)
			(xy 401.130961 -301.948082) (xy 401.147022 -301.997512) (xy 401.155152 -302.048847) (xy 401.155662 -302.074834)
			(xy 401.155152 -302.100821) (xy 401.444716 -302.100821) (xy 401.444716 -302.048847) (xy 401.452846 -301.997512)
			(xy 401.468907 -301.948082) (xy 401.492503 -301.901772) (xy 401.523053 -301.859724) (xy 401.559804 -301.822973)
			(xy 401.601852 -301.792423) (xy 401.648162 -301.768827) (xy 401.697592 -301.752766) (xy 401.748927 -301.744636)
			(xy 401.800901 -301.744636) (xy 401.852236 -301.752766) (xy 401.901666 -301.768827) (xy 401.947976 -301.792423)
			(xy 401.990024 -301.822973) (xy 402.026775 -301.859724) (xy 402.057325 -301.901772) (xy 402.080921 -301.948082)
			(xy 402.096982 -301.997512) (xy 402.105112 -302.048847) (xy 402.105622 -302.074834) (xy 402.105112 -302.100821)
			(xy 402.394676 -302.100821) (xy 402.394676 -302.048847) (xy 402.402806 -301.997512) (xy 402.418867 -301.948082)
			(xy 402.442463 -301.901772) (xy 402.473013 -301.859724) (xy 402.509764 -301.822973) (xy 402.551812 -301.792423)
			(xy 402.598122 -301.768827) (xy 402.647552 -301.752766) (xy 402.698887 -301.744636) (xy 402.750861 -301.744636)
			(xy 402.802196 -301.752766) (xy 402.851626 -301.768827) (xy 402.897936 -301.792423) (xy 402.939984 -301.822973)
			(xy 402.976735 -301.859724) (xy 403.007285 -301.901772) (xy 403.030881 -301.948082) (xy 403.046942 -301.997512)
			(xy 403.055072 -302.048847) (xy 403.055582 -302.074834) (xy 403.055072 -302.100821) (xy 403.344636 -302.100821)
			(xy 403.344636 -302.048847) (xy 403.352766 -301.997512) (xy 403.368827 -301.948082) (xy 403.392423 -301.901772)
			(xy 403.422973 -301.859724) (xy 403.459724 -301.822973) (xy 403.501772 -301.792423) (xy 403.548082 -301.768827)
			(xy 403.597512 -301.752766) (xy 403.648847 -301.744636) (xy 403.700821 -301.744636) (xy 403.752156 -301.752766)
			(xy 403.801586 -301.768827) (xy 403.847896 -301.792423) (xy 403.889944 -301.822973) (xy 403.926695 -301.859724)
			(xy 403.957245 -301.901772) (xy 403.980841 -301.948082) (xy 403.996902 -301.997512) (xy 404.005032 -302.048847)
			(xy 404.005542 -302.074834) (xy 404.005032 -302.100821) (xy 404.294596 -302.100821) (xy 404.294596 -302.048847)
			(xy 404.302726 -301.997512) (xy 404.318787 -301.948082) (xy 404.342383 -301.901772) (xy 404.372933 -301.859724)
			(xy 404.409684 -301.822973) (xy 404.451732 -301.792423) (xy 404.498042 -301.768827) (xy 404.547472 -301.752766)
			(xy 404.598807 -301.744636) (xy 404.650781 -301.744636) (xy 404.702116 -301.752766) (xy 404.751546 -301.768827)
			(xy 404.797856 -301.792423) (xy 404.839904 -301.822973) (xy 404.876655 -301.859724) (xy 404.907205 -301.901772)
			(xy 404.930801 -301.948082) (xy 404.946862 -301.997512) (xy 404.954992 -302.048847) (xy 404.955502 -302.074834)
			(xy 404.954992 -302.100821) (xy 405.24481 -302.100821) (xy 405.24481 -302.048847) (xy 405.25294 -301.997512)
			(xy 405.269001 -301.948082) (xy 405.292597 -301.901772) (xy 405.323147 -301.859724) (xy 405.359898 -301.822973)
			(xy 405.401946 -301.792423) (xy 405.448256 -301.768827) (xy 405.497686 -301.752766) (xy 405.549021 -301.744636)
			(xy 405.600995 -301.744636) (xy 405.65233 -301.752766) (xy 405.70176 -301.768827) (xy 405.74807 -301.792423)
			(xy 405.790118 -301.822973) (xy 405.826869 -301.859724) (xy 405.857419 -301.901772) (xy 405.881015 -301.948082)
			(xy 405.897076 -301.997512) (xy 405.905206 -302.048847) (xy 405.905716 -302.074834) (xy 405.905206 -302.100821)
			(xy 406.19477 -302.100821) (xy 406.19477 -302.048847) (xy 406.2029 -301.997512) (xy 406.218961 -301.948082)
			(xy 406.242557 -301.901772) (xy 406.273107 -301.859724) (xy 406.309858 -301.822973) (xy 406.351906 -301.792423)
			(xy 406.398216 -301.768827) (xy 406.447646 -301.752766) (xy 406.498981 -301.744636) (xy 406.550955 -301.744636)
			(xy 406.60229 -301.752766) (xy 406.65172 -301.768827) (xy 406.69803 -301.792423) (xy 406.740078 -301.822973)
			(xy 406.776829 -301.859724) (xy 406.807379 -301.901772) (xy 406.830975 -301.948082) (xy 406.847036 -301.997512)
			(xy 406.855166 -302.048847) (xy 406.855676 -302.074834) (xy 406.855166 -302.100821) (xy 408.09469 -302.100821)
			(xy 408.09469 -302.048847) (xy 408.10282 -301.997512) (xy 408.118881 -301.948082) (xy 408.142477 -301.901772)
			(xy 408.173027 -301.859724) (xy 408.209778 -301.822973) (xy 408.251826 -301.792423) (xy 408.298136 -301.768827)
			(xy 408.347566 -301.752766) (xy 408.398901 -301.744636) (xy 408.450875 -301.744636) (xy 408.50221 -301.752766)
			(xy 408.55164 -301.768827) (xy 408.59795 -301.792423) (xy 408.639998 -301.822973) (xy 408.676749 -301.859724)
			(xy 408.707299 -301.901772) (xy 408.730895 -301.948082) (xy 408.746956 -301.997512) (xy 408.755086 -302.048847)
			(xy 408.755596 -302.074834) (xy 408.755086 -302.100821) (xy 409.04465 -302.100821) (xy 409.04465 -302.048847)
			(xy 409.05278 -301.997512) (xy 409.068841 -301.948082) (xy 409.092437 -301.901772) (xy 409.122987 -301.859724)
			(xy 409.159738 -301.822973) (xy 409.201786 -301.792423) (xy 409.248096 -301.768827) (xy 409.297526 -301.752766)
			(xy 409.348861 -301.744636) (xy 409.400835 -301.744636) (xy 409.45217 -301.752766) (xy 409.5016 -301.768827)
			(xy 409.54791 -301.792423) (xy 409.589958 -301.822973) (xy 409.626709 -301.859724) (xy 409.657259 -301.901772)
			(xy 409.680855 -301.948082) (xy 409.696916 -301.997512) (xy 409.705046 -302.048847) (xy 409.705556 -302.074834)
			(xy 409.705046 -302.100821) (xy 409.99461 -302.100821) (xy 409.99461 -302.048847) (xy 410.00274 -301.997512)
			(xy 410.018801 -301.948082) (xy 410.042397 -301.901772) (xy 410.072947 -301.859724) (xy 410.109698 -301.822973)
			(xy 410.151746 -301.792423) (xy 410.198056 -301.768827) (xy 410.247486 -301.752766) (xy 410.298821 -301.744636)
			(xy 410.350795 -301.744636) (xy 410.40213 -301.752766) (xy 410.45156 -301.768827) (xy 410.49787 -301.792423)
			(xy 410.539918 -301.822973) (xy 410.576669 -301.859724) (xy 410.607219 -301.901772) (xy 410.630815 -301.948082)
			(xy 410.646876 -301.997512) (xy 410.655006 -302.048847) (xy 410.655516 -302.074834) (xy 410.655006 -302.100821)
			(xy 410.944824 -302.100821) (xy 410.944824 -302.048847) (xy 410.952954 -301.997512) (xy 410.969015 -301.948082)
			(xy 410.992611 -301.901772) (xy 411.023161 -301.859724) (xy 411.059912 -301.822973) (xy 411.10196 -301.792423)
			(xy 411.14827 -301.768827) (xy 411.1977 -301.752766) (xy 411.249035 -301.744636) (xy 411.301009 -301.744636)
			(xy 411.352344 -301.752766) (xy 411.401774 -301.768827) (xy 411.448084 -301.792423) (xy 411.490132 -301.822973)
			(xy 411.526883 -301.859724) (xy 411.557433 -301.901772) (xy 411.581029 -301.948082) (xy 411.59709 -301.997512)
			(xy 411.60522 -302.048847) (xy 411.60573 -302.074834) (xy 411.60522 -302.100821) (xy 411.894784 -302.100821)
			(xy 411.894784 -302.048847) (xy 411.902914 -301.997512) (xy 411.918975 -301.948082) (xy 411.942571 -301.901772)
			(xy 411.973121 -301.859724) (xy 412.009872 -301.822973) (xy 412.05192 -301.792423) (xy 412.09823 -301.768827)
			(xy 412.14766 -301.752766) (xy 412.198995 -301.744636) (xy 412.250969 -301.744636) (xy 412.302304 -301.752766)
			(xy 412.351734 -301.768827) (xy 412.398044 -301.792423) (xy 412.440092 -301.822973) (xy 412.476843 -301.859724)
			(xy 412.507393 -301.901772) (xy 412.530989 -301.948082) (xy 412.54705 -301.997512) (xy 412.55518 -302.048847)
			(xy 412.55569 -302.074834) (xy 412.55518 -302.100821) (xy 412.844744 -302.100821) (xy 412.844744 -302.048847)
			(xy 412.852874 -301.997512) (xy 412.868935 -301.948082) (xy 412.892531 -301.901772) (xy 412.923081 -301.859724)
			(xy 412.959832 -301.822973) (xy 413.00188 -301.792423) (xy 413.04819 -301.768827) (xy 413.09762 -301.752766)
			(xy 413.148955 -301.744636) (xy 413.200929 -301.744636) (xy 413.252264 -301.752766) (xy 413.301694 -301.768827)
			(xy 413.348004 -301.792423) (xy 413.390052 -301.822973) (xy 413.426803 -301.859724) (xy 413.457353 -301.901772)
			(xy 413.480949 -301.948082) (xy 413.49701 -301.997512) (xy 413.50514 -302.048847) (xy 413.50565 -302.074834)
			(xy 413.50514 -302.100821) (xy 413.794704 -302.100821) (xy 413.794704 -302.048847) (xy 413.802834 -301.997512)
			(xy 413.818895 -301.948082) (xy 413.842491 -301.901772) (xy 413.873041 -301.859724) (xy 413.909792 -301.822973)
			(xy 413.95184 -301.792423) (xy 413.99815 -301.768827) (xy 414.04758 -301.752766) (xy 414.098915 -301.744636)
			(xy 414.150889 -301.744636) (xy 414.202224 -301.752766) (xy 414.251654 -301.768827) (xy 414.297964 -301.792423)
			(xy 414.340012 -301.822973) (xy 414.376763 -301.859724) (xy 414.407313 -301.901772) (xy 414.430909 -301.948082)
			(xy 414.44697 -301.997512) (xy 414.4551 -302.048847) (xy 414.45561 -302.074834) (xy 414.4551 -302.100821)
			(xy 414.744664 -302.100821) (xy 414.744664 -302.048847) (xy 414.752794 -301.997512) (xy 414.768855 -301.948082)
			(xy 414.792451 -301.901772) (xy 414.823001 -301.859724) (xy 414.859752 -301.822973) (xy 414.9018 -301.792423)
			(xy 414.94811 -301.768827) (xy 414.99754 -301.752766) (xy 415.048875 -301.744636) (xy 415.100849 -301.744636)
			(xy 415.152184 -301.752766) (xy 415.201614 -301.768827) (xy 415.247924 -301.792423) (xy 415.289972 -301.822973)
			(xy 415.326723 -301.859724) (xy 415.357273 -301.901772) (xy 415.380869 -301.948082) (xy 415.39693 -301.997512)
			(xy 415.40506 -302.048847) (xy 415.40557 -302.074834) (xy 415.40506 -302.100821) (xy 415.694624 -302.100821)
			(xy 415.694624 -302.048847) (xy 415.702754 -301.997512) (xy 415.718815 -301.948082) (xy 415.742411 -301.901772)
			(xy 415.772961 -301.859724) (xy 415.809712 -301.822973) (xy 415.85176 -301.792423) (xy 415.89807 -301.768827)
			(xy 415.9475 -301.752766) (xy 415.998835 -301.744636) (xy 416.050809 -301.744636) (xy 416.102144 -301.752766)
			(xy 416.151574 -301.768827) (xy 416.197884 -301.792423) (xy 416.239932 -301.822973) (xy 416.276683 -301.859724)
			(xy 416.307233 -301.901772) (xy 416.330829 -301.948082) (xy 416.34689 -301.997512) (xy 416.35502 -302.048847)
			(xy 416.35553 -302.074834) (xy 416.35502 -302.100821) (xy 416.644584 -302.100821) (xy 416.644584 -302.048847)
			(xy 416.652714 -301.997512) (xy 416.668775 -301.948082) (xy 416.692371 -301.901772) (xy 416.722921 -301.859724)
			(xy 416.759672 -301.822973) (xy 416.80172 -301.792423) (xy 416.84803 -301.768827) (xy 416.89746 -301.752766)
			(xy 416.948795 -301.744636) (xy 417.000769 -301.744636) (xy 417.052104 -301.752766) (xy 417.101534 -301.768827)
			(xy 417.147844 -301.792423) (xy 417.189892 -301.822973) (xy 417.226643 -301.859724) (xy 417.257193 -301.901772)
			(xy 417.280789 -301.948082) (xy 417.29685 -301.997512) (xy 417.30498 -302.048847) (xy 417.30549 -302.074834)
			(xy 417.30498 -302.100821) (xy 417.29685 -302.152156) (xy 417.280789 -302.201586) (xy 417.257193 -302.247896)
			(xy 417.226643 -302.289944) (xy 417.189892 -302.326695) (xy 417.147844 -302.357245) (xy 417.101534 -302.380841)
			(xy 417.052104 -302.396902) (xy 417.000769 -302.405032) (xy 416.948795 -302.405032) (xy 416.89746 -302.396902)
			(xy 416.84803 -302.380841) (xy 416.80172 -302.357245) (xy 416.759672 -302.326695) (xy 416.722921 -302.289944)
			(xy 416.692371 -302.247896) (xy 416.668775 -302.201586) (xy 416.652714 -302.152156) (xy 416.644584 -302.100821)
			(xy 416.35502 -302.100821) (xy 416.34689 -302.152156) (xy 416.330829 -302.201586) (xy 416.307233 -302.247896)
			(xy 416.276683 -302.289944) (xy 416.239932 -302.326695) (xy 416.197884 -302.357245) (xy 416.151574 -302.380841)
			(xy 416.102144 -302.396902) (xy 416.050809 -302.405032) (xy 415.998835 -302.405032) (xy 415.9475 -302.396902)
			(xy 415.89807 -302.380841) (xy 415.85176 -302.357245) (xy 415.809712 -302.326695) (xy 415.772961 -302.289944)
			(xy 415.742411 -302.247896) (xy 415.718815 -302.201586) (xy 415.702754 -302.152156) (xy 415.694624 -302.100821)
			(xy 415.40506 -302.100821) (xy 415.39693 -302.152156) (xy 415.380869 -302.201586) (xy 415.357273 -302.247896)
			(xy 415.326723 -302.289944) (xy 415.289972 -302.326695) (xy 415.247924 -302.357245) (xy 415.201614 -302.380841)
			(xy 415.152184 -302.396902) (xy 415.100849 -302.405032) (xy 415.048875 -302.405032) (xy 414.99754 -302.396902)
			(xy 414.94811 -302.380841) (xy 414.9018 -302.357245) (xy 414.859752 -302.326695) (xy 414.823001 -302.289944)
			(xy 414.792451 -302.247896) (xy 414.768855 -302.201586) (xy 414.752794 -302.152156) (xy 414.744664 -302.100821)
			(xy 414.4551 -302.100821) (xy 414.44697 -302.152156) (xy 414.430909 -302.201586) (xy 414.407313 -302.247896)
			(xy 414.376763 -302.289944) (xy 414.340012 -302.326695) (xy 414.297964 -302.357245) (xy 414.251654 -302.380841)
			(xy 414.202224 -302.396902) (xy 414.150889 -302.405032) (xy 414.098915 -302.405032) (xy 414.04758 -302.396902)
			(xy 413.99815 -302.380841) (xy 413.95184 -302.357245) (xy 413.909792 -302.326695) (xy 413.873041 -302.289944)
			(xy 413.842491 -302.247896) (xy 413.818895 -302.201586) (xy 413.802834 -302.152156) (xy 413.794704 -302.100821)
			(xy 413.50514 -302.100821) (xy 413.49701 -302.152156) (xy 413.480949 -302.201586) (xy 413.457353 -302.247896)
			(xy 413.426803 -302.289944) (xy 413.390052 -302.326695) (xy 413.348004 -302.357245) (xy 413.301694 -302.380841)
			(xy 413.252264 -302.396902) (xy 413.200929 -302.405032) (xy 413.148955 -302.405032) (xy 413.09762 -302.396902)
			(xy 413.04819 -302.380841) (xy 413.00188 -302.357245) (xy 412.959832 -302.326695) (xy 412.923081 -302.289944)
			(xy 412.892531 -302.247896) (xy 412.868935 -302.201586) (xy 412.852874 -302.152156) (xy 412.844744 -302.100821)
			(xy 412.55518 -302.100821) (xy 412.54705 -302.152156) (xy 412.530989 -302.201586) (xy 412.507393 -302.247896)
			(xy 412.476843 -302.289944) (xy 412.440092 -302.326695) (xy 412.398044 -302.357245) (xy 412.351734 -302.380841)
			(xy 412.302304 -302.396902) (xy 412.250969 -302.405032) (xy 412.198995 -302.405032) (xy 412.14766 -302.396902)
			(xy 412.09823 -302.380841) (xy 412.05192 -302.357245) (xy 412.009872 -302.326695) (xy 411.973121 -302.289944)
			(xy 411.942571 -302.247896) (xy 411.918975 -302.201586) (xy 411.902914 -302.152156) (xy 411.894784 -302.100821)
			(xy 411.60522 -302.100821) (xy 411.59709 -302.152156) (xy 411.581029 -302.201586) (xy 411.557433 -302.247896)
			(xy 411.526883 -302.289944) (xy 411.490132 -302.326695) (xy 411.448084 -302.357245) (xy 411.401774 -302.380841)
			(xy 411.352344 -302.396902) (xy 411.301009 -302.405032) (xy 411.249035 -302.405032) (xy 411.1977 -302.396902)
			(xy 411.14827 -302.380841) (xy 411.10196 -302.357245) (xy 411.059912 -302.326695) (xy 411.023161 -302.289944)
			(xy 410.992611 -302.247896) (xy 410.969015 -302.201586) (xy 410.952954 -302.152156) (xy 410.944824 -302.100821)
			(xy 410.655006 -302.100821) (xy 410.646876 -302.152156) (xy 410.630815 -302.201586) (xy 410.607219 -302.247896)
			(xy 410.576669 -302.289944) (xy 410.539918 -302.326695) (xy 410.49787 -302.357245) (xy 410.45156 -302.380841)
			(xy 410.40213 -302.396902) (xy 410.350795 -302.405032) (xy 410.298821 -302.405032) (xy 410.247486 -302.396902)
			(xy 410.198056 -302.380841) (xy 410.151746 -302.357245) (xy 410.109698 -302.326695) (xy 410.072947 -302.289944)
			(xy 410.042397 -302.247896) (xy 410.018801 -302.201586) (xy 410.00274 -302.152156) (xy 409.99461 -302.100821)
			(xy 409.705046 -302.100821) (xy 409.696916 -302.152156) (xy 409.680855 -302.201586) (xy 409.657259 -302.247896)
			(xy 409.626709 -302.289944) (xy 409.589958 -302.326695) (xy 409.54791 -302.357245) (xy 409.5016 -302.380841)
			(xy 409.45217 -302.396902) (xy 409.400835 -302.405032) (xy 409.348861 -302.405032) (xy 409.297526 -302.396902)
			(xy 409.248096 -302.380841) (xy 409.201786 -302.357245) (xy 409.159738 -302.326695) (xy 409.122987 -302.289944)
			(xy 409.092437 -302.247896) (xy 409.068841 -302.201586) (xy 409.05278 -302.152156) (xy 409.04465 -302.100821)
			(xy 408.755086 -302.100821) (xy 408.746956 -302.152156) (xy 408.730895 -302.201586) (xy 408.707299 -302.247896)
			(xy 408.676749 -302.289944) (xy 408.639998 -302.326695) (xy 408.59795 -302.357245) (xy 408.55164 -302.380841)
			(xy 408.50221 -302.396902) (xy 408.450875 -302.405032) (xy 408.398901 -302.405032) (xy 408.347566 -302.396902)
			(xy 408.298136 -302.380841) (xy 408.251826 -302.357245) (xy 408.209778 -302.326695) (xy 408.173027 -302.289944)
			(xy 408.142477 -302.247896) (xy 408.118881 -302.201586) (xy 408.10282 -302.152156) (xy 408.09469 -302.100821)
			(xy 406.855166 -302.100821) (xy 406.847036 -302.152156) (xy 406.830975 -302.201586) (xy 406.807379 -302.247896)
			(xy 406.776829 -302.289944) (xy 406.740078 -302.326695) (xy 406.69803 -302.357245) (xy 406.65172 -302.380841)
			(xy 406.60229 -302.396902) (xy 406.550955 -302.405032) (xy 406.498981 -302.405032) (xy 406.447646 -302.396902)
			(xy 406.398216 -302.380841) (xy 406.351906 -302.357245) (xy 406.309858 -302.326695) (xy 406.273107 -302.289944)
			(xy 406.242557 -302.247896) (xy 406.218961 -302.201586) (xy 406.2029 -302.152156) (xy 406.19477 -302.100821)
			(xy 405.905206 -302.100821) (xy 405.897076 -302.152156) (xy 405.881015 -302.201586) (xy 405.857419 -302.247896)
			(xy 405.826869 -302.289944) (xy 405.790118 -302.326695) (xy 405.74807 -302.357245) (xy 405.70176 -302.380841)
			(xy 405.65233 -302.396902) (xy 405.600995 -302.405032) (xy 405.549021 -302.405032) (xy 405.497686 -302.396902)
			(xy 405.448256 -302.380841) (xy 405.401946 -302.357245) (xy 405.359898 -302.326695) (xy 405.323147 -302.289944)
			(xy 405.292597 -302.247896) (xy 405.269001 -302.201586) (xy 405.25294 -302.152156) (xy 405.24481 -302.100821)
			(xy 404.954992 -302.100821) (xy 404.946862 -302.152156) (xy 404.930801 -302.201586) (xy 404.907205 -302.247896)
			(xy 404.876655 -302.289944) (xy 404.839904 -302.326695) (xy 404.797856 -302.357245) (xy 404.751546 -302.380841)
			(xy 404.702116 -302.396902) (xy 404.650781 -302.405032) (xy 404.598807 -302.405032) (xy 404.547472 -302.396902)
			(xy 404.498042 -302.380841) (xy 404.451732 -302.357245) (xy 404.409684 -302.326695) (xy 404.372933 -302.289944)
			(xy 404.342383 -302.247896) (xy 404.318787 -302.201586) (xy 404.302726 -302.152156) (xy 404.294596 -302.100821)
			(xy 404.005032 -302.100821) (xy 403.996902 -302.152156) (xy 403.980841 -302.201586) (xy 403.957245 -302.247896)
			(xy 403.926695 -302.289944) (xy 403.889944 -302.326695) (xy 403.847896 -302.357245) (xy 403.801586 -302.380841)
			(xy 403.752156 -302.396902) (xy 403.700821 -302.405032) (xy 403.648847 -302.405032) (xy 403.597512 -302.396902)
			(xy 403.548082 -302.380841) (xy 403.501772 -302.357245) (xy 403.459724 -302.326695) (xy 403.422973 -302.289944)
			(xy 403.392423 -302.247896) (xy 403.368827 -302.201586) (xy 403.352766 -302.152156) (xy 403.344636 -302.100821)
			(xy 403.055072 -302.100821) (xy 403.046942 -302.152156) (xy 403.030881 -302.201586) (xy 403.007285 -302.247896)
			(xy 402.976735 -302.289944) (xy 402.939984 -302.326695) (xy 402.897936 -302.357245) (xy 402.851626 -302.380841)
			(xy 402.802196 -302.396902) (xy 402.750861 -302.405032) (xy 402.698887 -302.405032) (xy 402.647552 -302.396902)
			(xy 402.598122 -302.380841) (xy 402.551812 -302.357245) (xy 402.509764 -302.326695) (xy 402.473013 -302.289944)
			(xy 402.442463 -302.247896) (xy 402.418867 -302.201586) (xy 402.402806 -302.152156) (xy 402.394676 -302.100821)
			(xy 402.105112 -302.100821) (xy 402.096982 -302.152156) (xy 402.080921 -302.201586) (xy 402.057325 -302.247896)
			(xy 402.026775 -302.289944) (xy 401.990024 -302.326695) (xy 401.947976 -302.357245) (xy 401.901666 -302.380841)
			(xy 401.852236 -302.396902) (xy 401.800901 -302.405032) (xy 401.748927 -302.405032) (xy 401.697592 -302.396902)
			(xy 401.648162 -302.380841) (xy 401.601852 -302.357245) (xy 401.559804 -302.326695) (xy 401.523053 -302.289944)
			(xy 401.492503 -302.247896) (xy 401.468907 -302.201586) (xy 401.452846 -302.152156) (xy 401.444716 -302.100821)
			(xy 401.155152 -302.100821) (xy 401.147022 -302.152156) (xy 401.130961 -302.201586) (xy 401.107365 -302.247896)
			(xy 401.076815 -302.289944) (xy 401.040064 -302.326695) (xy 400.998016 -302.357245) (xy 400.951706 -302.380841)
			(xy 400.902276 -302.396902) (xy 400.850941 -302.405032) (xy 400.798967 -302.405032) (xy 400.747632 -302.396902)
			(xy 400.698202 -302.380841) (xy 400.651892 -302.357245) (xy 400.609844 -302.326695) (xy 400.573093 -302.289944)
			(xy 400.542543 -302.247896) (xy 400.518947 -302.201586) (xy 400.502886 -302.152156) (xy 400.494756 -302.100821)
			(xy 400.205192 -302.100821) (xy 400.197062 -302.152156) (xy 400.181001 -302.201586) (xy 400.157405 -302.247896)
			(xy 400.126855 -302.289944) (xy 400.090104 -302.326695) (xy 400.048056 -302.357245) (xy 400.001746 -302.380841)
			(xy 399.952316 -302.396902) (xy 399.900981 -302.405032) (xy 399.849007 -302.405032) (xy 399.797672 -302.396902)
			(xy 399.748242 -302.380841) (xy 399.701932 -302.357245) (xy 399.659884 -302.326695) (xy 399.623133 -302.289944)
			(xy 399.592583 -302.247896) (xy 399.568987 -302.201586) (xy 399.552926 -302.152156) (xy 399.544796 -302.100821)
			(xy 399.255232 -302.100821) (xy 399.247102 -302.152156) (xy 399.231041 -302.201586) (xy 399.207445 -302.247896)
			(xy 399.176895 -302.289944) (xy 399.140144 -302.326695) (xy 399.098096 -302.357245) (xy 399.051786 -302.380841)
			(xy 399.002356 -302.396902) (xy 398.951021 -302.405032) (xy 398.899047 -302.405032) (xy 398.847712 -302.396902)
			(xy 398.798282 -302.380841) (xy 398.751972 -302.357245) (xy 398.709924 -302.326695) (xy 398.673173 -302.289944)
			(xy 398.642623 -302.247896) (xy 398.619027 -302.201586) (xy 398.602966 -302.152156) (xy 398.594836 -302.100821)
			(xy 398.305018 -302.100821) (xy 398.296888 -302.152156) (xy 398.280827 -302.201586) (xy 398.257231 -302.247896)
			(xy 398.226681 -302.289944) (xy 398.18993 -302.326695) (xy 398.147882 -302.357245) (xy 398.101572 -302.380841)
			(xy 398.052142 -302.396902) (xy 398.000807 -302.405032) (xy 397.948833 -302.405032) (xy 397.897498 -302.396902)
			(xy 397.848068 -302.380841) (xy 397.801758 -302.357245) (xy 397.75971 -302.326695) (xy 397.722959 -302.289944)
			(xy 397.692409 -302.247896) (xy 397.668813 -302.201586) (xy 397.652752 -302.152156) (xy 397.644622 -302.100821)
			(xy 394.517706 -302.100821) (xy 394.52042 -302.10379) (xy 394.757148 -302.340518) (xy 394.757656 -302.341026)
			(xy 394.765036 -302.347611) (xy 394.783335 -302.355064) (xy 394.793216 -302.355504) (xy 397.372586 -302.355504)
			(xy 397.382649 -302.355943) (xy 397.40123 -302.36368) (xy 397.408654 -302.37049) (xy 397.691356 -302.653192)
			(xy 397.698208 -302.660588) (xy 397.705953 -302.679186) (xy 397.706342 -302.68926) (xy 397.706342 -302.695102)
			(xy 397.721074 -302.719232) (xy 397.76019 -302.739552) (xy 397.767916 -302.743245) (xy 397.784842 -302.745767)
			(xy 397.801652 -302.742556) (xy 397.809212 -302.738536) (xy 397.834553 -302.724567) (xy 397.888912 -302.704749)
			(xy 397.94589 -302.694689) (xy 397.97482 -302.694086) (xy 398.000807 -302.694597) (xy 398.05214 -302.70273)
			(xy 398.101568 -302.718793) (xy 398.147876 -302.742391) (xy 398.189922 -302.772941) (xy 398.226672 -302.809693)
			(xy 398.25722 -302.851741) (xy 398.280814 -302.89805) (xy 398.296874 -302.94748) (xy 398.305005 -302.998813)
			(xy 398.305005 -303.050781) (xy 398.594836 -303.050781) (xy 398.594836 -302.998807) (xy 398.602966 -302.947472)
			(xy 398.619027 -302.898042) (xy 398.642623 -302.851732) (xy 398.673173 -302.809684) (xy 398.709924 -302.772933)
			(xy 398.751972 -302.742383) (xy 398.798282 -302.718787) (xy 398.847712 -302.702726) (xy 398.899047 -302.694596)
			(xy 398.951021 -302.694596) (xy 399.002356 -302.702726) (xy 399.051786 -302.718787) (xy 399.098096 -302.742383)
			(xy 399.140144 -302.772933) (xy 399.176895 -302.809684) (xy 399.207445 -302.851732) (xy 399.231041 -302.898042)
			(xy 399.247102 -302.947472) (xy 399.255232 -302.998807) (xy 399.255742 -303.024794) (xy 399.255232 -303.050781)
			(xy 399.544796 -303.050781) (xy 399.544796 -302.998807) (xy 399.552926 -302.947472) (xy 399.568987 -302.898042)
			(xy 399.592583 -302.851732) (xy 399.623133 -302.809684) (xy 399.659884 -302.772933) (xy 399.701932 -302.742383)
			(xy 399.748242 -302.718787) (xy 399.797672 -302.702726) (xy 399.849007 -302.694596) (xy 399.900981 -302.694596)
			(xy 399.952316 -302.702726) (xy 400.001746 -302.718787) (xy 400.048056 -302.742383) (xy 400.090104 -302.772933)
			(xy 400.126855 -302.809684) (xy 400.157405 -302.851732) (xy 400.181001 -302.898042) (xy 400.197062 -302.947472)
			(xy 400.205192 -302.998807) (xy 400.205702 -303.024794) (xy 400.205192 -303.050781) (xy 400.494756 -303.050781)
			(xy 400.494756 -302.998807) (xy 400.502886 -302.947472) (xy 400.518947 -302.898042) (xy 400.542543 -302.851732)
			(xy 400.573093 -302.809684) (xy 400.609844 -302.772933) (xy 400.651892 -302.742383) (xy 400.698202 -302.718787)
			(xy 400.747632 -302.702726) (xy 400.798967 -302.694596) (xy 400.850941 -302.694596) (xy 400.902276 -302.702726)
			(xy 400.951706 -302.718787) (xy 400.998016 -302.742383) (xy 401.040064 -302.772933) (xy 401.076815 -302.809684)
			(xy 401.107365 -302.851732) (xy 401.130961 -302.898042) (xy 401.147022 -302.947472) (xy 401.155152 -302.998807)
			(xy 401.155662 -303.024794) (xy 401.155152 -303.050781) (xy 401.444716 -303.050781) (xy 401.444716 -302.998807)
			(xy 401.452846 -302.947472) (xy 401.468907 -302.898042) (xy 401.492503 -302.851732) (xy 401.523053 -302.809684)
			(xy 401.559804 -302.772933) (xy 401.601852 -302.742383) (xy 401.648162 -302.718787) (xy 401.697592 -302.702726)
			(xy 401.748927 -302.694596) (xy 401.800901 -302.694596) (xy 401.852236 -302.702726) (xy 401.901666 -302.718787)
			(xy 401.947976 -302.742383) (xy 401.990024 -302.772933) (xy 402.026775 -302.809684) (xy 402.057325 -302.851732)
			(xy 402.080921 -302.898042) (xy 402.096982 -302.947472) (xy 402.105112 -302.998807) (xy 402.105622 -303.024794)
			(xy 402.105112 -303.050781) (xy 402.394676 -303.050781) (xy 402.394676 -302.998807) (xy 402.402806 -302.947472)
			(xy 402.418867 -302.898042) (xy 402.442463 -302.851732) (xy 402.473013 -302.809684) (xy 402.509764 -302.772933)
			(xy 402.551812 -302.742383) (xy 402.598122 -302.718787) (xy 402.647552 -302.702726) (xy 402.698887 -302.694596)
			(xy 402.750861 -302.694596) (xy 402.802196 -302.702726) (xy 402.851626 -302.718787) (xy 402.897936 -302.742383)
			(xy 402.939984 -302.772933) (xy 402.976735 -302.809684) (xy 403.007285 -302.851732) (xy 403.030881 -302.898042)
			(xy 403.046942 -302.947472) (xy 403.055072 -302.998807) (xy 403.055582 -303.024794) (xy 403.055072 -303.050781)
			(xy 403.344636 -303.050781) (xy 403.344636 -302.998807) (xy 403.352766 -302.947472) (xy 403.368827 -302.898042)
			(xy 403.392423 -302.851732) (xy 403.422973 -302.809684) (xy 403.459724 -302.772933) (xy 403.501772 -302.742383)
			(xy 403.548082 -302.718787) (xy 403.597512 -302.702726) (xy 403.648847 -302.694596) (xy 403.700821 -302.694596)
			(xy 403.752156 -302.702726) (xy 403.801586 -302.718787) (xy 403.847896 -302.742383) (xy 403.889944 -302.772933)
			(xy 403.926695 -302.809684) (xy 403.957245 -302.851732) (xy 403.980841 -302.898042) (xy 403.996902 -302.947472)
			(xy 404.005032 -302.998807) (xy 404.005542 -303.024794) (xy 404.005032 -303.050781) (xy 404.294596 -303.050781)
			(xy 404.294596 -302.998807) (xy 404.302726 -302.947472) (xy 404.318787 -302.898042) (xy 404.342383 -302.851732)
			(xy 404.372933 -302.809684) (xy 404.409684 -302.772933) (xy 404.451732 -302.742383) (xy 404.498042 -302.718787)
			(xy 404.547472 -302.702726) (xy 404.598807 -302.694596) (xy 404.650781 -302.694596) (xy 404.702116 -302.702726)
			(xy 404.751546 -302.718787) (xy 404.797856 -302.742383) (xy 404.839904 -302.772933) (xy 404.876655 -302.809684)
			(xy 404.907205 -302.851732) (xy 404.930801 -302.898042) (xy 404.946862 -302.947472) (xy 404.954992 -302.998807)
			(xy 404.955502 -303.024794) (xy 404.954992 -303.050781) (xy 405.24481 -303.050781) (xy 405.24481 -302.998807)
			(xy 405.25294 -302.947472) (xy 405.269001 -302.898042) (xy 405.292597 -302.851732) (xy 405.323147 -302.809684)
			(xy 405.359898 -302.772933) (xy 405.401946 -302.742383) (xy 405.448256 -302.718787) (xy 405.497686 -302.702726)
			(xy 405.549021 -302.694596) (xy 405.600995 -302.694596) (xy 405.65233 -302.702726) (xy 405.70176 -302.718787)
			(xy 405.74807 -302.742383) (xy 405.790118 -302.772933) (xy 405.826869 -302.809684) (xy 405.857419 -302.851732)
			(xy 405.881015 -302.898042) (xy 405.897076 -302.947472) (xy 405.905206 -302.998807) (xy 405.905716 -303.024794)
			(xy 405.905206 -303.050781) (xy 406.19477 -303.050781) (xy 406.19477 -302.998807) (xy 406.2029 -302.947472)
			(xy 406.218961 -302.898042) (xy 406.242557 -302.851732) (xy 406.273107 -302.809684) (xy 406.309858 -302.772933)
			(xy 406.351906 -302.742383) (xy 406.398216 -302.718787) (xy 406.447646 -302.702726) (xy 406.498981 -302.694596)
			(xy 406.550955 -302.694596) (xy 406.60229 -302.702726) (xy 406.65172 -302.718787) (xy 406.69803 -302.742383)
			(xy 406.740078 -302.772933) (xy 406.776829 -302.809684) (xy 406.807379 -302.851732) (xy 406.830975 -302.898042)
			(xy 406.847036 -302.947472) (xy 406.855166 -302.998807) (xy 406.855676 -303.024794) (xy 406.855166 -303.050781)
			(xy 408.09469 -303.050781) (xy 408.09469 -302.998807) (xy 408.10282 -302.947472) (xy 408.118881 -302.898042)
			(xy 408.142477 -302.851732) (xy 408.173027 -302.809684) (xy 408.209778 -302.772933) (xy 408.251826 -302.742383)
			(xy 408.298136 -302.718787) (xy 408.347566 -302.702726) (xy 408.398901 -302.694596) (xy 408.450875 -302.694596)
			(xy 408.50221 -302.702726) (xy 408.55164 -302.718787) (xy 408.59795 -302.742383) (xy 408.639998 -302.772933)
			(xy 408.676749 -302.809684) (xy 408.707299 -302.851732) (xy 408.730895 -302.898042) (xy 408.746956 -302.947472)
			(xy 408.755086 -302.998807) (xy 408.755596 -303.024794) (xy 408.755086 -303.050781) (xy 409.04465 -303.050781)
			(xy 409.04465 -302.998807) (xy 409.05278 -302.947472) (xy 409.068841 -302.898042) (xy 409.092437 -302.851732)
			(xy 409.122987 -302.809684) (xy 409.159738 -302.772933) (xy 409.201786 -302.742383) (xy 409.248096 -302.718787)
			(xy 409.297526 -302.702726) (xy 409.348861 -302.694596) (xy 409.400835 -302.694596) (xy 409.45217 -302.702726)
			(xy 409.5016 -302.718787) (xy 409.54791 -302.742383) (xy 409.589958 -302.772933) (xy 409.626709 -302.809684)
			(xy 409.657259 -302.851732) (xy 409.680855 -302.898042) (xy 409.696916 -302.947472) (xy 409.705046 -302.998807)
			(xy 409.705556 -303.024794) (xy 409.705046 -303.050781) (xy 409.99461 -303.050781) (xy 409.99461 -302.998807)
			(xy 410.00274 -302.947472) (xy 410.018801 -302.898042) (xy 410.042397 -302.851732) (xy 410.072947 -302.809684)
			(xy 410.109698 -302.772933) (xy 410.151746 -302.742383) (xy 410.198056 -302.718787) (xy 410.247486 -302.702726)
			(xy 410.298821 -302.694596) (xy 410.350795 -302.694596) (xy 410.40213 -302.702726) (xy 410.45156 -302.718787)
			(xy 410.49787 -302.742383) (xy 410.539918 -302.772933) (xy 410.576669 -302.809684) (xy 410.607219 -302.851732)
			(xy 410.630815 -302.898042) (xy 410.646876 -302.947472) (xy 410.655006 -302.998807) (xy 410.655516 -303.024794)
			(xy 410.655006 -303.050781) (xy 410.944824 -303.050781) (xy 410.944824 -302.998807) (xy 410.952954 -302.947472)
			(xy 410.969015 -302.898042) (xy 410.992611 -302.851732) (xy 411.023161 -302.809684) (xy 411.059912 -302.772933)
			(xy 411.10196 -302.742383) (xy 411.14827 -302.718787) (xy 411.1977 -302.702726) (xy 411.249035 -302.694596)
			(xy 411.301009 -302.694596) (xy 411.352344 -302.702726) (xy 411.401774 -302.718787) (xy 411.448084 -302.742383)
			(xy 411.490132 -302.772933) (xy 411.526883 -302.809684) (xy 411.557433 -302.851732) (xy 411.581029 -302.898042)
			(xy 411.59709 -302.947472) (xy 411.60522 -302.998807) (xy 411.60573 -303.024794) (xy 411.60522 -303.050781)
			(xy 411.894784 -303.050781) (xy 411.894784 -302.998807) (xy 411.902914 -302.947472) (xy 411.918975 -302.898042)
			(xy 411.942571 -302.851732) (xy 411.973121 -302.809684) (xy 412.009872 -302.772933) (xy 412.05192 -302.742383)
			(xy 412.09823 -302.718787) (xy 412.14766 -302.702726) (xy 412.198995 -302.694596) (xy 412.250969 -302.694596)
			(xy 412.302304 -302.702726) (xy 412.351734 -302.718787) (xy 412.398044 -302.742383) (xy 412.440092 -302.772933)
			(xy 412.476843 -302.809684) (xy 412.507393 -302.851732) (xy 412.530989 -302.898042) (xy 412.54705 -302.947472)
			(xy 412.55518 -302.998807) (xy 412.55569 -303.024794) (xy 412.55518 -303.050781) (xy 412.844744 -303.050781)
			(xy 412.844744 -302.998807) (xy 412.852874 -302.947472) (xy 412.868935 -302.898042) (xy 412.892531 -302.851732)
			(xy 412.923081 -302.809684) (xy 412.959832 -302.772933) (xy 413.00188 -302.742383) (xy 413.04819 -302.718787)
			(xy 413.09762 -302.702726) (xy 413.148955 -302.694596) (xy 413.200929 -302.694596) (xy 413.252264 -302.702726)
			(xy 413.301694 -302.718787) (xy 413.348004 -302.742383) (xy 413.390052 -302.772933) (xy 413.426803 -302.809684)
			(xy 413.457353 -302.851732) (xy 413.480949 -302.898042) (xy 413.49701 -302.947472) (xy 413.50514 -302.998807)
			(xy 413.50565 -303.024794) (xy 413.50514 -303.050781) (xy 413.794704 -303.050781) (xy 413.794704 -302.998807)
			(xy 413.802834 -302.947472) (xy 413.818895 -302.898042) (xy 413.842491 -302.851732) (xy 413.873041 -302.809684)
			(xy 413.909792 -302.772933) (xy 413.95184 -302.742383) (xy 413.99815 -302.718787) (xy 414.04758 -302.702726)
			(xy 414.098915 -302.694596) (xy 414.150889 -302.694596) (xy 414.202224 -302.702726) (xy 414.251654 -302.718787)
			(xy 414.297964 -302.742383) (xy 414.340012 -302.772933) (xy 414.376763 -302.809684) (xy 414.407313 -302.851732)
			(xy 414.430909 -302.898042) (xy 414.44697 -302.947472) (xy 414.4551 -302.998807) (xy 414.45561 -303.024794)
			(xy 414.4551 -303.050781) (xy 414.744664 -303.050781) (xy 414.744664 -302.998807) (xy 414.752794 -302.947472)
			(xy 414.768855 -302.898042) (xy 414.792451 -302.851732) (xy 414.823001 -302.809684) (xy 414.859752 -302.772933)
			(xy 414.9018 -302.742383) (xy 414.94811 -302.718787) (xy 414.99754 -302.702726) (xy 415.048875 -302.694596)
			(xy 415.100849 -302.694596) (xy 415.152184 -302.702726) (xy 415.201614 -302.718787) (xy 415.247924 -302.742383)
			(xy 415.289972 -302.772933) (xy 415.326723 -302.809684) (xy 415.357273 -302.851732) (xy 415.380869 -302.898042)
			(xy 415.39693 -302.947472) (xy 415.40506 -302.998807) (xy 415.40557 -303.024794) (xy 415.40506 -303.050781)
			(xy 415.694624 -303.050781) (xy 415.694624 -302.998807) (xy 415.702754 -302.947472) (xy 415.718815 -302.898042)
			(xy 415.742411 -302.851732) (xy 415.772961 -302.809684) (xy 415.809712 -302.772933) (xy 415.85176 -302.742383)
			(xy 415.89807 -302.718787) (xy 415.9475 -302.702726) (xy 415.998835 -302.694596) (xy 416.050809 -302.694596)
			(xy 416.102144 -302.702726) (xy 416.151574 -302.718787) (xy 416.197884 -302.742383) (xy 416.239932 -302.772933)
			(xy 416.276683 -302.809684) (xy 416.307233 -302.851732) (xy 416.330829 -302.898042) (xy 416.34689 -302.947472)
			(xy 416.35502 -302.998807) (xy 416.35553 -303.024794) (xy 416.35502 -303.050781) (xy 416.644584 -303.050781)
			(xy 416.644584 -302.998807) (xy 416.652714 -302.947472) (xy 416.668775 -302.898042) (xy 416.692371 -302.851732)
			(xy 416.722921 -302.809684) (xy 416.759672 -302.772933) (xy 416.80172 -302.742383) (xy 416.84803 -302.718787)
			(xy 416.89746 -302.702726) (xy 416.948795 -302.694596) (xy 417.000769 -302.694596) (xy 417.052104 -302.702726)
			(xy 417.101534 -302.718787) (xy 417.147844 -302.742383) (xy 417.189892 -302.772933) (xy 417.226643 -302.809684)
			(xy 417.257193 -302.851732) (xy 417.280789 -302.898042) (xy 417.29685 -302.947472) (xy 417.30498 -302.998807)
			(xy 417.30549 -303.024794) (xy 417.30498 -303.050781) (xy 417.29685 -303.102116) (xy 417.280789 -303.151546)
			(xy 417.257193 -303.197856) (xy 417.226643 -303.239904) (xy 417.189892 -303.276655) (xy 417.147844 -303.307205)
			(xy 417.101534 -303.330801) (xy 417.052104 -303.346862) (xy 417.000769 -303.354992) (xy 416.948795 -303.354992)
			(xy 416.89746 -303.346862) (xy 416.84803 -303.330801) (xy 416.80172 -303.307205) (xy 416.759672 -303.276655)
			(xy 416.722921 -303.239904) (xy 416.692371 -303.197856) (xy 416.668775 -303.151546) (xy 416.652714 -303.102116)
			(xy 416.644584 -303.050781) (xy 416.35502 -303.050781) (xy 416.34689 -303.102116) (xy 416.330829 -303.151546)
			(xy 416.307233 -303.197856) (xy 416.276683 -303.239904) (xy 416.239932 -303.276655) (xy 416.197884 -303.307205)
			(xy 416.151574 -303.330801) (xy 416.102144 -303.346862) (xy 416.050809 -303.354992) (xy 415.998835 -303.354992)
			(xy 415.9475 -303.346862) (xy 415.89807 -303.330801) (xy 415.85176 -303.307205) (xy 415.809712 -303.276655)
			(xy 415.772961 -303.239904) (xy 415.742411 -303.197856) (xy 415.718815 -303.151546) (xy 415.702754 -303.102116)
			(xy 415.694624 -303.050781) (xy 415.40506 -303.050781) (xy 415.39693 -303.102116) (xy 415.380869 -303.151546)
			(xy 415.357273 -303.197856) (xy 415.326723 -303.239904) (xy 415.289972 -303.276655) (xy 415.247924 -303.307205)
			(xy 415.201614 -303.330801) (xy 415.152184 -303.346862) (xy 415.100849 -303.354992) (xy 415.048875 -303.354992)
			(xy 414.99754 -303.346862) (xy 414.94811 -303.330801) (xy 414.9018 -303.307205) (xy 414.859752 -303.276655)
			(xy 414.823001 -303.239904) (xy 414.792451 -303.197856) (xy 414.768855 -303.151546) (xy 414.752794 -303.102116)
			(xy 414.744664 -303.050781) (xy 414.4551 -303.050781) (xy 414.44697 -303.102116) (xy 414.430909 -303.151546)
			(xy 414.407313 -303.197856) (xy 414.376763 -303.239904) (xy 414.340012 -303.276655) (xy 414.297964 -303.307205)
			(xy 414.251654 -303.330801) (xy 414.202224 -303.346862) (xy 414.150889 -303.354992) (xy 414.098915 -303.354992)
			(xy 414.04758 -303.346862) (xy 413.99815 -303.330801) (xy 413.95184 -303.307205) (xy 413.909792 -303.276655)
			(xy 413.873041 -303.239904) (xy 413.842491 -303.197856) (xy 413.818895 -303.151546) (xy 413.802834 -303.102116)
			(xy 413.794704 -303.050781) (xy 413.50514 -303.050781) (xy 413.49701 -303.102116) (xy 413.480949 -303.151546)
			(xy 413.457353 -303.197856) (xy 413.426803 -303.239904) (xy 413.390052 -303.276655) (xy 413.348004 -303.307205)
			(xy 413.301694 -303.330801) (xy 413.252264 -303.346862) (xy 413.200929 -303.354992) (xy 413.148955 -303.354992)
			(xy 413.09762 -303.346862) (xy 413.04819 -303.330801) (xy 413.00188 -303.307205) (xy 412.959832 -303.276655)
			(xy 412.923081 -303.239904) (xy 412.892531 -303.197856) (xy 412.868935 -303.151546) (xy 412.852874 -303.102116)
			(xy 412.844744 -303.050781) (xy 412.55518 -303.050781) (xy 412.54705 -303.102116) (xy 412.530989 -303.151546)
			(xy 412.507393 -303.197856) (xy 412.476843 -303.239904) (xy 412.440092 -303.276655) (xy 412.398044 -303.307205)
			(xy 412.351734 -303.330801) (xy 412.302304 -303.346862) (xy 412.250969 -303.354992) (xy 412.198995 -303.354992)
			(xy 412.14766 -303.346862) (xy 412.09823 -303.330801) (xy 412.05192 -303.307205) (xy 412.009872 -303.276655)
			(xy 411.973121 -303.239904) (xy 411.942571 -303.197856) (xy 411.918975 -303.151546) (xy 411.902914 -303.102116)
			(xy 411.894784 -303.050781) (xy 411.60522 -303.050781) (xy 411.59709 -303.102116) (xy 411.581029 -303.151546)
			(xy 411.557433 -303.197856) (xy 411.526883 -303.239904) (xy 411.490132 -303.276655) (xy 411.448084 -303.307205)
			(xy 411.401774 -303.330801) (xy 411.352344 -303.346862) (xy 411.301009 -303.354992) (xy 411.249035 -303.354992)
			(xy 411.1977 -303.346862) (xy 411.14827 -303.330801) (xy 411.10196 -303.307205) (xy 411.059912 -303.276655)
			(xy 411.023161 -303.239904) (xy 410.992611 -303.197856) (xy 410.969015 -303.151546) (xy 410.952954 -303.102116)
			(xy 410.944824 -303.050781) (xy 410.655006 -303.050781) (xy 410.646876 -303.102116) (xy 410.630815 -303.151546)
			(xy 410.607219 -303.197856) (xy 410.576669 -303.239904) (xy 410.539918 -303.276655) (xy 410.49787 -303.307205)
			(xy 410.45156 -303.330801) (xy 410.40213 -303.346862) (xy 410.350795 -303.354992) (xy 410.298821 -303.354992)
			(xy 410.247486 -303.346862) (xy 410.198056 -303.330801) (xy 410.151746 -303.307205) (xy 410.109698 -303.276655)
			(xy 410.072947 -303.239904) (xy 410.042397 -303.197856) (xy 410.018801 -303.151546) (xy 410.00274 -303.102116)
			(xy 409.99461 -303.050781) (xy 409.705046 -303.050781) (xy 409.696916 -303.102116) (xy 409.680855 -303.151546)
			(xy 409.657259 -303.197856) (xy 409.626709 -303.239904) (xy 409.589958 -303.276655) (xy 409.54791 -303.307205)
			(xy 409.5016 -303.330801) (xy 409.45217 -303.346862) (xy 409.400835 -303.354992) (xy 409.348861 -303.354992)
			(xy 409.297526 -303.346862) (xy 409.248096 -303.330801) (xy 409.201786 -303.307205) (xy 409.159738 -303.276655)
			(xy 409.122987 -303.239904) (xy 409.092437 -303.197856) (xy 409.068841 -303.151546) (xy 409.05278 -303.102116)
			(xy 409.04465 -303.050781) (xy 408.755086 -303.050781) (xy 408.746956 -303.102116) (xy 408.730895 -303.151546)
			(xy 408.707299 -303.197856) (xy 408.676749 -303.239904) (xy 408.639998 -303.276655) (xy 408.59795 -303.307205)
			(xy 408.55164 -303.330801) (xy 408.50221 -303.346862) (xy 408.450875 -303.354992) (xy 408.398901 -303.354992)
			(xy 408.347566 -303.346862) (xy 408.298136 -303.330801) (xy 408.251826 -303.307205) (xy 408.209778 -303.276655)
			(xy 408.173027 -303.239904) (xy 408.142477 -303.197856) (xy 408.118881 -303.151546) (xy 408.10282 -303.102116)
			(xy 408.09469 -303.050781) (xy 406.855166 -303.050781) (xy 406.847036 -303.102116) (xy 406.830975 -303.151546)
			(xy 406.807379 -303.197856) (xy 406.776829 -303.239904) (xy 406.740078 -303.276655) (xy 406.69803 -303.307205)
			(xy 406.65172 -303.330801) (xy 406.60229 -303.346862) (xy 406.550955 -303.354992) (xy 406.498981 -303.354992)
			(xy 406.447646 -303.346862) (xy 406.398216 -303.330801) (xy 406.351906 -303.307205) (xy 406.309858 -303.276655)
			(xy 406.273107 -303.239904) (xy 406.242557 -303.197856) (xy 406.218961 -303.151546) (xy 406.2029 -303.102116)
			(xy 406.19477 -303.050781) (xy 405.905206 -303.050781) (xy 405.897076 -303.102116) (xy 405.881015 -303.151546)
			(xy 405.857419 -303.197856) (xy 405.826869 -303.239904) (xy 405.790118 -303.276655) (xy 405.74807 -303.307205)
			(xy 405.70176 -303.330801) (xy 405.65233 -303.346862) (xy 405.600995 -303.354992) (xy 405.549021 -303.354992)
			(xy 405.497686 -303.346862) (xy 405.448256 -303.330801) (xy 405.401946 -303.307205) (xy 405.359898 -303.276655)
			(xy 405.323147 -303.239904) (xy 405.292597 -303.197856) (xy 405.269001 -303.151546) (xy 405.25294 -303.102116)
			(xy 405.24481 -303.050781) (xy 404.954992 -303.050781) (xy 404.946862 -303.102116) (xy 404.930801 -303.151546)
			(xy 404.907205 -303.197856) (xy 404.876655 -303.239904) (xy 404.839904 -303.276655) (xy 404.797856 -303.307205)
			(xy 404.751546 -303.330801) (xy 404.702116 -303.346862) (xy 404.650781 -303.354992) (xy 404.598807 -303.354992)
			(xy 404.547472 -303.346862) (xy 404.498042 -303.330801) (xy 404.451732 -303.307205) (xy 404.409684 -303.276655)
			(xy 404.372933 -303.239904) (xy 404.342383 -303.197856) (xy 404.318787 -303.151546) (xy 404.302726 -303.102116)
			(xy 404.294596 -303.050781) (xy 404.005032 -303.050781) (xy 403.996902 -303.102116) (xy 403.980841 -303.151546)
			(xy 403.957245 -303.197856) (xy 403.926695 -303.239904) (xy 403.889944 -303.276655) (xy 403.847896 -303.307205)
			(xy 403.801586 -303.330801) (xy 403.752156 -303.346862) (xy 403.700821 -303.354992) (xy 403.648847 -303.354992)
			(xy 403.597512 -303.346862) (xy 403.548082 -303.330801) (xy 403.501772 -303.307205) (xy 403.459724 -303.276655)
			(xy 403.422973 -303.239904) (xy 403.392423 -303.197856) (xy 403.368827 -303.151546) (xy 403.352766 -303.102116)
			(xy 403.344636 -303.050781) (xy 403.055072 -303.050781) (xy 403.046942 -303.102116) (xy 403.030881 -303.151546)
			(xy 403.007285 -303.197856) (xy 402.976735 -303.239904) (xy 402.939984 -303.276655) (xy 402.897936 -303.307205)
			(xy 402.851626 -303.330801) (xy 402.802196 -303.346862) (xy 402.750861 -303.354992) (xy 402.698887 -303.354992)
			(xy 402.647552 -303.346862) (xy 402.598122 -303.330801) (xy 402.551812 -303.307205) (xy 402.509764 -303.276655)
			(xy 402.473013 -303.239904) (xy 402.442463 -303.197856) (xy 402.418867 -303.151546) (xy 402.402806 -303.102116)
			(xy 402.394676 -303.050781) (xy 402.105112 -303.050781) (xy 402.096982 -303.102116) (xy 402.080921 -303.151546)
			(xy 402.057325 -303.197856) (xy 402.026775 -303.239904) (xy 401.990024 -303.276655) (xy 401.947976 -303.307205)
			(xy 401.901666 -303.330801) (xy 401.852236 -303.346862) (xy 401.800901 -303.354992) (xy 401.748927 -303.354992)
			(xy 401.697592 -303.346862) (xy 401.648162 -303.330801) (xy 401.601852 -303.307205) (xy 401.559804 -303.276655)
			(xy 401.523053 -303.239904) (xy 401.492503 -303.197856) (xy 401.468907 -303.151546) (xy 401.452846 -303.102116)
			(xy 401.444716 -303.050781) (xy 401.155152 -303.050781) (xy 401.147022 -303.102116) (xy 401.130961 -303.151546)
			(xy 401.107365 -303.197856) (xy 401.076815 -303.239904) (xy 401.040064 -303.276655) (xy 400.998016 -303.307205)
			(xy 400.951706 -303.330801) (xy 400.902276 -303.346862) (xy 400.850941 -303.354992) (xy 400.798967 -303.354992)
			(xy 400.747632 -303.346862) (xy 400.698202 -303.330801) (xy 400.651892 -303.307205) (xy 400.609844 -303.276655)
			(xy 400.573093 -303.239904) (xy 400.542543 -303.197856) (xy 400.518947 -303.151546) (xy 400.502886 -303.102116)
			(xy 400.494756 -303.050781) (xy 400.205192 -303.050781) (xy 400.197062 -303.102116) (xy 400.181001 -303.151546)
			(xy 400.157405 -303.197856) (xy 400.126855 -303.239904) (xy 400.090104 -303.276655) (xy 400.048056 -303.307205)
			(xy 400.001746 -303.330801) (xy 399.952316 -303.346862) (xy 399.900981 -303.354992) (xy 399.849007 -303.354992)
			(xy 399.797672 -303.346862) (xy 399.748242 -303.330801) (xy 399.701932 -303.307205) (xy 399.659884 -303.276655)
			(xy 399.623133 -303.239904) (xy 399.592583 -303.197856) (xy 399.568987 -303.151546) (xy 399.552926 -303.102116)
			(xy 399.544796 -303.050781) (xy 399.255232 -303.050781) (xy 399.247102 -303.102116) (xy 399.231041 -303.151546)
			(xy 399.207445 -303.197856) (xy 399.176895 -303.239904) (xy 399.140144 -303.276655) (xy 399.098096 -303.307205)
			(xy 399.051786 -303.330801) (xy 399.002356 -303.346862) (xy 398.951021 -303.354992) (xy 398.899047 -303.354992)
			(xy 398.847712 -303.346862) (xy 398.798282 -303.330801) (xy 398.751972 -303.307205) (xy 398.709924 -303.276655)
			(xy 398.673173 -303.239904) (xy 398.642623 -303.197856) (xy 398.619027 -303.151546) (xy 398.602966 -303.102116)
			(xy 398.594836 -303.050781) (xy 398.305005 -303.050781) (xy 398.305005 -303.050787) (xy 398.296874 -303.10212)
			(xy 398.280814 -303.15155) (xy 398.25722 -303.197859) (xy 398.226672 -303.239907) (xy 398.189922 -303.276659)
			(xy 398.147876 -303.307209) (xy 398.101568 -303.330807) (xy 398.05214 -303.34687) (xy 398.000807 -303.355003)
			(xy 397.97482 -303.355502) (xy 397.95295 -303.355151) (xy 397.90959 -303.349393) (xy 397.867366 -303.337973)
			(xy 397.847058 -303.329848) (xy 397.83512 -303.324768) (xy 397.810228 -303.327308) (xy 397.728948 -303.38141)
			(xy 397.718889 -303.388928) (xy 397.707039 -303.411035) (xy 397.706342 -303.423574) (xy 397.706342 -303.575974)
			(xy 397.70698 -303.588532) (xy 397.718833 -303.610671) (xy 397.728948 -303.618138) (xy 397.810228 -303.67224)
			(xy 397.83512 -303.67478) (xy 397.847058 -303.6697) (xy 397.867369 -303.661583) (xy 397.909591 -303.650163)
			(xy 397.95295 -303.644403) (xy 397.97482 -303.644046) (xy 398.000807 -303.644557) (xy 398.052142 -303.65269)
			(xy 398.101573 -303.668752) (xy 398.147883 -303.692348) (xy 398.189932 -303.722897) (xy 398.226686 -303.759648)
			(xy 398.257238 -303.801695) (xy 398.280838 -303.848003) (xy 398.296904 -303.897432) (xy 398.305041 -303.948767)
			(xy 398.305528 -303.974754) (xy 398.304974 -304.002372) (xy 398.295794 -304.05684) (xy 398.277683 -304.109022)
			(xy 398.264888 -304.133504) (xy 398.258284 -304.145442) (xy 398.258792 -304.172112) (xy 398.310354 -304.25898)
			(xy 398.31515 -304.266362) (xy 398.3287 -304.277579) (xy 398.345247 -304.283549) (xy 398.354042 -304.283872)
		)
		(stroke
			(width 0)
			(type solid)
		)
		(fill yes)
		(layer "In9.Cu")
		(net "P1V8_PEX")
	)
	(gr_poly
		(pts
			(xy 200.605898 -417.980622) (xy 200.615969 -417.9802) (xy 200.634576 -417.972489) (xy 200.641966 -417.965636)
			(xy 201.16419 -417.443412) (xy 201.17104 -417.436015) (xy 201.17878 -417.417417) (xy 201.179176 -417.407344)
			(xy 201.179176 -415.115248) (xy 201.178743 -415.105183) (xy 201.171012 -415.086594) (xy 201.16419 -415.07918)
			(xy 200.878694 -414.793684) (xy 200.871299 -414.786829) (xy 200.8527 -414.779084) (xy 200.842626 -414.778698)
			(xy 187.929012 -414.778698) (xy 187.919721 -414.779116) (xy 187.902356 -414.785736) (xy 187.888468 -414.798085)
			(xy 187.8838 -414.80613) (xy 187.835794 -414.899094) (xy 187.837826 -414.927288) (xy 187.845954 -414.938972)
			(xy 187.86248 -414.963252) (xy 187.888662 -415.015823) (xy 187.90647 -415.071789) (xy 187.915481 -415.129825)
			(xy 187.916058 -415.15919) (xy 187.915572 -415.186441) (xy 187.907816 -415.240389) (xy 187.892461 -415.292684)
			(xy 187.869819 -415.342261) (xy 187.840353 -415.388111) (xy 187.804662 -415.429302) (xy 187.763471 -415.464993)
			(xy 187.717621 -415.494459) (xy 187.668044 -415.517101) (xy 187.615749 -415.532456) (xy 187.561801 -415.540212)
			(xy 187.507299 -415.540212) (xy 187.453351 -415.532456) (xy 187.401056 -415.517101) (xy 187.351479 -415.494459)
			(xy 187.305629 -415.464993) (xy 187.264438 -415.429302) (xy 187.228747 -415.388111) (xy 187.199281 -415.342261)
			(xy 187.176639 -415.292684) (xy 187.161284 -415.240389) (xy 187.153528 -415.186441) (xy 187.153042 -415.15919)
			(xy 187.153604 -415.129825) (xy 187.162641 -415.071795) (xy 187.180454 -415.015831) (xy 187.206624 -414.963254)
			(xy 187.223146 -414.938972) (xy 187.231274 -414.927288) (xy 187.233306 -414.899094) (xy 187.1853 -414.80613)
			(xy 187.180671 -414.798049) (xy 187.166791 -414.785658) (xy 187.149393 -414.779063) (xy 187.140088 -414.778698)
			(xy 185.492136 -414.778698) (xy 185.482071 -414.778263) (xy 185.463484 -414.770532) (xy 185.456068 -414.763712)
			(xy 184.429654 -413.737298) (xy 184.422802 -413.729902) (xy 184.41506 -413.711303) (xy 184.414668 -413.70123)
			(xy 184.414668 -363.339634) (xy 184.415171 -363.329582) (xy 184.422888 -363.311017) (xy 184.429654 -363.303566)
			(xy 187.450984 -360.282236) (xy 187.458385 -360.275399) (xy 187.476984 -360.267689) (xy 187.487052 -360.26725)
			(xy 198.004176 -360.26725) (xy 198.014239 -360.266812) (xy 198.032819 -360.259072) (xy 198.040244 -360.252264)
			(xy 201.582528 -360.252264) (xy 201.591316 -360.25189) (xy 201.607851 -360.245932) (xy 201.621393 -360.234729)
			(xy 201.626216 -360.227372) (xy 201.670666 -360.15168) (xy 201.674836 -360.143926) (xy 201.678134 -360.126645)
			(xy 201.675344 -360.109275) (xy 201.671428 -360.101388) (xy 201.656429 -360.072944) (xy 201.635149 -360.012268)
			(xy 201.624361 -359.94888) (xy 201.623676 -359.91673) (xy 201.623676 -359.916222) (xy 201.624061 -359.892342)
			(xy 201.630044 -359.844958) (xy 201.635614 -359.821734) (xy 201.635614 -359.82148) (xy 201.637524 -359.812578)
			(xy 201.635621 -359.794485) (xy 201.627506 -359.778202) (xy 201.621136 -359.771696) (xy 201.545444 -359.701592)
			(xy 201.518012 -359.69575) (xy 201.505058 -359.700068) (xy 201.475628 -359.709327) (xy 201.414746 -359.719291)
			(xy 201.3839 -359.71988) (xy 201.383392 -359.71988) (xy 201.356143 -359.719393) (xy 201.302201 -359.711637)
			(xy 201.249911 -359.696282) (xy 201.200339 -359.673642) (xy 201.154493 -359.644178) (xy 201.113307 -359.60849)
			(xy 201.077619 -359.567304) (xy 201.048156 -359.521457) (xy 201.025517 -359.471885) (xy 201.010163 -359.419595)
			(xy 201.002406 -359.365653) (xy 201.002406 -359.311155) (xy 201.010161 -359.257213) (xy 201.025514 -359.204923)
			(xy 201.048152 -359.15535) (xy 201.077614 -359.109503) (xy 201.113301 -359.068316) (xy 201.154487 -359.032626)
			(xy 201.200332 -359.003161) (xy 201.249904 -358.980521) (xy 201.302193 -358.965165) (xy 201.356135 -358.957407)
			(xy 201.410633 -358.957405) (xy 201.464576 -358.965158) (xy 201.516866 -358.98051) (xy 201.56644 -359.003146)
			(xy 201.612288 -359.032607) (xy 201.653476 -359.068293) (xy 201.689166 -359.109477) (xy 201.718633 -359.155321)
			(xy 201.741275 -359.204893) (xy 201.756632 -359.257181) (xy 201.764392 -359.311123) (xy 201.7649 -359.338372)
			(xy 201.7649 -359.33888) (xy 201.764515 -359.36276) (xy 201.758531 -359.410144) (xy 201.752962 -359.433368)
			(xy 201.752962 -359.433622) (xy 201.751053 -359.442524) (xy 201.752956 -359.460617) (xy 201.761068 -359.476902)
			(xy 201.76744 -359.483406) (xy 201.843132 -359.55351) (xy 201.870564 -359.559352) (xy 201.883518 -359.555034)
			(xy 201.912949 -359.545781) (xy 201.973831 -359.535829) (xy 202.004676 -359.535222) (xy 202.005184 -359.535222)
			(xy 202.032437 -359.535684) (xy 202.086388 -359.54344) (xy 202.138686 -359.558795) (xy 202.188266 -359.581437)
			(xy 202.234119 -359.610905) (xy 202.275311 -359.646599) (xy 202.311004 -359.687792) (xy 202.34047 -359.733646)
			(xy 202.36311 -359.783227) (xy 202.378463 -359.835526) (xy 202.386217 -359.889477) (xy 202.386692 -359.91673)
			(xy 202.386004 -359.948878) (xy 202.375192 -360.01226) (xy 202.35393 -360.07294) (xy 202.33894 -360.101388)
			(xy 202.332336 -360.113326) (xy 202.33259 -360.139996) (xy 202.384152 -360.227372) (xy 202.388955 -360.234744)
			(xy 202.402509 -360.24594) (xy 202.41905 -360.2519) (xy 202.42784 -360.252264) (xy 235.33989 -360.252264)
			(xy 235.34996 -360.251842) (xy 235.368564 -360.244126) (xy 235.375958 -360.237278) (xy 236.82071 -358.792526)
			(xy 236.827555 -358.785128) (xy 236.835276 -358.766528) (xy 236.835696 -358.756458) (xy 236.835696 -358.012492)
			(xy 236.835271 -358.002423) (xy 236.827554 -357.983821) (xy 236.82071 -357.976424) (xy 236.244638 -357.400606)
			(xy 236.223903 -357.37903) (xy 236.18874 -357.330613) (xy 236.16158 -357.277294) (xy 236.14309 -357.220385)
			(xy 236.133724 -357.161285) (xy 236.133132 -357.131366) (xy 236.133132 -357.130858) (xy 236.13362 -357.103627)
			(xy 236.141377 -357.049719) (xy 236.156725 -356.997463) (xy 236.179353 -356.947923) (xy 236.208801 -356.902107)
			(xy 236.244468 -356.860949) (xy 236.28563 -356.825284) (xy 236.331448 -356.79584) (xy 236.380989 -356.773215)
			(xy 236.433246 -356.757871) (xy 236.487154 -356.750118) (xy 236.514386 -356.749604) (xy 236.514894 -356.749604)
			(xy 236.544811 -356.75021) (xy 236.603905 -356.759594) (xy 236.66081 -356.778087) (xy 236.714132 -356.805235)
			(xy 236.762563 -356.840372) (xy 236.784134 -356.86111) (xy 237.130082 -357.207058) (xy 237.137481 -357.213749)
			(xy 237.155896 -357.221365) (xy 237.175824 -357.22138) (xy 237.1852 -357.21798) (xy 237.199678 -357.212138)
			(xy 237.216696 -357.186484) (xy 237.216696 -356.463092) (xy 237.216271 -356.453023) (xy 237.208554 -356.434421)
			(xy 237.20171 -356.427024) (xy 237.038388 -356.263702) (xy 237.028816 -356.255215) (xy 237.004297 -356.248034)
			(xy 236.991652 -356.249986) (xy 236.89564 -356.271068) (xy 236.876082 -356.287832) (xy 236.87151 -356.300024)
			(xy 236.860842 -356.326882) (xy 236.832578 -356.377287) (xy 236.797034 -356.42285) (xy 236.755023 -356.462531)
			(xy 236.707507 -356.495419) (xy 236.655573 -356.520763) (xy 236.60041 -356.537983) (xy 236.54328 -356.546683)
			(xy 236.514386 -356.547166) (xy 236.487135 -356.546702) (xy 236.433188 -356.538943) (xy 236.380894 -356.523585)
			(xy 236.331318 -356.500941) (xy 236.28547 -356.471472) (xy 236.244282 -356.435778) (xy 236.208594 -356.394585)
			(xy 236.179132 -356.348733) (xy 236.156495 -356.299153) (xy 236.141145 -356.246857) (xy 236.133394 -356.192909)
			(xy 236.132878 -356.165658) (xy 236.133413 -356.136769) (xy 236.142129 -356.079652) (xy 236.159356 -356.024502)
			(xy 236.184699 -355.972579) (xy 236.21758 -355.92507) (xy 236.257247 -355.88306) (xy 236.302794 -355.84751)
			(xy 236.353179 -355.819232) (xy 236.38002 -355.808534) (xy 236.392212 -355.803962) (xy 236.408976 -355.784404)
			(xy 236.430058 -355.688392) (xy 236.431576 -355.680029) (xy 236.429571 -355.663162) (xy 236.422111 -355.647901)
			(xy 236.416342 -355.641656) (xy 236.244638 -355.470206) (xy 236.223903 -355.44863) (xy 236.18874 -355.400213)
			(xy 236.16158 -355.346894) (xy 236.14309 -355.289985) (xy 236.133724 -355.230885) (xy 236.133132 -355.200966)
			(xy 236.133132 -355.200458) (xy 236.13362 -355.173227) (xy 236.141377 -355.119319) (xy 236.156725 -355.067063)
			(xy 236.179353 -355.017523) (xy 236.208801 -354.971707) (xy 236.244468 -354.930549) (xy 236.28563 -354.894884)
			(xy 236.331448 -354.86544) (xy 236.380989 -354.842815) (xy 236.433246 -354.827471) (xy 236.487154 -354.819718)
			(xy 236.514386 -354.819204) (xy 236.514894 -354.819204) (xy 236.544811 -354.81981) (xy 236.603905 -354.829194)
			(xy 236.66081 -354.847687) (xy 236.714132 -354.874835) (xy 236.762563 -354.909972) (xy 236.784134 -354.93071)
			(xy 237.053882 -355.200458) (xy 238.265968 -355.200458) (xy 238.270039 -355.144836) (xy 238.282165 -355.090399)
			(xy 238.302088 -355.038308) (xy 238.329384 -354.989673) (xy 238.36347 -354.94553) (xy 238.403619 -354.906821)
			(xy 238.448977 -354.87437) (xy 238.498577 -354.848869) (xy 238.551361 -354.830862) (xy 238.606204 -354.820732)
			(xy 238.661938 -354.818695) (xy 238.717375 -354.824795) (xy 238.771332 -354.838901) (xy 238.822661 -354.860713)
			(xy 238.870267 -354.889767) (xy 238.88284 -354.90023) (xy 248.54992 -354.90023) (xy 248.553991 -354.844608)
			(xy 248.566117 -354.790171) (xy 248.58604 -354.73808) (xy 248.613336 -354.689445) (xy 248.647422 -354.645302)
			(xy 248.687571 -354.606593) (xy 248.732929 -354.574142) (xy 248.782529 -354.548641) (xy 248.835313 -354.530634)
			(xy 248.890156 -354.520504) (xy 248.94589 -354.518467) (xy 249.001327 -354.524567) (xy 249.055284 -354.538673)
			(xy 249.106613 -354.560485) (xy 249.154219 -354.589539) (xy 249.197087 -354.625214) (xy 249.234304 -354.666751)
			(xy 249.265077 -354.713264) (xy 249.288749 -354.763761) (xy 249.304817 -354.817168) (xy 249.312937 -354.872344)
			(xy 249.313446 -354.90023) (xy 249.312937 -354.928116) (xy 249.304817 -354.983292) (xy 249.288749 -355.036699)
			(xy 249.265077 -355.087196) (xy 249.234304 -355.133709) (xy 249.21 -355.160834) (xy 249.921774 -355.160834)
			(xy 249.925845 -355.105212) (xy 249.937971 -355.050775) (xy 249.957894 -354.998684) (xy 249.98519 -354.950049)
			(xy 250.019276 -354.905906) (xy 250.059425 -354.867197) (xy 250.104783 -354.834746) (xy 250.154383 -354.809245)
			(xy 250.207167 -354.791238) (xy 250.26201 -354.781108) (xy 250.317744 -354.779071) (xy 250.373181 -354.785171)
			(xy 250.427138 -354.799277) (xy 250.478467 -354.821089) (xy 250.526073 -354.850143) (xy 250.568941 -354.885818)
			(xy 250.606158 -354.927355) (xy 250.636931 -354.973868) (xy 250.660603 -355.024365) (xy 250.676671 -355.077772)
			(xy 250.684791 -355.132948) (xy 250.6853 -355.160834) (xy 250.684791 -355.18872) (xy 250.676671 -355.243896)
			(xy 250.660603 -355.297303) (xy 250.636931 -355.3478) (xy 250.606158 -355.394313) (xy 250.568941 -355.43585)
			(xy 250.526073 -355.471525) (xy 250.478467 -355.500579) (xy 250.427138 -355.522391) (xy 250.373181 -355.536497)
			(xy 250.317744 -355.542597) (xy 250.26201 -355.54056) (xy 250.207167 -355.53043) (xy 250.154383 -355.512423)
			(xy 250.104783 -355.486922) (xy 250.059425 -355.454471) (xy 250.019276 -355.415762) (xy 249.98519 -355.371619)
			(xy 249.957894 -355.322984) (xy 249.937971 -355.270893) (xy 249.925845 -355.216456) (xy 249.921774 -355.160834)
			(xy 249.21 -355.160834) (xy 249.197087 -355.175246) (xy 249.154219 -355.210921) (xy 249.106613 -355.239975)
			(xy 249.055284 -355.261787) (xy 249.001327 -355.275893) (xy 248.94589 -355.281993) (xy 248.890156 -355.279956)
			(xy 248.835313 -355.269826) (xy 248.782529 -355.251819) (xy 248.732929 -355.226318) (xy 248.687571 -355.193867)
			(xy 248.647422 -355.155158) (xy 248.613336 -355.111015) (xy 248.58604 -355.06238) (xy 248.566117 -355.010289)
			(xy 248.553991 -354.955852) (xy 248.54992 -354.90023) (xy 238.88284 -354.90023) (xy 238.913135 -354.925442)
			(xy 238.950352 -354.966979) (xy 238.981125 -355.013492) (xy 239.004797 -355.063989) (xy 239.020865 -355.117396)
			(xy 239.028985 -355.172572) (xy 239.029494 -355.200458) (xy 239.028985 -355.228344) (xy 239.020865 -355.28352)
			(xy 239.004797 -355.336927) (xy 238.981125 -355.387424) (xy 238.950352 -355.433937) (xy 238.913135 -355.475474)
			(xy 238.870267 -355.511149) (xy 238.822661 -355.540203) (xy 238.771332 -355.562015) (xy 238.717375 -355.576121)
			(xy 238.661938 -355.582221) (xy 238.606204 -355.580184) (xy 238.551361 -355.570054) (xy 238.498577 -355.552047)
			(xy 238.448977 -355.526546) (xy 238.403619 -355.494095) (xy 238.36347 -355.455386) (xy 238.329384 -355.411243)
			(xy 238.302088 -355.362608) (xy 238.282165 -355.310517) (xy 238.270039 -355.25608) (xy 238.265968 -355.200458)
			(xy 237.053882 -355.200458) (xy 237.867698 -356.014274) (xy 237.888433 -356.035851) (xy 237.923594 -356.084268)
			(xy 237.950755 -356.137586) (xy 237.959876 -356.165658) (xy 238.265968 -356.165658) (xy 238.270039 -356.110036)
			(xy 238.282165 -356.055599) (xy 238.302088 -356.003508) (xy 238.329384 -355.954873) (xy 238.36347 -355.91073)
			(xy 238.403619 -355.872021) (xy 238.448977 -355.83957) (xy 238.498577 -355.814069) (xy 238.551361 -355.796062)
			(xy 238.606204 -355.785932) (xy 238.661938 -355.783895) (xy 238.717375 -355.789995) (xy 238.771332 -355.804101)
			(xy 238.822661 -355.825913) (xy 238.870267 -355.854967) (xy 238.913135 -355.890642) (xy 238.950352 -355.932179)
			(xy 238.981125 -355.978692) (xy 239.004797 -356.029189) (xy 239.008878 -356.042752) (xy 249.589499 -356.042752)
			(xy 249.589499 -355.988248) (xy 249.597257 -355.9343) (xy 249.612613 -355.882004) (xy 249.635256 -355.832427)
			(xy 249.664725 -355.786577) (xy 249.700419 -355.745388) (xy 249.741612 -355.709698) (xy 249.787466 -355.680235)
			(xy 249.837046 -355.657598) (xy 249.889343 -355.642247) (xy 249.943292 -355.634496) (xy 249.970544 -355.634036)
			(xy 249.99946 -355.634581) (xy 250.056631 -355.643302) (xy 250.11183 -355.660554) (xy 250.163792 -355.685941)
			(xy 250.211326 -355.71888) (xy 250.253344 -355.758618) (xy 250.271534 -355.781102) (xy 250.279136 -355.789915)
			(xy 250.30004 -355.800095) (xy 250.311666 -355.80066) (xy 250.391422 -355.80066) (xy 250.403056 -355.800133)
			(xy 250.423966 -355.789937) (xy 250.431554 -355.781102) (xy 250.449771 -355.758641) (xy 250.491786 -355.718904)
			(xy 250.539315 -355.685963) (xy 250.591271 -355.66057) (xy 250.646464 -355.643309) (xy 250.70363 -355.634574)
			(xy 250.732544 -355.634036) (xy 250.759796 -355.634437) (xy 250.813746 -355.642199) (xy 250.866041 -355.65756)
			(xy 250.915618 -355.680206) (xy 250.961469 -355.709677) (xy 251.002658 -355.745373) (xy 251.038349 -355.786567)
			(xy 251.067815 -355.83242) (xy 251.090455 -355.882) (xy 251.10581 -355.934298) (xy 251.113566 -355.988248)
			(xy 251.113566 -356.042752) (xy 251.10581 -356.096702) (xy 251.090455 -356.149) (xy 251.067815 -356.19858)
			(xy 251.038349 -356.244433) (xy 251.002658 -356.285627) (xy 250.961469 -356.321323) (xy 250.915618 -356.350794)
			(xy 250.866041 -356.37344) (xy 250.813746 -356.388801) (xy 250.759796 -356.396563) (xy 250.732544 -356.397052)
			(xy 250.703627 -356.39652) (xy 250.646456 -356.387797) (xy 250.591257 -356.370543) (xy 250.539294 -356.345154)
			(xy 250.49176 -356.312211) (xy 250.449744 -356.272471) (xy 250.431554 -356.249986) (xy 250.423959 -356.241166)
			(xy 250.403049 -356.23099) (xy 250.391422 -356.230428) (xy 250.311666 -356.230428) (xy 250.300032 -356.230952)
			(xy 250.279122 -356.241151) (xy 250.271534 -356.249986) (xy 250.25332 -356.27245) (xy 250.211306 -356.312187)
			(xy 250.163776 -356.345129) (xy 250.111819 -356.370521) (xy 250.056625 -356.387781) (xy 249.999459 -356.396515)
			(xy 249.970544 -356.397052) (xy 249.943292 -356.396504) (xy 249.889343 -356.388753) (xy 249.837046 -356.373402)
			(xy 249.787466 -356.350765) (xy 249.741612 -356.321302) (xy 249.700419 -356.285612) (xy 249.664725 -356.244423)
			(xy 249.635256 -356.198573) (xy 249.612613 -356.148996) (xy 249.597257 -356.0967) (xy 249.589499 -356.042752)
			(xy 239.008878 -356.042752) (xy 239.020865 -356.082596) (xy 239.028985 -356.137772) (xy 239.029494 -356.165658)
			(xy 239.028985 -356.193544) (xy 239.020865 -356.24872) (xy 239.004797 -356.302127) (xy 238.981125 -356.352624)
			(xy 238.950352 -356.399137) (xy 238.913135 -356.440674) (xy 238.870267 -356.476349) (xy 238.822661 -356.505403)
			(xy 238.771332 -356.527215) (xy 238.717375 -356.541321) (xy 238.661938 -356.547421) (xy 238.606204 -356.545384)
			(xy 238.551361 -356.535254) (xy 238.498577 -356.517247) (xy 238.448977 -356.491746) (xy 238.403619 -356.459295)
			(xy 238.36347 -356.420586) (xy 238.329384 -356.376443) (xy 238.302088 -356.327808) (xy 238.282165 -356.275717)
			(xy 238.270039 -356.22128) (xy 238.265968 -356.165658) (xy 237.959876 -356.165658) (xy 237.969246 -356.194495)
			(xy 237.978614 -356.253595) (xy 237.979204 -356.283514) (xy 237.979204 -357.190548) (xy 239.453672 -357.190548)
			(xy 239.457743 -357.134926) (xy 239.469869 -357.080489) (xy 239.489792 -357.028398) (xy 239.517088 -356.979763)
			(xy 239.551174 -356.93562) (xy 239.591323 -356.896911) (xy 239.636681 -356.86446) (xy 239.686281 -356.838959)
			(xy 239.739065 -356.820952) (xy 239.793908 -356.810822) (xy 239.849642 -356.808785) (xy 239.905079 -356.814885)
			(xy 239.959036 -356.828991) (xy 240.010365 -356.850803) (xy 240.057971 -356.879857) (xy 240.100839 -356.915532)
			(xy 240.138056 -356.957069) (xy 240.168829 -357.003582) (xy 240.192501 -357.054079) (xy 240.208569 -357.107486)
			(xy 240.216689 -357.162662) (xy 240.217198 -357.190548) (xy 240.469672 -357.190548) (xy 240.473743 -357.134926)
			(xy 240.485869 -357.080489) (xy 240.505792 -357.028398) (xy 240.533088 -356.979763) (xy 240.567174 -356.93562)
			(xy 240.607323 -356.896911) (xy 240.652681 -356.86446) (xy 240.702281 -356.838959) (xy 240.755065 -356.820952)
			(xy 240.809908 -356.810822) (xy 240.865642 -356.808785) (xy 240.921079 -356.814885) (xy 240.975036 -356.828991)
			(xy 241.026365 -356.850803) (xy 241.073971 -356.879857) (xy 241.116839 -356.915532) (xy 241.154056 -356.957069)
			(xy 241.184829 -357.003582) (xy 241.208501 -357.054079) (xy 241.224569 -357.107486) (xy 241.232689 -357.162662)
			(xy 241.233198 -357.190548) (xy 241.232689 -357.218434) (xy 241.224569 -357.27361) (xy 241.208501 -357.327017)
			(xy 241.184829 -357.377514) (xy 241.154056 -357.424027) (xy 241.116839 -357.465564) (xy 241.073971 -357.501239)
			(xy 241.026365 -357.530293) (xy 240.975036 -357.552105) (xy 240.921079 -357.566211) (xy 240.865642 -357.572311)
			(xy 240.809908 -357.570274) (xy 240.755065 -357.560144) (xy 240.702281 -357.542137) (xy 240.652681 -357.516636)
			(xy 240.607323 -357.484185) (xy 240.567174 -357.445476) (xy 240.533088 -357.401333) (xy 240.505792 -357.352698)
			(xy 240.485869 -357.300607) (xy 240.473743 -357.24617) (xy 240.469672 -357.190548) (xy 240.217198 -357.190548)
			(xy 240.216689 -357.218434) (xy 240.208569 -357.27361) (xy 240.192501 -357.327017) (xy 240.168829 -357.377514)
			(xy 240.138056 -357.424027) (xy 240.100839 -357.465564) (xy 240.057971 -357.501239) (xy 240.010365 -357.530293)
			(xy 239.959036 -357.552105) (xy 239.905079 -357.566211) (xy 239.849642 -357.572311) (xy 239.793908 -357.570274)
			(xy 239.739065 -357.560144) (xy 239.686281 -357.542137) (xy 239.636681 -357.516636) (xy 239.591323 -357.484185)
			(xy 239.551174 -357.445476) (xy 239.517088 -357.401333) (xy 239.489792 -357.352698) (xy 239.469869 -357.300607)
			(xy 239.457743 -357.24617) (xy 239.453672 -357.190548) (xy 237.979204 -357.190548) (xy 237.979204 -358.054262)
			(xy 240.979625 -358.054262) (xy 240.979625 -357.99975) (xy 240.987382 -357.945794) (xy 241.002739 -357.893491)
			(xy 241.025383 -357.843906) (xy 241.054854 -357.798048) (xy 241.090551 -357.756851) (xy 241.131748 -357.721154)
			(xy 241.177606 -357.691683) (xy 241.227191 -357.669039) (xy 241.279494 -357.653682) (xy 241.33345 -357.645925)
			(xy 241.360706 -357.645462) (xy 241.386106 -357.646224) (xy 241.400221 -357.646776) (xy 241.427834 -357.64085)
			(xy 241.452769 -357.627589) (xy 241.47312 -357.608007) (xy 241.487331 -357.583601) (xy 241.494315 -357.556237)
			(xy 241.493539 -357.528005) (xy 241.489738 -357.514398) (xy 241.481556 -357.486534) (xy 241.472755 -357.429134)
			(xy 241.472212 -357.400098) (xy 241.47268 -357.372847) (xy 241.480436 -357.3189) (xy 241.495791 -357.266607)
			(xy 241.518432 -357.21703) (xy 241.547898 -357.171181) (xy 241.583589 -357.129991) (xy 241.624778 -357.0943)
			(xy 241.670627 -357.064834) (xy 241.720204 -357.042193) (xy 241.772497 -357.026837) (xy 241.826444 -357.01908)
			(xy 241.880945 -357.019079) (xy 241.934892 -357.026835) (xy 241.987186 -357.042189) (xy 242.036763 -357.064829)
			(xy 242.082613 -357.094293) (xy 242.123804 -357.129983) (xy 242.159496 -357.171172) (xy 242.188963 -357.217021)
			(xy 242.211605 -357.266597) (xy 242.226961 -357.31889) (xy 242.234719 -357.372837) (xy 242.234721 -357.427338)
			(xy 242.226967 -357.481285) (xy 242.211614 -357.53358) (xy 242.188975 -357.583157) (xy 242.159511 -357.629008)
			(xy 242.123822 -357.670199) (xy 242.082634 -357.705891) (xy 242.036786 -357.735359) (xy 241.98721 -357.758002)
			(xy 241.934917 -357.77336) (xy 241.880971 -357.781119) (xy 241.85372 -357.781606) (xy 241.82832 -357.780844)
			(xy 241.814205 -357.780356) (xy 241.7866 -357.786274) (xy 241.76167 -357.799525) (xy 241.741322 -357.819096)
			(xy 241.72711 -357.84349) (xy 241.720122 -357.870844) (xy 241.720891 -357.899066) (xy 241.724688 -357.91267)
			(xy 241.732863 -357.940536) (xy 241.741668 -357.997935) (xy 241.742214 -358.02697) (xy 241.741777 -358.054226)
			(xy 241.734024 -358.108182) (xy 241.71867 -358.160487) (xy 241.696029 -358.210073) (xy 241.666561 -358.255933)
			(xy 241.630866 -358.297132) (xy 241.589671 -358.332832) (xy 241.543816 -358.362305) (xy 241.494232 -358.384953)
			(xy 241.441929 -358.400313) (xy 241.387974 -358.408074) (xy 241.333462 -358.408076) (xy 241.279506 -358.400321)
			(xy 241.227202 -358.384966) (xy 241.177616 -358.362323) (xy 241.131757 -358.332853) (xy 241.090559 -358.297158)
			(xy 241.054861 -358.255962) (xy 241.025389 -358.210105) (xy 241.002743 -358.16052) (xy 240.987384 -358.108218)
			(xy 240.979625 -358.054262) (xy 237.979204 -358.054262) (xy 237.979204 -359.094024) (xy 237.978596 -359.12394)
			(xy 237.969208 -359.183032) (xy 237.950712 -359.239935) (xy 237.923561 -359.293253) (xy 237.888423 -359.341681)
			(xy 237.867698 -359.363264) (xy 237.65764 -359.573068) (xy 237.650964 -359.580469) (xy 237.64338 -359.598878)
			(xy 237.643393 -359.618788) (xy 237.646718 -359.628186) (xy 237.65256 -359.642664) (xy 237.678214 -359.659682)
			(xy 245.382034 -359.659682) (xy 245.392101 -359.659252) (xy 245.410695 -359.651527) (xy 245.418102 -359.644696)
			(xy 246.133874 -358.928924) (xy 246.139708 -358.922677) (xy 246.147176 -358.907313) (xy 246.14913 -358.890343)
			(xy 246.14759 -358.881934) (xy 246.126 -358.785414) (xy 246.108728 -358.765856) (xy 246.096536 -358.761538)
			(xy 246.056902 -358.746739) (xy 245.980376 -358.710654) (xy 245.907622 -358.667465) (xy 245.839298 -358.617564)
			(xy 245.776021 -358.5614) (xy 245.718363 -358.499481) (xy 245.666845 -358.432367) (xy 245.621932 -358.360665)
			(xy 245.584032 -358.285022) (xy 245.553485 -358.206121) (xy 245.530568 -358.124677) (xy 245.515488 -358.041425)
			(xy 245.508381 -357.957117) (xy 245.509312 -357.872514) (xy 245.518273 -357.788383) (xy 245.535182 -357.705483)
			(xy 245.559886 -357.624563) (xy 245.592162 -357.546354) (xy 245.631719 -357.471563) (xy 245.678198 -357.400867)
			(xy 245.731181 -357.334903) (xy 245.790188 -357.274269) (xy 245.854686 -357.219511) (xy 245.924092 -357.171125)
			(xy 245.997779 -357.129549) (xy 246.075081 -357.095157) (xy 246.155299 -357.068261) (xy 246.237709 -357.049104)
			(xy 246.321565 -357.037858) (xy 246.406111 -357.034626) (xy 246.490581 -357.039436) (xy 246.574213 -357.052246)
			(xy 246.656251 -357.072939) (xy 246.735953 -357.101329) (xy 246.812599 -357.137158) (xy 246.885496 -357.180103)
			(xy 246.953987 -357.229777) (xy 247.017451 -357.285729) (xy 247.075315 -357.347455) (xy 247.127057 -357.414397)
			(xy 247.172208 -357.485949) (xy 247.210361 -357.561465) (xy 247.241171 -357.640263) (xy 247.26436 -357.72163)
			(xy 247.279718 -357.804832) (xy 247.287105 -357.889116) (xy 247.286456 -357.973721) (xy 247.277777 -358.057881)
			(xy 247.261145 -358.140838) (xy 247.236711 -358.22184) (xy 247.204696 -358.300156) (xy 247.165389 -358.375078)
			(xy 247.119145 -358.445929) (xy 247.066383 -358.512069) (xy 247.037352 -358.542844) (xy 247.026684 -358.553766)
			(xy 247.021096 -358.583738) (xy 247.063514 -358.684068) (xy 247.06783 -358.693024) (xy 247.081953 -358.70699)
			(xy 247.10032 -358.714548) (xy 247.11025 -358.715056) (xy 251.017532 -358.715056) (xy 251.027599 -358.714626)
			(xy 251.04619 -358.706898) (xy 251.0536 -358.70007) (xy 251.76353 -357.99014) (xy 251.770375 -357.982742)
			(xy 251.778098 -357.964143) (xy 251.778516 -357.954072) (xy 251.778516 -356.421944) (xy 251.77895 -356.411879)
			(xy 251.78668 -356.39329) (xy 251.793502 -356.385876) (xy 252.267212 -355.912166) (xy 252.274608 -355.905314)
			(xy 252.293207 -355.897574) (xy 252.30328 -355.89718) (xy 262.650732 -355.89718) (xy 262.660799 -355.896751)
			(xy 262.679393 -355.889026) (xy 262.6868 -355.882194) (xy 263.082024 -355.48697) (xy 263.088874 -355.479574)
			(xy 263.09661 -355.460975) (xy 263.09701 -355.450902) (xy 263.09701 -351.983294) (xy 263.096586 -351.973224)
			(xy 263.088871 -351.95462) (xy 263.082024 -351.947226) (xy 262.81507 -351.680018) (xy 262.807671 -351.673174)
			(xy 262.789072 -351.665448) (xy 262.779002 -351.665032) (xy 255.146302 -351.665032) (xy 255.136232 -351.665455)
			(xy 255.11763 -351.673173) (xy 255.110234 -351.680018) (xy 254.002286 -352.78822) (xy 253.995433 -352.795615)
			(xy 253.987693 -352.814214) (xy 253.9873 -352.824288) (xy 253.9873 -354.960174) (xy 253.987467 -354.96604)
			(xy 253.990164 -354.977457) (xy 253.992634 -354.98278) (xy 253.992888 -354.983288) (xy 254.006724 -355.010816)
			(xy 254.026304 -355.069229) (xy 254.036237 -355.130031) (xy 254.03683 -355.160834) (xy 254.036344 -355.188085)
			(xy 254.028588 -355.242033) (xy 254.013233 -355.294328) (xy 253.990591 -355.343905) (xy 253.961125 -355.389755)
			(xy 253.925434 -355.430946) (xy 253.884243 -355.466637) (xy 253.838393 -355.496103) (xy 253.788816 -355.518745)
			(xy 253.736521 -355.5341) (xy 253.682573 -355.541856) (xy 253.628071 -355.541856) (xy 253.574123 -355.5341)
			(xy 253.521828 -355.518745) (xy 253.472251 -355.496103) (xy 253.426401 -355.466637) (xy 253.38521 -355.430946)
			(xy 253.349519 -355.389755) (xy 253.320053 -355.343905) (xy 253.297411 -355.294328) (xy 253.282056 -355.242033)
			(xy 253.2743 -355.188085) (xy 253.273814 -355.160834) (xy 253.274449 -355.130129) (xy 253.284324 -355.069518)
			(xy 253.303776 -355.011269) (xy 253.317502 -354.983796) (xy 253.31801 -354.98278) (xy 253.320804 -354.977446)
			(xy 253.323344 -354.96627) (xy 253.323344 -352.665792) (xy 253.323831 -352.639705) (xy 253.331999 -352.588174)
			(xy 253.348132 -352.538557) (xy 253.371832 -352.492077) (xy 253.402516 -352.449879) (xy 253.420626 -352.431096)
			(xy 254.75311 -351.098612) (xy 254.771882 -351.080582) (xy 254.814 -351.050006) (xy 254.860376 -351.026384)
			(xy 254.909873 -351.010296) (xy 254.961275 -351.002135) (xy 254.987298 -351.001584) (xy 255.680972 -351.001584)
			(xy 255.69348 -351.00094) (xy 255.715584 -350.989223) (xy 255.723136 -350.979232) (xy 255.777492 -350.899222)
			(xy 255.780032 -350.87433) (xy 255.77546 -350.862646) (xy 255.76702 -350.840289) (xy 255.755144 -350.793999)
			(xy 255.749153 -350.746586) (xy 255.74879 -350.722692) (xy 255.74879 -350.722438) (xy 255.749276 -350.695187)
			(xy 255.757032 -350.641239) (xy 255.772387 -350.588944) (xy 255.795029 -350.539367) (xy 255.824495 -350.493517)
			(xy 255.860186 -350.452326) (xy 255.901377 -350.416635) (xy 255.947227 -350.387169) (xy 255.996804 -350.364527)
			(xy 256.049099 -350.349172) (xy 256.103047 -350.341416) (xy 256.157549 -350.341416) (xy 256.211497 -350.349172)
			(xy 256.263792 -350.364527) (xy 256.313369 -350.387169) (xy 256.359219 -350.416635) (xy 256.40041 -350.452326)
			(xy 256.436101 -350.493517) (xy 256.465567 -350.539367) (xy 256.488209 -350.588944) (xy 256.503564 -350.641239)
			(xy 256.51132 -350.695187) (xy 256.511806 -350.722438) (xy 256.511806 -350.722692) (xy 256.511419 -350.746585)
			(xy 256.505427 -350.793995) (xy 256.493573 -350.840289) (xy 256.485136 -350.862646) (xy 256.480564 -350.87433)
			(xy 256.483104 -350.899222) (xy 256.53746 -350.979232) (xy 256.54499 -350.989248) (xy 256.567108 -351.000958)
			(xy 256.579624 -351.001584) (xy 262.937498 -351.001584) (xy 262.948642 -351.001624) (xy 262.970887 -351.003021)
			(xy 262.981948 -351.004378) (xy 262.992784 -351.005278) (xy 263.013567 -350.998952) (xy 263.02208 -350.992186)
			(xy 263.079738 -350.942148) (xy 263.087574 -350.934561) (xy 263.096518 -350.91469) (xy 263.09701 -350.903794)
			(xy 263.09701 -349.842582) (xy 263.097501 -349.832577) (xy 263.105164 -349.814094) (xy 263.119317 -349.799949)
			(xy 263.137805 -349.792296) (xy 263.14781 -349.791782) (xy 263.661652 -349.791782) (xy 263.671678 -349.791371)
			(xy 263.690209 -349.783709) (xy 263.704392 -349.769534) (xy 263.712065 -349.751008) (xy 263.712452 -349.740982)
			(xy 263.712452 -346.945712) (xy 263.71203 -346.935642) (xy 263.704313 -346.917039) (xy 263.697466 -346.909644)
			(xy 262.939784 -346.151962) (xy 262.932387 -346.145112) (xy 262.913789 -346.137373) (xy 262.903716 -346.136976)
			(xy 260.936232 -346.136976) (xy 260.926167 -346.137411) (xy 260.907578 -346.14514) (xy 260.900164 -346.151962)
			(xy 260.274562 -346.777564) (xy 260.251869 -346.799504) (xy 260.201778 -346.837913) (xy 260.14711 -346.869467)
			(xy 260.088796 -346.893629) (xy 260.027831 -346.909987) (xy 259.965254 -346.918262) (xy 259.933694 -346.918788)
			(xy 258.335018 -346.918788) (xy 258.303461 -346.918238) (xy 258.240892 -346.909946) (xy 258.179935 -346.89358)
			(xy 258.121627 -346.869418) (xy 258.066961 -346.837871) (xy 258.016867 -346.799476) (xy 257.99415 -346.777564)
			(xy 257.212084 -345.995498) (xy 257.190085 -345.972772) (xy 257.151611 -345.922567) (xy 257.120021 -345.867769)
			(xy 257.095853 -345.809317) (xy 257.079523 -345.74821) (xy 257.071309 -345.685494) (xy 257.07086 -345.653868)
			(xy 257.071252 -345.625156) (xy 257.078026 -345.568134) (xy 257.091523 -345.51232) (xy 257.111551 -345.458503)
			(xy 257.137827 -345.407445) (xy 257.16998 -345.359868) (xy 257.188462 -345.337892) (xy 257.198368 -345.326462)
			(xy 257.202432 -345.297252) (xy 257.157728 -345.199462) (xy 257.15331 -345.190796) (xy 257.139257 -345.177372)
			(xy 257.121217 -345.170141) (xy 257.1115 -345.169744) (xy 235.527342 -345.169744) (xy 235.494487 -345.169286)
			(xy 235.42919 -345.161934) (xy 235.365127 -345.147318) (xy 235.303103 -345.125622) (xy 235.243897 -345.097119)
			(xy 235.188255 -345.062166) (xy 235.136876 -345.021203) (xy 235.113322 -344.998294) (xy 232.501694 -342.386666)
			(xy 232.494298 -342.379813) (xy 232.4757 -342.37207) (xy 232.465626 -342.37168) (xy 232.164382 -342.37168)
			(xy 232.127178 -342.371097) (xy 232.05337 -342.361674) (xy 231.981346 -342.342994) (xy 231.912262 -342.315357)
			(xy 231.847226 -342.279206) (xy 231.81691 -342.257634) (xy 231.808188 -342.251831) (xy 231.787791 -342.247143)
			(xy 231.767214 -342.250962) (xy 231.758236 -342.256364) (xy 231.729016 -342.275646) (xy 231.666867 -342.307876)
			(xy 231.60132 -342.332469) (xy 231.533308 -342.349074) (xy 231.463802 -342.357454) (xy 231.428798 -342.357964)
			(xy 231.42829 -342.357964) (xy 231.392888 -342.357429) (xy 231.322599 -342.348896) (xy 231.253851 -342.331955)
			(xy 231.187645 -342.306852) (xy 231.124947 -342.273955) (xy 231.06667 -342.233742) (xy 231.013664 -342.186799)
			(xy 230.9667 -342.133811) (xy 230.926464 -342.07555) (xy 230.893542 -342.012865) (xy 230.868414 -341.946669)
			(xy 230.851446 -341.877927) (xy 230.842885 -341.807642) (xy 230.842312 -341.77224) (xy 230.842792 -341.739363)
			(xy 230.850187 -341.674026) (xy 230.864843 -341.609925) (xy 230.886577 -341.547867) (xy 230.915117 -341.488628)
			(xy 230.950103 -341.432954) (xy 230.991097 -341.381542) (xy 231.014016 -341.357966) (xy 231.55148 -340.820502)
			(xy 231.575044 -340.797604) (xy 231.626427 -340.75665) (xy 231.682069 -340.721702) (xy 231.741273 -340.6932)
			(xy 231.803294 -340.671501) (xy 231.867353 -340.656878) (xy 231.932646 -340.649515) (xy 231.9655 -340.649052)
			(xy 232.564432 -340.649052) (xy 232.574472 -340.648621) (xy 232.59301 -340.640904) (xy 232.607168 -340.626664)
			(xy 232.611422 -340.617556) (xy 232.617518 -340.603332) (xy 232.611422 -340.57336) (xy 227.543106 -335.50479)
			(xy 227.535712 -335.497933) (xy 227.517113 -335.490182) (xy 227.507038 -335.489804) (xy 225.734626 -335.489804)
			(xy 225.708603 -335.489275) (xy 225.6572 -335.481106) (xy 225.607704 -335.465011) (xy 225.561327 -335.441385)
			(xy 225.519209 -335.410808) (xy 225.500438 -335.392776) (xy 224.606104 -334.498442) (xy 224.588071 -334.479671)
			(xy 224.55749 -334.437555) (xy 224.533861 -334.391179) (xy 224.517765 -334.341681) (xy 224.509597 -334.290278)
			(xy 224.509076 -334.264254) (xy 224.509076 -330.310744) (xy 224.509604 -330.284721) (xy 224.517772 -330.233318)
			(xy 224.533868 -330.183822) (xy 224.557496 -330.137448) (xy 224.588077 -330.095332) (xy 224.606104 -330.076556)
			(xy 224.902522 -329.780138) (xy 224.906689 -329.775784) (xy 224.912978 -329.765507) (xy 224.914968 -329.759818)
			(xy 224.914968 -329.759564) (xy 224.923402 -329.734005) (xy 224.946452 -329.68537) (xy 224.976109 -329.640456)
			(xy 225.011782 -329.600156) (xy 225.052765 -329.565268) (xy 225.098244 -329.536487) (xy 225.147317 -329.514382)
			(xy 225.199008 -329.499392) (xy 225.252294 -329.491815) (xy 225.279204 -329.49134) (xy 225.306455 -329.491804)
			(xy 225.360403 -329.499561) (xy 225.412698 -329.514918) (xy 225.462275 -329.537562) (xy 225.508124 -329.56703)
			(xy 225.549312 -329.602725) (xy 225.585001 -329.643918) (xy 225.614463 -329.689771) (xy 225.6371 -329.739351)
			(xy 225.65245 -329.791648) (xy 225.6602 -329.845597) (xy 225.660712 -329.872848) (xy 225.660248 -329.899747)
			(xy 225.652684 -329.95301) (xy 225.637712 -330.004682) (xy 225.61563 -330.053738) (xy 225.586875 -330.099206)
			(xy 225.552018 -330.140183) (xy 225.51175 -330.175858) (xy 225.46687 -330.205521) (xy 225.418268 -330.228586)
			(xy 225.392742 -330.237084) (xy 225.392234 -330.237084) (xy 225.386574 -330.239132) (xy 225.376315 -330.245422)
			(xy 225.371914 -330.24953) (xy 225.18751 -330.43368) (xy 225.180675 -330.441082) (xy 225.172968 -330.459681)
			(xy 225.172524 -330.469748) (xy 225.172524 -333.537052) (xy 225.173078 -333.548581) (xy 225.183137 -333.569332)
			(xy 225.191828 -333.57693) (xy 225.254312 -333.62646) (xy 225.263731 -333.633072) (xy 225.286157 -333.638093)
			(xy 225.297492 -333.636112) (xy 225.319024 -333.63137) (xy 225.362822 -333.62628) (xy 225.384868 -333.625952)
			(xy 225.412122 -333.626436) (xy 225.466075 -333.634188) (xy 225.518376 -333.64954) (xy 225.56796 -333.672179)
			(xy 225.613817 -333.701644) (xy 225.655014 -333.737335) (xy 225.690713 -333.778525) (xy 225.720187 -333.824377)
			(xy 225.724341 -333.83347) (xy 225.95916 -333.83347) (xy 225.963231 -333.777848) (xy 225.975357 -333.723411)
			(xy 225.99528 -333.67132) (xy 226.022576 -333.622685) (xy 226.056662 -333.578542) (xy 226.096811 -333.539833)
			(xy 226.142169 -333.507382) (xy 226.191769 -333.481881) (xy 226.244553 -333.463874) (xy 226.299396 -333.453744)
			(xy 226.35513 -333.451707) (xy 226.410567 -333.457807) (xy 226.464524 -333.471913) (xy 226.515853 -333.493725)
			(xy 226.563459 -333.522779) (xy 226.606327 -333.558454) (xy 226.643544 -333.599991) (xy 226.674317 -333.646504)
			(xy 226.697989 -333.697001) (xy 226.714057 -333.750408) (xy 226.722177 -333.805584) (xy 226.722686 -333.83347)
			(xy 226.722177 -333.861356) (xy 226.714057 -333.916532) (xy 226.697989 -333.969939) (xy 226.674317 -334.020436)
			(xy 226.643544 -334.066949) (xy 226.606327 -334.108486) (xy 226.563459 -334.144161) (xy 226.515853 -334.173215)
			(xy 226.464524 -334.195027) (xy 226.410567 -334.209133) (xy 226.35513 -334.215233) (xy 226.299396 -334.213196)
			(xy 226.244553 -334.203066) (xy 226.191769 -334.185059) (xy 226.142169 -334.159558) (xy 226.096811 -334.127107)
			(xy 226.056662 -334.088398) (xy 226.022576 -334.044255) (xy 225.99528 -333.99562) (xy 225.975357 -333.943529)
			(xy 225.963231 -333.889092) (xy 225.95916 -333.83347) (xy 225.724341 -333.83347) (xy 225.742835 -333.873956)
			(xy 225.758197 -333.926254) (xy 225.765959 -333.980206) (xy 225.766376 -334.00746) (xy 225.765839 -334.036455)
			(xy 225.75707 -334.093777) (xy 225.739729 -334.149113) (xy 225.714215 -334.201188) (xy 225.681114 -334.248802)
			(xy 225.64119 -334.29086) (xy 225.595362 -334.326393) (xy 225.570288 -334.340962) (xy 225.559874 -334.346804)
			(xy 225.546412 -334.366108) (xy 225.533458 -334.458564) (xy 225.5324 -334.47032) (xy 225.539804 -334.492703)
			(xy 225.547682 -334.50149) (xy 225.857562 -334.81137) (xy 225.864962 -334.81821) (xy 225.883561 -334.825926)
			(xy 225.89363 -334.826356) (xy 227.008182 -334.826356) (xy 227.018202 -334.825939) (xy 227.036718 -334.818271)
			(xy 227.050885 -334.804096) (xy 227.058544 -334.785577) (xy 227.058982 -334.775556) (xy 227.058982 -334.405478)
			(xy 227.058748 -334.398209) (xy 227.05461 -334.384274) (xy 227.050854 -334.378046) (xy 227.038396 -334.357926)
			(xy 227.01873 -334.314883) (xy 227.005393 -334.269478) (xy 226.998658 -334.222637) (xy 226.998276 -334.198976)
			(xy 226.998276 -330.558394) (xy 226.997851 -330.548325) (xy 226.990133 -330.529724) (xy 226.98329 -330.522326)
			(xy 225.898456 -329.437746) (xy 225.894102 -329.43358) (xy 225.883825 -329.427291) (xy 225.878136 -329.4253)
			(xy 225.877882 -329.4253) (xy 225.852325 -329.416862) (xy 225.803693 -329.393807) (xy 225.758783 -329.364148)
			(xy 225.718486 -329.328474) (xy 225.683599 -329.287492) (xy 225.654817 -329.242015) (xy 225.632709 -329.192945)
			(xy 225.617714 -329.141256) (xy 225.61013 -329.087974) (xy 225.609658 -329.061064) (xy 225.610146 -329.033814)
			(xy 225.617907 -328.979868) (xy 225.633265 -328.927576) (xy 225.655907 -328.878001) (xy 225.685374 -328.832152)
			(xy 225.721065 -328.790964) (xy 225.762254 -328.755273) (xy 225.808102 -328.725806) (xy 225.857677 -328.703164)
			(xy 225.90997 -328.687806) (xy 225.963916 -328.680046) (xy 225.991166 -328.679556) (xy 226.018068 -328.680015)
			(xy 226.07134 -328.687569) (xy 226.123023 -328.702532) (xy 226.17209 -328.724608) (xy 226.21757 -328.753358)
			(xy 226.258559 -328.788213) (xy 226.294245 -328.82848) (xy 226.32392 -328.873362) (xy 226.346995 -328.921967)
			(xy 226.355402 -328.947526) (xy 226.355402 -328.948034) (xy 226.357448 -328.953696) (xy 226.363736 -328.963957)
			(xy 226.367848 -328.968354) (xy 226.972114 -329.572874) (xy 226.979541 -329.579684) (xy 226.998159 -329.587355)
			(xy 227.018295 -329.587305) (xy 227.02774 -329.583796) (xy 227.03677 -329.579538) (xy 227.050886 -329.565449)
			(xy 227.058537 -329.547031) (xy 227.058982 -329.53706) (xy 227.058982 -328.91222) (xy 227.059419 -328.902156)
			(xy 227.067152 -328.883571) (xy 227.073968 -328.876152) (xy 227.245672 -328.704448) (xy 227.252362 -328.697036)
			(xy 227.259971 -328.678597) (xy 227.25998 -328.658651) (xy 227.252389 -328.640205) (xy 227.245672 -328.63282)
			(xy 223.571816 -324.95871) (xy 223.564413 -324.951876) (xy 223.545815 -324.94417) (xy 223.535748 -324.943724)
			(xy 217.017346 -324.943724) (xy 216.984491 -324.943266) (xy 216.919194 -324.935915) (xy 216.855131 -324.921299)
			(xy 216.793107 -324.899602) (xy 216.733902 -324.871098) (xy 216.67826 -324.836145) (xy 216.626882 -324.795181)
			(xy 216.603326 -324.772274) (xy 214.444326 -322.613274) (xy 214.421428 -322.58971) (xy 214.380474 -322.538326)
			(xy 214.345526 -322.482683) (xy 214.317022 -322.42348) (xy 214.295321 -322.36146) (xy 214.280694 -322.297401)
			(xy 214.273326 -322.232108) (xy 214.272876 -322.199254) (xy 214.272876 -318.043052) (xy 214.272444 -318.032986)
			(xy 214.264714 -318.014397) (xy 214.25789 -318.006984) (xy 210.583526 -314.332874) (xy 210.560628 -314.30931)
			(xy 210.519674 -314.257926) (xy 210.484726 -314.202283) (xy 210.456222 -314.14308) (xy 210.434521 -314.08106)
			(xy 210.419894 -314.017001) (xy 210.412526 -313.951708) (xy 210.412076 -313.918854) (xy 210.412076 -288.79165)
			(xy 210.411579 -288.781651) (xy 210.40391 -288.76318) (xy 210.389758 -288.749049) (xy 210.371276 -288.741406)
			(xy 210.361276 -288.74085) (xy 210.219544 -288.74085) (xy 210.209669 -288.741316) (xy 210.191376 -288.748763)
			(xy 210.183984 -288.755328) (xy 210.133184 -288.805112) (xy 210.126475 -288.812314) (xy 210.118632 -288.830346)
			(xy 210.117944 -288.840164) (xy 210.117944 -288.840418) (xy 210.116857 -288.871224) (xy 210.107824 -288.932202)
			(xy 210.091106 -288.991534) (xy 210.066976 -289.048258) (xy 210.035825 -289.101451) (xy 209.99816 -289.150248)
			(xy 209.97672 -289.172396) (xy 209.209386 -289.939476) (xy 209.202542 -289.946874) (xy 209.194822 -289.965474)
			(xy 209.1944 -289.975544) (xy 209.1944 -291.536374) (xy 209.194837 -291.546438) (xy 209.20257 -291.565023)
			(xy 209.209386 -291.572442) (xy 209.261202 -291.624258) (xy 209.268599 -291.631109) (xy 209.287197 -291.638849)
			(xy 209.29727 -291.639244) (xy 209.738976 -291.639244) (xy 209.770593 -291.639737) (xy 209.833285 -291.647988)
			(xy 209.894365 -291.664351) (xy 209.952786 -291.688547) (xy 210.007548 -291.720162) (xy 210.057716 -291.758655)
			(xy 210.102429 -291.803366) (xy 210.140924 -291.853532) (xy 210.172542 -291.908293) (xy 210.196741 -291.966713)
			(xy 210.213108 -292.027791) (xy 210.221361 -292.090483) (xy 210.221361 -292.153717) (xy 210.213108 -292.216409)
			(xy 210.196741 -292.277487) (xy 210.172542 -292.335907) (xy 210.140924 -292.390668) (xy 210.102429 -292.440834)
			(xy 210.057716 -292.485545) (xy 210.007548 -292.524038) (xy 209.952786 -292.555653) (xy 209.894365 -292.579849)
			(xy 209.833285 -292.596212) (xy 209.770593 -292.604463) (xy 209.738976 -292.604952) (xy 209.075274 -292.604952)
			(xy 209.043715 -292.604406) (xy 208.981142 -292.596122) (xy 208.920179 -292.579763) (xy 208.861864 -292.555608)
			(xy 208.80719 -292.524067) (xy 208.757087 -292.485678) (xy 208.734406 -292.463728) (xy 208.369916 -292.099238)
			(xy 208.347978 -292.076544) (xy 208.309573 -292.026452) (xy 208.278023 -291.971783) (xy 208.253865 -291.913469)
			(xy 208.237511 -291.852505) (xy 208.229239 -291.78993) (xy 208.228692 -291.75837) (xy 208.228692 -289.753548)
			(xy 208.22924 -289.72199) (xy 208.237528 -289.659419) (xy 208.25389 -289.598459) (xy 208.278049 -289.540148)
			(xy 208.309594 -289.485478) (xy 208.347986 -289.43538) (xy 208.369916 -289.41268) (xy 208.955386 -288.827464)
			(xy 208.962065 -288.820063) (xy 208.969656 -288.801652) (xy 208.969654 -288.781737) (xy 208.966308 -288.772346)
			(xy 208.960466 -288.757868) (xy 208.934812 -288.74085) (xy 202.68438 -288.74085) (xy 202.67936 -288.740939)
			(xy 202.669505 -288.742852) (xy 202.664822 -288.74466) (xy 202.65009 -288.750756) (xy 202.640223 -288.755407)
			(xy 202.625335 -288.771323) (xy 202.621388 -288.78149) (xy 202.59675 -288.853626) (xy 202.593765 -288.86399)
			(xy 202.595889 -288.885431) (xy 202.600814 -288.895028) (xy 202.600814 -288.895282) (xy 202.612816 -288.917025)
			(xy 202.631714 -288.962953) (xy 202.644496 -289.010944) (xy 202.650947 -289.060188) (xy 202.65136 -289.08502)
			(xy 202.650874 -289.112271) (xy 202.643118 -289.166219) (xy 202.627763 -289.218514) (xy 202.605121 -289.268091)
			(xy 202.575655 -289.313941) (xy 202.539964 -289.355132) (xy 202.498773 -289.390823) (xy 202.452923 -289.420289)
			(xy 202.403346 -289.442931) (xy 202.351051 -289.458286) (xy 202.297103 -289.466042) (xy 202.242601 -289.466042)
			(xy 202.188653 -289.458286) (xy 202.136358 -289.442931) (xy 202.086781 -289.420289) (xy 202.040931 -289.390823)
			(xy 201.99974 -289.355132) (xy 201.964049 -289.313941) (xy 201.934583 -289.268091) (xy 201.911941 -289.218514)
			(xy 201.896586 -289.166219) (xy 201.88883 -289.112271) (xy 201.888344 -289.08502) (xy 201.888598 -289.069018)
			(xy 201.889106 -289.058604) (xy 201.881994 -289.0393) (xy 201.823828 -288.978848) (xy 201.816401 -288.971735)
			(xy 201.797524 -288.963629) (xy 201.787252 -288.9631) (xy 200.017634 -288.9631) (xy 199.971429 -288.962605)
			(xy 199.87941 -288.954102) (xy 199.788576 -288.93711) (xy 199.699706 -288.911776) (xy 199.656446 -288.895536)
			(xy 199.652041 -288.893934) (xy 199.642842 -288.892146) (xy 199.638158 -288.89198) (xy 197.10654 -288.89198)
			(xy 197.096512 -288.892392) (xy 197.077978 -288.900055) (xy 197.063788 -288.914227) (xy 197.056104 -288.932752)
			(xy 197.05574 -288.94278) (xy 197.05574 -289.30346) (xy 197.055259 -289.313476) (xy 197.047608 -289.331988)
			(xy 197.033455 -289.346164) (xy 197.014955 -289.353844) (xy 197.00494 -289.35426) (xy 196.477128 -289.35426)
			(xy 196.467859 -289.355219) (xy 196.450893 -289.362888) (xy 196.437795 -289.37612) (xy 196.433694 -289.384486)
			(xy 196.394578 -289.47237) (xy 196.393118 -289.476477) (xy 196.391465 -289.485033) (xy 196.391276 -289.489388)
			(xy 196.393308 -289.494722) (xy 196.403722 -289.522408) (xy 196.40931 -289.529266) (xy 196.409564 -289.52952)
			(xy 196.426067 -289.550268) (xy 196.452406 -289.596271) (xy 196.47042 -289.646127) (xy 196.479568 -289.698341)
			(xy 196.480176 -289.724846) (xy 196.479654 -289.750101) (xy 196.471341 -289.799923) (xy 196.45494 -289.847697)
			(xy 196.430899 -289.89212) (xy 196.399875 -289.93198) (xy 196.362713 -289.96619) (xy 196.320427 -289.993816)
			(xy 196.274171 -290.014106) (xy 196.225206 -290.026506) (xy 196.174868 -290.030677) (xy 196.12453 -290.026506)
			(xy 196.075565 -290.014106) (xy 196.029309 -289.993816) (xy 195.987023 -289.96619) (xy 195.949861 -289.93198)
			(xy 195.918837 -289.89212) (xy 195.894796 -289.847697) (xy 195.878395 -289.799923) (xy 195.870082 -289.750101)
			(xy 195.86956 -289.724846) (xy 195.869699 -289.712083) (xy 195.871863 -289.686649) (xy 195.873878 -289.674046)
			(xy 195.87337 -289.674046) (xy 195.87464 -289.663124) (xy 195.797424 -289.589464) (xy 195.788487 -289.581755)
			(xy 195.76598 -289.574745) (xy 195.754244 -289.576002) (xy 195.75399 -289.576002) (xy 195.740564 -289.578122)
			(xy 195.713479 -289.580411) (xy 195.699888 -289.580574) (xy 195.686234 -289.580414) (xy 195.65902 -289.578129)
			(xy 195.645532 -289.576002) (xy 195.633594 -289.57397) (xy 195.610988 -289.581082) (xy 195.534534 -289.65398)
			(xy 195.526406 -289.676332) (xy 195.526914 -289.680142) (xy 195.528451 -289.691254) (xy 195.530101 -289.713629)
			(xy 195.530216 -289.724846) (xy 195.529694 -289.750101) (xy 195.521381 -289.799923) (xy 195.50498 -289.847697)
			(xy 195.480939 -289.89212) (xy 195.449915 -289.93198) (xy 195.412753 -289.96619) (xy 195.370467 -289.993816)
			(xy 195.324211 -290.014106) (xy 195.275246 -290.026506) (xy 195.224908 -290.030677) (xy 195.17457 -290.026506)
			(xy 195.125605 -290.014106) (xy 195.079349 -289.993816) (xy 195.037063 -289.96619) (xy 194.999901 -289.93198)
			(xy 194.968877 -289.89212) (xy 194.944836 -289.847697) (xy 194.928435 -289.799923) (xy 194.920122 -289.750101)
			(xy 194.9196 -289.724846) (xy 194.921124 -289.694874) (xy 194.921378 -289.692334) (xy 194.921378 -289.691572)
			(xy 194.922648 -289.680142) (xy 194.916298 -289.667696) (xy 194.913563 -289.662542) (xy 194.90613 -289.653551)
			(xy 194.901566 -289.649916) (xy 194.90055 -289.649408) (xy 194.89801 -289.647376) (xy 194.862704 -289.625024)
			(xy 194.818508 -289.597084) (xy 194.812843 -289.594149) (xy 194.800501 -289.590935) (xy 194.794124 -289.590734)
			(xy 194.767962 -289.597846) (xy 194.76212 -289.601402) (xy 194.719448 -289.625024) (xy 194.697934 -289.636087)
			(xy 194.653971 -289.656291) (xy 194.631564 -289.66541) (xy 194.623637 -289.67027) (xy 194.611653 -289.684465)
			(xy 194.608196 -289.693096) (xy 194.608196 -289.693604) (xy 194.606418 -289.699192) (xy 194.605402 -289.709606)
			(xy 194.605656 -289.724592) (xy 194.605656 -289.7251) (xy 194.605124 -289.751073) (xy 194.596957 -289.802374)
			(xy 194.58087 -289.851768) (xy 194.557259 -289.898039) (xy 194.526705 -289.94005) (xy 194.489958 -289.976769)
			(xy 194.447924 -290.007291) (xy 194.401635 -290.030866) (xy 194.352229 -290.046916) (xy 194.300922 -290.055044)
			(xy 194.274948 -290.055554) (xy 194.262198 -290.055461) (xy 194.23677 -290.053552) (xy 194.224148 -290.051744)
			(xy 194.199163 -290.047369) (xy 194.150821 -290.03202) (xy 194.105386 -290.009476) (xy 194.063923 -289.980263)
			(xy 194.027402 -289.945067) (xy 193.996679 -289.90471) (xy 193.972473 -289.860138) (xy 193.95535 -289.812395)
			(xy 193.950082 -289.787584) (xy 193.946526 -289.776154) (xy 193.944494 -289.772344) (xy 193.941192 -289.766502)
			(xy 193.92265 -289.748976) (xy 193.919588 -289.746131) (xy 193.912691 -289.74141) (xy 193.908934 -289.739578)
			(xy 193.897504 -289.734498) (xy 193.890646 -289.731958) (xy 193.878962 -289.728656) (xy 193.869564 -289.727386)
			(xy 193.869056 -289.727386) (xy 193.865246 -289.726878) (xy 193.810128 -289.718242) (xy 193.807334 -289.717734)
			(xy 193.799968 -289.717226) (xy 193.792602 -289.717734) (xy 193.789808 -289.718242) (xy 193.74739 -289.7251)
			(xy 193.705734 -289.729926) (xy 193.702432 -289.730434) (xy 193.694812 -289.731196) (xy 193.688462 -289.73272)
			(xy 193.670174 -289.753294) (xy 193.661792 -289.762946) (xy 193.654172 -289.774122) (xy 193.651378 -289.779964)
			(xy 193.650108 -289.786822) (xy 193.646553 -289.804095) (xy 193.636241 -289.837822) (xy 193.629534 -289.854132)
			(xy 193.620775 -289.873877) (xy 193.598867 -289.911106) (xy 193.572297 -289.945164) (xy 193.557144 -289.960558)
			(xy 193.546235 -289.970997) (xy 193.522828 -289.990072) (xy 193.510408 -289.998658) (xy 193.486984 -290.013849)
			(xy 193.436177 -290.036977) (xy 193.382202 -290.051227) (xy 193.354452 -290.054284) (xy 193.352928 -290.054538)
			(xy 193.35115 -290.054792) (xy 193.33845 -290.055808) (xy 193.324734 -290.055808) (xy 193.29653 -290.055222)
			(xy 193.240945 -290.04562) (xy 193.187796 -290.026723) (xy 193.162936 -290.01339) (xy 193.157094 -290.010088)
			(xy 193.131948 -290.003484) (xy 193.12665 -290.00362) (xy 193.116278 -290.005793) (xy 193.111374 -290.007802)
			(xy 193.102738 -290.014406) (xy 193.102484 -290.014406) (xy 193.092832 -290.022026) (xy 193.087631 -290.028989)
			(xy 193.081792 -290.045347) (xy 193.081402 -290.05403) (xy 193.081402 -290.189666) (xy 193.081614 -290.195752)
			(xy 193.084573 -290.207561) (xy 193.087244 -290.213034) (xy 193.087244 -290.213288) (xy 193.089784 -290.218114)
			(xy 193.099413 -290.23778) (xy 193.113562 -290.279217) (xy 193.117978 -290.300664) (xy 193.12001 -290.311586)
			(xy 193.125598 -290.319968) (xy 193.1283 -290.323702) (xy 193.134819 -290.330217) (xy 193.138552 -290.332922)
			(xy 193.173604 -290.35502) (xy 193.173858 -290.355274) (xy 193.18224 -290.360608) (xy 193.207894 -290.376356)
			(xy 193.2178 -290.380166) (xy 193.24447 -290.380166) (xy 193.24955 -290.378896) (xy 193.26225 -290.375848)
			(xy 193.262504 -290.375848) (xy 193.26733 -290.374832) (xy 193.280228 -290.372512) (xy 193.3063 -290.369842)
			(xy 193.3194 -290.369498) (xy 193.328036 -290.369498) (xy 193.351871 -290.370194) (xy 193.398897 -290.378074)
			(xy 193.444125 -290.393169) (xy 193.486458 -290.415111) (xy 193.524865 -290.443368) (xy 193.558412 -290.477251)
			(xy 193.586285 -290.515937) (xy 193.607804 -290.558486) (xy 193.622447 -290.603864) (xy 193.629859 -290.650965)
			(xy 193.630296 -290.674806) (xy 193.969144 -290.674806) (xy 193.973104 -290.625752) (xy 193.984881 -290.577968)
			(xy 194.004172 -290.532692) (xy 194.030475 -290.491096) (xy 194.06311 -290.454259) (xy 194.101231 -290.423134)
			(xy 194.143852 -290.398527) (xy 194.189868 -290.381075) (xy 194.238087 -290.371231) (xy 194.287262 -290.36925)
			(xy 194.336117 -290.375182) (xy 194.383388 -290.388874) (xy 194.42785 -290.409972) (xy 194.468353 -290.437928)
			(xy 194.503846 -290.47202) (xy 194.533411 -290.511364) (xy 194.556282 -290.554941) (xy 194.571866 -290.601622)
			(xy 194.579761 -290.650199) (xy 194.580256 -290.674806) (xy 197.769238 -290.674806) (xy 197.773198 -290.625752)
			(xy 197.784975 -290.577968) (xy 197.804266 -290.532692) (xy 197.830569 -290.491096) (xy 197.863204 -290.454259)
			(xy 197.901325 -290.423134) (xy 197.943946 -290.398527) (xy 197.989962 -290.381075) (xy 198.038181 -290.371231)
			(xy 198.087356 -290.36925) (xy 198.136211 -290.375182) (xy 198.183482 -290.388874) (xy 198.227944 -290.409972)
			(xy 198.268447 -290.437928) (xy 198.30394 -290.47202) (xy 198.333505 -290.511364) (xy 198.356376 -290.554941)
			(xy 198.37196 -290.601622) (xy 198.379855 -290.650199) (xy 198.38035 -290.674806) (xy 198.719198 -290.674806)
			(xy 198.723158 -290.625752) (xy 198.734935 -290.577968) (xy 198.754226 -290.532692) (xy 198.780529 -290.491096)
			(xy 198.813164 -290.454259) (xy 198.851285 -290.423134) (xy 198.893906 -290.398527) (xy 198.939922 -290.381075)
			(xy 198.988141 -290.371231) (xy 199.037316 -290.36925) (xy 199.086171 -290.375182) (xy 199.133442 -290.388874)
			(xy 199.177904 -290.409972) (xy 199.19176 -290.419536) (xy 201.25385 -290.419536) (xy 201.257921 -290.363914)
			(xy 201.270047 -290.309477) (xy 201.28997 -290.257386) (xy 201.317266 -290.208751) (xy 201.351352 -290.164608)
			(xy 201.391501 -290.125899) (xy 201.436859 -290.093448) (xy 201.486459 -290.067947) (xy 201.539243 -290.04994)
			(xy 201.594086 -290.03981) (xy 201.64982 -290.037773) (xy 201.705257 -290.043873) (xy 201.759214 -290.057979)
			(xy 201.810543 -290.079791) (xy 201.858149 -290.108845) (xy 201.901017 -290.14452) (xy 201.938234 -290.186057)
			(xy 201.969007 -290.23257) (xy 201.971161 -290.237164) (xy 205.26451 -290.237164) (xy 205.268581 -290.181542)
			(xy 205.280707 -290.127105) (xy 205.30063 -290.075014) (xy 205.327926 -290.026379) (xy 205.362012 -289.982236)
			(xy 205.402161 -289.943527) (xy 205.447519 -289.911076) (xy 205.497119 -289.885575) (xy 205.549903 -289.867568)
			(xy 205.604746 -289.857438) (xy 205.66048 -289.855401) (xy 205.715917 -289.861501) (xy 205.769874 -289.875607)
			(xy 205.821203 -289.897419) (xy 205.868809 -289.926473) (xy 205.911677 -289.962148) (xy 205.948894 -290.003685)
			(xy 205.979667 -290.050198) (xy 206.003339 -290.100695) (xy 206.019407 -290.154102) (xy 206.027527 -290.209278)
			(xy 206.028036 -290.237164) (xy 206.027527 -290.26505) (xy 206.019407 -290.320226) (xy 206.003339 -290.373633)
			(xy 205.979667 -290.42413) (xy 205.948894 -290.470643) (xy 205.911677 -290.51218) (xy 205.868809 -290.547855)
			(xy 205.821203 -290.576909) (xy 205.769874 -290.598721) (xy 205.715917 -290.612827) (xy 205.66048 -290.618927)
			(xy 205.604746 -290.61689) (xy 205.549903 -290.60676) (xy 205.497119 -290.588753) (xy 205.447519 -290.563252)
			(xy 205.402161 -290.530801) (xy 205.362012 -290.492092) (xy 205.327926 -290.447949) (xy 205.30063 -290.399314)
			(xy 205.280707 -290.347223) (xy 205.268581 -290.292786) (xy 205.26451 -290.237164) (xy 201.971161 -290.237164)
			(xy 201.992679 -290.283067) (xy 202.008747 -290.336474) (xy 202.016867 -290.39165) (xy 202.017376 -290.419536)
			(xy 202.016867 -290.447422) (xy 202.008747 -290.502598) (xy 201.992679 -290.556005) (xy 201.969007 -290.606502)
			(xy 201.938234 -290.653015) (xy 201.901017 -290.694552) (xy 201.858149 -290.730227) (xy 201.810543 -290.759281)
			(xy 201.759214 -290.781093) (xy 201.705257 -290.795199) (xy 201.64982 -290.801299) (xy 201.594086 -290.799262)
			(xy 201.539243 -290.789132) (xy 201.486459 -290.771125) (xy 201.436859 -290.745624) (xy 201.391501 -290.713173)
			(xy 201.351352 -290.674464) (xy 201.317266 -290.630321) (xy 201.28997 -290.581686) (xy 201.270047 -290.529595)
			(xy 201.257921 -290.475158) (xy 201.25385 -290.419536) (xy 199.19176 -290.419536) (xy 199.218407 -290.437928)
			(xy 199.2539 -290.47202) (xy 199.283465 -290.511364) (xy 199.306336 -290.554941) (xy 199.32192 -290.601622)
			(xy 199.329815 -290.650199) (xy 199.33031 -290.674806) (xy 199.329815 -290.699413) (xy 199.32192 -290.74799)
			(xy 199.306336 -290.794671) (xy 199.283465 -290.838248) (xy 199.2539 -290.877592) (xy 199.218407 -290.911684)
			(xy 199.177904 -290.93964) (xy 199.133442 -290.960738) (xy 199.086171 -290.97443) (xy 199.037316 -290.980362)
			(xy 198.988141 -290.978381) (xy 198.939922 -290.968537) (xy 198.893906 -290.951085) (xy 198.851285 -290.926478)
			(xy 198.813164 -290.895353) (xy 198.780529 -290.858516) (xy 198.754226 -290.81692) (xy 198.734935 -290.771644)
			(xy 198.723158 -290.72386) (xy 198.719198 -290.674806) (xy 198.38035 -290.674806) (xy 198.379855 -290.699413)
			(xy 198.37196 -290.74799) (xy 198.356376 -290.794671) (xy 198.333505 -290.838248) (xy 198.30394 -290.877592)
			(xy 198.268447 -290.911684) (xy 198.227944 -290.93964) (xy 198.183482 -290.960738) (xy 198.136211 -290.97443)
			(xy 198.087356 -290.980362) (xy 198.038181 -290.978381) (xy 197.989962 -290.968537) (xy 197.943946 -290.951085)
			(xy 197.901325 -290.926478) (xy 197.863204 -290.895353) (xy 197.830569 -290.858516) (xy 197.804266 -290.81692)
			(xy 197.784975 -290.771644) (xy 197.773198 -290.72386) (xy 197.769238 -290.674806) (xy 194.580256 -290.674806)
			(xy 194.579761 -290.699413) (xy 194.571866 -290.74799) (xy 194.556282 -290.794671) (xy 194.533411 -290.838248)
			(xy 194.503846 -290.877592) (xy 194.468353 -290.911684) (xy 194.42785 -290.93964) (xy 194.383388 -290.960738)
			(xy 194.336117 -290.97443) (xy 194.287262 -290.980362) (xy 194.238087 -290.978381) (xy 194.189868 -290.968537)
			(xy 194.143852 -290.951085) (xy 194.101231 -290.926478) (xy 194.06311 -290.895353) (xy 194.030475 -290.858516)
			(xy 194.004172 -290.81692) (xy 193.984881 -290.771644) (xy 193.973104 -290.72386) (xy 193.969144 -290.674806)
			(xy 193.630296 -290.674806) (xy 193.629849 -290.698798) (xy 193.622342 -290.746193) (xy 193.607513 -290.791829)
			(xy 193.585727 -290.834583) (xy 193.557521 -290.873403) (xy 193.523589 -290.907332) (xy 193.484768 -290.935536)
			(xy 193.442012 -290.957319) (xy 193.396375 -290.972146) (xy 193.348981 -290.979651) (xy 193.324988 -290.980114)
			(xy 193.312225 -290.979977) (xy 193.286791 -290.977816) (xy 193.274188 -290.975796) (xy 193.274188 -290.97605)
			(xy 193.251582 -290.971224) (xy 193.251328 -290.971224) (xy 193.248788 -290.970462) (xy 193.238374 -290.969192)
			(xy 193.229685 -290.969368) (xy 193.213193 -290.974816) (xy 193.206116 -290.97986) (xy 193.14287 -291.029136)
			(xy 193.13652 -291.034978) (xy 193.131929 -291.040347) (xy 193.125608 -291.052975) (xy 193.124074 -291.05987)
			(xy 193.123312 -291.067998) (xy 193.123312 -291.238686) (xy 202.096622 -291.238686) (xy 202.100693 -291.183064)
			(xy 202.112819 -291.128627) (xy 202.132742 -291.076536) (xy 202.160038 -291.027901) (xy 202.194124 -290.983758)
			(xy 202.234273 -290.945049) (xy 202.279631 -290.912598) (xy 202.329231 -290.887097) (xy 202.382015 -290.86909)
			(xy 202.436858 -290.85896) (xy 202.492592 -290.856923) (xy 202.548029 -290.863023) (xy 202.601986 -290.877129)
			(xy 202.653315 -290.898941) (xy 202.700921 -290.927995) (xy 202.743789 -290.96367) (xy 202.781006 -291.005207)
			(xy 202.811779 -291.05172) (xy 202.835451 -291.102217) (xy 202.851519 -291.155624) (xy 202.859639 -291.2108)
			(xy 202.860148 -291.238686) (xy 202.859639 -291.266572) (xy 202.851519 -291.321748) (xy 202.835451 -291.375155)
			(xy 202.811779 -291.425652) (xy 202.781006 -291.472165) (xy 202.743789 -291.513702) (xy 202.700921 -291.549377)
			(xy 202.653315 -291.578431) (xy 202.601986 -291.600243) (xy 202.548029 -291.614349) (xy 202.492592 -291.620449)
			(xy 202.436858 -291.618412) (xy 202.382015 -291.608282) (xy 202.329231 -291.590275) (xy 202.279631 -291.564774)
			(xy 202.234273 -291.532323) (xy 202.194124 -291.493614) (xy 202.160038 -291.449471) (xy 202.132742 -291.400836)
			(xy 202.112819 -291.348745) (xy 202.100693 -291.294308) (xy 202.096622 -291.238686) (xy 193.123312 -291.238686)
			(xy 193.123312 -291.534342) (xy 193.124836 -291.545772) (xy 193.126612 -291.551967) (xy 193.132778 -291.563279)
			(xy 193.137028 -291.568124) (xy 193.150236 -291.581078) (xy 193.15692 -291.588488) (xy 193.164504 -291.606924)
			(xy 193.164968 -291.616892) (xy 193.164968 -291.624766) (xy 194.919104 -291.624766) (xy 194.923064 -291.575712)
			(xy 194.934841 -291.527928) (xy 194.954132 -291.482652) (xy 194.980435 -291.441056) (xy 195.01307 -291.404219)
			(xy 195.051191 -291.373094) (xy 195.093812 -291.348487) (xy 195.139828 -291.331035) (xy 195.188047 -291.321191)
			(xy 195.237222 -291.31921) (xy 195.286077 -291.325142) (xy 195.333348 -291.338834) (xy 195.37781 -291.359932)
			(xy 195.418313 -291.387888) (xy 195.453806 -291.42198) (xy 195.483371 -291.461324) (xy 195.506242 -291.504901)
			(xy 195.521826 -291.551582) (xy 195.529721 -291.600159) (xy 195.530216 -291.624766) (xy 195.869064 -291.624766)
			(xy 195.873024 -291.575712) (xy 195.884801 -291.527928) (xy 195.904092 -291.482652) (xy 195.930395 -291.441056)
			(xy 195.96303 -291.404219) (xy 196.001151 -291.373094) (xy 196.043772 -291.348487) (xy 196.089788 -291.331035)
			(xy 196.138007 -291.321191) (xy 196.187182 -291.31921) (xy 196.236037 -291.325142) (xy 196.283308 -291.338834)
			(xy 196.32777 -291.359932) (xy 196.368273 -291.387888) (xy 196.403766 -291.42198) (xy 196.433331 -291.461324)
			(xy 196.456202 -291.504901) (xy 196.471786 -291.551582) (xy 196.479681 -291.600159) (xy 196.480176 -291.624766)
			(xy 196.479681 -291.649373) (xy 196.471786 -291.69795) (xy 196.456202 -291.744631) (xy 196.433331 -291.788208)
			(xy 196.403766 -291.827552) (xy 196.368273 -291.861644) (xy 196.32777 -291.8896) (xy 196.283308 -291.910698)
			(xy 196.236037 -291.92439) (xy 196.187182 -291.930322) (xy 196.138007 -291.928341) (xy 196.089788 -291.918497)
			(xy 196.043772 -291.901045) (xy 196.001151 -291.876438) (xy 195.96303 -291.845313) (xy 195.930395 -291.808476)
			(xy 195.904092 -291.76688) (xy 195.884801 -291.721604) (xy 195.873024 -291.67382) (xy 195.869064 -291.624766)
			(xy 195.530216 -291.624766) (xy 195.529721 -291.649373) (xy 195.521826 -291.69795) (xy 195.506242 -291.744631)
			(xy 195.483371 -291.788208) (xy 195.453806 -291.827552) (xy 195.418313 -291.861644) (xy 195.37781 -291.8896)
			(xy 195.333348 -291.910698) (xy 195.286077 -291.92439) (xy 195.237222 -291.930322) (xy 195.188047 -291.928341)
			(xy 195.139828 -291.918497) (xy 195.093812 -291.901045) (xy 195.051191 -291.876438) (xy 195.01307 -291.845313)
			(xy 194.980435 -291.808476) (xy 194.954132 -291.76688) (xy 194.934841 -291.721604) (xy 194.923064 -291.67382)
			(xy 194.919104 -291.624766) (xy 193.164968 -291.624766) (xy 193.164968 -292.172136) (xy 193.165514 -292.182493)
			(xy 193.173774 -292.201496) (xy 193.18097 -292.208966) (xy 193.240914 -292.260782) (xy 193.245145 -292.26426)
			(xy 193.254752 -292.269515) (xy 193.259964 -292.271196) (xy 193.269616 -292.27399) (xy 193.280792 -292.272466)
			(xy 193.291781 -292.270993) (xy 193.313901 -292.269467) (xy 193.324988 -292.269418) (xy 193.350244 -292.26991)
			(xy 193.400068 -292.278222) (xy 193.447844 -292.294622) (xy 193.492269 -292.318662) (xy 193.532131 -292.349686)
			(xy 193.566343 -292.386849) (xy 193.593971 -292.429136) (xy 193.614262 -292.475393) (xy 193.626663 -292.52436)
			(xy 193.630834 -292.5747) (xy 193.630832 -292.574726) (xy 193.969144 -292.574726) (xy 193.973104 -292.525672)
			(xy 193.984881 -292.477888) (xy 194.004172 -292.432612) (xy 194.030475 -292.391016) (xy 194.06311 -292.354179)
			(xy 194.101231 -292.323054) (xy 194.143852 -292.298447) (xy 194.189868 -292.280995) (xy 194.238087 -292.271151)
			(xy 194.287262 -292.26917) (xy 194.336117 -292.275102) (xy 194.383388 -292.288794) (xy 194.42785 -292.309892)
			(xy 194.468353 -292.337848) (xy 194.503846 -292.37194) (xy 194.533411 -292.411284) (xy 194.556282 -292.454861)
			(xy 194.571866 -292.501542) (xy 194.579761 -292.550119) (xy 194.580256 -292.574726) (xy 194.580251 -292.57498)
			(xy 197.769238 -292.57498) (xy 197.773198 -292.525926) (xy 197.784975 -292.478142) (xy 197.804266 -292.432866)
			(xy 197.830569 -292.39127) (xy 197.863204 -292.354433) (xy 197.901325 -292.323308) (xy 197.943946 -292.298701)
			(xy 197.989962 -292.281249) (xy 198.038181 -292.271405) (xy 198.087356 -292.269424) (xy 198.136211 -292.275356)
			(xy 198.183482 -292.289048) (xy 198.227944 -292.310146) (xy 198.268447 -292.338102) (xy 198.30394 -292.372194)
			(xy 198.333505 -292.411538) (xy 198.356376 -292.455115) (xy 198.37196 -292.501796) (xy 198.379855 -292.550373)
			(xy 198.38035 -292.57498) (xy 198.719198 -292.57498) (xy 198.723158 -292.525926) (xy 198.734935 -292.478142)
			(xy 198.754226 -292.432866) (xy 198.780529 -292.39127) (xy 198.813164 -292.354433) (xy 198.851285 -292.323308)
			(xy 198.893906 -292.298701) (xy 198.939922 -292.281249) (xy 198.988141 -292.271405) (xy 199.037316 -292.269424)
			(xy 199.086171 -292.275356) (xy 199.133442 -292.289048) (xy 199.177904 -292.310146) (xy 199.218407 -292.338102)
			(xy 199.2539 -292.372194) (xy 199.283465 -292.411538) (xy 199.306336 -292.455115) (xy 199.32192 -292.501796)
			(xy 199.329815 -292.550373) (xy 199.33031 -292.57498) (xy 199.329815 -292.599587) (xy 199.32192 -292.648164)
			(xy 199.306336 -292.694845) (xy 199.283465 -292.738422) (xy 199.2539 -292.777766) (xy 199.218407 -292.811858)
			(xy 199.177904 -292.839814) (xy 199.133442 -292.860912) (xy 199.086171 -292.874604) (xy 199.037316 -292.880536)
			(xy 198.988141 -292.878555) (xy 198.939922 -292.868711) (xy 198.893906 -292.851259) (xy 198.851285 -292.826652)
			(xy 198.813164 -292.795527) (xy 198.780529 -292.75869) (xy 198.754226 -292.717094) (xy 198.734935 -292.671818)
			(xy 198.723158 -292.624034) (xy 198.719198 -292.57498) (xy 198.38035 -292.57498) (xy 198.379855 -292.599587)
			(xy 198.37196 -292.648164) (xy 198.356376 -292.694845) (xy 198.333505 -292.738422) (xy 198.30394 -292.777766)
			(xy 198.268447 -292.811858) (xy 198.227944 -292.839814) (xy 198.183482 -292.860912) (xy 198.136211 -292.874604)
			(xy 198.087356 -292.880536) (xy 198.038181 -292.878555) (xy 197.989962 -292.868711) (xy 197.943946 -292.851259)
			(xy 197.901325 -292.826652) (xy 197.863204 -292.795527) (xy 197.830569 -292.75869) (xy 197.804266 -292.717094)
			(xy 197.784975 -292.671818) (xy 197.773198 -292.624034) (xy 197.769238 -292.57498) (xy 194.580251 -292.57498)
			(xy 194.579761 -292.599333) (xy 194.571866 -292.64791) (xy 194.556282 -292.694591) (xy 194.533411 -292.738168)
			(xy 194.503846 -292.777512) (xy 194.468353 -292.811604) (xy 194.42785 -292.83956) (xy 194.383388 -292.860658)
			(xy 194.336117 -292.87435) (xy 194.287262 -292.880282) (xy 194.238087 -292.878301) (xy 194.189868 -292.868457)
			(xy 194.143852 -292.851005) (xy 194.101231 -292.826398) (xy 194.06311 -292.795273) (xy 194.030475 -292.758436)
			(xy 194.004172 -292.71684) (xy 193.984881 -292.671564) (xy 193.973104 -292.62378) (xy 193.969144 -292.574726)
			(xy 193.630832 -292.574726) (xy 193.626663 -292.62504) (xy 193.614262 -292.674007) (xy 193.593971 -292.720264)
			(xy 193.566343 -292.762551) (xy 193.532131 -292.799714) (xy 193.492269 -292.830738) (xy 193.447844 -292.854778)
			(xy 193.400068 -292.871178) (xy 193.350244 -292.87949) (xy 193.324988 -292.880034) (xy 193.313902 -292.879968)
			(xy 193.291782 -292.878442) (xy 193.280792 -292.876986) (xy 193.269616 -292.875462) (xy 193.259964 -292.878256)
			(xy 193.254744 -292.87992) (xy 193.245137 -292.885179) (xy 193.240914 -292.88867) (xy 193.18097 -292.940486)
			(xy 193.173738 -292.947933) (xy 193.165469 -292.966949) (xy 193.164968 -292.977316) (xy 193.164968 -293.52494)
			(xy 194.919104 -293.52494) (xy 194.923064 -293.475886) (xy 194.934841 -293.428102) (xy 194.954132 -293.382826)
			(xy 194.980435 -293.34123) (xy 195.01307 -293.304393) (xy 195.051191 -293.273268) (xy 195.093812 -293.248661)
			(xy 195.139828 -293.231209) (xy 195.188047 -293.221365) (xy 195.237222 -293.219384) (xy 195.286077 -293.225316)
			(xy 195.333348 -293.239008) (xy 195.37781 -293.260106) (xy 195.418313 -293.288062) (xy 195.453806 -293.322154)
			(xy 195.483371 -293.361498) (xy 195.506242 -293.405075) (xy 195.521826 -293.451756) (xy 195.529721 -293.500333)
			(xy 195.530216 -293.52494) (xy 195.869064 -293.52494) (xy 195.873024 -293.475886) (xy 195.884801 -293.428102)
			(xy 195.904092 -293.382826) (xy 195.930395 -293.34123) (xy 195.96303 -293.304393) (xy 196.001151 -293.273268)
			(xy 196.043772 -293.248661) (xy 196.089788 -293.231209) (xy 196.138007 -293.221365) (xy 196.187182 -293.219384)
			(xy 196.236037 -293.225316) (xy 196.283308 -293.239008) (xy 196.32777 -293.260106) (xy 196.368273 -293.288062)
			(xy 196.403766 -293.322154) (xy 196.433331 -293.361498) (xy 196.456202 -293.405075) (xy 196.471786 -293.451756)
			(xy 196.479681 -293.500333) (xy 196.480176 -293.52494) (xy 196.479681 -293.549547) (xy 196.471786 -293.598124)
			(xy 196.456202 -293.644805) (xy 196.433331 -293.688382) (xy 196.403766 -293.727726) (xy 196.368273 -293.761818)
			(xy 196.32777 -293.789774) (xy 196.283308 -293.810872) (xy 196.236037 -293.824564) (xy 196.187182 -293.830496)
			(xy 196.138007 -293.828515) (xy 196.089788 -293.818671) (xy 196.043772 -293.801219) (xy 196.001151 -293.776612)
			(xy 195.96303 -293.745487) (xy 195.930395 -293.70865) (xy 195.904092 -293.667054) (xy 195.884801 -293.621778)
			(xy 195.873024 -293.573994) (xy 195.869064 -293.52494) (xy 195.530216 -293.52494) (xy 195.529721 -293.549547)
			(xy 195.521826 -293.598124) (xy 195.506242 -293.644805) (xy 195.483371 -293.688382) (xy 195.453806 -293.727726)
			(xy 195.418313 -293.761818) (xy 195.37781 -293.789774) (xy 195.333348 -293.810872) (xy 195.286077 -293.824564)
			(xy 195.237222 -293.830496) (xy 195.188047 -293.828515) (xy 195.139828 -293.818671) (xy 195.093812 -293.801219)
			(xy 195.051191 -293.776612) (xy 195.01307 -293.745487) (xy 194.980435 -293.70865) (xy 194.954132 -293.667054)
			(xy 194.934841 -293.621778) (xy 194.923064 -293.573994) (xy 194.919104 -293.52494) (xy 193.164968 -293.52494)
			(xy 193.164968 -294.016176) (xy 205.74076 -294.016176) (xy 205.744831 -293.960554) (xy 205.756957 -293.906117)
			(xy 205.77688 -293.854026) (xy 205.804176 -293.805391) (xy 205.838262 -293.761248) (xy 205.878411 -293.722539)
			(xy 205.923769 -293.690088) (xy 205.973369 -293.664587) (xy 206.026153 -293.64658) (xy 206.080996 -293.63645)
			(xy 206.13673 -293.634413) (xy 206.192167 -293.640513) (xy 206.246124 -293.654619) (xy 206.297453 -293.676431)
			(xy 206.345059 -293.705485) (xy 206.387927 -293.74116) (xy 206.425144 -293.782697) (xy 206.455917 -293.82921)
			(xy 206.479589 -293.879707) (xy 206.495657 -293.933114) (xy 206.502648 -293.980616) (xy 207.380838 -293.980616)
			(xy 207.384909 -293.924994) (xy 207.397035 -293.870557) (xy 207.416958 -293.818466) (xy 207.444254 -293.769831)
			(xy 207.47834 -293.725688) (xy 207.518489 -293.686979) (xy 207.563847 -293.654528) (xy 207.613447 -293.629027)
			(xy 207.666231 -293.61102) (xy 207.721074 -293.60089) (xy 207.776808 -293.598853) (xy 207.832245 -293.604953)
			(xy 207.886202 -293.619059) (xy 207.937531 -293.640871) (xy 207.985137 -293.669925) (xy 208.028005 -293.7056)
			(xy 208.065222 -293.747137) (xy 208.095995 -293.79365) (xy 208.119667 -293.844147) (xy 208.135735 -293.897554)
			(xy 208.143855 -293.95273) (xy 208.144364 -293.980616) (xy 208.143855 -294.008502) (xy 208.135735 -294.063678)
			(xy 208.119667 -294.117085) (xy 208.095995 -294.167582) (xy 208.065222 -294.214095) (xy 208.028005 -294.255632)
			(xy 207.985137 -294.291307) (xy 207.937531 -294.320361) (xy 207.886202 -294.342173) (xy 207.832245 -294.356279)
			(xy 207.776808 -294.362379) (xy 207.721074 -294.360342) (xy 207.666231 -294.350212) (xy 207.613447 -294.332205)
			(xy 207.563847 -294.306704) (xy 207.518489 -294.274253) (xy 207.47834 -294.235544) (xy 207.444254 -294.191401)
			(xy 207.416958 -294.142766) (xy 207.397035 -294.090675) (xy 207.384909 -294.036238) (xy 207.380838 -293.980616)
			(xy 206.502648 -293.980616) (xy 206.503777 -293.98829) (xy 206.504286 -294.016176) (xy 206.503777 -294.044062)
			(xy 206.495657 -294.099238) (xy 206.479589 -294.152645) (xy 206.455917 -294.203142) (xy 206.425144 -294.249655)
			(xy 206.387927 -294.291192) (xy 206.345059 -294.326867) (xy 206.297453 -294.355921) (xy 206.246124 -294.377733)
			(xy 206.192167 -294.391839) (xy 206.13673 -294.397939) (xy 206.080996 -294.395902) (xy 206.026153 -294.385772)
			(xy 205.973369 -294.367765) (xy 205.923769 -294.342264) (xy 205.878411 -294.309813) (xy 205.838262 -294.271104)
			(xy 205.804176 -294.226961) (xy 205.77688 -294.178326) (xy 205.756957 -294.126235) (xy 205.744831 -294.071798)
			(xy 205.74076 -294.016176) (xy 193.164968 -294.016176) (xy 193.164968 -294.07231) (xy 193.165509 -294.082669)
			(xy 193.173763 -294.10168) (xy 193.18097 -294.10914) (xy 193.240914 -294.160956) (xy 193.245144 -294.164435)
			(xy 193.25475 -294.169692) (xy 193.259964 -294.17137) (xy 193.269616 -294.174164) (xy 193.280792 -294.17264)
			(xy 193.291781 -294.171167) (xy 193.313901 -294.169642) (xy 193.324988 -294.169592) (xy 193.350246 -294.170084)
			(xy 193.400074 -294.178397) (xy 193.447854 -294.194798) (xy 193.492283 -294.21884) (xy 193.532149 -294.249867)
			(xy 193.566363 -294.287033) (xy 193.593994 -294.329323) (xy 193.614287 -294.375585) (xy 193.626688 -294.424556)
			(xy 193.63086 -294.4749) (xy 197.769238 -294.4749) (xy 197.773198 -294.425846) (xy 197.784975 -294.378062)
			(xy 197.804266 -294.332786) (xy 197.830569 -294.29119) (xy 197.863204 -294.254353) (xy 197.901325 -294.223228)
			(xy 197.943946 -294.198621) (xy 197.989962 -294.181169) (xy 198.038181 -294.171325) (xy 198.087356 -294.169344)
			(xy 198.136211 -294.175276) (xy 198.183482 -294.188968) (xy 198.227944 -294.210066) (xy 198.268447 -294.238022)
			(xy 198.30394 -294.272114) (xy 198.333505 -294.311458) (xy 198.356376 -294.355035) (xy 198.37196 -294.401716)
			(xy 198.379855 -294.450293) (xy 198.38035 -294.4749) (xy 198.719198 -294.4749) (xy 198.723158 -294.425846)
			(xy 198.734935 -294.378062) (xy 198.754226 -294.332786) (xy 198.780529 -294.29119) (xy 198.813164 -294.254353)
			(xy 198.851285 -294.223228) (xy 198.893906 -294.198621) (xy 198.939922 -294.181169) (xy 198.988141 -294.171325)
			(xy 199.037316 -294.169344) (xy 199.086171 -294.175276) (xy 199.133442 -294.188968) (xy 199.177904 -294.210066)
			(xy 199.218407 -294.238022) (xy 199.2539 -294.272114) (xy 199.283465 -294.311458) (xy 199.306336 -294.355035)
			(xy 199.32192 -294.401716) (xy 199.329815 -294.450293) (xy 199.33031 -294.4749) (xy 199.329815 -294.499507)
			(xy 199.32192 -294.548084) (xy 199.306336 -294.594765) (xy 199.283465 -294.638342) (xy 199.2539 -294.677686)
			(xy 199.218407 -294.711778) (xy 199.177904 -294.739734) (xy 199.133442 -294.760832) (xy 199.086171 -294.774524)
			(xy 199.037316 -294.780456) (xy 198.988141 -294.778475) (xy 198.939922 -294.768631) (xy 198.893906 -294.751179)
			(xy 198.851285 -294.726572) (xy 198.813164 -294.695447) (xy 198.780529 -294.65861) (xy 198.754226 -294.617014)
			(xy 198.734935 -294.571738) (xy 198.723158 -294.523954) (xy 198.719198 -294.4749) (xy 198.38035 -294.4749)
			(xy 198.379855 -294.499507) (xy 198.37196 -294.548084) (xy 198.356376 -294.594765) (xy 198.333505 -294.638342)
			(xy 198.30394 -294.677686) (xy 198.268447 -294.711778) (xy 198.227944 -294.739734) (xy 198.183482 -294.760832)
			(xy 198.136211 -294.774524) (xy 198.087356 -294.780456) (xy 198.038181 -294.778475) (xy 197.989962 -294.768631)
			(xy 197.943946 -294.751179) (xy 197.901325 -294.726572) (xy 197.863204 -294.695447) (xy 197.830569 -294.65861)
			(xy 197.804266 -294.617014) (xy 197.784975 -294.571738) (xy 197.773198 -294.523954) (xy 197.769238 -294.4749)
			(xy 193.63086 -294.4749) (xy 193.626688 -294.525244) (xy 193.614287 -294.574215) (xy 193.593994 -294.620477)
			(xy 193.566363 -294.662767) (xy 193.532149 -294.699933) (xy 193.492283 -294.73096) (xy 193.447854 -294.755002)
			(xy 193.400074 -294.771403) (xy 193.350246 -294.779716) (xy 193.324988 -294.780208) (xy 193.313902 -294.780142)
			(xy 193.291782 -294.778616) (xy 193.280792 -294.77716) (xy 193.269616 -294.775636) (xy 193.259964 -294.77843)
			(xy 193.254744 -294.780093) (xy 193.245134 -294.78535) (xy 193.240914 -294.788844) (xy 193.18097 -294.84066)
			(xy 193.173734 -294.848105) (xy 193.165455 -294.867121) (xy 193.164968 -294.87749) (xy 193.164968 -295.97223)
			(xy 193.165513 -295.982588) (xy 193.173772 -296.001592) (xy 193.18097 -296.00906) (xy 193.240914 -296.060876)
			(xy 193.245145 -296.064354) (xy 193.254752 -296.069609) (xy 193.259964 -296.07129) (xy 193.269616 -296.074084)
			(xy 193.280792 -296.07256) (xy 193.291781 -296.071087) (xy 193.313901 -296.069561) (xy 193.324988 -296.069512)
			(xy 193.350245 -296.070004) (xy 193.400069 -296.078316) (xy 193.447846 -296.094716) (xy 193.492272 -296.118757)
			(xy 193.532135 -296.149782) (xy 193.566348 -296.186945) (xy 193.593976 -296.229233) (xy 193.614268 -296.275492)
			(xy 193.626669 -296.324459) (xy 193.63084 -296.3748) (xy 193.630838 -296.37482) (xy 193.969144 -296.37482)
			(xy 193.973104 -296.325766) (xy 193.984881 -296.277982) (xy 194.004172 -296.232706) (xy 194.030475 -296.19111)
			(xy 194.06311 -296.154273) (xy 194.101231 -296.123148) (xy 194.143852 -296.098541) (xy 194.189868 -296.081089)
			(xy 194.238087 -296.071245) (xy 194.287262 -296.069264) (xy 194.336117 -296.075196) (xy 194.383388 -296.088888)
			(xy 194.42785 -296.109986) (xy 194.468353 -296.137942) (xy 194.503846 -296.172034) (xy 194.533411 -296.211378)
			(xy 194.556282 -296.254955) (xy 194.571866 -296.301636) (xy 194.579761 -296.350213) (xy 194.580256 -296.37482)
			(xy 194.579761 -296.399427) (xy 194.571866 -296.448004) (xy 194.556282 -296.494685) (xy 194.533411 -296.538262)
			(xy 194.503846 -296.577606) (xy 194.468353 -296.611698) (xy 194.466362 -296.613072) (xy 205.362554 -296.613072)
			(xy 205.366625 -296.55745) (xy 205.378751 -296.503013) (xy 205.398674 -296.450922) (xy 205.42597 -296.402287)
			(xy 205.460056 -296.358144) (xy 205.500205 -296.319435) (xy 205.545563 -296.286984) (xy 205.595163 -296.261483)
			(xy 205.647947 -296.243476) (xy 205.70279 -296.233346) (xy 205.758524 -296.231309) (xy 205.813961 -296.237409)
			(xy 205.867918 -296.251515) (xy 205.919247 -296.273327) (xy 205.966853 -296.302381) (xy 206.009721 -296.338056)
			(xy 206.046938 -296.379593) (xy 206.077711 -296.426106) (xy 206.101383 -296.476603) (xy 206.117451 -296.53001)
			(xy 206.125571 -296.585186) (xy 206.12608 -296.613072) (xy 206.63738 -296.613072) (xy 206.641451 -296.55745)
			(xy 206.653577 -296.503013) (xy 206.6735 -296.450922) (xy 206.700796 -296.402287) (xy 206.734882 -296.358144)
			(xy 206.775031 -296.319435) (xy 206.820389 -296.286984) (xy 206.869989 -296.261483) (xy 206.922773 -296.243476)
			(xy 206.977616 -296.233346) (xy 207.03335 -296.231309) (xy 207.088787 -296.237409) (xy 207.142744 -296.251515)
			(xy 207.194073 -296.273327) (xy 207.241679 -296.302381) (xy 207.284547 -296.338056) (xy 207.321764 -296.379593)
			(xy 207.352537 -296.426106) (xy 207.376209 -296.476603) (xy 207.392277 -296.53001) (xy 207.400397 -296.585186)
			(xy 207.400906 -296.613072) (xy 207.400397 -296.640958) (xy 207.392277 -296.696134) (xy 207.376209 -296.749541)
			(xy 207.352537 -296.800038) (xy 207.321764 -296.846551) (xy 207.284547 -296.888088) (xy 207.241679 -296.923763)
			(xy 207.194073 -296.952817) (xy 207.142744 -296.974629) (xy 207.088787 -296.988735) (xy 207.03335 -296.994835)
			(xy 206.977616 -296.992798) (xy 206.922773 -296.982668) (xy 206.869989 -296.964661) (xy 206.820389 -296.93916)
			(xy 206.775031 -296.906709) (xy 206.734882 -296.868) (xy 206.700796 -296.823857) (xy 206.6735 -296.775222)
			(xy 206.653577 -296.723131) (xy 206.641451 -296.668694) (xy 206.63738 -296.613072) (xy 206.12608 -296.613072)
			(xy 206.125571 -296.640958) (xy 206.117451 -296.696134) (xy 206.101383 -296.749541) (xy 206.077711 -296.800038)
			(xy 206.046938 -296.846551) (xy 206.009721 -296.888088) (xy 205.966853 -296.923763) (xy 205.919247 -296.952817)
			(xy 205.867918 -296.974629) (xy 205.813961 -296.988735) (xy 205.758524 -296.994835) (xy 205.70279 -296.992798)
			(xy 205.647947 -296.982668) (xy 205.595163 -296.964661) (xy 205.545563 -296.93916) (xy 205.500205 -296.906709)
			(xy 205.460056 -296.868) (xy 205.42597 -296.823857) (xy 205.398674 -296.775222) (xy 205.378751 -296.723131)
			(xy 205.366625 -296.668694) (xy 205.362554 -296.613072) (xy 194.466362 -296.613072) (xy 194.42785 -296.639654)
			(xy 194.383388 -296.660752) (xy 194.336117 -296.674444) (xy 194.287262 -296.680376) (xy 194.238087 -296.678395)
			(xy 194.189868 -296.668551) (xy 194.143852 -296.651099) (xy 194.101231 -296.626492) (xy 194.06311 -296.595367)
			(xy 194.030475 -296.55853) (xy 194.004172 -296.516934) (xy 193.984881 -296.471658) (xy 193.973104 -296.423874)
			(xy 193.969144 -296.37482) (xy 193.630838 -296.37482) (xy 193.626669 -296.425141) (xy 193.614268 -296.474108)
			(xy 193.593976 -296.520367) (xy 193.566348 -296.562655) (xy 193.532135 -296.599818) (xy 193.492272 -296.630843)
			(xy 193.447846 -296.654884) (xy 193.400069 -296.671284) (xy 193.350245 -296.679596) (xy 193.324988 -296.680128)
			(xy 193.313902 -296.680062) (xy 193.291782 -296.678536) (xy 193.280792 -296.67708) (xy 193.269616 -296.675556)
			(xy 193.259964 -296.67835) (xy 193.254744 -296.680014) (xy 193.245136 -296.685273) (xy 193.240914 -296.688764)
			(xy 193.18097 -296.74058) (xy 193.173738 -296.748026) (xy 193.165466 -296.767042) (xy 193.164968 -296.77741)
			(xy 193.164968 -297.32478) (xy 194.919104 -297.32478) (xy 194.923064 -297.275726) (xy 194.934841 -297.227942)
			(xy 194.954132 -297.182666) (xy 194.980435 -297.14107) (xy 195.01307 -297.104233) (xy 195.051191 -297.073108)
			(xy 195.093812 -297.048501) (xy 195.139828 -297.031049) (xy 195.188047 -297.021205) (xy 195.237222 -297.019224)
			(xy 195.286077 -297.025156) (xy 195.333348 -297.038848) (xy 195.37781 -297.059946) (xy 195.418313 -297.087902)
			(xy 195.453806 -297.121994) (xy 195.483371 -297.161338) (xy 195.506242 -297.204915) (xy 195.521826 -297.251596)
			(xy 195.529721 -297.300173) (xy 195.530216 -297.32478) (xy 195.869064 -297.32478) (xy 195.873024 -297.275726)
			(xy 195.884801 -297.227942) (xy 195.904092 -297.182666) (xy 195.930395 -297.14107) (xy 195.96303 -297.104233)
			(xy 196.001151 -297.073108) (xy 196.043772 -297.048501) (xy 196.089788 -297.031049) (xy 196.138007 -297.021205)
			(xy 196.187182 -297.019224) (xy 196.236037 -297.025156) (xy 196.283308 -297.038848) (xy 196.32777 -297.059946)
			(xy 196.368273 -297.087902) (xy 196.403766 -297.121994) (xy 196.433331 -297.161338) (xy 196.456202 -297.204915)
			(xy 196.471786 -297.251596) (xy 196.479681 -297.300173) (xy 196.480176 -297.32478) (xy 196.479681 -297.349387)
			(xy 196.471786 -297.397964) (xy 196.456202 -297.444645) (xy 196.433331 -297.488222) (xy 196.403766 -297.527566)
			(xy 196.368273 -297.561658) (xy 196.32777 -297.589614) (xy 196.283308 -297.610712) (xy 196.236037 -297.624404)
			(xy 196.187182 -297.630336) (xy 196.138007 -297.628355) (xy 196.089788 -297.618511) (xy 196.043772 -297.601059)
			(xy 196.001151 -297.576452) (xy 195.96303 -297.545327) (xy 195.930395 -297.50849) (xy 195.904092 -297.466894)
			(xy 195.884801 -297.421618) (xy 195.873024 -297.373834) (xy 195.869064 -297.32478) (xy 195.530216 -297.32478)
			(xy 195.529721 -297.349387) (xy 195.521826 -297.397964) (xy 195.506242 -297.444645) (xy 195.483371 -297.488222)
			(xy 195.453806 -297.527566) (xy 195.418313 -297.561658) (xy 195.37781 -297.589614) (xy 195.333348 -297.610712)
			(xy 195.286077 -297.624404) (xy 195.237222 -297.630336) (xy 195.188047 -297.628355) (xy 195.139828 -297.618511)
			(xy 195.093812 -297.601059) (xy 195.051191 -297.576452) (xy 195.01307 -297.545327) (xy 194.980435 -297.50849)
			(xy 194.954132 -297.466894) (xy 194.934841 -297.421618) (xy 194.923064 -297.373834) (xy 194.919104 -297.32478)
			(xy 193.164968 -297.32478) (xy 193.164968 -297.87215) (xy 193.165516 -297.882506) (xy 193.173781 -297.901505)
			(xy 193.18097 -297.90898) (xy 193.240914 -297.960796) (xy 193.245145 -297.964273) (xy 193.254753 -297.969526)
			(xy 193.259964 -297.97121) (xy 193.269616 -297.974004) (xy 193.280792 -297.97248) (xy 193.291781 -297.971007)
			(xy 193.313901 -297.969481) (xy 193.324988 -297.969432) (xy 193.350243 -297.969924) (xy 193.400065 -297.978236)
			(xy 193.447838 -297.994635) (xy 193.492261 -298.018674) (xy 193.532122 -298.049697) (xy 193.566332 -298.086857)
			(xy 193.593959 -298.129142) (xy 193.614249 -298.175398) (xy 193.626649 -298.224362) (xy 193.63082 -298.2747)
			(xy 193.630817 -298.27474) (xy 193.969144 -298.27474) (xy 193.973104 -298.225686) (xy 193.984881 -298.177902)
			(xy 194.004172 -298.132626) (xy 194.030475 -298.09103) (xy 194.06311 -298.054193) (xy 194.101231 -298.023068)
			(xy 194.143852 -297.998461) (xy 194.189868 -297.981009) (xy 194.238087 -297.971165) (xy 194.287262 -297.969184)
			(xy 194.336117 -297.975116) (xy 194.383388 -297.988808) (xy 194.42785 -298.009906) (xy 194.468353 -298.037862)
			(xy 194.503846 -298.071954) (xy 194.533411 -298.111298) (xy 194.556282 -298.154875) (xy 194.571866 -298.201556)
			(xy 194.579761 -298.250133) (xy 194.580256 -298.27474) (xy 197.769238 -298.27474) (xy 197.773198 -298.225686)
			(xy 197.784975 -298.177902) (xy 197.804266 -298.132626) (xy 197.830569 -298.09103) (xy 197.863204 -298.054193)
			(xy 197.901325 -298.023068) (xy 197.943946 -297.998461) (xy 197.989962 -297.981009) (xy 198.038181 -297.971165)
			(xy 198.087356 -297.969184) (xy 198.136211 -297.975116) (xy 198.183482 -297.988808) (xy 198.227944 -298.009906)
			(xy 198.268447 -298.037862) (xy 198.30394 -298.071954) (xy 198.333505 -298.111298) (xy 198.356376 -298.154875)
			(xy 198.37196 -298.201556) (xy 198.379855 -298.250133) (xy 198.38035 -298.27474) (xy 198.719198 -298.27474)
			(xy 198.723158 -298.225686) (xy 198.734935 -298.177902) (xy 198.754226 -298.132626) (xy 198.780529 -298.09103)
			(xy 198.813164 -298.054193) (xy 198.851285 -298.023068) (xy 198.893906 -297.998461) (xy 198.939922 -297.981009)
			(xy 198.988141 -297.971165) (xy 199.037316 -297.969184) (xy 199.086171 -297.975116) (xy 199.133442 -297.988808)
			(xy 199.177904 -298.009906) (xy 199.218407 -298.037862) (xy 199.2539 -298.071954) (xy 199.283465 -298.111298)
			(xy 199.306336 -298.154875) (xy 199.32192 -298.201556) (xy 199.329815 -298.250133) (xy 199.33031 -298.27474)
			(xy 199.329815 -298.299347) (xy 199.32192 -298.347924) (xy 199.321344 -298.349649) (xy 199.767688 -298.349649)
			(xy 199.767688 -298.296351) (xy 199.775631 -298.243647) (xy 199.791341 -298.192717) (xy 199.814467 -298.144696)
			(xy 199.844491 -298.100659) (xy 199.880743 -298.061588) (xy 199.922414 -298.028357) (xy 199.968572 -298.001708)
			(xy 200.018186 -297.982236) (xy 200.070148 -297.970376) (xy 200.123298 -297.966393) (xy 200.176448 -297.970376)
			(xy 200.22841 -297.982236) (xy 200.235858 -297.985159) (xy 200.882748 -297.985159) (xy 200.882748 -297.931861)
			(xy 200.890691 -297.879157) (xy 200.906401 -297.828227) (xy 200.929527 -297.780206) (xy 200.959551 -297.736169)
			(xy 200.995803 -297.697098) (xy 201.037474 -297.663867) (xy 201.083632 -297.637218) (xy 201.133246 -297.617746)
			(xy 201.185208 -297.605886) (xy 201.238358 -297.601903) (xy 201.291508 -297.605886) (xy 201.34347 -297.617746)
			(xy 201.393084 -297.637218) (xy 201.439242 -297.663867) (xy 201.473008 -297.690794) (xy 202.399644 -297.690794)
			(xy 202.403715 -297.635172) (xy 202.415841 -297.580735) (xy 202.435764 -297.528644) (xy 202.46306 -297.480009)
			(xy 202.497146 -297.435866) (xy 202.537295 -297.397157) (xy 202.582653 -297.364706) (xy 202.632253 -297.339205)
			(xy 202.685037 -297.321198) (xy 202.73988 -297.311068) (xy 202.795614 -297.309031) (xy 202.851051 -297.315131)
			(xy 202.905008 -297.329237) (xy 202.956337 -297.351049) (xy 202.995283 -297.374818) (xy 208.715862 -297.374818)
			(xy 208.719933 -297.319196) (xy 208.732059 -297.264759) (xy 208.751982 -297.212668) (xy 208.779278 -297.164033)
			(xy 208.813364 -297.11989) (xy 208.853513 -297.081181) (xy 208.898871 -297.04873) (xy 208.948471 -297.023229)
			(xy 209.001255 -297.005222) (xy 209.056098 -296.995092) (xy 209.111832 -296.993055) (xy 209.167269 -296.999155)
			(xy 209.221226 -297.013261) (xy 209.272555 -297.035073) (xy 209.320161 -297.064127) (xy 209.363029 -297.099802)
			(xy 209.400246 -297.141339) (xy 209.431019 -297.187852) (xy 209.454691 -297.238349) (xy 209.470759 -297.291756)
			(xy 209.478879 -297.346932) (xy 209.479388 -297.374818) (xy 209.478879 -297.402704) (xy 209.470759 -297.45788)
			(xy 209.454691 -297.511287) (xy 209.431019 -297.561784) (xy 209.400246 -297.608297) (xy 209.363029 -297.649834)
			(xy 209.320161 -297.685509) (xy 209.272555 -297.714563) (xy 209.221226 -297.736375) (xy 209.167269 -297.750481)
			(xy 209.111832 -297.756581) (xy 209.056098 -297.754544) (xy 209.001255 -297.744414) (xy 208.948471 -297.726407)
			(xy 208.898871 -297.700906) (xy 208.853513 -297.668455) (xy 208.813364 -297.629746) (xy 208.779278 -297.585603)
			(xy 208.751982 -297.536968) (xy 208.732059 -297.484877) (xy 208.719933 -297.43044) (xy 208.715862 -297.374818)
			(xy 202.995283 -297.374818) (xy 203.003943 -297.380103) (xy 203.046811 -297.415778) (xy 203.084028 -297.457315)
			(xy 203.114801 -297.503828) (xy 203.138473 -297.554325) (xy 203.154541 -297.607732) (xy 203.162661 -297.662908)
			(xy 203.16317 -297.690794) (xy 203.162661 -297.71868) (xy 203.154541 -297.773856) (xy 203.138473 -297.827263)
			(xy 203.114801 -297.87776) (xy 203.084028 -297.924273) (xy 203.046811 -297.96581) (xy 203.003943 -298.001485)
			(xy 202.956337 -298.030539) (xy 202.905008 -298.052351) (xy 202.851051 -298.066457) (xy 202.795614 -298.072557)
			(xy 202.73988 -298.07052) (xy 202.685037 -298.06039) (xy 202.632253 -298.042383) (xy 202.582653 -298.016882)
			(xy 202.537295 -297.984431) (xy 202.497146 -297.945722) (xy 202.46306 -297.901579) (xy 202.435764 -297.852944)
			(xy 202.415841 -297.800853) (xy 202.403715 -297.746416) (xy 202.399644 -297.690794) (xy 201.473008 -297.690794)
			(xy 201.480913 -297.697098) (xy 201.517165 -297.736169) (xy 201.547189 -297.780206) (xy 201.570315 -297.828227)
			(xy 201.586025 -297.879157) (xy 201.593968 -297.931861) (xy 201.594466 -297.95851) (xy 201.593968 -297.985159)
			(xy 201.586025 -298.037863) (xy 201.570315 -298.088793) (xy 201.547189 -298.136814) (xy 201.517165 -298.180851)
			(xy 201.480913 -298.219922) (xy 201.439242 -298.253153) (xy 201.393084 -298.279802) (xy 201.34347 -298.299274)
			(xy 201.291508 -298.311134) (xy 201.238358 -298.315118) (xy 201.185208 -298.311134) (xy 201.133246 -298.299274)
			(xy 201.083632 -298.279802) (xy 201.037474 -298.253153) (xy 200.995803 -298.219922) (xy 200.959551 -298.180851)
			(xy 200.929527 -298.136814) (xy 200.906401 -298.088793) (xy 200.890691 -298.037863) (xy 200.882748 -297.985159)
			(xy 200.235858 -297.985159) (xy 200.278024 -298.001708) (xy 200.324182 -298.028357) (xy 200.365853 -298.061588)
			(xy 200.402105 -298.100659) (xy 200.432129 -298.144696) (xy 200.455255 -298.192717) (xy 200.470965 -298.243647)
			(xy 200.478908 -298.296351) (xy 200.479406 -298.323) (xy 200.478908 -298.349649) (xy 200.470965 -298.402353)
			(xy 200.455255 -298.453283) (xy 200.432129 -298.501304) (xy 200.402105 -298.545341) (xy 200.365853 -298.584412)
			(xy 200.324182 -298.617643) (xy 200.278024 -298.644292) (xy 200.22841 -298.663764) (xy 200.176448 -298.675624)
			(xy 200.123298 -298.679608) (xy 200.070148 -298.675624) (xy 200.018186 -298.663764) (xy 199.968572 -298.644292)
			(xy 199.922414 -298.617643) (xy 199.880743 -298.584412) (xy 199.844491 -298.545341) (xy 199.814467 -298.501304)
			(xy 199.791341 -298.453283) (xy 199.775631 -298.402353) (xy 199.767688 -298.349649) (xy 199.321344 -298.349649)
			(xy 199.306336 -298.394605) (xy 199.283465 -298.438182) (xy 199.2539 -298.477526) (xy 199.218407 -298.511618)
			(xy 199.177904 -298.539574) (xy 199.133442 -298.560672) (xy 199.086171 -298.574364) (xy 199.037316 -298.580296)
			(xy 198.988141 -298.578315) (xy 198.939922 -298.568471) (xy 198.893906 -298.551019) (xy 198.851285 -298.526412)
			(xy 198.813164 -298.495287) (xy 198.780529 -298.45845) (xy 198.754226 -298.416854) (xy 198.734935 -298.371578)
			(xy 198.723158 -298.323794) (xy 198.719198 -298.27474) (xy 198.38035 -298.27474) (xy 198.379855 -298.299347)
			(xy 198.37196 -298.347924) (xy 198.356376 -298.394605) (xy 198.333505 -298.438182) (xy 198.30394 -298.477526)
			(xy 198.268447 -298.511618) (xy 198.227944 -298.539574) (xy 198.183482 -298.560672) (xy 198.136211 -298.574364)
			(xy 198.087356 -298.580296) (xy 198.038181 -298.578315) (xy 197.989962 -298.568471) (xy 197.943946 -298.551019)
			(xy 197.901325 -298.526412) (xy 197.863204 -298.495287) (xy 197.830569 -298.45845) (xy 197.804266 -298.416854)
			(xy 197.784975 -298.371578) (xy 197.773198 -298.323794) (xy 197.769238 -298.27474) (xy 194.580256 -298.27474)
			(xy 194.579761 -298.299347) (xy 194.571866 -298.347924) (xy 194.556282 -298.394605) (xy 194.533411 -298.438182)
			(xy 194.503846 -298.477526) (xy 194.468353 -298.511618) (xy 194.42785 -298.539574) (xy 194.383388 -298.560672)
			(xy 194.336117 -298.574364) (xy 194.287262 -298.580296) (xy 194.238087 -298.578315) (xy 194.189868 -298.568471)
			(xy 194.143852 -298.551019) (xy 194.101231 -298.526412) (xy 194.06311 -298.495287) (xy 194.030475 -298.45845)
			(xy 194.004172 -298.416854) (xy 193.984881 -298.371578) (xy 193.973104 -298.323794) (xy 193.969144 -298.27474)
			(xy 193.630817 -298.27474) (xy 193.626649 -298.325038) (xy 193.614249 -298.374002) (xy 193.593959 -298.420258)
			(xy 193.566332 -298.462543) (xy 193.532122 -298.499703) (xy 193.492261 -298.530726) (xy 193.447838 -298.554765)
			(xy 193.400065 -298.571164) (xy 193.350243 -298.579476) (xy 193.324988 -298.580048) (xy 193.313902 -298.579982)
			(xy 193.291782 -298.578456) (xy 193.280792 -298.577) (xy 193.269616 -298.575476) (xy 193.259964 -298.57827)
			(xy 193.254745 -298.579934) (xy 193.245138 -298.585195) (xy 193.240914 -298.588684) (xy 193.18097 -298.6405)
			(xy 193.173741 -298.647947) (xy 193.165476 -298.666963) (xy 193.164968 -298.67733) (xy 193.164968 -298.69765)
			(xy 202.569062 -298.69765) (xy 202.573133 -298.642028) (xy 202.585259 -298.587591) (xy 202.605182 -298.5355)
			(xy 202.632478 -298.486865) (xy 202.666564 -298.442722) (xy 202.706713 -298.404013) (xy 202.752071 -298.371562)
			(xy 202.801671 -298.346061) (xy 202.854455 -298.328054) (xy 202.909298 -298.317924) (xy 202.965032 -298.315887)
			(xy 203.020469 -298.321987) (xy 203.074426 -298.336093) (xy 203.125755 -298.357905) (xy 203.173361 -298.386959)
			(xy 203.216229 -298.422634) (xy 203.253446 -298.464171) (xy 203.284219 -298.510684) (xy 203.307891 -298.561181)
			(xy 203.323959 -298.614588) (xy 203.332079 -298.669764) (xy 203.332588 -298.69765) (xy 203.332079 -298.725536)
			(xy 203.323959 -298.780712) (xy 203.307891 -298.834119) (xy 203.284219 -298.884616) (xy 203.253446 -298.931129)
			(xy 203.216229 -298.972666) (xy 203.173361 -299.008341) (xy 203.125755 -299.037395) (xy 203.074426 -299.059207)
			(xy 203.020469 -299.073313) (xy 202.965032 -299.079413) (xy 202.909298 -299.077376) (xy 202.854455 -299.067246)
			(xy 202.801671 -299.049239) (xy 202.752071 -299.023738) (xy 202.706713 -298.991287) (xy 202.666564 -298.952578)
			(xy 202.632478 -298.908435) (xy 202.605182 -298.8598) (xy 202.585259 -298.807709) (xy 202.573133 -298.753272)
			(xy 202.569062 -298.69765) (xy 193.164968 -298.69765) (xy 193.164968 -299.224954) (xy 194.919104 -299.224954)
			(xy 194.923064 -299.1759) (xy 194.934841 -299.128116) (xy 194.954132 -299.08284) (xy 194.980435 -299.041244)
			(xy 195.01307 -299.004407) (xy 195.051191 -298.973282) (xy 195.093812 -298.948675) (xy 195.139828 -298.931223)
			(xy 195.188047 -298.921379) (xy 195.237222 -298.919398) (xy 195.286077 -298.92533) (xy 195.333348 -298.939022)
			(xy 195.37781 -298.96012) (xy 195.418313 -298.988076) (xy 195.453806 -299.022168) (xy 195.483371 -299.061512)
			(xy 195.506242 -299.105089) (xy 195.521826 -299.15177) (xy 195.529721 -299.200347) (xy 195.530216 -299.224954)
			(xy 195.869064 -299.224954) (xy 195.873024 -299.1759) (xy 195.884801 -299.128116) (xy 195.904092 -299.08284)
			(xy 195.930395 -299.041244) (xy 195.96303 -299.004407) (xy 196.001151 -298.973282) (xy 196.043772 -298.948675)
			(xy 196.089788 -298.931223) (xy 196.138007 -298.921379) (xy 196.187182 -298.919398) (xy 196.236037 -298.92533)
			(xy 196.283308 -298.939022) (xy 196.32777 -298.96012) (xy 196.368273 -298.988076) (xy 196.403766 -299.022168)
			(xy 196.433331 -299.061512) (xy 196.456202 -299.105089) (xy 196.471786 -299.15177) (xy 196.479681 -299.200347)
			(xy 196.480176 -299.224954) (xy 196.479681 -299.249561) (xy 196.475878 -299.27296) (xy 206.414622 -299.27296)
			(xy 206.418693 -299.217338) (xy 206.430819 -299.162901) (xy 206.450742 -299.11081) (xy 206.478038 -299.062175)
			(xy 206.512124 -299.018032) (xy 206.552273 -298.979323) (xy 206.597631 -298.946872) (xy 206.647231 -298.921371)
			(xy 206.700015 -298.903364) (xy 206.754858 -298.893234) (xy 206.810592 -298.891197) (xy 206.866029 -298.897297)
			(xy 206.919986 -298.911403) (xy 206.971315 -298.933215) (xy 207.018921 -298.962269) (xy 207.061789 -298.997944)
			(xy 207.099006 -299.039481) (xy 207.129779 -299.085994) (xy 207.153451 -299.136491) (xy 207.169519 -299.189898)
			(xy 207.177639 -299.245074) (xy 207.178148 -299.27296) (xy 207.177639 -299.300846) (xy 207.169519 -299.356022)
			(xy 207.153451 -299.409429) (xy 207.129779 -299.459926) (xy 207.099006 -299.506439) (xy 207.061789 -299.547976)
			(xy 207.018921 -299.583651) (xy 206.971315 -299.612705) (xy 206.919986 -299.634517) (xy 206.866029 -299.648623)
			(xy 206.810592 -299.654723) (xy 206.754858 -299.652686) (xy 206.700015 -299.642556) (xy 206.647231 -299.624549)
			(xy 206.597631 -299.599048) (xy 206.552273 -299.566597) (xy 206.512124 -299.527888) (xy 206.478038 -299.483745)
			(xy 206.450742 -299.43511) (xy 206.430819 -299.383019) (xy 206.418693 -299.328582) (xy 206.414622 -299.27296)
			(xy 196.475878 -299.27296) (xy 196.471786 -299.298138) (xy 196.456202 -299.344819) (xy 196.433331 -299.388396)
			(xy 196.403766 -299.42774) (xy 196.368273 -299.461832) (xy 196.32777 -299.489788) (xy 196.283308 -299.510886)
			(xy 196.236037 -299.524578) (xy 196.187182 -299.53051) (xy 196.138007 -299.528529) (xy 196.089788 -299.518685)
			(xy 196.043772 -299.501233) (xy 196.001151 -299.476626) (xy 195.96303 -299.445501) (xy 195.930395 -299.408664)
			(xy 195.904092 -299.367068) (xy 195.884801 -299.321792) (xy 195.873024 -299.274008) (xy 195.869064 -299.224954)
			(xy 195.530216 -299.224954) (xy 195.529721 -299.249561) (xy 195.521826 -299.298138) (xy 195.506242 -299.344819)
			(xy 195.483371 -299.388396) (xy 195.453806 -299.42774) (xy 195.418313 -299.461832) (xy 195.37781 -299.489788)
			(xy 195.333348 -299.510886) (xy 195.286077 -299.524578) (xy 195.237222 -299.53051) (xy 195.188047 -299.528529)
			(xy 195.139828 -299.518685) (xy 195.093812 -299.501233) (xy 195.051191 -299.476626) (xy 195.01307 -299.445501)
			(xy 194.980435 -299.408664) (xy 194.954132 -299.367068) (xy 194.934841 -299.321792) (xy 194.923064 -299.274008)
			(xy 194.919104 -299.224954) (xy 193.164968 -299.224954) (xy 193.164968 -299.76445) (xy 204.14183 -299.76445)
			(xy 204.145901 -299.708828) (xy 204.158027 -299.654391) (xy 204.17795 -299.6023) (xy 204.205246 -299.553665)
			(xy 204.239332 -299.509522) (xy 204.279481 -299.470813) (xy 204.324839 -299.438362) (xy 204.374439 -299.412861)
			(xy 204.427223 -299.394854) (xy 204.482066 -299.384724) (xy 204.5378 -299.382687) (xy 204.593237 -299.388787)
			(xy 204.647194 -299.402893) (xy 204.698523 -299.424705) (xy 204.746129 -299.453759) (xy 204.788997 -299.489434)
			(xy 204.826214 -299.530971) (xy 204.856987 -299.577484) (xy 204.880659 -299.627981) (xy 204.896727 -299.681388)
			(xy 204.904847 -299.736564) (xy 204.905356 -299.76445) (xy 204.905078 -299.77969) (xy 208.738468 -299.77969)
			(xy 208.742539 -299.724068) (xy 208.754665 -299.669631) (xy 208.774588 -299.61754) (xy 208.801884 -299.568905)
			(xy 208.83597 -299.524762) (xy 208.876119 -299.486053) (xy 208.921477 -299.453602) (xy 208.971077 -299.428101)
			(xy 209.023861 -299.410094) (xy 209.078704 -299.399964) (xy 209.134438 -299.397927) (xy 209.189875 -299.404027)
			(xy 209.243832 -299.418133) (xy 209.295161 -299.439945) (xy 209.342767 -299.468999) (xy 209.385635 -299.504674)
			(xy 209.422852 -299.546211) (xy 209.453625 -299.592724) (xy 209.477297 -299.643221) (xy 209.493365 -299.696628)
			(xy 209.501485 -299.751804) (xy 209.501994 -299.77969) (xy 209.501485 -299.807576) (xy 209.493365 -299.862752)
			(xy 209.477297 -299.916159) (xy 209.453625 -299.966656) (xy 209.422852 -300.013169) (xy 209.385635 -300.054706)
			(xy 209.342767 -300.090381) (xy 209.295161 -300.119435) (xy 209.243832 -300.141247) (xy 209.189875 -300.155353)
			(xy 209.134438 -300.161453) (xy 209.078704 -300.159416) (xy 209.023861 -300.149286) (xy 208.971077 -300.131279)
			(xy 208.921477 -300.105778) (xy 208.876119 -300.073327) (xy 208.83597 -300.034618) (xy 208.801884 -299.990475)
			(xy 208.774588 -299.94184) (xy 208.754665 -299.889749) (xy 208.742539 -299.835312) (xy 208.738468 -299.77969)
			(xy 204.905078 -299.77969) (xy 204.904847 -299.792336) (xy 204.896727 -299.847512) (xy 204.880659 -299.900919)
			(xy 204.856987 -299.951416) (xy 204.826214 -299.997929) (xy 204.788997 -300.039466) (xy 204.746129 -300.075141)
			(xy 204.698523 -300.104195) (xy 204.647194 -300.126007) (xy 204.593237 -300.140113) (xy 204.5378 -300.146213)
			(xy 204.482066 -300.144176) (xy 204.427223 -300.134046) (xy 204.374439 -300.116039) (xy 204.324839 -300.090538)
			(xy 204.279481 -300.058087) (xy 204.239332 -300.019378) (xy 204.205246 -299.975235) (xy 204.17795 -299.9266)
			(xy 204.158027 -299.874509) (xy 204.145901 -299.820072) (xy 204.14183 -299.76445) (xy 193.164968 -299.76445)
			(xy 193.164968 -299.772324) (xy 193.165511 -299.782682) (xy 193.173769 -299.801688) (xy 193.18097 -299.809154)
			(xy 193.240914 -299.86097) (xy 193.245145 -299.864448) (xy 193.254751 -299.869704) (xy 193.259964 -299.871384)
			(xy 193.269616 -299.874178) (xy 193.280792 -299.872654) (xy 193.291781 -299.871181) (xy 193.313901 -299.869655)
			(xy 193.324988 -299.869606) (xy 193.350245 -299.870098) (xy 193.400071 -299.87841) (xy 193.447849 -299.894811)
			(xy 193.492276 -299.918852) (xy 193.532139 -299.949877) (xy 193.566352 -299.987042) (xy 193.593982 -300.02933)
			(xy 193.614274 -300.07559) (xy 193.626674 -300.124558) (xy 193.630846 -300.1749) (xy 193.630845 -300.174914)
			(xy 193.969144 -300.174914) (xy 193.973104 -300.12586) (xy 193.984881 -300.078076) (xy 194.004172 -300.0328)
			(xy 194.030475 -299.991204) (xy 194.06311 -299.954367) (xy 194.101231 -299.923242) (xy 194.143852 -299.898635)
			(xy 194.189868 -299.881183) (xy 194.238087 -299.871339) (xy 194.287262 -299.869358) (xy 194.336117 -299.87529)
			(xy 194.383388 -299.888982) (xy 194.42785 -299.91008) (xy 194.468353 -299.938036) (xy 194.503846 -299.972128)
			(xy 194.533411 -300.011472) (xy 194.556282 -300.055049) (xy 194.571866 -300.10173) (xy 194.579761 -300.150307)
			(xy 194.580256 -300.174914) (xy 197.769238 -300.174914) (xy 197.773198 -300.12586) (xy 197.784975 -300.078076)
			(xy 197.804266 -300.0328) (xy 197.830569 -299.991204) (xy 197.863204 -299.954367) (xy 197.901325 -299.923242)
			(xy 197.943946 -299.898635) (xy 197.989962 -299.881183) (xy 198.038181 -299.871339) (xy 198.087356 -299.869358)
			(xy 198.136211 -299.87529) (xy 198.183482 -299.888982) (xy 198.227944 -299.91008) (xy 198.268447 -299.938036)
			(xy 198.30394 -299.972128) (xy 198.333505 -300.011472) (xy 198.356376 -300.055049) (xy 198.37196 -300.10173)
			(xy 198.379855 -300.150307) (xy 198.38035 -300.174914) (xy 198.719198 -300.174914) (xy 198.723158 -300.12586)
			(xy 198.734935 -300.078076) (xy 198.754226 -300.0328) (xy 198.780529 -299.991204) (xy 198.813164 -299.954367)
			(xy 198.851285 -299.923242) (xy 198.893906 -299.898635) (xy 198.939922 -299.881183) (xy 198.988141 -299.871339)
			(xy 199.037316 -299.869358) (xy 199.086171 -299.87529) (xy 199.133442 -299.888982) (xy 199.177904 -299.91008)
			(xy 199.218407 -299.938036) (xy 199.2539 -299.972128) (xy 199.283465 -300.011472) (xy 199.306336 -300.055049)
			(xy 199.32192 -300.10173) (xy 199.329815 -300.150307) (xy 199.33031 -300.174914) (xy 199.329815 -300.199521)
			(xy 199.32192 -300.248098) (xy 199.306336 -300.294779) (xy 199.283465 -300.338356) (xy 199.2539 -300.3777)
			(xy 199.218407 -300.411792) (xy 199.177904 -300.439748) (xy 199.133442 -300.460846) (xy 199.086171 -300.474538)
			(xy 199.037316 -300.48047) (xy 198.988141 -300.478489) (xy 198.939922 -300.468645) (xy 198.893906 -300.451193)
			(xy 198.851285 -300.426586) (xy 198.813164 -300.395461) (xy 198.780529 -300.358624) (xy 198.754226 -300.317028)
			(xy 198.734935 -300.271752) (xy 198.723158 -300.223968) (xy 198.719198 -300.174914) (xy 198.38035 -300.174914)
			(xy 198.379855 -300.199521) (xy 198.37196 -300.248098) (xy 198.356376 -300.294779) (xy 198.333505 -300.338356)
			(xy 198.30394 -300.3777) (xy 198.268447 -300.411792) (xy 198.227944 -300.439748) (xy 198.183482 -300.460846)
			(xy 198.136211 -300.474538) (xy 198.087356 -300.48047) (xy 198.038181 -300.478489) (xy 197.989962 -300.468645)
			(xy 197.943946 -300.451193) (xy 197.901325 -300.426586) (xy 197.863204 -300.395461) (xy 197.830569 -300.358624)
			(xy 197.804266 -300.317028) (xy 197.784975 -300.271752) (xy 197.773198 -300.223968) (xy 197.769238 -300.174914)
			(xy 194.580256 -300.174914) (xy 194.579761 -300.199521) (xy 194.571866 -300.248098) (xy 194.556282 -300.294779)
			(xy 194.533411 -300.338356) (xy 194.503846 -300.3777) (xy 194.468353 -300.411792) (xy 194.42785 -300.439748)
			(xy 194.383388 -300.460846) (xy 194.336117 -300.474538) (xy 194.287262 -300.48047) (xy 194.238087 -300.478489)
			(xy 194.189868 -300.468645) (xy 194.143852 -300.451193) (xy 194.101231 -300.426586) (xy 194.06311 -300.395461)
			(xy 194.030475 -300.358624) (xy 194.004172 -300.317028) (xy 193.984881 -300.271752) (xy 193.973104 -300.223968)
			(xy 193.969144 -300.174914) (xy 193.630845 -300.174914) (xy 193.626674 -300.225242) (xy 193.614274 -300.27421)
			(xy 193.593982 -300.32047) (xy 193.566352 -300.362758) (xy 193.532139 -300.399923) (xy 193.492276 -300.430948)
			(xy 193.447849 -300.454989) (xy 193.400071 -300.47139) (xy 193.350245 -300.479702) (xy 193.324988 -300.480222)
			(xy 193.313902 -300.480156) (xy 193.291782 -300.47863) (xy 193.280792 -300.477174) (xy 193.269616 -300.47565)
			(xy 193.259964 -300.478444) (xy 193.254744 -300.480107) (xy 193.245136 -300.485366) (xy 193.240914 -300.488858)
			(xy 193.18097 -300.540674) (xy 193.173737 -300.54812) (xy 193.165463 -300.567136) (xy 193.164968 -300.577504)
			(xy 193.164968 -301.124874) (xy 194.919104 -301.124874) (xy 194.923064 -301.07582) (xy 194.934841 -301.028036)
			(xy 194.954132 -300.98276) (xy 194.980435 -300.941164) (xy 195.01307 -300.904327) (xy 195.051191 -300.873202)
			(xy 195.093812 -300.848595) (xy 195.139828 -300.831143) (xy 195.188047 -300.821299) (xy 195.237222 -300.819318)
			(xy 195.286077 -300.82525) (xy 195.333348 -300.838942) (xy 195.37781 -300.86004) (xy 195.418313 -300.887996)
			(xy 195.453806 -300.922088) (xy 195.483371 -300.961432) (xy 195.506242 -301.005009) (xy 195.521826 -301.05169)
			(xy 195.529721 -301.100267) (xy 195.530216 -301.124874) (xy 195.869064 -301.124874) (xy 195.873024 -301.07582)
			(xy 195.884801 -301.028036) (xy 195.904092 -300.98276) (xy 195.930395 -300.941164) (xy 195.96303 -300.904327)
			(xy 196.001151 -300.873202) (xy 196.043772 -300.848595) (xy 196.089788 -300.831143) (xy 196.138007 -300.821299)
			(xy 196.187182 -300.819318) (xy 196.236037 -300.82525) (xy 196.283308 -300.838942) (xy 196.32777 -300.86004)
			(xy 196.368273 -300.887996) (xy 196.403766 -300.922088) (xy 196.433331 -300.961432) (xy 196.456202 -301.005009)
			(xy 196.468574 -301.04207) (xy 206.417162 -301.04207) (xy 206.421233 -300.986448) (xy 206.433359 -300.932011)
			(xy 206.453282 -300.87992) (xy 206.480578 -300.831285) (xy 206.514664 -300.787142) (xy 206.554813 -300.748433)
			(xy 206.600171 -300.715982) (xy 206.649771 -300.690481) (xy 206.702555 -300.672474) (xy 206.757398 -300.662344)
			(xy 206.813132 -300.660307) (xy 206.868569 -300.666407) (xy 206.922526 -300.680513) (xy 206.973855 -300.702325)
			(xy 207.021461 -300.731379) (xy 207.064329 -300.767054) (xy 207.101546 -300.808591) (xy 207.132319 -300.855104)
			(xy 207.155991 -300.905601) (xy 207.172059 -300.959008) (xy 207.180179 -301.014184) (xy 207.180688 -301.04207)
			(xy 207.180535 -301.050452) (xy 208.791046 -301.050452) (xy 208.795117 -300.99483) (xy 208.807243 -300.940393)
			(xy 208.827166 -300.888302) (xy 208.854462 -300.839667) (xy 208.888548 -300.795524) (xy 208.928697 -300.756815)
			(xy 208.974055 -300.724364) (xy 209.023655 -300.698863) (xy 209.076439 -300.680856) (xy 209.131282 -300.670726)
			(xy 209.187016 -300.668689) (xy 209.242453 -300.674789) (xy 209.29641 -300.688895) (xy 209.347739 -300.710707)
			(xy 209.395345 -300.739761) (xy 209.438213 -300.775436) (xy 209.47543 -300.816973) (xy 209.506203 -300.863486)
			(xy 209.529875 -300.913983) (xy 209.545943 -300.96739) (xy 209.554063 -301.022566) (xy 209.554572 -301.050452)
			(xy 209.554063 -301.078338) (xy 209.545943 -301.133514) (xy 209.529875 -301.186921) (xy 209.506203 -301.237418)
			(xy 209.47543 -301.283931) (xy 209.438213 -301.325468) (xy 209.395345 -301.361143) (xy 209.347739 -301.390197)
			(xy 209.29641 -301.412009) (xy 209.242453 -301.426115) (xy 209.187016 -301.432215) (xy 209.131282 -301.430178)
			(xy 209.076439 -301.420048) (xy 209.023655 -301.402041) (xy 208.974055 -301.37654) (xy 208.928697 -301.344089)
			(xy 208.888548 -301.30538) (xy 208.854462 -301.261237) (xy 208.827166 -301.212602) (xy 208.807243 -301.160511)
			(xy 208.795117 -301.106074) (xy 208.791046 -301.050452) (xy 207.180535 -301.050452) (xy 207.180179 -301.069956)
			(xy 207.172059 -301.125132) (xy 207.155991 -301.178539) (xy 207.132319 -301.229036) (xy 207.101546 -301.275549)
			(xy 207.064329 -301.317086) (xy 207.021461 -301.352761) (xy 206.973855 -301.381815) (xy 206.922526 -301.403627)
			(xy 206.868569 -301.417733) (xy 206.813132 -301.423833) (xy 206.757398 -301.421796) (xy 206.702555 -301.411666)
			(xy 206.649771 -301.393659) (xy 206.600171 -301.368158) (xy 206.554813 -301.335707) (xy 206.514664 -301.296998)
			(xy 206.480578 -301.252855) (xy 206.453282 -301.20422) (xy 206.433359 -301.152129) (xy 206.421233 -301.097692)
			(xy 206.417162 -301.04207) (xy 196.468574 -301.04207) (xy 196.471786 -301.05169) (xy 196.479681 -301.100267)
			(xy 196.480176 -301.124874) (xy 196.479681 -301.149481) (xy 196.471786 -301.198058) (xy 196.456202 -301.244739)
			(xy 196.433331 -301.288316) (xy 196.403766 -301.32766) (xy 196.368273 -301.361752) (xy 196.32777 -301.389708)
			(xy 196.283308 -301.410806) (xy 196.236037 -301.424498) (xy 196.187182 -301.43043) (xy 196.138007 -301.428449)
			(xy 196.089788 -301.418605) (xy 196.043772 -301.401153) (xy 196.001151 -301.376546) (xy 195.96303 -301.345421)
			(xy 195.930395 -301.308584) (xy 195.904092 -301.266988) (xy 195.884801 -301.221712) (xy 195.873024 -301.173928)
			(xy 195.869064 -301.124874) (xy 195.530216 -301.124874) (xy 195.529721 -301.149481) (xy 195.521826 -301.198058)
			(xy 195.506242 -301.244739) (xy 195.483371 -301.288316) (xy 195.453806 -301.32766) (xy 195.418313 -301.361752)
			(xy 195.37781 -301.389708) (xy 195.333348 -301.410806) (xy 195.286077 -301.424498) (xy 195.237222 -301.43043)
			(xy 195.188047 -301.428449) (xy 195.139828 -301.418605) (xy 195.093812 -301.401153) (xy 195.051191 -301.376546)
			(xy 195.01307 -301.345421) (xy 194.980435 -301.308584) (xy 194.954132 -301.266988) (xy 194.934841 -301.221712)
			(xy 194.923064 -301.173928) (xy 194.919104 -301.124874) (xy 193.164968 -301.124874) (xy 193.164968 -301.672244)
			(xy 193.165515 -301.6826) (xy 193.173778 -301.701601) (xy 193.18097 -301.709074) (xy 193.240914 -301.76089)
			(xy 193.245145 -301.764367) (xy 193.254752 -301.769621) (xy 193.259964 -301.771304) (xy 193.269616 -301.774098)
			(xy 193.280792 -301.772574) (xy 193.291781 -301.771101) (xy 193.313901 -301.769575) (xy 193.324988 -301.769526)
			(xy 193.350244 -301.770018) (xy 193.400066 -301.77833) (xy 193.447841 -301.794729) (xy 193.492265 -301.818769)
			(xy 193.532126 -301.849792) (xy 193.566337 -301.886954) (xy 193.593964 -301.92924) (xy 193.614255 -301.975496)
			(xy 193.626655 -302.024461) (xy 193.630826 -302.0748) (xy 193.630823 -302.074834) (xy 197.769238 -302.074834)
			(xy 197.773198 -302.02578) (xy 197.784975 -301.977996) (xy 197.804266 -301.93272) (xy 197.830569 -301.891124)
			(xy 197.863204 -301.854287) (xy 197.901325 -301.823162) (xy 197.943946 -301.798555) (xy 197.989962 -301.781103)
			(xy 198.038181 -301.771259) (xy 198.087356 -301.769278) (xy 198.136211 -301.77521) (xy 198.183482 -301.788902)
			(xy 198.227944 -301.81) (xy 198.268447 -301.837956) (xy 198.30394 -301.872048) (xy 198.333505 -301.911392)
			(xy 198.356376 -301.954969) (xy 198.37196 -302.00165) (xy 198.379855 -302.050227) (xy 198.38035 -302.074834)
			(xy 198.719198 -302.074834) (xy 198.723158 -302.02578) (xy 198.734935 -301.977996) (xy 198.754226 -301.93272)
			(xy 198.780529 -301.891124) (xy 198.813164 -301.854287) (xy 198.851285 -301.823162) (xy 198.893906 -301.798555)
			(xy 198.939922 -301.781103) (xy 198.988141 -301.771259) (xy 199.037316 -301.769278) (xy 199.086171 -301.77521)
			(xy 199.133442 -301.788902) (xy 199.177904 -301.81) (xy 199.218407 -301.837956) (xy 199.22015 -301.83963)
			(xy 202.44765 -301.83963) (xy 202.451721 -301.784008) (xy 202.463847 -301.729571) (xy 202.48377 -301.67748)
			(xy 202.511066 -301.628845) (xy 202.545152 -301.584702) (xy 202.585301 -301.545993) (xy 202.630659 -301.513542)
			(xy 202.680259 -301.488041) (xy 202.733043 -301.470034) (xy 202.787886 -301.459904) (xy 202.84362 -301.457867)
			(xy 202.899057 -301.463967) (xy 202.953014 -301.478073) (xy 203.004343 -301.499885) (xy 203.051949 -301.528939)
			(xy 203.080393 -301.55261) (xy 204.219808 -301.55261) (xy 204.223879 -301.496988) (xy 204.236005 -301.442551)
			(xy 204.255928 -301.39046) (xy 204.283224 -301.341825) (xy 204.31731 -301.297682) (xy 204.357459 -301.258973)
			(xy 204.402817 -301.226522) (xy 204.452417 -301.201021) (xy 204.505201 -301.183014) (xy 204.560044 -301.172884)
			(xy 204.615778 -301.170847) (xy 204.671215 -301.176947) (xy 204.725172 -301.191053) (xy 204.776501 -301.212865)
			(xy 204.824107 -301.241919) (xy 204.866975 -301.277594) (xy 204.904192 -301.319131) (xy 204.934965 -301.365644)
			(xy 204.958637 -301.416141) (xy 204.974705 -301.469548) (xy 204.982825 -301.524724) (xy 204.983334 -301.55261)
			(xy 204.982894 -301.57674) (xy 207.613248 -301.57674) (xy 207.617319 -301.521118) (xy 207.629445 -301.466681)
			(xy 207.649368 -301.41459) (xy 207.676664 -301.365955) (xy 207.71075 -301.321812) (xy 207.750899 -301.283103)
			(xy 207.796257 -301.250652) (xy 207.845857 -301.225151) (xy 207.898641 -301.207144) (xy 207.953484 -301.197014)
			(xy 208.009218 -301.194977) (xy 208.064655 -301.201077) (xy 208.118612 -301.215183) (xy 208.169941 -301.236995)
			(xy 208.217547 -301.266049) (xy 208.260415 -301.301724) (xy 208.297632 -301.343261) (xy 208.328405 -301.389774)
			(xy 208.352077 -301.440271) (xy 208.368145 -301.493678) (xy 208.376265 -301.548854) (xy 208.376774 -301.57674)
			(xy 208.376265 -301.604626) (xy 208.368145 -301.659802) (xy 208.352077 -301.713209) (xy 208.328405 -301.763706)
			(xy 208.297632 -301.810219) (xy 208.260415 -301.851756) (xy 208.217547 -301.887431) (xy 208.169941 -301.916485)
			(xy 208.118612 -301.938297) (xy 208.064655 -301.952403) (xy 208.009218 -301.958503) (xy 207.953484 -301.956466)
			(xy 207.898641 -301.946336) (xy 207.845857 -301.928329) (xy 207.796257 -301.902828) (xy 207.750899 -301.870377)
			(xy 207.71075 -301.831668) (xy 207.676664 -301.787525) (xy 207.649368 -301.73889) (xy 207.629445 -301.686799)
			(xy 207.617319 -301.632362) (xy 207.613248 -301.57674) (xy 204.982894 -301.57674) (xy 204.982825 -301.580496)
			(xy 204.974705 -301.635672) (xy 204.958637 -301.689079) (xy 204.934965 -301.739576) (xy 204.904192 -301.786089)
			(xy 204.866975 -301.827626) (xy 204.824107 -301.863301) (xy 204.776501 -301.892355) (xy 204.725172 -301.914167)
			(xy 204.671215 -301.928273) (xy 204.615778 -301.934373) (xy 204.560044 -301.932336) (xy 204.505201 -301.922206)
			(xy 204.452417 -301.904199) (xy 204.402817 -301.878698) (xy 204.357459 -301.846247) (xy 204.31731 -301.807538)
			(xy 204.283224 -301.763395) (xy 204.255928 -301.71476) (xy 204.236005 -301.662669) (xy 204.223879 -301.608232)
			(xy 204.219808 -301.55261) (xy 203.080393 -301.55261) (xy 203.094817 -301.564614) (xy 203.132034 -301.606151)
			(xy 203.162807 -301.652664) (xy 203.186479 -301.703161) (xy 203.202547 -301.756568) (xy 203.210667 -301.811744)
			(xy 203.211176 -301.83963) (xy 203.210667 -301.867516) (xy 203.202547 -301.922692) (xy 203.186479 -301.976099)
			(xy 203.162807 -302.026596) (xy 203.132034 -302.073109) (xy 203.094817 -302.114646) (xy 203.051949 -302.150321)
			(xy 203.004343 -302.179375) (xy 202.953014 -302.201187) (xy 202.899057 -302.215293) (xy 202.84362 -302.221393)
			(xy 202.787886 -302.219356) (xy 202.733043 -302.209226) (xy 202.680259 -302.191219) (xy 202.630659 -302.165718)
			(xy 202.585301 -302.133267) (xy 202.545152 -302.094558) (xy 202.511066 -302.050415) (xy 202.48377 -302.00178)
			(xy 202.463847 -301.949689) (xy 202.451721 -301.895252) (xy 202.44765 -301.83963) (xy 199.22015 -301.83963)
			(xy 199.2539 -301.872048) (xy 199.283465 -301.911392) (xy 199.306336 -301.954969) (xy 199.32192 -302.00165)
			(xy 199.329815 -302.050227) (xy 199.33031 -302.074834) (xy 199.329815 -302.099441) (xy 199.32192 -302.148018)
			(xy 199.306336 -302.194699) (xy 199.283465 -302.238276) (xy 199.2539 -302.27762) (xy 199.218407 -302.311712)
			(xy 199.177904 -302.339668) (xy 199.133442 -302.360766) (xy 199.086171 -302.374458) (xy 199.037316 -302.38039)
			(xy 198.988141 -302.378409) (xy 198.939922 -302.368565) (xy 198.893906 -302.351113) (xy 198.851285 -302.326506)
			(xy 198.813164 -302.295381) (xy 198.780529 -302.258544) (xy 198.754226 -302.216948) (xy 198.734935 -302.171672)
			(xy 198.723158 -302.123888) (xy 198.719198 -302.074834) (xy 198.38035 -302.074834) (xy 198.379855 -302.099441)
			(xy 198.37196 -302.148018) (xy 198.356376 -302.194699) (xy 198.333505 -302.238276) (xy 198.30394 -302.27762)
			(xy 198.268447 -302.311712) (xy 198.227944 -302.339668) (xy 198.183482 -302.360766) (xy 198.136211 -302.374458)
			(xy 198.087356 -302.38039) (xy 198.038181 -302.378409) (xy 197.989962 -302.368565) (xy 197.943946 -302.351113)
			(xy 197.901325 -302.326506) (xy 197.863204 -302.295381) (xy 197.830569 -302.258544) (xy 197.804266 -302.216948)
			(xy 197.784975 -302.171672) (xy 197.773198 -302.123888) (xy 197.769238 -302.074834) (xy 193.630823 -302.074834)
			(xy 193.626655 -302.125139) (xy 193.614255 -302.174104) (xy 193.593964 -302.22036) (xy 193.566337 -302.262646)
			(xy 193.532126 -302.299808) (xy 193.492265 -302.330831) (xy 193.447841 -302.354871) (xy 193.400066 -302.37127)
			(xy 193.350244 -302.379582) (xy 193.324988 -302.380142) (xy 193.313902 -302.380076) (xy 193.291782 -302.37855)
			(xy 193.280792 -302.377094) (xy 193.269616 -302.37557) (xy 193.259964 -302.378364) (xy 193.254745 -302.380028)
			(xy 193.245137 -302.385288) (xy 193.240914 -302.388778) (xy 193.209164 -302.41621) (xy 193.180716 -302.440848)
			(xy 193.176926 -302.444625) (xy 193.170893 -302.45346) (xy 193.168778 -302.458374) (xy 193.173604 -302.481488)
			(xy 193.176936 -302.498308) (xy 193.1805 -302.532414) (xy 193.180716 -302.54956) (xy 193.180716 -302.549814)
			(xy 193.180283 -302.573652) (xy 193.1734 -302.620828) (xy 193.167 -302.643794) (xy 193.164968 -302.650906)
			(xy 193.164968 -302.709305) (xy 200.909418 -302.709305) (xy 200.909418 -302.656007) (xy 200.917361 -302.603303)
			(xy 200.933071 -302.552373) (xy 200.956197 -302.504352) (xy 200.986221 -302.460315) (xy 201.022473 -302.421244)
			(xy 201.064144 -302.388013) (xy 201.110302 -302.361364) (xy 201.159916 -302.341892) (xy 201.211878 -302.330032)
			(xy 201.265028 -302.326049) (xy 201.318178 -302.330032) (xy 201.37014 -302.341892) (xy 201.419754 -302.361364)
			(xy 201.465912 -302.388013) (xy 201.507583 -302.421244) (xy 201.543835 -302.460315) (xy 201.573859 -302.504352)
			(xy 201.596985 -302.552373) (xy 201.612695 -302.603303) (xy 201.620638 -302.656007) (xy 201.621136 -302.682656)
			(xy 201.620638 -302.709305) (xy 201.612695 -302.762009) (xy 201.596985 -302.812939) (xy 201.573859 -302.86096)
			(xy 201.543835 -302.904997) (xy 201.507583 -302.944068) (xy 201.465912 -302.977299) (xy 201.419754 -303.003948)
			(xy 201.37014 -303.02342) (xy 201.318178 -303.03528) (xy 201.265028 -303.039264) (xy 201.211878 -303.03528)
			(xy 201.159916 -303.02342) (xy 201.110302 -303.003948) (xy 201.064144 -302.977299) (xy 201.022473 -302.944068)
			(xy 200.986221 -302.904997) (xy 200.956197 -302.86096) (xy 200.933071 -302.812939) (xy 200.917361 -302.762009)
			(xy 200.909418 -302.709305) (xy 193.164968 -302.709305) (xy 193.164968 -303.024794) (xy 194.919104 -303.024794)
			(xy 194.923064 -302.97574) (xy 194.934841 -302.927956) (xy 194.954132 -302.88268) (xy 194.980435 -302.841084)
			(xy 195.01307 -302.804247) (xy 195.051191 -302.773122) (xy 195.093812 -302.748515) (xy 195.139828 -302.731063)
			(xy 195.188047 -302.721219) (xy 195.237222 -302.719238) (xy 195.286077 -302.72517) (xy 195.333348 -302.738862)
			(xy 195.37781 -302.75996) (xy 195.418313 -302.787916) (xy 195.453806 -302.822008) (xy 195.483371 -302.861352)
			(xy 195.506242 -302.904929) (xy 195.521826 -302.95161) (xy 195.529721 -303.000187) (xy 195.530216 -303.024794)
			(xy 195.869064 -303.024794) (xy 195.873024 -302.97574) (xy 195.884801 -302.927956) (xy 195.904092 -302.88268)
			(xy 195.930395 -302.841084) (xy 195.96303 -302.804247) (xy 196.001151 -302.773122) (xy 196.043772 -302.748515)
			(xy 196.089788 -302.731063) (xy 196.138007 -302.721219) (xy 196.187182 -302.719238) (xy 196.236037 -302.72517)
			(xy 196.283308 -302.738862) (xy 196.32777 -302.75996) (xy 196.368273 -302.787916) (xy 196.403766 -302.822008)
			(xy 196.433331 -302.861352) (xy 196.456202 -302.904929) (xy 196.471786 -302.95161) (xy 196.479681 -303.000187)
			(xy 196.480176 -303.024794) (xy 196.479681 -303.049401) (xy 196.479511 -303.050448) (xy 203.950314 -303.050448)
			(xy 203.954385 -302.994826) (xy 203.966511 -302.940389) (xy 203.986434 -302.888298) (xy 204.01373 -302.839663)
			(xy 204.047816 -302.79552) (xy 204.087965 -302.756811) (xy 204.133323 -302.72436) (xy 204.182923 -302.698859)
			(xy 204.235707 -302.680852) (xy 204.29055 -302.670722) (xy 204.346284 -302.668685) (xy 204.401721 -302.674785)
			(xy 204.455678 -302.688891) (xy 204.507007 -302.710703) (xy 204.554613 -302.739757) (xy 204.597481 -302.775432)
			(xy 204.634698 -302.816969) (xy 204.665471 -302.863482) (xy 204.689143 -302.913979) (xy 204.705211 -302.967386)
			(xy 204.713331 -303.022562) (xy 204.71384 -303.050448) (xy 204.713331 -303.078334) (xy 204.705211 -303.13351)
			(xy 204.689143 -303.186917) (xy 204.665471 -303.237414) (xy 204.634698 -303.283927) (xy 204.597481 -303.325464)
			(xy 204.554613 -303.361139) (xy 204.507007 -303.390193) (xy 204.455678 -303.412005) (xy 204.401721 -303.426111)
			(xy 204.346284 -303.432211) (xy 204.29055 -303.430174) (xy 204.235707 -303.420044) (xy 204.182923 -303.402037)
			(xy 204.133323 -303.376536) (xy 204.087965 -303.344085) (xy 204.047816 -303.305376) (xy 204.01373 -303.261233)
			(xy 203.986434 -303.212598) (xy 203.966511 -303.160507) (xy 203.954385 -303.10607) (xy 203.950314 -303.050448)
			(xy 196.479511 -303.050448) (xy 196.471786 -303.097978) (xy 196.456202 -303.144659) (xy 196.433331 -303.188236)
			(xy 196.403766 -303.22758) (xy 196.368273 -303.261672) (xy 196.32777 -303.289628) (xy 196.283308 -303.310726)
			(xy 196.236037 -303.324418) (xy 196.187182 -303.33035) (xy 196.138007 -303.328369) (xy 196.089788 -303.318525)
			(xy 196.043772 -303.301073) (xy 196.001151 -303.276466) (xy 195.96303 -303.245341) (xy 195.930395 -303.208504)
			(xy 195.904092 -303.166908) (xy 195.884801 -303.121632) (xy 195.873024 -303.073848) (xy 195.869064 -303.024794)
			(xy 195.530216 -303.024794) (xy 195.529721 -303.049401) (xy 195.521826 -303.097978) (xy 195.506242 -303.144659)
			(xy 195.483371 -303.188236) (xy 195.453806 -303.22758) (xy 195.418313 -303.261672) (xy 195.37781 -303.289628)
			(xy 195.333348 -303.310726) (xy 195.286077 -303.324418) (xy 195.237222 -303.33035) (xy 195.188047 -303.328369)
			(xy 195.139828 -303.318525) (xy 195.093812 -303.301073) (xy 195.051191 -303.276466) (xy 195.01307 -303.245341)
			(xy 194.980435 -303.208504) (xy 194.954132 -303.166908) (xy 194.934841 -303.121632) (xy 194.923064 -303.073848)
			(xy 194.919104 -303.024794) (xy 193.164968 -303.024794) (xy 193.164968 -303.572164) (xy 193.165519 -303.582519)
			(xy 193.173787 -303.601514) (xy 193.18097 -303.608994) (xy 193.240914 -303.66081) (xy 193.245146 -303.664286)
			(xy 193.254753 -303.669538) (xy 193.259964 -303.671224) (xy 193.269616 -303.674018) (xy 193.280792 -303.672494)
			(xy 193.291781 -303.671021) (xy 193.313901 -303.669496) (xy 193.324988 -303.669446) (xy 193.35025 -303.669938)
			(xy 193.400086 -303.678252) (xy 193.447873 -303.694656) (xy 193.492308 -303.718702) (xy 193.49984 -303.724564)
			(xy 201.429364 -303.724564) (xy 201.433435 -303.668942) (xy 201.445561 -303.614505) (xy 201.465484 -303.562414)
			(xy 201.49278 -303.513779) (xy 201.526866 -303.469636) (xy 201.567015 -303.430927) (xy 201.612373 -303.398476)
			(xy 201.661973 -303.372975) (xy 201.714757 -303.354968) (xy 201.7696 -303.344838) (xy 201.825334 -303.342801)
			(xy 201.880771 -303.348901) (xy 201.934728 -303.363007) (xy 201.986057 -303.384819) (xy 202.033663 -303.413873)
			(xy 202.076531 -303.449548) (xy 202.113748 -303.491085) (xy 202.144521 -303.537598) (xy 202.168193 -303.588095)
			(xy 202.184261 -303.641502) (xy 202.192381 -303.696678) (xy 202.19289 -303.724564) (xy 202.192381 -303.75245)
			(xy 202.184261 -303.807626) (xy 202.168193 -303.861033) (xy 202.144521 -303.91153) (xy 202.113748 -303.958043)
			(xy 202.076531 -303.99958) (xy 202.033663 -304.035255) (xy 201.986057 -304.064309) (xy 201.934728 -304.086121)
			(xy 201.880771 -304.100227) (xy 201.825334 -304.106327) (xy 201.7696 -304.10429) (xy 201.714757 -304.09416)
			(xy 201.661973 -304.076153) (xy 201.612373 -304.050652) (xy 201.567015 -304.018201) (xy 201.526866 -303.979492)
			(xy 201.49278 -303.935349) (xy 201.465484 -303.886714) (xy 201.445561 -303.834623) (xy 201.433435 -303.780186)
			(xy 201.429364 -303.724564) (xy 193.49984 -303.724564) (xy 193.53218 -303.749733) (xy 193.5664 -303.786905)
			(xy 193.594034 -303.829201) (xy 193.61433 -303.87547) (xy 193.626734 -303.924448) (xy 193.630906 -303.9748)
			(xy 193.626734 -304.025152) (xy 193.61433 -304.07413) (xy 193.594034 -304.120399) (xy 193.5664 -304.162695)
			(xy 193.53218 -304.199867) (xy 193.492308 -304.230898) (xy 193.447873 -304.254944) (xy 193.400086 -304.271348)
			(xy 193.35025 -304.279662) (xy 193.324988 -304.280062) (xy 193.313902 -304.279996) (xy 193.291782 -304.278471)
			(xy 193.280792 -304.277014) (xy 193.269616 -304.27549) (xy 193.259964 -304.278284) (xy 193.254743 -304.279946)
			(xy 193.24513 -304.285199) (xy 193.240914 -304.288698) (xy 193.209164 -304.31613) (xy 193.180716 -304.340768)
			(xy 193.176927 -304.344546) (xy 193.170898 -304.353382) (xy 193.168778 -304.358294) (xy 193.173604 -304.381408)
			(xy 193.176935 -304.398229) (xy 193.180497 -304.432334) (xy 193.180716 -304.44948) (xy 193.180716 -304.449734)
			(xy 193.180281 -304.473571) (xy 193.180008 -304.475442) (xy 197.273414 -304.475442) (xy 197.273414 -304.424026)
			(xy 197.281457 -304.373244) (xy 197.297345 -304.324345) (xy 197.320688 -304.278533) (xy 197.350909 -304.236937)
			(xy 197.387265 -304.200581) (xy 197.428861 -304.17036) (xy 197.474673 -304.147017) (xy 197.523572 -304.131129)
			(xy 197.574354 -304.123086) (xy 197.62577 -304.123086) (xy 197.676552 -304.131129) (xy 197.725451 -304.147017)
			(xy 197.771263 -304.17036) (xy 197.812859 -304.200581) (xy 197.849215 -304.236937) (xy 197.879436 -304.278533)
			(xy 197.902779 -304.324345) (xy 197.918667 -304.373244) (xy 197.92671 -304.424026) (xy 197.927214 -304.449734)
			(xy 197.92671 -304.475442) (xy 198.223374 -304.475442) (xy 198.223374 -304.424026) (xy 198.231417 -304.373244)
			(xy 198.247305 -304.324345) (xy 198.270648 -304.278533) (xy 198.300869 -304.236937) (xy 198.337225 -304.200581)
			(xy 198.378821 -304.17036) (xy 198.424633 -304.147017) (xy 198.473532 -304.131129) (xy 198.524314 -304.123086)
			(xy 198.57573 -304.123086) (xy 198.626512 -304.131129) (xy 198.675411 -304.147017) (xy 198.721223 -304.17036)
			(xy 198.762819 -304.200581) (xy 198.799175 -304.236937) (xy 198.829396 -304.278533) (xy 198.852739 -304.324345)
			(xy 198.868627 -304.373244) (xy 198.87667 -304.424026) (xy 198.877174 -304.449734) (xy 198.87667 -304.475442)
			(xy 198.868627 -304.526224) (xy 198.852739 -304.575123) (xy 198.829396 -304.620935) (xy 198.799175 -304.662531)
			(xy 198.762819 -304.698887) (xy 198.721223 -304.729108) (xy 198.675411 -304.752451) (xy 198.626512 -304.768339)
			(xy 198.57573 -304.776382) (xy 198.524314 -304.776382) (xy 198.473532 -304.768339) (xy 198.424633 -304.752451)
			(xy 198.378821 -304.729108) (xy 198.337225 -304.698887) (xy 198.300869 -304.662531) (xy 198.270648 -304.620935)
			(xy 198.247305 -304.575123) (xy 198.231417 -304.526224) (xy 198.223374 -304.475442) (xy 197.92671 -304.475442)
			(xy 197.918667 -304.526224) (xy 197.902779 -304.575123) (xy 197.879436 -304.620935) (xy 197.849215 -304.662531)
			(xy 197.812859 -304.698887) (xy 197.771263 -304.729108) (xy 197.725451 -304.752451) (xy 197.676552 -304.768339)
			(xy 197.62577 -304.776382) (xy 197.574354 -304.776382) (xy 197.523572 -304.768339) (xy 197.474673 -304.752451)
			(xy 197.428861 -304.729108) (xy 197.387265 -304.698887) (xy 197.350909 -304.662531) (xy 197.320688 -304.620935)
			(xy 197.297345 -304.575123) (xy 197.281457 -304.526224) (xy 197.273414 -304.475442) (xy 193.180008 -304.475442)
			(xy 193.173396 -304.520747) (xy 193.167 -304.543714) (xy 193.164968 -304.550826) (xy 193.164968 -304.780056)
			(xy 203.949711 -304.780056) (xy 203.949711 -304.725544) (xy 203.957469 -304.671586) (xy 203.972827 -304.619281)
			(xy 203.995473 -304.569695) (xy 204.024945 -304.523836) (xy 204.060644 -304.482638) (xy 204.101842 -304.44694)
			(xy 204.147702 -304.417469) (xy 204.197289 -304.394824) (xy 204.249594 -304.379467) (xy 204.303552 -304.37171)
			(xy 204.330808 -304.371248) (xy 204.357952 -304.371727) (xy 204.411695 -304.379403) (xy 204.463805 -304.394627)
			(xy 204.513227 -304.417092) (xy 204.558962 -304.446341) (xy 204.600084 -304.481785) (xy 204.63576 -304.522705)
			(xy 204.665269 -304.568273) (xy 204.688013 -304.617567) (xy 204.703533 -304.669589) (xy 204.707998 -304.696368)
			(xy 204.710733 -304.711218) (xy 204.723778 -304.738439) (xy 204.744199 -304.760668) (xy 204.770219 -304.775969)
			(xy 204.799571 -304.783011) (xy 204.829701 -304.78118) (xy 204.857985 -304.770637) (xy 204.870304 -304.7619)
			(xy 204.89035 -304.747071) (xy 204.933571 -304.722205) (xy 204.979661 -304.703176) (xy 205.027835 -304.690307)
			(xy 205.077274 -304.683818) (xy 205.102206 -304.683414) (xy 205.129459 -304.683856) (xy 205.183409 -304.691614)
			(xy 205.235706 -304.70697) (xy 205.285285 -304.729613) (xy 205.331137 -304.759081) (xy 205.372329 -304.794775)
			(xy 205.408022 -304.835967) (xy 205.43749 -304.88182) (xy 205.460132 -304.9314) (xy 205.475487 -304.983697)
			(xy 205.483244 -305.037647) (xy 205.483244 -305.064922) (xy 205.735172 -305.064922) (xy 205.739243 -305.0093)
			(xy 205.751369 -304.954863) (xy 205.771292 -304.902772) (xy 205.798588 -304.854137) (xy 205.832674 -304.809994)
			(xy 205.872823 -304.771285) (xy 205.918181 -304.738834) (xy 205.967781 -304.713333) (xy 206.020565 -304.695326)
			(xy 206.075408 -304.685196) (xy 206.131142 -304.683159) (xy 206.186579 -304.689259) (xy 206.240536 -304.703365)
			(xy 206.291865 -304.725177) (xy 206.339471 -304.754231) (xy 206.382339 -304.789906) (xy 206.419556 -304.831443)
			(xy 206.450329 -304.877956) (xy 206.474001 -304.928453) (xy 206.490069 -304.98186) (xy 206.498189 -305.037036)
			(xy 206.498698 -305.064922) (xy 206.743552 -305.064922) (xy 206.747623 -305.0093) (xy 206.759749 -304.954863)
			(xy 206.779672 -304.902772) (xy 206.806968 -304.854137) (xy 206.841054 -304.809994) (xy 206.881203 -304.771285)
			(xy 206.926561 -304.738834) (xy 206.976161 -304.713333) (xy 207.028945 -304.695326) (xy 207.083788 -304.685196)
			(xy 207.139522 -304.683159) (xy 207.194959 -304.689259) (xy 207.248916 -304.703365) (xy 207.300245 -304.725177)
			(xy 207.347851 -304.754231) (xy 207.390719 -304.789906) (xy 207.427936 -304.831443) (xy 207.458709 -304.877956)
			(xy 207.482381 -304.928453) (xy 207.498449 -304.98186) (xy 207.506569 -305.037036) (xy 207.507059 -305.063906)
			(xy 207.768188 -305.063906) (xy 207.772259 -305.008284) (xy 207.784385 -304.953847) (xy 207.804308 -304.901756)
			(xy 207.831604 -304.853121) (xy 207.86569 -304.808978) (xy 207.905839 -304.770269) (xy 207.951197 -304.737818)
			(xy 208.000797 -304.712317) (xy 208.053581 -304.69431) (xy 208.108424 -304.68418) (xy 208.164158 -304.682143)
			(xy 208.219595 -304.688243) (xy 208.273552 -304.702349) (xy 208.324881 -304.724161) (xy 208.372487 -304.753215)
			(xy 208.415355 -304.78889) (xy 208.452572 -304.830427) (xy 208.483345 -304.87694) (xy 208.507017 -304.927437)
			(xy 208.523085 -304.980844) (xy 208.531205 -305.03602) (xy 208.531389 -305.046126) (xy 208.784188 -305.046126)
			(xy 208.788259 -304.990504) (xy 208.800385 -304.936067) (xy 208.820308 -304.883976) (xy 208.847604 -304.835341)
			(xy 208.88169 -304.791198) (xy 208.921839 -304.752489) (xy 208.967197 -304.720038) (xy 209.016797 -304.694537)
			(xy 209.069581 -304.67653) (xy 209.124424 -304.6664) (xy 209.180158 -304.664363) (xy 209.235595 -304.670463)
			(xy 209.289552 -304.684569) (xy 209.340881 -304.706381) (xy 209.388487 -304.735435) (xy 209.431355 -304.77111)
			(xy 209.468572 -304.812647) (xy 209.499345 -304.85916) (xy 209.523017 -304.909657) (xy 209.539085 -304.963064)
			(xy 209.547205 -305.01824) (xy 209.547714 -305.046126) (xy 209.547205 -305.074012) (xy 209.539085 -305.129188)
			(xy 209.523017 -305.182595) (xy 209.499345 -305.233092) (xy 209.468572 -305.279605) (xy 209.431355 -305.321142)
			(xy 209.388487 -305.356817) (xy 209.340881 -305.385871) (xy 209.289552 -305.407683) (xy 209.235595 -305.421789)
			(xy 209.180158 -305.427889) (xy 209.124424 -305.425852) (xy 209.069581 -305.415722) (xy 209.016797 -305.397715)
			(xy 208.967197 -305.372214) (xy 208.921839 -305.339763) (xy 208.88169 -305.301054) (xy 208.847604 -305.256911)
			(xy 208.820308 -305.208276) (xy 208.800385 -305.156185) (xy 208.788259 -305.101748) (xy 208.784188 -305.046126)
			(xy 208.531389 -305.046126) (xy 208.531714 -305.063906) (xy 208.531205 -305.091792) (xy 208.523085 -305.146968)
			(xy 208.507017 -305.200375) (xy 208.483345 -305.250872) (xy 208.452572 -305.297385) (xy 208.415355 -305.338922)
			(xy 208.372487 -305.374597) (xy 208.324881 -305.403651) (xy 208.273552 -305.425463) (xy 208.219595 -305.439569)
			(xy 208.164158 -305.445669) (xy 208.108424 -305.443632) (xy 208.053581 -305.433502) (xy 208.000797 -305.415495)
			(xy 207.951197 -305.389994) (xy 207.905839 -305.357543) (xy 207.86569 -305.318834) (xy 207.831604 -305.274691)
			(xy 207.804308 -305.226056) (xy 207.784385 -305.173965) (xy 207.772259 -305.119528) (xy 207.768188 -305.063906)
			(xy 207.507059 -305.063906) (xy 207.507078 -305.064922) (xy 207.506569 -305.092808) (xy 207.498449 -305.147984)
			(xy 207.482381 -305.201391) (xy 207.458709 -305.251888) (xy 207.427936 -305.298401) (xy 207.390719 -305.339938)
			(xy 207.347851 -305.375613) (xy 207.300245 -305.404667) (xy 207.248916 -305.426479) (xy 207.194959 -305.440585)
			(xy 207.139522 -305.446685) (xy 207.083788 -305.444648) (xy 207.028945 -305.434518) (xy 206.976161 -305.416511)
			(xy 206.926561 -305.39101) (xy 206.881203 -305.358559) (xy 206.841054 -305.31985) (xy 206.806968 -305.275707)
			(xy 206.779672 -305.227072) (xy 206.759749 -305.174981) (xy 206.747623 -305.120544) (xy 206.743552 -305.064922)
			(xy 206.498698 -305.064922) (xy 206.498189 -305.092808) (xy 206.490069 -305.147984) (xy 206.474001 -305.201391)
			(xy 206.450329 -305.251888) (xy 206.419556 -305.298401) (xy 206.382339 -305.339938) (xy 206.339471 -305.375613)
			(xy 206.291865 -305.404667) (xy 206.240536 -305.426479) (xy 206.186579 -305.440585) (xy 206.131142 -305.446685)
			(xy 206.075408 -305.444648) (xy 206.020565 -305.434518) (xy 205.967781 -305.416511) (xy 205.918181 -305.39101)
			(xy 205.872823 -305.358559) (xy 205.832674 -305.31985) (xy 205.798588 -305.275707) (xy 205.771292 -305.227072)
			(xy 205.751369 -305.174981) (xy 205.739243 -305.120544) (xy 205.735172 -305.064922) (xy 205.483244 -305.064922)
			(xy 205.483244 -305.092153) (xy 205.475487 -305.146103) (xy 205.460132 -305.1984) (xy 205.43749 -305.24798)
			(xy 205.408022 -305.293833) (xy 205.372329 -305.335025) (xy 205.331137 -305.370719) (xy 205.285285 -305.400187)
			(xy 205.235706 -305.42283) (xy 205.183409 -305.438186) (xy 205.129459 -305.445944) (xy 205.102206 -305.44643)
			(xy 205.075061 -305.445957) (xy 205.021317 -305.438282) (xy 204.969206 -305.423059) (xy 204.919783 -305.400594)
			(xy 204.874047 -305.371344) (xy 204.832925 -305.3359) (xy 204.797249 -305.294979) (xy 204.767741 -305.249409)
			(xy 204.744997 -305.200114) (xy 204.72948 -305.148089) (xy 204.725016 -305.12131) (xy 204.722271 -305.106463)
			(xy 204.709224 -305.079247) (xy 204.688803 -305.057023) (xy 204.662787 -305.041723) (xy 204.633438 -305.034681)
			(xy 204.603312 -305.036508) (xy 204.575029 -305.047045) (xy 204.56271 -305.055778) (xy 204.542667 -305.070611)
			(xy 204.499445 -305.095475) (xy 204.453354 -305.114502) (xy 204.405179 -305.12737) (xy 204.35574 -305.13386)
			(xy 204.330808 -305.134264) (xy 204.303552 -305.13389) (xy 204.249594 -305.126133) (xy 204.197289 -305.110776)
			(xy 204.147702 -305.088131) (xy 204.101842 -305.05866) (xy 204.060644 -305.022962) (xy 204.024945 -304.981764)
			(xy 203.995473 -304.935905) (xy 203.972827 -304.886319) (xy 203.957469 -304.834014) (xy 203.949711 -304.780056)
			(xy 193.164968 -304.780056) (xy 193.164968 -305.31181) (xy 193.166492 -305.317906) (xy 193.171419 -305.337995)
			(xy 193.176768 -305.379013) (xy 193.17716 -305.399694) (xy 193.17716 -305.400202) (xy 193.176982 -305.411803)
			(xy 193.1752 -305.434938) (xy 193.173604 -305.44643) (xy 193.170302 -305.46929) (xy 193.175128 -305.47691)
			(xy 193.175636 -305.477418) (xy 193.181732 -305.484276) (xy 193.19367 -305.49469) (xy 193.194178 -305.49469)
			(xy 193.239898 -305.534568) (xy 193.243807 -305.537802) (xy 193.252636 -305.542796) (xy 193.257424 -305.544474)
			(xy 193.269108 -305.54803) (xy 193.276474 -305.547268) (xy 193.288343 -305.545613) (xy 193.312243 -305.543834)
			(xy 193.324226 -305.543712) (xy 193.373248 -305.543712) (xy 193.383973 -305.543293) (xy 193.403578 -305.53461)
			(xy 193.411094 -305.526948) (xy 193.46164 -305.471068) (xy 193.468305 -305.462919) (xy 193.474993 -305.44298)
			(xy 193.474594 -305.43246) (xy 193.474594 -305.432206) (xy 193.472816 -305.400202) (xy 193.472816 -305.399694)
			(xy 193.473339 -305.373999) (xy 193.481414 -305.323247) (xy 193.497324 -305.274382) (xy 193.52068 -305.228606)
			(xy 193.550906 -305.187045) (xy 193.587258 -305.15072) (xy 193.628843 -305.120527) (xy 193.674637 -305.097207)
			(xy 193.723515 -305.081334) (xy 193.774273 -305.073299) (xy 193.825663 -305.073299) (xy 193.876421 -305.081334)
			(xy 193.925299 -305.097207) (xy 193.971093 -305.120527) (xy 194.012678 -305.15072) (xy 194.04903 -305.187045)
			(xy 194.079256 -305.228606) (xy 194.102612 -305.274382) (xy 194.118522 -305.323247) (xy 194.126597 -305.373999)
			(xy 194.12712 -305.399694) (xy 194.12712 -305.400202) (xy 194.125695 -305.425656) (xy 195.37324 -305.425656)
			(xy 195.37324 -305.37424) (xy 195.381283 -305.323458) (xy 195.397171 -305.274559) (xy 195.420514 -305.228747)
			(xy 195.450735 -305.187151) (xy 195.487091 -305.150795) (xy 195.528687 -305.120574) (xy 195.574499 -305.097231)
			(xy 195.623398 -305.081343) (xy 195.67418 -305.0733) (xy 195.725596 -305.0733) (xy 195.776378 -305.081343)
			(xy 195.825277 -305.097231) (xy 195.871089 -305.120574) (xy 195.912685 -305.150795) (xy 195.949041 -305.187151)
			(xy 195.979262 -305.228747) (xy 196.002605 -305.274559) (xy 196.018493 -305.323458) (xy 196.026536 -305.37424)
			(xy 196.02704 -305.399948) (xy 196.026536 -305.425656) (xy 196.3232 -305.425656) (xy 196.3232 -305.37424)
			(xy 196.331243 -305.323458) (xy 196.347131 -305.274559) (xy 196.370474 -305.228747) (xy 196.400695 -305.187151)
			(xy 196.437051 -305.150795) (xy 196.478647 -305.120574) (xy 196.524459 -305.097231) (xy 196.573358 -305.081343)
			(xy 196.62414 -305.0733) (xy 196.675556 -305.0733) (xy 196.726338 -305.081343) (xy 196.775237 -305.097231)
			(xy 196.821049 -305.120574) (xy 196.862645 -305.150795) (xy 196.899001 -305.187151) (xy 196.929222 -305.228747)
			(xy 196.952565 -305.274559) (xy 196.968453 -305.323458) (xy 196.976496 -305.37424) (xy 196.977 -305.399948)
			(xy 196.976496 -305.425656) (xy 196.968453 -305.476438) (xy 196.952565 -305.525337) (xy 196.929222 -305.571149)
			(xy 196.899001 -305.612745) (xy 196.862645 -305.649101) (xy 196.821049 -305.679322) (xy 196.775237 -305.702665)
			(xy 196.726338 -305.718553) (xy 196.675556 -305.726596) (xy 196.62414 -305.726596) (xy 196.573358 -305.718553)
			(xy 196.524459 -305.702665) (xy 196.478647 -305.679322) (xy 196.437051 -305.649101) (xy 196.400695 -305.612745)
			(xy 196.370474 -305.571149) (xy 196.347131 -305.525337) (xy 196.331243 -305.476438) (xy 196.3232 -305.425656)
			(xy 196.026536 -305.425656) (xy 196.018493 -305.476438) (xy 196.002605 -305.525337) (xy 195.979262 -305.571149)
			(xy 195.949041 -305.612745) (xy 195.912685 -305.649101) (xy 195.871089 -305.679322) (xy 195.825277 -305.702665)
			(xy 195.776378 -305.718553) (xy 195.725596 -305.726596) (xy 195.67418 -305.726596) (xy 195.623398 -305.718553)
			(xy 195.574499 -305.702665) (xy 195.528687 -305.679322) (xy 195.487091 -305.649101) (xy 195.450735 -305.612745)
			(xy 195.420514 -305.571149) (xy 195.397171 -305.525337) (xy 195.381283 -305.476438) (xy 195.37324 -305.425656)
			(xy 194.125695 -305.425656) (xy 194.125342 -305.431952) (xy 194.125342 -305.43246) (xy 194.124326 -305.443128)
			(xy 194.13093 -305.46294) (xy 194.188842 -305.526948) (xy 194.196441 -305.534489) (xy 194.215997 -305.543138)
			(xy 194.226688 -305.543712) (xy 194.274948 -305.543712) (xy 194.300955 -305.544226) (xy 194.352327 -305.552369)
			(xy 194.401793 -305.568448) (xy 194.448135 -305.592067) (xy 194.490212 -305.622643) (xy 194.526988 -305.659425)
			(xy 194.557559 -305.701506) (xy 194.58117 -305.747852) (xy 194.597242 -305.79732) (xy 194.605378 -305.848693)
			(xy 194.605378 -305.900707) (xy 194.597242 -305.95208) (xy 194.58117 -306.001548) (xy 194.557559 -306.047894)
			(xy 194.526988 -306.089975) (xy 194.490212 -306.126757) (xy 194.448135 -306.157333) (xy 194.401793 -306.180952)
			(xy 194.352327 -306.197031) (xy 194.300955 -306.205174) (xy 194.274948 -306.205636) (xy 193.324226 -306.205636)
			(xy 193.312244 -306.205499) (xy 193.288344 -306.20372) (xy 193.276474 -306.20208) (xy 193.269108 -306.201318)
			(xy 193.257424 -306.204874) (xy 193.252642 -306.206565) (xy 193.243814 -306.211557) (xy 193.239898 -306.21478)
			(xy 193.220848 -306.23129) (xy 193.180462 -306.266342) (xy 193.176398 -306.270914) (xy 193.17462 -306.273454)
			(xy 193.173096 -306.275486) (xy 193.176906 -306.300632) (xy 193.178662 -306.312876) (xy 193.180566 -306.33754)
			(xy 193.180716 -306.349908) (xy 193.180283 -306.373746) (xy 193.18001 -306.375616) (xy 197.273414 -306.375616)
			(xy 197.273414 -306.3242) (xy 197.281457 -306.273418) (xy 197.297345 -306.224519) (xy 197.320688 -306.178707)
			(xy 197.350909 -306.137111) (xy 197.387265 -306.100755) (xy 197.428861 -306.070534) (xy 197.474673 -306.047191)
			(xy 197.523572 -306.031303) (xy 197.574354 -306.02326) (xy 197.62577 -306.02326) (xy 197.676552 -306.031303)
			(xy 197.725451 -306.047191) (xy 197.771263 -306.070534) (xy 197.812859 -306.100755) (xy 197.849215 -306.137111)
			(xy 197.879436 -306.178707) (xy 197.902779 -306.224519) (xy 197.918667 -306.273418) (xy 197.92671 -306.3242)
			(xy 197.927214 -306.349908) (xy 197.92671 -306.375616) (xy 198.223374 -306.375616) (xy 198.223374 -306.3242)
			(xy 198.231417 -306.273418) (xy 198.247305 -306.224519) (xy 198.270648 -306.178707) (xy 198.300869 -306.137111)
			(xy 198.337225 -306.100755) (xy 198.378821 -306.070534) (xy 198.424633 -306.047191) (xy 198.473532 -306.031303)
			(xy 198.524314 -306.02326) (xy 198.57573 -306.02326) (xy 198.626512 -306.031303) (xy 198.675411 -306.047191)
			(xy 198.721223 -306.070534) (xy 198.762819 -306.100755) (xy 198.799175 -306.137111) (xy 198.829396 -306.178707)
			(xy 198.852739 -306.224519) (xy 198.868627 -306.273418) (xy 198.87667 -306.3242) (xy 198.877174 -306.349908)
			(xy 198.87667 -306.375616) (xy 198.868627 -306.426398) (xy 198.852739 -306.475297) (xy 198.829396 -306.521109)
			(xy 198.799175 -306.562705) (xy 198.762819 -306.599061) (xy 198.721223 -306.629282) (xy 198.675411 -306.652625)
			(xy 198.626512 -306.668513) (xy 198.57573 -306.676556) (xy 198.524314 -306.676556) (xy 198.473532 -306.668513)
			(xy 198.424633 -306.652625) (xy 198.378821 -306.629282) (xy 198.337225 -306.599061) (xy 198.300869 -306.562705)
			(xy 198.270648 -306.521109) (xy 198.247305 -306.475297) (xy 198.231417 -306.426398) (xy 198.223374 -306.375616)
			(xy 197.92671 -306.375616) (xy 197.918667 -306.426398) (xy 197.902779 -306.475297) (xy 197.879436 -306.521109)
			(xy 197.849215 -306.562705) (xy 197.812859 -306.599061) (xy 197.771263 -306.629282) (xy 197.725451 -306.652625)
			(xy 197.676552 -306.668513) (xy 197.62577 -306.676556) (xy 197.574354 -306.676556) (xy 197.523572 -306.668513)
			(xy 197.474673 -306.652625) (xy 197.428861 -306.629282) (xy 197.387265 -306.599061) (xy 197.350909 -306.562705)
			(xy 197.320688 -306.521109) (xy 197.297345 -306.475297) (xy 197.281457 -306.426398) (xy 197.273414 -306.375616)
			(xy 193.18001 -306.375616) (xy 193.173401 -306.420922) (xy 193.167 -306.443888) (xy 193.164968 -306.451)
			(xy 193.164968 -307.21173) (xy 193.166492 -307.217826) (xy 193.171418 -307.237916) (xy 193.176765 -307.278933)
			(xy 193.17716 -307.299614) (xy 193.17716 -307.300122) (xy 193.176985 -307.311723) (xy 193.175208 -307.334859)
			(xy 193.173604 -307.34635) (xy 193.170302 -307.36921) (xy 193.175128 -307.37683) (xy 193.175636 -307.377338)
			(xy 193.181732 -307.384196) (xy 193.19367 -307.39461) (xy 193.194178 -307.39461) (xy 193.239898 -307.434488)
			(xy 193.243808 -307.437721) (xy 193.252637 -307.442713) (xy 193.257424 -307.444394) (xy 193.269108 -307.44795)
			(xy 193.276474 -307.447188) (xy 193.288343 -307.445533) (xy 193.312243 -307.443753) (xy 193.324226 -307.443632)
			(xy 193.373248 -307.443632) (xy 193.383973 -307.443214) (xy 193.403581 -307.434533) (xy 193.411094 -307.426868)
			(xy 193.46164 -307.370988) (xy 193.468309 -307.36284) (xy 193.475004 -307.342901) (xy 193.474594 -307.33238)
			(xy 193.474594 -307.332126) (xy 193.472816 -307.300122) (xy 193.472816 -307.299614) (xy 193.473339 -307.273919)
			(xy 193.481414 -307.223167) (xy 193.497324 -307.174302) (xy 193.52068 -307.128526) (xy 193.550906 -307.086965)
			(xy 193.587258 -307.05064) (xy 193.628843 -307.020447) (xy 193.674637 -306.997127) (xy 193.723515 -306.981254)
			(xy 193.774273 -306.973219) (xy 193.825663 -306.973219) (xy 193.876421 -306.981254) (xy 193.925299 -306.997127)
			(xy 193.971093 -307.020447) (xy 194.012678 -307.05064) (xy 194.04903 -307.086965) (xy 194.079256 -307.128526)
			(xy 194.102612 -307.174302) (xy 194.118522 -307.223167) (xy 194.126597 -307.273919) (xy 194.12712 -307.299614)
			(xy 194.12712 -307.300122) (xy 194.125695 -307.325576) (xy 195.37324 -307.325576) (xy 195.37324 -307.27416)
			(xy 195.381283 -307.223378) (xy 195.397171 -307.174479) (xy 195.420514 -307.128667) (xy 195.450735 -307.087071)
			(xy 195.487091 -307.050715) (xy 195.528687 -307.020494) (xy 195.574499 -306.997151) (xy 195.623398 -306.981263)
			(xy 195.67418 -306.97322) (xy 195.725596 -306.97322) (xy 195.776378 -306.981263) (xy 195.825277 -306.997151)
			(xy 195.871089 -307.020494) (xy 195.912685 -307.050715) (xy 195.949041 -307.087071) (xy 195.979262 -307.128667)
			(xy 196.002605 -307.174479) (xy 196.018493 -307.223378) (xy 196.026536 -307.27416) (xy 196.02704 -307.299868)
			(xy 196.026536 -307.325576) (xy 196.3232 -307.325576) (xy 196.3232 -307.27416) (xy 196.331243 -307.223378)
			(xy 196.347131 -307.174479) (xy 196.370474 -307.128667) (xy 196.400695 -307.087071) (xy 196.437051 -307.050715)
			(xy 196.478647 -307.020494) (xy 196.524459 -306.997151) (xy 196.573358 -306.981263) (xy 196.62414 -306.97322)
			(xy 196.675556 -306.97322) (xy 196.726338 -306.981263) (xy 196.775237 -306.997151) (xy 196.821049 -307.020494)
			(xy 196.862645 -307.050715) (xy 196.896152 -307.084222) (xy 208.814414 -307.084222) (xy 208.818485 -307.0286)
			(xy 208.830611 -306.974163) (xy 208.850534 -306.922072) (xy 208.87783 -306.873437) (xy 208.911916 -306.829294)
			(xy 208.952065 -306.790585) (xy 208.997423 -306.758134) (xy 209.047023 -306.732633) (xy 209.099807 -306.714626)
			(xy 209.15465 -306.704496) (xy 209.210384 -306.702459) (xy 209.265821 -306.708559) (xy 209.319778 -306.722665)
			(xy 209.371107 -306.744477) (xy 209.418713 -306.773531) (xy 209.461581 -306.809206) (xy 209.498798 -306.850743)
			(xy 209.529571 -306.897256) (xy 209.553243 -306.947753) (xy 209.569311 -307.00116) (xy 209.577431 -307.056336)
			(xy 209.57794 -307.084222) (xy 209.577431 -307.112108) (xy 209.569311 -307.167284) (xy 209.553243 -307.220691)
			(xy 209.529571 -307.271188) (xy 209.498798 -307.317701) (xy 209.461581 -307.359238) (xy 209.418713 -307.394913)
			(xy 209.371107 -307.423967) (xy 209.319778 -307.445779) (xy 209.265821 -307.459885) (xy 209.210384 -307.465985)
			(xy 209.15465 -307.463948) (xy 209.099807 -307.453818) (xy 209.047023 -307.435811) (xy 208.997423 -307.41031)
			(xy 208.952065 -307.377859) (xy 208.911916 -307.33915) (xy 208.87783 -307.295007) (xy 208.850534 -307.246372)
			(xy 208.830611 -307.194281) (xy 208.818485 -307.139844) (xy 208.814414 -307.084222) (xy 196.896152 -307.084222)
			(xy 196.899001 -307.087071) (xy 196.929222 -307.128667) (xy 196.952565 -307.174479) (xy 196.968453 -307.223378)
			(xy 196.976496 -307.27416) (xy 196.977 -307.299868) (xy 196.976496 -307.325576) (xy 196.968453 -307.376358)
			(xy 196.952565 -307.425257) (xy 196.929222 -307.471069) (xy 196.899001 -307.512665) (xy 196.862645 -307.549021)
			(xy 196.821049 -307.579242) (xy 196.775237 -307.602585) (xy 196.726338 -307.618473) (xy 196.675556 -307.626516)
			(xy 196.62414 -307.626516) (xy 196.573358 -307.618473) (xy 196.524459 -307.602585) (xy 196.478647 -307.579242)
			(xy 196.437051 -307.549021) (xy 196.400695 -307.512665) (xy 196.370474 -307.471069) (xy 196.347131 -307.425257)
			(xy 196.331243 -307.376358) (xy 196.3232 -307.325576) (xy 196.026536 -307.325576) (xy 196.018493 -307.376358)
			(xy 196.002605 -307.425257) (xy 195.979262 -307.471069) (xy 195.949041 -307.512665) (xy 195.912685 -307.549021)
			(xy 195.871089 -307.579242) (xy 195.825277 -307.602585) (xy 195.776378 -307.618473) (xy 195.725596 -307.626516)
			(xy 195.67418 -307.626516) (xy 195.623398 -307.618473) (xy 195.574499 -307.602585) (xy 195.528687 -307.579242)
			(xy 195.487091 -307.549021) (xy 195.450735 -307.512665) (xy 195.420514 -307.471069) (xy 195.397171 -307.425257)
			(xy 195.381283 -307.376358) (xy 195.37324 -307.325576) (xy 194.125695 -307.325576) (xy 194.125342 -307.331872)
			(xy 194.125342 -307.33238) (xy 194.124326 -307.343048) (xy 194.13093 -307.36286) (xy 194.188842 -307.426868)
			(xy 194.196441 -307.434407) (xy 194.215997 -307.443052) (xy 194.226688 -307.443632) (xy 194.274948 -307.443632)
			(xy 194.300953 -307.444146) (xy 194.352322 -307.452289) (xy 194.401785 -307.468367) (xy 194.448124 -307.491984)
			(xy 194.490199 -307.522558) (xy 194.526973 -307.559338) (xy 194.557542 -307.601417) (xy 194.581152 -307.647759)
			(xy 194.597222 -307.697225) (xy 194.605358 -307.748595) (xy 194.605358 -307.800605) (xy 194.597222 -307.851975)
			(xy 194.581152 -307.901441) (xy 194.557542 -307.947783) (xy 194.526973 -307.989862) (xy 194.490199 -308.026642)
			(xy 194.448124 -308.057216) (xy 194.401785 -308.080833) (xy 194.352322 -308.096911) (xy 194.300953 -308.105054)
			(xy 194.274948 -308.105556) (xy 193.324226 -308.105556) (xy 193.312244 -308.105419) (xy 193.288344 -308.10364)
			(xy 193.276474 -308.102) (xy 193.269108 -308.101238) (xy 193.257424 -308.104794) (xy 193.252642 -308.106486)
			(xy 193.243816 -308.111479) (xy 193.239898 -308.1147) (xy 193.220848 -308.13121) (xy 193.180462 -308.166262)
			(xy 193.176398 -308.170834) (xy 193.17462 -308.173374) (xy 193.173096 -308.175406) (xy 193.176906 -308.200552)
			(xy 193.178665 -308.212796) (xy 193.180575 -308.23746) (xy 193.180716 -308.249828) (xy 193.180282 -308.273665)
			(xy 193.180009 -308.275536) (xy 197.273414 -308.275536) (xy 197.273414 -308.22412) (xy 197.281457 -308.173338)
			(xy 197.297345 -308.124439) (xy 197.320688 -308.078627) (xy 197.350909 -308.037031) (xy 197.387265 -308.000675)
			(xy 197.428861 -307.970454) (xy 197.474673 -307.947111) (xy 197.523572 -307.931223) (xy 197.574354 -307.92318)
			(xy 197.62577 -307.92318) (xy 197.676552 -307.931223) (xy 197.725451 -307.947111) (xy 197.771263 -307.970454)
			(xy 197.812859 -308.000675) (xy 197.849215 -308.037031) (xy 197.879436 -308.078627) (xy 197.902779 -308.124439)
			(xy 197.918667 -308.173338) (xy 197.92671 -308.22412) (xy 197.927214 -308.249828) (xy 197.92671 -308.275536)
			(xy 198.223374 -308.275536) (xy 198.223374 -308.22412) (xy 198.231417 -308.173338) (xy 198.247305 -308.124439)
			(xy 198.270648 -308.078627) (xy 198.300869 -308.037031) (xy 198.337225 -308.000675) (xy 198.378821 -307.970454)
			(xy 198.424633 -307.947111) (xy 198.473532 -307.931223) (xy 198.524314 -307.92318) (xy 198.57573 -307.92318)
			(xy 198.626512 -307.931223) (xy 198.675411 -307.947111) (xy 198.721223 -307.970454) (xy 198.762819 -308.000675)
			(xy 198.799175 -308.037031) (xy 198.829396 -308.078627) (xy 198.852739 -308.124439) (xy 198.868627 -308.173338)
			(xy 198.87667 -308.22412) (xy 198.877174 -308.249828) (xy 198.87667 -308.275536) (xy 198.868627 -308.326318)
			(xy 198.852739 -308.375217) (xy 198.829396 -308.421029) (xy 198.799175 -308.462625) (xy 198.762819 -308.498981)
			(xy 198.721223 -308.529202) (xy 198.675411 -308.552545) (xy 198.626512 -308.568433) (xy 198.57573 -308.576476)
			(xy 198.524314 -308.576476) (xy 198.473532 -308.568433) (xy 198.424633 -308.552545) (xy 198.378821 -308.529202)
			(xy 198.337225 -308.498981) (xy 198.300869 -308.462625) (xy 198.270648 -308.421029) (xy 198.247305 -308.375217)
			(xy 198.231417 -308.326318) (xy 198.223374 -308.275536) (xy 197.92671 -308.275536) (xy 197.918667 -308.326318)
			(xy 197.902779 -308.375217) (xy 197.879436 -308.421029) (xy 197.849215 -308.462625) (xy 197.812859 -308.498981)
			(xy 197.771263 -308.529202) (xy 197.725451 -308.552545) (xy 197.676552 -308.568433) (xy 197.62577 -308.576476)
			(xy 197.574354 -308.576476) (xy 197.523572 -308.568433) (xy 197.474673 -308.552545) (xy 197.428861 -308.529202)
			(xy 197.387265 -308.498981) (xy 197.350909 -308.462625) (xy 197.320688 -308.421029) (xy 197.297345 -308.375217)
			(xy 197.281457 -308.326318) (xy 197.273414 -308.275536) (xy 193.180009 -308.275536) (xy 193.173397 -308.320841)
			(xy 193.167 -308.343808) (xy 193.164968 -308.35092) (xy 193.164968 -309.11165) (xy 193.166492 -309.117746)
			(xy 193.171417 -309.137836) (xy 193.176761 -309.178853) (xy 193.17716 -309.199534) (xy 193.17716 -309.200042)
			(xy 193.176976 -309.211579) (xy 193.175196 -309.234587) (xy 193.173604 -309.246016) (xy 193.173604 -309.246524)
			(xy 193.170302 -309.269384) (xy 193.175382 -309.277258) (xy 193.181986 -309.28437) (xy 193.24066 -309.335678)
			(xy 193.251074 -309.342282) (xy 193.253868 -309.343298) (xy 193.269616 -309.348378) (xy 193.274696 -309.347616)
			(xy 193.279776 -309.346854) (xy 193.28003 -309.346854) (xy 193.282062 -309.3466) (xy 193.28257 -309.3466)
			(xy 193.289682 -309.345838) (xy 193.29019 -309.345838) (xy 193.292476 -309.345584) (xy 193.324988 -309.34406)
			(xy 193.373502 -309.34406) (xy 193.384229 -309.343649) (xy 193.403843 -309.334971) (xy 193.411348 -309.327296)
			(xy 193.46164 -309.27167) (xy 193.468366 -309.263407) (xy 193.475046 -309.2432) (xy 193.474594 -309.232554)
			(xy 193.474594 -309.2323) (xy 193.472816 -309.200042) (xy 193.472816 -309.199534) (xy 193.473339 -309.173839)
			(xy 193.481414 -309.123087) (xy 193.497324 -309.074222) (xy 193.52068 -309.028446) (xy 193.550906 -308.986885)
			(xy 193.587258 -308.95056) (xy 193.628843 -308.920367) (xy 193.674637 -308.897047) (xy 193.723515 -308.881174)
			(xy 193.774273 -308.873139) (xy 193.825663 -308.873139) (xy 193.876421 -308.881174) (xy 193.925299 -308.897047)
			(xy 193.971093 -308.920367) (xy 194.012678 -308.95056) (xy 194.04903 -308.986885) (xy 194.079256 -309.028446)
			(xy 194.102612 -309.074222) (xy 194.118522 -309.123087) (xy 194.126597 -309.173839) (xy 194.12712 -309.199534)
			(xy 194.12712 -309.200042) (xy 194.125717 -309.225496) (xy 195.37324 -309.225496) (xy 195.37324 -309.17408)
			(xy 195.381283 -309.123298) (xy 195.397171 -309.074399) (xy 195.420514 -309.028587) (xy 195.450735 -308.986991)
			(xy 195.487091 -308.950635) (xy 195.528687 -308.920414) (xy 195.574499 -308.897071) (xy 195.623398 -308.881183)
			(xy 195.67418 -308.87314) (xy 195.725596 -308.87314) (xy 195.776378 -308.881183) (xy 195.825277 -308.897071)
			(xy 195.871089 -308.920414) (xy 195.912685 -308.950635) (xy 195.949041 -308.986991) (xy 195.979262 -309.028587)
			(xy 196.002605 -309.074399) (xy 196.018493 -309.123298) (xy 196.026536 -309.17408) (xy 196.02704 -309.199788)
			(xy 196.026536 -309.225496) (xy 196.3232 -309.225496) (xy 196.3232 -309.17408) (xy 196.331243 -309.123298)
			(xy 196.347131 -309.074399) (xy 196.370474 -309.028587) (xy 196.400695 -308.986991) (xy 196.437051 -308.950635)
			(xy 196.478647 -308.920414) (xy 196.524459 -308.897071) (xy 196.573358 -308.881183) (xy 196.62414 -308.87314)
			(xy 196.675556 -308.87314) (xy 196.726338 -308.881183) (xy 196.775237 -308.897071) (xy 196.821049 -308.920414)
			(xy 196.862645 -308.950635) (xy 196.899001 -308.986991) (xy 196.929222 -309.028587) (xy 196.952565 -309.074399)
			(xy 196.968453 -309.123298) (xy 196.976496 -309.17408) (xy 196.977 -309.199788) (xy 196.976496 -309.225496)
			(xy 196.968453 -309.276278) (xy 196.952565 -309.325177) (xy 196.929222 -309.370989) (xy 196.927154 -309.373836)
			(xy 204.602097 -309.373836) (xy 204.602099 -309.319337) (xy 204.609857 -309.265393) (xy 204.625213 -309.213102)
			(xy 204.647854 -309.163529) (xy 204.67732 -309.117682) (xy 204.71301 -309.076496) (xy 204.754198 -309.040808)
			(xy 204.800047 -309.011344) (xy 204.849621 -308.988706) (xy 204.901913 -308.973353) (xy 204.955857 -308.965598)
			(xy 205.010356 -308.965599) (xy 205.0643 -308.973356) (xy 205.116591 -308.98871) (xy 205.166165 -309.011351)
			(xy 205.212012 -309.040816) (xy 205.253199 -309.076505) (xy 205.288888 -309.117693) (xy 205.318352 -309.163541)
			(xy 205.340992 -309.213115) (xy 205.356346 -309.265406) (xy 205.364102 -309.319351) (xy 205.364588 -309.3466)
			(xy 205.36408 -309.365904) (xy 205.36408 -309.366158) (xy 205.364157 -309.376749) (xy 205.371924 -309.396433)
			(xy 205.379066 -309.404258) (xy 205.43266 -309.457598) (xy 205.440553 -309.464839) (xy 205.460556 -309.472459)
			(xy 205.471268 -309.47233) (xy 205.492858 -309.471822) (xy 205.520114 -309.47221) (xy 205.574072 -309.479962)
			(xy 205.626378 -309.495314) (xy 205.675966 -309.517954) (xy 205.721828 -309.547421) (xy 205.763029 -309.583114)
			(xy 205.798731 -309.624308) (xy 205.828208 -309.670163) (xy 205.850858 -309.719747) (xy 205.866221 -309.772049)
			(xy 205.873984 -309.826006) (xy 205.87399 -309.880518) (xy 205.866237 -309.934476) (xy 205.850884 -309.986782)
			(xy 205.828244 -310.03637) (xy 205.798777 -310.082231) (xy 205.763083 -310.123432) (xy 205.721889 -310.159134)
			(xy 205.676033 -310.18861) (xy 205.626449 -310.211259) (xy 205.574147 -310.226622) (xy 205.52019 -310.234385)
			(xy 205.465678 -310.234389) (xy 205.41172 -310.226636) (xy 205.359415 -310.211283) (xy 205.309827 -310.188642)
			(xy 205.263966 -310.159175) (xy 205.222765 -310.12348) (xy 205.187064 -310.082286) (xy 205.157589 -310.03643)
			(xy 205.134939 -309.986845) (xy 205.119577 -309.934543) (xy 205.111815 -309.880586) (xy 205.11135 -309.85333)
			(xy 205.111858 -309.834026) (xy 205.111858 -309.833772) (xy 205.111754 -309.823183) (xy 205.104004 -309.8035)
			(xy 205.096872 -309.795672) (xy 205.043278 -309.742332) (xy 205.035367 -309.735113) (xy 205.015378 -309.72748)
			(xy 205.00467 -309.7276) (xy 204.98308 -309.728108) (xy 204.955831 -309.7276) (xy 204.901887 -309.719842)
			(xy 204.849596 -309.704485) (xy 204.800023 -309.681843) (xy 204.754177 -309.652376) (xy 204.712991 -309.616685)
			(xy 204.677304 -309.575496) (xy 204.647841 -309.529648) (xy 204.625203 -309.480073) (xy 204.609851 -309.427781)
			(xy 204.602097 -309.373836) (xy 196.927154 -309.373836) (xy 196.899001 -309.412585) (xy 196.862645 -309.448941)
			(xy 196.821049 -309.479162) (xy 196.775237 -309.502505) (xy 196.726338 -309.518393) (xy 196.675556 -309.526436)
			(xy 196.62414 -309.526436) (xy 196.573358 -309.518393) (xy 196.524459 -309.502505) (xy 196.478647 -309.479162)
			(xy 196.437051 -309.448941) (xy 196.400695 -309.412585) (xy 196.370474 -309.370989) (xy 196.347131 -309.325177)
			(xy 196.331243 -309.276278) (xy 196.3232 -309.225496) (xy 196.026536 -309.225496) (xy 196.018493 -309.276278)
			(xy 196.002605 -309.325177) (xy 195.979262 -309.370989) (xy 195.949041 -309.412585) (xy 195.912685 -309.448941)
			(xy 195.871089 -309.479162) (xy 195.825277 -309.502505) (xy 195.776378 -309.518393) (xy 195.725596 -309.526436)
			(xy 195.67418 -309.526436) (xy 195.623398 -309.518393) (xy 195.574499 -309.502505) (xy 195.528687 -309.479162)
			(xy 195.487091 -309.448941) (xy 195.450735 -309.412585) (xy 195.420514 -309.370989) (xy 195.397171 -309.325177)
			(xy 195.381283 -309.276278) (xy 195.37324 -309.225496) (xy 194.125717 -309.225496) (xy 194.125342 -309.2323)
			(xy 194.125342 -309.232554) (xy 194.124731 -309.243219) (xy 194.131434 -309.263484) (xy 194.138296 -309.27167)
			(xy 194.188588 -309.327296) (xy 194.196186 -309.33484) (xy 194.215741 -309.343501) (xy 194.226434 -309.34406)
			(xy 194.274948 -309.34406) (xy 194.300935 -309.344573) (xy 194.352269 -309.352711) (xy 194.401698 -309.368777)
			(xy 194.448005 -309.392378) (xy 194.490051 -309.422932) (xy 194.5268 -309.459686) (xy 194.557347 -309.501736)
			(xy 194.580941 -309.548047) (xy 194.597001 -309.597478) (xy 194.605131 -309.648813) (xy 194.605131 -309.700787)
			(xy 194.597001 -309.752122) (xy 194.580941 -309.801553) (xy 194.557347 -309.847864) (xy 194.5268 -309.889914)
			(xy 194.490051 -309.926668) (xy 194.448005 -309.957222) (xy 194.401698 -309.980823) (xy 194.352269 -309.996889)
			(xy 194.300935 -310.005027) (xy 194.274948 -310.005476) (xy 193.322448 -310.005476) (xy 193.299343 -310.004958)
			(xy 193.253618 -309.998249) (xy 193.209278 -309.985221) (xy 193.188082 -309.976012) (xy 193.173248 -309.969191)
			(xy 193.144873 -309.953035) (xy 193.13144 -309.943754) (xy 193.130932 -309.943246) (xy 193.113406 -309.931308)
			(xy 193.108072 -309.92826) (xy 193.104516 -309.926736) (xy 193.100706 -309.925212) (xy 193.096642 -309.929276)
			(xy 193.112375 -309.947554) (xy 193.138932 -309.987808) (xy 193.159369 -310.031489) (xy 193.173254 -310.077673)
			(xy 193.180293 -310.125382) (xy 193.180716 -310.149494) (xy 193.180716 -310.149748) (xy 193.180208 -310.175456)
			(xy 197.273414 -310.175456) (xy 197.273414 -310.12404) (xy 197.281457 -310.073258) (xy 197.297345 -310.024359)
			(xy 197.320688 -309.978547) (xy 197.350909 -309.936951) (xy 197.387265 -309.900595) (xy 197.428861 -309.870374)
			(xy 197.474673 -309.847031) (xy 197.523572 -309.831143) (xy 197.574354 -309.8231) (xy 197.62577 -309.8231)
			(xy 197.676552 -309.831143) (xy 197.725451 -309.847031) (xy 197.771263 -309.870374) (xy 197.812859 -309.900595)
			(xy 197.849215 -309.936951) (xy 197.879436 -309.978547) (xy 197.902779 -310.024359) (xy 197.918667 -310.073258)
			(xy 197.92671 -310.12404) (xy 197.927214 -310.149748) (xy 197.92671 -310.175456) (xy 198.223374 -310.175456)
			(xy 198.223374 -310.12404) (xy 198.231417 -310.073258) (xy 198.247305 -310.024359) (xy 198.270648 -309.978547)
			(xy 198.300869 -309.936951) (xy 198.337225 -309.900595) (xy 198.378821 -309.870374) (xy 198.424633 -309.847031)
			(xy 198.473532 -309.831143) (xy 198.524314 -309.8231) (xy 198.57573 -309.8231) (xy 198.626512 -309.831143)
			(xy 198.675411 -309.847031) (xy 198.721223 -309.870374) (xy 198.762819 -309.900595) (xy 198.799175 -309.936951)
			(xy 198.829396 -309.978547) (xy 198.852739 -310.024359) (xy 198.868627 -310.073258) (xy 198.87667 -310.12404)
			(xy 198.877174 -310.149748) (xy 198.87667 -310.175456) (xy 198.868627 -310.226238) (xy 198.852739 -310.275137)
			(xy 198.829396 -310.320949) (xy 198.799175 -310.362545) (xy 198.762819 -310.398901) (xy 198.721223 -310.429122)
			(xy 198.675411 -310.452465) (xy 198.626512 -310.468353) (xy 198.57573 -310.476396) (xy 198.524314 -310.476396)
			(xy 198.473532 -310.468353) (xy 198.424633 -310.452465) (xy 198.378821 -310.429122) (xy 198.337225 -310.398901)
			(xy 198.300869 -310.362545) (xy 198.270648 -310.320949) (xy 198.247305 -310.275137) (xy 198.231417 -310.226238)
			(xy 198.223374 -310.175456) (xy 197.92671 -310.175456) (xy 197.918667 -310.226238) (xy 197.902779 -310.275137)
			(xy 197.879436 -310.320949) (xy 197.849215 -310.362545) (xy 197.812859 -310.398901) (xy 197.771263 -310.429122)
			(xy 197.725451 -310.452465) (xy 197.676552 -310.468353) (xy 197.62577 -310.476396) (xy 197.574354 -310.476396)
			(xy 197.523572 -310.468353) (xy 197.474673 -310.452465) (xy 197.428861 -310.429122) (xy 197.387265 -310.398901)
			(xy 197.350909 -310.362545) (xy 197.320688 -310.320949) (xy 197.297345 -310.275137) (xy 197.281457 -310.226238)
			(xy 197.273414 -310.175456) (xy 193.180208 -310.175456) (xy 193.180203 -310.175733) (xy 193.172066 -310.227062)
			(xy 193.156001 -310.276487) (xy 193.132403 -310.32279) (xy 193.101853 -310.364832) (xy 193.065102 -310.401579)
			(xy 193.023056 -310.432124) (xy 192.97675 -310.455717) (xy 192.927323 -310.471776) (xy 192.875993 -310.479906)
			(xy 192.850008 -310.480456) (xy 192.849754 -310.480456) (xy 192.825641 -310.480021) (xy 192.777926 -310.473012)
			(xy 192.731739 -310.459137) (xy 192.688062 -310.438689) (xy 192.647825 -310.412104) (xy 192.629536 -310.396382)
			(xy 192.625472 -310.400446) (xy 192.626234 -310.402224) (xy 192.626742 -310.403748) (xy 192.62852 -310.407812)
			(xy 192.631568 -310.413146) (xy 192.643506 -310.430672) (xy 192.644014 -310.43118) (xy 192.653291 -310.444616)
			(xy 192.669452 -310.472988) (xy 192.676272 -310.487822) (xy 192.685423 -310.509039) (xy 192.698431 -310.553376)
			(xy 192.705168 -310.599089) (xy 192.705736 -310.622188) (xy 192.705736 -310.68518) (xy 205.94269 -310.68518)
			(xy 205.946761 -310.629558) (xy 205.958887 -310.575121) (xy 205.97881 -310.52303) (xy 206.006106 -310.474395)
			(xy 206.040192 -310.430252) (xy 206.080341 -310.391543) (xy 206.125699 -310.359092) (xy 206.175299 -310.333591)
			(xy 206.228083 -310.315584) (xy 206.282926 -310.305454) (xy 206.33866 -310.303417) (xy 206.394097 -310.309517)
			(xy 206.448054 -310.323623) (xy 206.499383 -310.345435) (xy 206.546989 -310.374489) (xy 206.589857 -310.410164)
			(xy 206.627074 -310.451701) (xy 206.657847 -310.498214) (xy 206.681519 -310.548711) (xy 206.697587 -310.602118)
			(xy 206.705707 -310.657294) (xy 206.706216 -310.68518) (xy 206.705707 -310.713066) (xy 206.697587 -310.768242)
			(xy 206.681519 -310.821649) (xy 206.657847 -310.872146) (xy 206.627074 -310.918659) (xy 206.589857 -310.960196)
			(xy 206.546989 -310.995871) (xy 206.499383 -311.024925) (xy 206.448054 -311.046737) (xy 206.394097 -311.060843)
			(xy 206.33866 -311.066943) (xy 206.282926 -311.064906) (xy 206.228083 -311.054776) (xy 206.175299 -311.036769)
			(xy 206.125699 -311.011268) (xy 206.080341 -310.978817) (xy 206.040192 -310.940108) (xy 206.006106 -310.895965)
			(xy 205.97881 -310.84733) (xy 205.958887 -310.795239) (xy 205.946761 -310.740802) (xy 205.94269 -310.68518)
			(xy 192.705736 -310.68518) (xy 192.705736 -311.12567) (xy 193.47332 -311.12567) (xy 193.47332 -311.074254)
			(xy 193.481363 -311.023472) (xy 193.497251 -310.974573) (xy 193.520594 -310.928761) (xy 193.550815 -310.887165)
			(xy 193.587171 -310.850809) (xy 193.628767 -310.820588) (xy 193.674579 -310.797245) (xy 193.723478 -310.781357)
			(xy 193.77426 -310.773314) (xy 193.825676 -310.773314) (xy 193.876458 -310.781357) (xy 193.925357 -310.797245)
			(xy 193.971169 -310.820588) (xy 194.012765 -310.850809) (xy 194.049121 -310.887165) (xy 194.079342 -310.928761)
			(xy 194.102685 -310.974573) (xy 194.118573 -311.023472) (xy 194.126616 -311.074254) (xy 194.12712 -311.099962)
			(xy 194.126616 -311.12567) (xy 195.37324 -311.12567) (xy 195.37324 -311.074254) (xy 195.381283 -311.023472)
			(xy 195.397171 -310.974573) (xy 195.420514 -310.928761) (xy 195.450735 -310.887165) (xy 195.487091 -310.850809)
			(xy 195.528687 -310.820588) (xy 195.574499 -310.797245) (xy 195.623398 -310.781357) (xy 195.67418 -310.773314)
			(xy 195.725596 -310.773314) (xy 195.776378 -310.781357) (xy 195.825277 -310.797245) (xy 195.871089 -310.820588)
			(xy 195.912685 -310.850809) (xy 195.949041 -310.887165) (xy 195.979262 -310.928761) (xy 196.002605 -310.974573)
			(xy 196.018493 -311.023472) (xy 196.026536 -311.074254) (xy 196.02704 -311.099962) (xy 196.026536 -311.12567)
			(xy 196.018493 -311.176452) (xy 196.002605 -311.225351) (xy 195.979262 -311.271163) (xy 195.949041 -311.312759)
			(xy 195.912685 -311.349115) (xy 195.871089 -311.379336) (xy 195.868047 -311.380886) (xy 206.666706 -311.380886)
			(xy 206.674458 -311.326928) (xy 206.68981 -311.274621) (xy 206.71245 -311.225033) (xy 206.741917 -311.17917)
			(xy 206.777611 -311.137969) (xy 206.818805 -311.102266) (xy 206.86466 -311.072789) (xy 206.914245 -311.050139)
			(xy 206.966547 -311.034775) (xy 207.020504 -311.027012) (xy 207.075017 -311.027006) (xy 207.128976 -311.034759)
			(xy 207.181282 -311.050111) (xy 207.23087 -311.072752) (xy 207.276732 -311.102219) (xy 207.317934 -311.137913)
			(xy 207.353636 -311.179107) (xy 207.383112 -311.224963) (xy 207.405762 -311.274548) (xy 207.421125 -311.326851)
			(xy 207.428888 -311.380808) (xy 207.429354 -311.408064) (xy 207.429157 -311.425112) (xy 207.426103 -311.459072)
			(xy 207.423258 -311.475882) (xy 207.420972 -311.488328) (xy 207.428338 -311.51195) (xy 207.5053 -311.588912)
			(xy 207.528922 -311.596278) (xy 207.541368 -311.593992) (xy 207.558177 -311.591134) (xy 207.592137 -311.588079)
			(xy 207.609186 -311.587896) (xy 207.60944 -311.587896) (xy 207.636692 -311.588341) (xy 207.690642 -311.596103)
			(xy 207.742938 -311.611463) (xy 207.792515 -311.634109) (xy 207.838366 -311.66358) (xy 207.879555 -311.699276)
			(xy 207.915246 -311.74047) (xy 207.944712 -311.786323) (xy 207.967352 -311.835904) (xy 207.982707 -311.888201)
			(xy 207.990463 -311.942152) (xy 207.990948 -311.969404) (xy 207.989932 -311.99836) (xy 207.98917 -312.009536)
			(xy 207.99679 -312.030364) (xy 208.06791 -312.100468) (xy 208.088738 -312.108088) (xy 208.099914 -312.107072)
			(xy 208.132426 -312.105802) (xy 208.159675 -312.106306) (xy 208.213617 -312.114065) (xy 208.265906 -312.129422)
			(xy 208.315478 -312.152064) (xy 208.361322 -312.181531) (xy 208.402507 -312.217221) (xy 208.438193 -312.25841)
			(xy 208.467655 -312.304257) (xy 208.490292 -312.353831) (xy 208.505643 -312.406122) (xy 208.513397 -312.460065)
			(xy 208.513395 -312.514563) (xy 208.505637 -312.568505) (xy 208.490282 -312.620795) (xy 208.467641 -312.670367)
			(xy 208.438176 -312.716213) (xy 208.402487 -312.757399) (xy 208.3613 -312.793086) (xy 208.315453 -312.822549)
			(xy 208.26588 -312.845187) (xy 208.21359 -312.860541) (xy 208.159647 -312.868296) (xy 208.105149 -312.868296)
			(xy 208.051206 -312.86054) (xy 207.998916 -312.845186) (xy 207.949343 -312.822547) (xy 207.903497 -312.793084)
			(xy 207.86231 -312.757396) (xy 207.826621 -312.71621) (xy 207.797157 -312.670364) (xy 207.774517 -312.620791)
			(xy 207.759162 -312.568502) (xy 207.751405 -312.514559) (xy 207.750918 -312.48731) (xy 207.751934 -312.458354)
			(xy 207.752696 -312.447178) (xy 207.745076 -312.42635) (xy 207.673956 -312.356246) (xy 207.653128 -312.348626)
			(xy 207.641952 -312.349642) (xy 207.60944 -312.350912) (xy 207.582188 -312.350408) (xy 207.528239 -312.342656)
			(xy 207.475942 -312.327305) (xy 207.426363 -312.304668) (xy 207.380509 -312.275204) (xy 207.339316 -312.239515)
			(xy 207.303622 -312.198326) (xy 207.274153 -312.152476) (xy 207.25151 -312.102899) (xy 207.236153 -312.050604)
			(xy 207.228396 -311.996656) (xy 207.227932 -311.969404) (xy 207.228138 -311.952356) (xy 207.231186 -311.918397)
			(xy 207.234028 -311.901586) (xy 207.236314 -311.88914) (xy 207.228948 -311.865518) (xy 207.151986 -311.788556)
			(xy 207.128364 -311.78119) (xy 207.115918 -311.783476) (xy 207.09911 -311.786335) (xy 207.065149 -311.78939)
			(xy 207.0481 -311.789572) (xy 207.047846 -311.789572) (xy 207.02059 -311.789194) (xy 206.966631 -311.781443)
			(xy 206.914325 -311.766091) (xy 206.864735 -311.743452) (xy 206.818873 -311.713985) (xy 206.777671 -311.678292)
			(xy 206.741968 -311.637098) (xy 206.712491 -311.591242) (xy 206.68984 -311.541659) (xy 206.674476 -311.489356)
			(xy 206.666712 -311.435399) (xy 206.666706 -311.380886) (xy 195.868047 -311.380886) (xy 195.825277 -311.402679)
			(xy 195.776378 -311.418567) (xy 195.725596 -311.42661) (xy 195.67418 -311.42661) (xy 195.623398 -311.418567)
			(xy 195.574499 -311.402679) (xy 195.528687 -311.379336) (xy 195.487091 -311.349115) (xy 195.450735 -311.312759)
			(xy 195.420514 -311.271163) (xy 195.397171 -311.225351) (xy 195.381283 -311.176452) (xy 195.37324 -311.12567)
			(xy 194.126616 -311.12567) (xy 194.118573 -311.176452) (xy 194.102685 -311.225351) (xy 194.079342 -311.271163)
			(xy 194.049121 -311.312759) (xy 194.012765 -311.349115) (xy 193.971169 -311.379336) (xy 193.925357 -311.402679)
			(xy 193.876458 -311.418567) (xy 193.825676 -311.42661) (xy 193.77426 -311.42661) (xy 193.723478 -311.418567)
			(xy 193.674579 -311.402679) (xy 193.628767 -311.379336) (xy 193.587171 -311.349115) (xy 193.550815 -311.312759)
			(xy 193.520594 -311.271163) (xy 193.497251 -311.225351) (xy 193.481363 -311.176452) (xy 193.47332 -311.12567)
			(xy 192.705736 -311.12567) (xy 192.705736 -311.574688) (xy 192.705227 -311.600677) (xy 192.697098 -311.652014)
			(xy 192.681039 -311.701448) (xy 192.657444 -311.747761) (xy 192.626895 -311.789813) (xy 192.590144 -311.826569)
			(xy 192.548095 -311.857123) (xy 192.501785 -311.880724) (xy 192.452353 -311.896789) (xy 192.401017 -311.904924)
			(xy 192.375028 -311.905396) (xy 192.365674 -311.905354) (xy 192.346993 -311.904339) (xy 192.33769 -311.903364)
			(xy 192.32626 -311.902094) (xy 192.304416 -311.90946) (xy 192.2399 -311.973722) (xy 192.232281 -311.982152)
			(xy 192.224638 -312.003519) (xy 192.225168 -312.01487) (xy 192.225168 -312.015124) (xy 192.2272 -312.049668)
			(xy 192.2272 -312.050176) (xy 192.22668 -312.07563) (xy 193.47332 -312.07563) (xy 193.47332 -312.024214)
			(xy 193.481363 -311.973432) (xy 193.497251 -311.924533) (xy 193.520594 -311.878721) (xy 193.550815 -311.837125)
			(xy 193.587171 -311.800769) (xy 193.628767 -311.770548) (xy 193.674579 -311.747205) (xy 193.723478 -311.731317)
			(xy 193.77426 -311.723274) (xy 193.825676 -311.723274) (xy 193.876458 -311.731317) (xy 193.925357 -311.747205)
			(xy 193.971169 -311.770548) (xy 194.012765 -311.800769) (xy 194.049121 -311.837125) (xy 194.079342 -311.878721)
			(xy 194.102685 -311.924533) (xy 194.118573 -311.973432) (xy 194.126616 -312.024214) (xy 194.12712 -312.049922)
			(xy 194.126616 -312.07563) (xy 195.37324 -312.07563) (xy 195.37324 -312.024214) (xy 195.381283 -311.973432)
			(xy 195.397171 -311.924533) (xy 195.420514 -311.878721) (xy 195.450735 -311.837125) (xy 195.487091 -311.800769)
			(xy 195.528687 -311.770548) (xy 195.574499 -311.747205) (xy 195.623398 -311.731317) (xy 195.67418 -311.723274)
			(xy 195.725596 -311.723274) (xy 195.776378 -311.731317) (xy 195.825277 -311.747205) (xy 195.871089 -311.770548)
			(xy 195.912685 -311.800769) (xy 195.949041 -311.837125) (xy 195.979262 -311.878721) (xy 196.002605 -311.924533)
			(xy 196.018493 -311.973432) (xy 196.026536 -312.024214) (xy 196.02704 -312.049922) (xy 196.026536 -312.07563)
			(xy 197.273414 -312.07563) (xy 197.273414 -312.024214) (xy 197.281457 -311.973432) (xy 197.297345 -311.924533)
			(xy 197.320688 -311.878721) (xy 197.350909 -311.837125) (xy 197.387265 -311.800769) (xy 197.428861 -311.770548)
			(xy 197.474673 -311.747205) (xy 197.523572 -311.731317) (xy 197.574354 -311.723274) (xy 197.62577 -311.723274)
			(xy 197.676552 -311.731317) (xy 197.725451 -311.747205) (xy 197.771263 -311.770548) (xy 197.812859 -311.800769)
			(xy 197.849215 -311.837125) (xy 197.879436 -311.878721) (xy 197.902779 -311.924533) (xy 197.918667 -311.973432)
			(xy 197.92671 -312.024214) (xy 197.927214 -312.049922) (xy 197.92671 -312.07563) (xy 198.223374 -312.07563)
			(xy 198.223374 -312.024214) (xy 198.231417 -311.973432) (xy 198.247305 -311.924533) (xy 198.270648 -311.878721)
			(xy 198.300869 -311.837125) (xy 198.337225 -311.800769) (xy 198.378821 -311.770548) (xy 198.424633 -311.747205)
			(xy 198.473532 -311.731317) (xy 198.524314 -311.723274) (xy 198.57573 -311.723274) (xy 198.626512 -311.731317)
			(xy 198.675411 -311.747205) (xy 198.721223 -311.770548) (xy 198.762819 -311.800769) (xy 198.799175 -311.837125)
			(xy 198.829396 -311.878721) (xy 198.852739 -311.924533) (xy 198.868627 -311.973432) (xy 198.87667 -312.024214)
			(xy 198.877174 -312.049922) (xy 198.87667 -312.07563) (xy 198.868627 -312.126412) (xy 198.852739 -312.175311)
			(xy 198.829396 -312.221123) (xy 198.799175 -312.262719) (xy 198.762819 -312.299075) (xy 198.721223 -312.329296)
			(xy 198.675411 -312.352639) (xy 198.626512 -312.368527) (xy 198.57573 -312.37657) (xy 198.524314 -312.37657)
			(xy 198.473532 -312.368527) (xy 198.424633 -312.352639) (xy 198.378821 -312.329296) (xy 198.337225 -312.299075)
			(xy 198.300869 -312.262719) (xy 198.270648 -312.221123) (xy 198.247305 -312.175311) (xy 198.231417 -312.126412)
			(xy 198.223374 -312.07563) (xy 197.92671 -312.07563) (xy 197.918667 -312.126412) (xy 197.902779 -312.175311)
			(xy 197.879436 -312.221123) (xy 197.849215 -312.262719) (xy 197.812859 -312.299075) (xy 197.771263 -312.329296)
			(xy 197.725451 -312.352639) (xy 197.676552 -312.368527) (xy 197.62577 -312.37657) (xy 197.574354 -312.37657)
			(xy 197.523572 -312.368527) (xy 197.474673 -312.352639) (xy 197.428861 -312.329296) (xy 197.387265 -312.299075)
			(xy 197.350909 -312.262719) (xy 197.320688 -312.221123) (xy 197.297345 -312.175311) (xy 197.281457 -312.126412)
			(xy 197.273414 -312.07563) (xy 196.026536 -312.07563) (xy 196.018493 -312.126412) (xy 196.002605 -312.175311)
			(xy 195.979262 -312.221123) (xy 195.949041 -312.262719) (xy 195.912685 -312.299075) (xy 195.871089 -312.329296)
			(xy 195.825277 -312.352639) (xy 195.776378 -312.368527) (xy 195.725596 -312.37657) (xy 195.67418 -312.37657)
			(xy 195.623398 -312.368527) (xy 195.574499 -312.352639) (xy 195.528687 -312.329296) (xy 195.487091 -312.299075)
			(xy 195.450735 -312.262719) (xy 195.420514 -312.221123) (xy 195.397171 -312.175311) (xy 195.381283 -312.126412)
			(xy 195.37324 -312.07563) (xy 194.126616 -312.07563) (xy 194.118573 -312.126412) (xy 194.102685 -312.175311)
			(xy 194.079342 -312.221123) (xy 194.049121 -312.262719) (xy 194.012765 -312.299075) (xy 193.971169 -312.329296)
			(xy 193.925357 -312.352639) (xy 193.876458 -312.368527) (xy 193.825676 -312.37657) (xy 193.77426 -312.37657)
			(xy 193.723478 -312.368527) (xy 193.674579 -312.352639) (xy 193.628767 -312.329296) (xy 193.587171 -312.299075)
			(xy 193.550815 -312.262719) (xy 193.520594 -312.221123) (xy 193.497251 -312.175311) (xy 193.481363 -312.126412)
			(xy 193.47332 -312.07563) (xy 192.22668 -312.07563) (xy 192.226675 -312.075855) (xy 192.218601 -312.126574)
			(xy 192.202694 -312.175407) (xy 192.179347 -312.221152) (xy 192.149133 -312.262683) (xy 192.112796 -312.298978)
			(xy 192.071231 -312.329144) (xy 192.025459 -312.352439) (xy 191.976608 -312.368289) (xy 191.925879 -312.376305)
			(xy 191.874521 -312.376289) (xy 191.823797 -312.368242) (xy 191.774955 -312.352362) (xy 191.729198 -312.329039)
			(xy 191.687651 -312.298848) (xy 191.651337 -312.262531) (xy 191.621148 -312.220981) (xy 191.597829 -312.175222)
			(xy 191.581952 -312.12638) (xy 191.573909 -312.075655) (xy 191.573897 -312.024297) (xy 191.581917 -311.973568)
			(xy 191.597771 -311.924718) (xy 191.621069 -311.878949) (xy 191.651238 -311.837385) (xy 191.687535 -311.801051)
			(xy 191.729068 -311.770841) (xy 191.774815 -311.747496) (xy 191.823649 -311.731593) (xy 191.874369 -311.723523)
			(xy 191.900048 -311.723024) (xy 191.934846 -311.724802) (xy 191.946276 -311.726072) (xy 191.967866 -311.718198)
			(xy 192.040256 -311.645554) (xy 192.047622 -311.62371) (xy 192.046352 -311.61228) (xy 192.045377 -311.602913)
			(xy 192.044362 -311.584106) (xy 192.04432 -311.574688) (xy 192.04432 -311.526428) (xy 192.043897 -311.515705)
			(xy 192.035208 -311.496106) (xy 192.027556 -311.488582) (xy 191.97193 -311.43829) (xy 191.963667 -311.431561)
			(xy 191.94346 -311.424867) (xy 191.932814 -311.425336) (xy 191.93256 -311.425336) (xy 191.900048 -311.42686)
			(xy 191.899794 -311.42686) (xy 191.875213 -311.42639) (xy 191.826611 -311.418987) (xy 191.77966 -311.404409)
			(xy 191.735413 -311.382981) (xy 191.714882 -311.369456) (xy 191.704815 -311.363285) (xy 191.681456 -311.360049)
			(xy 191.659125 -311.367629) (xy 191.650366 -311.375552) (xy 191.128396 -311.897522) (xy 191.121001 -311.904376)
			(xy 191.102402 -311.912121) (xy 191.092328 -311.912508) (xy 191.0588 -311.912508) (xy 191.04873 -311.912931)
			(xy 191.030126 -311.920647) (xy 191.022732 -311.927494) (xy 190.7032 -312.246772) (xy 190.695803 -312.253621)
			(xy 190.677205 -312.26136) (xy 190.667132 -312.261758) (xy 190.2714 -312.261758) (xy 190.26122 -312.262262)
			(xy 190.242486 -312.270251) (xy 190.235078 -312.277252) (xy 190.216449 -312.295762) (xy 190.174376 -312.327185)
			(xy 190.127818 -312.351475) (xy 190.077976 -312.368006) (xy 190.026131 -312.376353) (xy 189.999874 -312.37682)
			(xy 189.973621 -312.376313) (xy 189.921786 -312.367953) (xy 189.871951 -312.351422) (xy 189.825396 -312.327142)
			(xy 189.783318 -312.295738) (xy 189.76467 -312.277252) (xy 189.757272 -312.270234) (xy 189.738533 -312.262237)
			(xy 189.728348 -312.261758) (xy 189.326774 -312.261758) (xy 189.316438 -312.262239) (xy 189.297428 -312.270361)
			(xy 189.289944 -312.277506) (xy 189.271072 -312.296648) (xy 189.228269 -312.32916) (xy 189.180773 -312.354324)
			(xy 189.129833 -312.371477) (xy 189.076789 -312.380167) (xy 189.023039 -312.380167) (xy 188.969995 -312.371477)
			(xy 188.919055 -312.354324) (xy 188.871559 -312.32916) (xy 188.828756 -312.296648) (xy 188.809884 -312.277506)
			(xy 188.802411 -312.270341) (xy 188.783397 -312.262202) (xy 188.773054 -312.261758) (xy 188.340492 -312.261758)
			(xy 188.331069 -312.262195) (xy 188.313479 -312.268965) (xy 188.306202 -312.274966) (xy 188.287288 -312.291584)
			(xy 188.245081 -312.31903) (xy 188.198945 -312.339182) (xy 188.150129 -312.351496) (xy 188.099954 -312.355638)
			(xy 188.049779 -312.351496) (xy 188.000963 -312.339182) (xy 187.954827 -312.31903) (xy 187.91262 -312.291584)
			(xy 187.893706 -312.274966) (xy 187.886483 -312.268868) (xy 187.868862 -312.262063) (xy 187.859416 -312.261758)
			(xy 187.426854 -312.261758) (xy 187.41652 -312.262243) (xy 187.397515 -312.27037) (xy 187.390024 -312.277506)
			(xy 187.371152 -312.296648) (xy 187.328349 -312.32916) (xy 187.280853 -312.354324) (xy 187.229913 -312.371477)
			(xy 187.176869 -312.380167) (xy 187.123119 -312.380167) (xy 187.070075 -312.371477) (xy 187.019135 -312.354324)
			(xy 186.971639 -312.32916) (xy 186.928836 -312.296648) (xy 186.909964 -312.277506) (xy 186.902489 -312.270345)
			(xy 186.883475 -312.262213) (xy 186.873134 -312.261758) (xy 186.440572 -312.261758) (xy 186.431151 -312.262199)
			(xy 186.413565 -312.268973) (xy 186.406282 -312.274966) (xy 186.387368 -312.291584) (xy 186.345161 -312.31903)
			(xy 186.299025 -312.339182) (xy 186.250209 -312.351496) (xy 186.200034 -312.355638) (xy 186.149859 -312.351496)
			(xy 186.101043 -312.339182) (xy 186.054907 -312.31903) (xy 186.0127 -312.291584) (xy 185.993786 -312.274966)
			(xy 185.986562 -312.268871) (xy 185.968941 -312.262073) (xy 185.959496 -312.261758) (xy 185.526934 -312.261758)
			(xy 185.516601 -312.262246) (xy 185.497602 -312.270379) (xy 185.490104 -312.277506) (xy 185.471232 -312.296648)
			(xy 185.428429 -312.32916) (xy 185.380933 -312.354324) (xy 185.329993 -312.371477) (xy 185.276949 -312.380167)
			(xy 185.223199 -312.380167) (xy 185.170155 -312.371477) (xy 185.119215 -312.354324) (xy 185.071719 -312.32916)
			(xy 185.028916 -312.296648) (xy 185.010044 -312.277506) (xy 185.002568 -312.270348) (xy 184.983554 -312.262223)
			(xy 184.973214 -312.261758) (xy 184.540398 -312.261758) (xy 184.530975 -312.262194) (xy 184.513383 -312.268962)
			(xy 184.506108 -312.274966) (xy 184.487194 -312.291584) (xy 184.444987 -312.31903) (xy 184.398851 -312.339182)
			(xy 184.350035 -312.351496) (xy 184.29986 -312.355638) (xy 184.249685 -312.351496) (xy 184.200869 -312.339182)
			(xy 184.154733 -312.31903) (xy 184.112526 -312.291584) (xy 184.093612 -312.274966) (xy 184.086389 -312.268867)
			(xy 184.068769 -312.26206) (xy 184.059322 -312.261758) (xy 183.62676 -312.261758) (xy 183.616425 -312.262242)
			(xy 183.597419 -312.270367) (xy 183.58993 -312.277506) (xy 183.571058 -312.296648) (xy 183.528255 -312.32916)
			(xy 183.480759 -312.354324) (xy 183.429819 -312.371477) (xy 183.376775 -312.380167) (xy 183.323025 -312.380167)
			(xy 183.269981 -312.371477) (xy 183.219041 -312.354324) (xy 183.171545 -312.32916) (xy 183.128742 -312.296648)
			(xy 183.10987 -312.277506) (xy 183.102396 -312.270344) (xy 183.083382 -312.26221) (xy 183.07304 -312.261758)
			(xy 182.640478 -312.261758) (xy 182.631056 -312.262198) (xy 182.613469 -312.26897) (xy 182.606188 -312.274966)
			(xy 182.587274 -312.291584) (xy 182.545067 -312.31903) (xy 182.498931 -312.339182) (xy 182.450115 -312.351496)
			(xy 182.39994 -312.355638) (xy 182.349765 -312.351496) (xy 182.300949 -312.339182) (xy 182.254813 -312.31903)
			(xy 182.212606 -312.291584) (xy 182.193692 -312.274966) (xy 182.186468 -312.26887) (xy 182.168848 -312.26207)
			(xy 182.159402 -312.261758) (xy 181.72684 -312.261758) (xy 181.716507 -312.262245) (xy 181.697506 -312.270376)
			(xy 181.69001 -312.277506) (xy 181.671138 -312.296648) (xy 181.628335 -312.32916) (xy 181.580839 -312.354324)
			(xy 181.529899 -312.371477) (xy 181.476855 -312.380167) (xy 181.423105 -312.380167) (xy 181.370061 -312.371477)
			(xy 181.319121 -312.354324) (xy 181.271625 -312.32916) (xy 181.228822 -312.296648) (xy 181.20995 -312.277506)
			(xy 181.202475 -312.270347) (xy 181.183461 -312.26222) (xy 181.17312 -312.261758) (xy 180.771546 -312.261758)
			(xy 180.761362 -312.262254) (xy 180.742616 -312.270231) (xy 180.735224 -312.277252) (xy 180.716594 -312.295759)
			(xy 180.674519 -312.327175) (xy 180.627961 -312.351457) (xy 180.578119 -312.36798) (xy 180.526275 -312.376318)
			(xy 180.50002 -312.37682) (xy 180.473766 -312.376316) (xy 180.421926 -312.367963) (xy 180.372087 -312.351437)
			(xy 180.325527 -312.327161) (xy 180.283443 -312.29576) (xy 180.264816 -312.277252) (xy 180.257415 -312.270243)
			(xy 180.238676 -312.262265) (xy 180.228494 -312.261758) (xy 179.82692 -312.261758) (xy 179.816589 -312.262249)
			(xy 179.797593 -312.270385) (xy 179.79009 -312.277506) (xy 179.771218 -312.296648) (xy 179.728415 -312.32916)
			(xy 179.680919 -312.354324) (xy 179.629979 -312.371477) (xy 179.576935 -312.380167) (xy 179.523185 -312.380167)
			(xy 179.470141 -312.371477) (xy 179.419201 -312.354324) (xy 179.371705 -312.32916) (xy 179.328902 -312.296648)
			(xy 179.31003 -312.277506) (xy 179.302554 -312.27035) (xy 179.283539 -312.262231) (xy 179.2732 -312.261758)
			(xy 178.871372 -312.261758) (xy 178.861194 -312.262268) (xy 178.842468 -312.270263) (xy 178.83505 -312.277252)
			(xy 178.81642 -312.29576) (xy 178.774346 -312.32718) (xy 178.727789 -312.351466) (xy 178.677946 -312.367993)
			(xy 178.626102 -312.376335) (xy 178.599846 -312.37682) (xy 178.573591 -312.376318) (xy 178.521749 -312.367969)
			(xy 178.471907 -312.351446) (xy 178.425345 -312.327172) (xy 178.383257 -312.295773) (xy 178.364642 -312.277252)
			(xy 178.357242 -312.270239) (xy 178.338504 -312.262252) (xy 178.32832 -312.261758) (xy 177.926746 -312.261758)
			(xy 177.916412 -312.262244) (xy 177.89741 -312.270373) (xy 177.889916 -312.277506) (xy 177.871044 -312.296648)
			(xy 177.828241 -312.32916) (xy 177.780745 -312.354324) (xy 177.729805 -312.371477) (xy 177.676761 -312.380167)
			(xy 177.623011 -312.380167) (xy 177.569967 -312.371477) (xy 177.519027 -312.354324) (xy 177.471531 -312.32916)
			(xy 177.428728 -312.296648) (xy 177.409856 -312.277506) (xy 177.402381 -312.270346) (xy 177.383367 -312.262217)
			(xy 177.373026 -312.261758) (xy 176.971452 -312.261758) (xy 176.961276 -312.262271) (xy 176.942555 -312.270272)
			(xy 176.93513 -312.277252) (xy 176.9165 -312.295759) (xy 176.874425 -312.327176) (xy 176.827867 -312.351459)
			(xy 176.778025 -312.367983) (xy 176.726182 -312.376322) (xy 176.699926 -312.37682) (xy 176.673671 -312.376317)
			(xy 176.621832 -312.367965) (xy 176.571991 -312.351439) (xy 176.525431 -312.327164) (xy 176.483347 -312.295763)
			(xy 176.464722 -312.277252) (xy 176.457321 -312.270242) (xy 176.438582 -312.262262) (xy 176.4284 -312.261758)
			(xy 176.026826 -312.261758) (xy 176.016494 -312.262248) (xy 175.997497 -312.270382) (xy 175.989996 -312.277506)
			(xy 175.971124 -312.296648) (xy 175.928321 -312.32916) (xy 175.880825 -312.354324) (xy 175.829885 -312.371477)
			(xy 175.776841 -312.380167) (xy 175.723091 -312.380167) (xy 175.670047 -312.371477) (xy 175.619107 -312.354324)
			(xy 175.571611 -312.32916) (xy 175.528808 -312.296648) (xy 175.509936 -312.277506) (xy 175.50246 -312.270349)
			(xy 175.483446 -312.262228) (xy 175.473106 -312.261758) (xy 175.071532 -312.261758) (xy 175.061349 -312.262256)
			(xy 175.042606 -312.270237) (xy 175.03521 -312.277252) (xy 175.016579 -312.295758) (xy 174.974504 -312.327172)
			(xy 174.927946 -312.351452) (xy 174.878104 -312.367973) (xy 174.826261 -312.376309) (xy 174.800006 -312.37682)
			(xy 174.773752 -312.376315) (xy 174.721914 -312.36796) (xy 174.672076 -312.351432) (xy 174.625518 -312.327156)
			(xy 174.583436 -312.295754) (xy 174.564802 -312.277252) (xy 174.5574 -312.270246) (xy 174.538661 -312.262273)
			(xy 174.52848 -312.261758) (xy 174.126906 -312.261758) (xy 174.116576 -312.262252) (xy 174.097584 -312.270391)
			(xy 174.090076 -312.277506) (xy 174.071204 -312.296648) (xy 174.028401 -312.32916) (xy 173.980905 -312.354324)
			(xy 173.929965 -312.371477) (xy 173.876921 -312.380167) (xy 173.823171 -312.380167) (xy 173.770127 -312.371477)
			(xy 173.719187 -312.354324) (xy 173.671691 -312.32916) (xy 173.628888 -312.296648) (xy 173.610016 -312.277506)
			(xy 173.602544 -312.270336) (xy 173.583531 -312.262185) (xy 173.573186 -312.261758) (xy 173.171612 -312.261758)
			(xy 173.161431 -312.26226) (xy 173.142693 -312.270246) (xy 173.13529 -312.277252) (xy 173.116661 -312.295763)
			(xy 173.074588 -312.327187) (xy 173.028031 -312.351479) (xy 172.978188 -312.368012) (xy 172.926343 -312.376361)
			(xy 172.900086 -312.37682) (xy 172.873833 -312.376313) (xy 172.821996 -312.367956) (xy 172.77216 -312.351426)
			(xy 172.725604 -312.327147) (xy 172.683525 -312.295744) (xy 172.664882 -312.277252) (xy 172.657484 -312.270233)
			(xy 172.638746 -312.262231) (xy 172.62856 -312.261758) (xy 172.226732 -312.261758) (xy 172.216399 -312.262247)
			(xy 172.197401 -312.27038) (xy 172.189902 -312.277506) (xy 172.17103 -312.296648) (xy 172.128227 -312.32916)
			(xy 172.080731 -312.354324) (xy 172.029791 -312.371477) (xy 171.976747 -312.380167) (xy 171.922997 -312.380167)
			(xy 171.869953 -312.371477) (xy 171.819013 -312.354324) (xy 171.771517 -312.32916) (xy 171.728714 -312.296648)
			(xy 171.709842 -312.277506) (xy 171.702366 -312.270348) (xy 171.683352 -312.262224) (xy 171.673012 -312.261758)
			(xy 171.271438 -312.261758) (xy 171.261255 -312.262255) (xy 171.24251 -312.270234) (xy 171.235116 -312.277252)
			(xy 171.216485 -312.295758) (xy 171.174411 -312.327173) (xy 171.127853 -312.351454) (xy 171.07801 -312.367976)
			(xy 171.026167 -312.376313) (xy 170.999912 -312.37682) (xy 170.973658 -312.376316) (xy 170.921819 -312.367962)
			(xy 170.87198 -312.351434) (xy 170.825422 -312.327158) (xy 170.783339 -312.295756) (xy 170.764708 -312.277252)
			(xy 170.757306 -312.270244) (xy 170.738568 -312.26227) (xy 170.728386 -312.261758) (xy 170.326812 -312.261758)
			(xy 170.316481 -312.26225) (xy 170.297488 -312.270388) (xy 170.289982 -312.277506) (xy 170.27111 -312.296648)
			(xy 170.228307 -312.32916) (xy 170.180811 -312.354324) (xy 170.129871 -312.371477) (xy 170.076827 -312.380167)
			(xy 170.023077 -312.380167) (xy 169.970033 -312.371477) (xy 169.919093 -312.354324) (xy 169.871597 -312.32916)
			(xy 169.828794 -312.296648) (xy 169.809922 -312.277506) (xy 169.80245 -312.270335) (xy 169.783437 -312.262182)
			(xy 169.773092 -312.261758) (xy 169.371518 -312.261758) (xy 169.361336 -312.262259) (xy 169.342597 -312.270243)
			(xy 169.335196 -312.277252) (xy 169.316567 -312.295763) (xy 169.274495 -312.327189) (xy 169.227938 -312.351481)
			(xy 169.178095 -312.368015) (xy 169.126249 -312.376364) (xy 169.099992 -312.37682) (xy 169.073739 -312.376314)
			(xy 169.021901 -312.367957) (xy 168.972065 -312.351428) (xy 168.925509 -312.32715) (xy 168.883428 -312.295747)
			(xy 168.864788 -312.277252) (xy 168.857391 -312.270232) (xy 168.838653 -312.262228) (xy 168.828466 -312.261758)
			(xy 168.426892 -312.261758) (xy 168.416554 -312.262236) (xy 168.397539 -312.270353) (xy 168.390062 -312.277506)
			(xy 168.37119 -312.296648) (xy 168.328387 -312.32916) (xy 168.280891 -312.354324) (xy 168.229951 -312.371477)
			(xy 168.176907 -312.380167) (xy 168.123157 -312.380167) (xy 168.070113 -312.371477) (xy 168.019173 -312.354324)
			(xy 167.971677 -312.32916) (xy 167.928874 -312.296648) (xy 167.910002 -312.277506) (xy 167.902529 -312.270339)
			(xy 167.883516 -312.262192) (xy 167.873172 -312.261758) (xy 167.471598 -312.261758) (xy 167.461418 -312.262263)
			(xy 167.442684 -312.270252) (xy 167.435276 -312.277252) (xy 167.416647 -312.295762) (xy 167.374574 -312.327185)
			(xy 167.328016 -312.351474) (xy 167.278174 -312.368005) (xy 167.226329 -312.376352) (xy 167.200072 -312.37682)
			(xy 167.173819 -312.376312) (xy 167.121984 -312.367953) (xy 167.072149 -312.351421) (xy 167.025595 -312.327141)
			(xy 166.983517 -312.295737) (xy 166.964868 -312.277252) (xy 166.95747 -312.270235) (xy 166.938731 -312.262238)
			(xy 166.928546 -312.261758) (xy 166.526718 -312.261758) (xy 166.516387 -312.262249) (xy 166.497392 -312.270386)
			(xy 166.489888 -312.277506) (xy 166.471016 -312.296648) (xy 166.428213 -312.32916) (xy 166.380717 -312.354324)
			(xy 166.329777 -312.371477) (xy 166.276733 -312.380167) (xy 166.222983 -312.380167) (xy 166.169939 -312.371477)
			(xy 166.118999 -312.354324) (xy 166.071503 -312.32916) (xy 166.0287 -312.296648) (xy 166.009828 -312.277506)
			(xy 166.002351 -312.27035) (xy 165.983337 -312.262232) (xy 165.972998 -312.261758) (xy 165.540436 -312.261758)
			(xy 165.531017 -312.262205) (xy 165.51344 -312.268988) (xy 165.506146 -312.274966) (xy 165.487232 -312.291584)
			(xy 165.445025 -312.31903) (xy 165.398889 -312.339182) (xy 165.350073 -312.351496) (xy 165.299898 -312.355638)
			(xy 165.249723 -312.351496) (xy 165.200907 -312.339182) (xy 165.154771 -312.31903) (xy 165.112564 -312.291584)
			(xy 165.09365 -312.274966) (xy 165.086424 -312.268877) (xy 165.068804 -312.262091) (xy 165.05936 -312.261758)
			(xy 164.626798 -312.261758) (xy 164.616468 -312.262253) (xy 164.597479 -312.270395) (xy 164.589968 -312.277506)
			(xy 164.571096 -312.296648) (xy 164.528293 -312.32916) (xy 164.480797 -312.354324) (xy 164.429857 -312.371477)
			(xy 164.376813 -312.380167) (xy 164.323063 -312.380167) (xy 164.270019 -312.371477) (xy 164.219079 -312.354324)
			(xy 164.171583 -312.32916) (xy 164.12878 -312.296648) (xy 164.109908 -312.277506) (xy 164.102436 -312.270338)
			(xy 164.083422 -312.262189) (xy 164.073078 -312.261758) (xy 163.640516 -312.261758) (xy 163.631091 -312.262191)
			(xy 163.613496 -312.268954) (xy 163.606226 -312.274966) (xy 163.587312 -312.291584) (xy 163.545105 -312.31903)
			(xy 163.498969 -312.339182) (xy 163.450153 -312.351496) (xy 163.399978 -312.355638) (xy 163.349803 -312.351496)
			(xy 163.300987 -312.339182) (xy 163.254851 -312.31903) (xy 163.212644 -312.291584) (xy 163.19373 -312.274966)
			(xy 163.186503 -312.26888) (xy 163.168883 -312.262101) (xy 163.15944 -312.261758) (xy 162.726878 -312.261758)
			(xy 162.716542 -312.262238) (xy 162.69753 -312.270359) (xy 162.690048 -312.277506) (xy 162.671176 -312.296648)
			(xy 162.628373 -312.32916) (xy 162.580877 -312.354324) (xy 162.529937 -312.371477) (xy 162.476893 -312.380167)
			(xy 162.423143 -312.380167) (xy 162.370099 -312.371477) (xy 162.319159 -312.354324) (xy 162.271663 -312.32916)
			(xy 162.22886 -312.296648) (xy 162.209988 -312.277506) (xy 162.202515 -312.270341) (xy 162.183501 -312.2622)
			(xy 162.173158 -312.261758) (xy 161.740596 -312.261758) (xy 161.731173 -312.262195) (xy 161.713582 -312.268963)
			(xy 161.706306 -312.274966) (xy 161.687392 -312.291584) (xy 161.645185 -312.31903) (xy 161.599049 -312.339182)
			(xy 161.550233 -312.351496) (xy 161.500058 -312.355638) (xy 161.449883 -312.351496) (xy 161.401067 -312.339182)
			(xy 161.354931 -312.31903) (xy 161.312724 -312.291584) (xy 161.29381 -312.274966) (xy 161.286587 -312.268868)
			(xy 161.268967 -312.262061) (xy 161.25952 -312.261758) (xy 160.826704 -312.261758) (xy 160.816374 -312.262252)
			(xy 160.797383 -312.270392) (xy 160.789874 -312.277506) (xy 160.771002 -312.296648) (xy 160.728199 -312.32916)
			(xy 160.680703 -312.354324) (xy 160.629763 -312.371477) (xy 160.576719 -312.380167) (xy 160.522969 -312.380167)
			(xy 160.469925 -312.371477) (xy 160.418985 -312.354324) (xy 160.371489 -312.32916) (xy 160.328686 -312.296648)
			(xy 160.309814 -312.277506) (xy 160.302342 -312.270337) (xy 160.283328 -312.262186) (xy 160.272984 -312.261758)
			(xy 159.840422 -312.261758) (xy 159.830997 -312.26219) (xy 159.8134 -312.268952) (xy 159.806132 -312.274966)
			(xy 159.787218 -312.291584) (xy 159.745011 -312.31903) (xy 159.698875 -312.339182) (xy 159.650059 -312.351496)
			(xy 159.599884 -312.355638) (xy 159.549709 -312.351496) (xy 159.500893 -312.339182) (xy 159.454757 -312.31903)
			(xy 159.41255 -312.291584) (xy 159.393636 -312.274966) (xy 159.38641 -312.268879) (xy 159.368789 -312.262098)
			(xy 159.359346 -312.261758) (xy 158.926784 -312.261758) (xy 158.916447 -312.262237) (xy 158.897434 -312.270357)
			(xy 158.889954 -312.277506) (xy 158.872628 -312.295086) (xy 158.833701 -312.32543) (xy 158.790701 -312.349659)
			(xy 158.74458 -312.367235) (xy 158.696361 -312.37777) (xy 158.671768 -312.379868) (xy 158.662116 -312.380376)
			(xy 158.64459 -312.388758) (xy 158.590488 -312.446416) (xy 158.584201 -312.453705) (xy 158.577145 -312.471596)
			(xy 158.576772 -312.481214) (xy 158.576772 -312.59399) (xy 158.577187 -312.603599) (xy 158.584235 -312.62148)
			(xy 158.590488 -312.628788) (xy 158.637732 -312.679334) (xy 158.644482 -312.68601) (xy 158.661576 -312.69424)
			(xy 158.671006 -312.695336) (xy 158.67126 -312.695336) (xy 158.695292 -312.697479) (xy 158.742291 -312.708382)
			(xy 158.78699 -312.726541) (xy 158.828277 -312.751504) (xy 158.865124 -312.78265) (xy 158.896614 -312.819204)
			(xy 158.921963 -312.860255) (xy 158.94054 -312.904782) (xy 158.951882 -312.951677) (xy 158.955709 -312.999772)
			(xy 158.9557 -312.999882) (xy 160.24404 -312.999882) (xy 160.248 -312.950828) (xy 160.259777 -312.903044)
			(xy 160.279068 -312.857768) (xy 160.305371 -312.816172) (xy 160.338006 -312.779335) (xy 160.376127 -312.74821)
			(xy 160.418748 -312.723603) (xy 160.464764 -312.706151) (xy 160.512983 -312.696307) (xy 160.562158 -312.694326)
			(xy 160.611013 -312.700258) (xy 160.658284 -312.71395) (xy 160.702746 -312.735048) (xy 160.743249 -312.763004)
			(xy 160.778742 -312.797096) (xy 160.808307 -312.83644) (xy 160.831178 -312.880017) (xy 160.846762 -312.926698)
			(xy 160.854657 -312.975275) (xy 160.855152 -312.999882) (xy 162.144214 -312.999882) (xy 162.148174 -312.950828)
			(xy 162.159951 -312.903044) (xy 162.179242 -312.857768) (xy 162.205545 -312.816172) (xy 162.23818 -312.779335)
			(xy 162.276301 -312.74821) (xy 162.318922 -312.723603) (xy 162.364938 -312.706151) (xy 162.413157 -312.696307)
			(xy 162.462332 -312.694326) (xy 162.511187 -312.700258) (xy 162.558458 -312.71395) (xy 162.60292 -312.735048)
			(xy 162.643423 -312.763004) (xy 162.678916 -312.797096) (xy 162.708481 -312.83644) (xy 162.731352 -312.880017)
			(xy 162.746936 -312.926698) (xy 162.754831 -312.975275) (xy 162.755326 -312.999882) (xy 164.044134 -312.999882)
			(xy 164.048094 -312.950828) (xy 164.059871 -312.903044) (xy 164.079162 -312.857768) (xy 164.105465 -312.816172)
			(xy 164.1381 -312.779335) (xy 164.176221 -312.74821) (xy 164.218842 -312.723603) (xy 164.264858 -312.706151)
			(xy 164.313077 -312.696307) (xy 164.362252 -312.694326) (xy 164.411107 -312.700258) (xy 164.458378 -312.71395)
			(xy 164.50284 -312.735048) (xy 164.543343 -312.763004) (xy 164.578836 -312.797096) (xy 164.608401 -312.83644)
			(xy 164.631272 -312.880017) (xy 164.646856 -312.926698) (xy 164.654751 -312.975275) (xy 164.655246 -312.999882)
			(xy 165.944054 -312.999882) (xy 165.948014 -312.950828) (xy 165.959791 -312.903044) (xy 165.979082 -312.857768)
			(xy 166.005385 -312.816172) (xy 166.03802 -312.779335) (xy 166.076141 -312.74821) (xy 166.118762 -312.723603)
			(xy 166.164778 -312.706151) (xy 166.212997 -312.696307) (xy 166.262172 -312.694326) (xy 166.311027 -312.700258)
			(xy 166.358298 -312.71395) (xy 166.40276 -312.735048) (xy 166.443263 -312.763004) (xy 166.478756 -312.797096)
			(xy 166.508321 -312.83644) (xy 166.531192 -312.880017) (xy 166.546776 -312.926698) (xy 166.554671 -312.975275)
			(xy 166.555166 -312.999882) (xy 166.554671 -313.024489) (xy 166.554492 -313.02559) (xy 167.823384 -313.02559)
			(xy 167.823384 -312.974174) (xy 167.831427 -312.923392) (xy 167.847315 -312.874493) (xy 167.870658 -312.828681)
			(xy 167.900879 -312.787085) (xy 167.937235 -312.750729) (xy 167.978831 -312.720508) (xy 168.024643 -312.697165)
			(xy 168.073542 -312.681277) (xy 168.124324 -312.673234) (xy 168.17574 -312.673234) (xy 168.226522 -312.681277)
			(xy 168.275421 -312.697165) (xy 168.321233 -312.720508) (xy 168.362829 -312.750729) (xy 168.399185 -312.787085)
			(xy 168.429406 -312.828681) (xy 168.452749 -312.874493) (xy 168.468637 -312.923392) (xy 168.47668 -312.974174)
			(xy 168.477184 -312.999882) (xy 168.47668 -313.02559) (xy 169.723304 -313.02559) (xy 169.723304 -312.974174)
			(xy 169.731347 -312.923392) (xy 169.747235 -312.874493) (xy 169.770578 -312.828681) (xy 169.800799 -312.787085)
			(xy 169.837155 -312.750729) (xy 169.878751 -312.720508) (xy 169.924563 -312.697165) (xy 169.973462 -312.681277)
			(xy 170.024244 -312.673234) (xy 170.07566 -312.673234) (xy 170.126442 -312.681277) (xy 170.175341 -312.697165)
			(xy 170.221153 -312.720508) (xy 170.262749 -312.750729) (xy 170.299105 -312.787085) (xy 170.329326 -312.828681)
			(xy 170.352669 -312.874493) (xy 170.368557 -312.923392) (xy 170.3766 -312.974174) (xy 170.377104 -312.999882)
			(xy 170.3766 -313.02559) (xy 171.623224 -313.02559) (xy 171.623224 -312.974174) (xy 171.631267 -312.923392)
			(xy 171.647155 -312.874493) (xy 171.670498 -312.828681) (xy 171.700719 -312.787085) (xy 171.737075 -312.750729)
			(xy 171.778671 -312.720508) (xy 171.824483 -312.697165) (xy 171.873382 -312.681277) (xy 171.924164 -312.673234)
			(xy 171.97558 -312.673234) (xy 172.026362 -312.681277) (xy 172.075261 -312.697165) (xy 172.121073 -312.720508)
			(xy 172.162669 -312.750729) (xy 172.199025 -312.787085) (xy 172.229246 -312.828681) (xy 172.252589 -312.874493)
			(xy 172.268477 -312.923392) (xy 172.27652 -312.974174) (xy 172.277024 -312.999882) (xy 172.27652 -313.02559)
			(xy 173.523398 -313.02559) (xy 173.523398 -312.974174) (xy 173.531441 -312.923392) (xy 173.547329 -312.874493)
			(xy 173.570672 -312.828681) (xy 173.600893 -312.787085) (xy 173.637249 -312.750729) (xy 173.678845 -312.720508)
			(xy 173.724657 -312.697165) (xy 173.773556 -312.681277) (xy 173.824338 -312.673234) (xy 173.875754 -312.673234)
			(xy 173.926536 -312.681277) (xy 173.975435 -312.697165) (xy 174.021247 -312.720508) (xy 174.062843 -312.750729)
			(xy 174.099199 -312.787085) (xy 174.12942 -312.828681) (xy 174.152763 -312.874493) (xy 174.168651 -312.923392)
			(xy 174.176694 -312.974174) (xy 174.177198 -312.999882) (xy 174.176694 -313.02559) (xy 175.423318 -313.02559)
			(xy 175.423318 -312.974174) (xy 175.431361 -312.923392) (xy 175.447249 -312.874493) (xy 175.470592 -312.828681)
			(xy 175.500813 -312.787085) (xy 175.537169 -312.750729) (xy 175.578765 -312.720508) (xy 175.624577 -312.697165)
			(xy 175.673476 -312.681277) (xy 175.724258 -312.673234) (xy 175.775674 -312.673234) (xy 175.826456 -312.681277)
			(xy 175.875355 -312.697165) (xy 175.921167 -312.720508) (xy 175.962763 -312.750729) (xy 175.999119 -312.787085)
			(xy 176.02934 -312.828681) (xy 176.052683 -312.874493) (xy 176.068571 -312.923392) (xy 176.076614 -312.974174)
			(xy 176.077118 -312.999882) (xy 176.076614 -313.02559) (xy 177.323238 -313.02559) (xy 177.323238 -312.974174)
			(xy 177.331281 -312.923392) (xy 177.347169 -312.874493) (xy 177.370512 -312.828681) (xy 177.400733 -312.787085)
			(xy 177.437089 -312.750729) (xy 177.478685 -312.720508) (xy 177.524497 -312.697165) (xy 177.573396 -312.681277)
			(xy 177.624178 -312.673234) (xy 177.675594 -312.673234) (xy 177.726376 -312.681277) (xy 177.775275 -312.697165)
			(xy 177.821087 -312.720508) (xy 177.862683 -312.750729) (xy 177.899039 -312.787085) (xy 177.92926 -312.828681)
			(xy 177.952603 -312.874493) (xy 177.968491 -312.923392) (xy 177.976534 -312.974174) (xy 177.977038 -312.999882)
			(xy 177.976534 -313.02559) (xy 179.223412 -313.02559) (xy 179.223412 -312.974174) (xy 179.231455 -312.923392)
			(xy 179.247343 -312.874493) (xy 179.270686 -312.828681) (xy 179.300907 -312.787085) (xy 179.337263 -312.750729)
			(xy 179.378859 -312.720508) (xy 179.424671 -312.697165) (xy 179.47357 -312.681277) (xy 179.524352 -312.673234)
			(xy 179.575768 -312.673234) (xy 179.62655 -312.681277) (xy 179.675449 -312.697165) (xy 179.721261 -312.720508)
			(xy 179.762857 -312.750729) (xy 179.799213 -312.787085) (xy 179.829434 -312.828681) (xy 179.852777 -312.874493)
			(xy 179.868665 -312.923392) (xy 179.876708 -312.974174) (xy 179.877212 -312.999882) (xy 179.876708 -313.02559)
			(xy 181.123332 -313.02559) (xy 181.123332 -312.974174) (xy 181.131375 -312.923392) (xy 181.147263 -312.874493)
			(xy 181.170606 -312.828681) (xy 181.200827 -312.787085) (xy 181.237183 -312.750729) (xy 181.278779 -312.720508)
			(xy 181.324591 -312.697165) (xy 181.37349 -312.681277) (xy 181.424272 -312.673234) (xy 181.475688 -312.673234)
			(xy 181.52647 -312.681277) (xy 181.575369 -312.697165) (xy 181.621181 -312.720508) (xy 181.662777 -312.750729)
			(xy 181.699133 -312.787085) (xy 181.729354 -312.828681) (xy 181.752697 -312.874493) (xy 181.768585 -312.923392)
			(xy 181.776628 -312.974174) (xy 181.777132 -312.999882) (xy 183.044096 -312.999882) (xy 183.048056 -312.950828)
			(xy 183.059833 -312.903044) (xy 183.079124 -312.857768) (xy 183.105427 -312.816172) (xy 183.138062 -312.779335)
			(xy 183.176183 -312.74821) (xy 183.218804 -312.723603) (xy 183.26482 -312.706151) (xy 183.313039 -312.696307)
			(xy 183.362214 -312.694326) (xy 183.411069 -312.700258) (xy 183.45834 -312.71395) (xy 183.502802 -312.735048)
			(xy 183.543305 -312.763004) (xy 183.578798 -312.797096) (xy 183.608363 -312.83644) (xy 183.631234 -312.880017)
			(xy 183.646818 -312.926698) (xy 183.654713 -312.975275) (xy 183.655208 -312.999882) (xy 184.94427 -312.999882)
			(xy 184.94823 -312.950828) (xy 184.960007 -312.903044) (xy 184.979298 -312.857768) (xy 185.005601 -312.816172)
			(xy 185.038236 -312.779335) (xy 185.076357 -312.74821) (xy 185.118978 -312.723603) (xy 185.164994 -312.706151)
			(xy 185.213213 -312.696307) (xy 185.262388 -312.694326) (xy 185.311243 -312.700258) (xy 185.358514 -312.71395)
			(xy 185.402976 -312.735048) (xy 185.443479 -312.763004) (xy 185.478972 -312.797096) (xy 185.508537 -312.83644)
			(xy 185.531408 -312.880017) (xy 185.546992 -312.926698) (xy 185.554887 -312.975275) (xy 185.555382 -312.999882)
			(xy 186.84419 -312.999882) (xy 186.84815 -312.950828) (xy 186.859927 -312.903044) (xy 186.879218 -312.857768)
			(xy 186.905521 -312.816172) (xy 186.938156 -312.779335) (xy 186.976277 -312.74821) (xy 187.018898 -312.723603)
			(xy 187.064914 -312.706151) (xy 187.113133 -312.696307) (xy 187.162308 -312.694326) (xy 187.211163 -312.700258)
			(xy 187.258434 -312.71395) (xy 187.302896 -312.735048) (xy 187.343399 -312.763004) (xy 187.378892 -312.797096)
			(xy 187.408457 -312.83644) (xy 187.431328 -312.880017) (xy 187.446912 -312.926698) (xy 187.454807 -312.975275)
			(xy 187.455302 -312.999882) (xy 188.74411 -312.999882) (xy 188.74807 -312.950828) (xy 188.759847 -312.903044)
			(xy 188.779138 -312.857768) (xy 188.805441 -312.816172) (xy 188.838076 -312.779335) (xy 188.876197 -312.74821)
			(xy 188.918818 -312.723603) (xy 188.964834 -312.706151) (xy 189.013053 -312.696307) (xy 189.062228 -312.694326)
			(xy 189.111083 -312.700258) (xy 189.158354 -312.71395) (xy 189.202816 -312.735048) (xy 189.243319 -312.763004)
			(xy 189.278812 -312.797096) (xy 189.308377 -312.83644) (xy 189.331248 -312.880017) (xy 189.346832 -312.926698)
			(xy 189.354727 -312.975275) (xy 189.355222 -312.999882) (xy 189.354727 -313.024489) (xy 189.354548 -313.02559)
			(xy 190.62344 -313.02559) (xy 190.62344 -312.974174) (xy 190.631483 -312.923392) (xy 190.647371 -312.874493)
			(xy 190.670714 -312.828681) (xy 190.700935 -312.787085) (xy 190.737291 -312.750729) (xy 190.778887 -312.720508)
			(xy 190.824699 -312.697165) (xy 190.873598 -312.681277) (xy 190.92438 -312.673234) (xy 190.975796 -312.673234)
			(xy 191.026578 -312.681277) (xy 191.075477 -312.697165) (xy 191.121289 -312.720508) (xy 191.162885 -312.750729)
			(xy 191.199241 -312.787085) (xy 191.229462 -312.828681) (xy 191.252805 -312.874493) (xy 191.268693 -312.923392)
			(xy 191.276736 -312.974174) (xy 191.27724 -312.999882) (xy 191.276736 -313.02559) (xy 192.52336 -313.02559)
			(xy 192.52336 -312.974174) (xy 192.531403 -312.923392) (xy 192.547291 -312.874493) (xy 192.570634 -312.828681)
			(xy 192.600855 -312.787085) (xy 192.637211 -312.750729) (xy 192.678807 -312.720508) (xy 192.724619 -312.697165)
			(xy 192.773518 -312.681277) (xy 192.8243 -312.673234) (xy 192.875716 -312.673234) (xy 192.926498 -312.681277)
			(xy 192.975397 -312.697165) (xy 193.021209 -312.720508) (xy 193.062805 -312.750729) (xy 193.099161 -312.787085)
			(xy 193.129382 -312.828681) (xy 193.152725 -312.874493) (xy 193.168613 -312.923392) (xy 193.176656 -312.974174)
			(xy 193.17716 -312.999882) (xy 193.176656 -313.02559) (xy 194.42328 -313.02559) (xy 194.42328 -312.974174)
			(xy 194.431323 -312.923392) (xy 194.447211 -312.874493) (xy 194.470554 -312.828681) (xy 194.500775 -312.787085)
			(xy 194.537131 -312.750729) (xy 194.578727 -312.720508) (xy 194.624539 -312.697165) (xy 194.673438 -312.681277)
			(xy 194.72422 -312.673234) (xy 194.775636 -312.673234) (xy 194.826418 -312.681277) (xy 194.875317 -312.697165)
			(xy 194.921129 -312.720508) (xy 194.962725 -312.750729) (xy 194.999081 -312.787085) (xy 195.029302 -312.828681)
			(xy 195.052645 -312.874493) (xy 195.068533 -312.923392) (xy 195.076576 -312.974174) (xy 195.07708 -312.999882)
			(xy 195.076576 -313.02559) (xy 196.3232 -313.02559) (xy 196.3232 -312.974174) (xy 196.331243 -312.923392)
			(xy 196.347131 -312.874493) (xy 196.370474 -312.828681) (xy 196.400695 -312.787085) (xy 196.437051 -312.750729)
			(xy 196.478647 -312.720508) (xy 196.524459 -312.697165) (xy 196.573358 -312.681277) (xy 196.62414 -312.673234)
			(xy 196.675556 -312.673234) (xy 196.726338 -312.681277) (xy 196.775237 -312.697165) (xy 196.821049 -312.720508)
			(xy 196.862645 -312.750729) (xy 196.899001 -312.787085) (xy 196.929222 -312.828681) (xy 196.952565 -312.874493)
			(xy 196.968453 -312.923392) (xy 196.976496 -312.974174) (xy 196.977 -312.999882) (xy 196.976496 -313.02559)
			(xy 196.968453 -313.076372) (xy 196.952565 -313.125271) (xy 196.929222 -313.171083) (xy 196.899001 -313.212679)
			(xy 196.862645 -313.249035) (xy 196.821049 -313.279256) (xy 196.775237 -313.302599) (xy 196.726338 -313.318487)
			(xy 196.675556 -313.32653) (xy 196.62414 -313.32653) (xy 196.573358 -313.318487) (xy 196.524459 -313.302599)
			(xy 196.478647 -313.279256) (xy 196.437051 -313.249035) (xy 196.400695 -313.212679) (xy 196.370474 -313.171083)
			(xy 196.347131 -313.125271) (xy 196.331243 -313.076372) (xy 196.3232 -313.02559) (xy 195.076576 -313.02559)
			(xy 195.068533 -313.076372) (xy 195.052645 -313.125271) (xy 195.029302 -313.171083) (xy 194.999081 -313.212679)
			(xy 194.962725 -313.249035) (xy 194.921129 -313.279256) (xy 194.875317 -313.302599) (xy 194.826418 -313.318487)
			(xy 194.775636 -313.32653) (xy 194.72422 -313.32653) (xy 194.673438 -313.318487) (xy 194.624539 -313.302599)
			(xy 194.578727 -313.279256) (xy 194.537131 -313.249035) (xy 194.500775 -313.212679) (xy 194.470554 -313.171083)
			(xy 194.447211 -313.125271) (xy 194.431323 -313.076372) (xy 194.42328 -313.02559) (xy 193.176656 -313.02559)
			(xy 193.168613 -313.076372) (xy 193.152725 -313.125271) (xy 193.129382 -313.171083) (xy 193.099161 -313.212679)
			(xy 193.062805 -313.249035) (xy 193.021209 -313.279256) (xy 192.975397 -313.302599) (xy 192.926498 -313.318487)
			(xy 192.875716 -313.32653) (xy 192.8243 -313.32653) (xy 192.773518 -313.318487) (xy 192.724619 -313.302599)
			(xy 192.678807 -313.279256) (xy 192.637211 -313.249035) (xy 192.600855 -313.212679) (xy 192.570634 -313.171083)
			(xy 192.547291 -313.125271) (xy 192.531403 -313.076372) (xy 192.52336 -313.02559) (xy 191.276736 -313.02559)
			(xy 191.268693 -313.076372) (xy 191.252805 -313.125271) (xy 191.229462 -313.171083) (xy 191.199241 -313.212679)
			(xy 191.162885 -313.249035) (xy 191.121289 -313.279256) (xy 191.075477 -313.302599) (xy 191.026578 -313.318487)
			(xy 190.975796 -313.32653) (xy 190.92438 -313.32653) (xy 190.873598 -313.318487) (xy 190.824699 -313.302599)
			(xy 190.778887 -313.279256) (xy 190.737291 -313.249035) (xy 190.700935 -313.212679) (xy 190.670714 -313.171083)
			(xy 190.647371 -313.125271) (xy 190.631483 -313.076372) (xy 190.62344 -313.02559) (xy 189.354548 -313.02559)
			(xy 189.346832 -313.073066) (xy 189.331248 -313.119747) (xy 189.308377 -313.163324) (xy 189.278812 -313.202668)
			(xy 189.243319 -313.23676) (xy 189.202816 -313.264716) (xy 189.158354 -313.285814) (xy 189.111083 -313.299506)
			(xy 189.062228 -313.305438) (xy 189.013053 -313.303457) (xy 188.964834 -313.293613) (xy 188.918818 -313.276161)
			(xy 188.876197 -313.251554) (xy 188.838076 -313.220429) (xy 188.805441 -313.183592) (xy 188.779138 -313.141996)
			(xy 188.759847 -313.09672) (xy 188.74807 -313.048936) (xy 188.74411 -312.999882) (xy 187.455302 -312.999882)
			(xy 187.454807 -313.024489) (xy 187.446912 -313.073066) (xy 187.431328 -313.119747) (xy 187.408457 -313.163324)
			(xy 187.378892 -313.202668) (xy 187.343399 -313.23676) (xy 187.302896 -313.264716) (xy 187.258434 -313.285814)
			(xy 187.211163 -313.299506) (xy 187.162308 -313.305438) (xy 187.113133 -313.303457) (xy 187.064914 -313.293613)
			(xy 187.018898 -313.276161) (xy 186.976277 -313.251554) (xy 186.938156 -313.220429) (xy 186.905521 -313.183592)
			(xy 186.879218 -313.141996) (xy 186.859927 -313.09672) (xy 186.84815 -313.048936) (xy 186.84419 -312.999882)
			(xy 185.555382 -312.999882) (xy 185.554887 -313.024489) (xy 185.546992 -313.073066) (xy 185.531408 -313.119747)
			(xy 185.508537 -313.163324) (xy 185.478972 -313.202668) (xy 185.443479 -313.23676) (xy 185.402976 -313.264716)
			(xy 185.358514 -313.285814) (xy 185.311243 -313.299506) (xy 185.262388 -313.305438) (xy 185.213213 -313.303457)
			(xy 185.164994 -313.293613) (xy 185.118978 -313.276161) (xy 185.076357 -313.251554) (xy 185.038236 -313.220429)
			(xy 185.005601 -313.183592) (xy 184.979298 -313.141996) (xy 184.960007 -313.09672) (xy 184.94823 -313.048936)
			(xy 184.94427 -312.999882) (xy 183.655208 -312.999882) (xy 183.654713 -313.024489) (xy 183.646818 -313.073066)
			(xy 183.631234 -313.119747) (xy 183.608363 -313.163324) (xy 183.578798 -313.202668) (xy 183.543305 -313.23676)
			(xy 183.502802 -313.264716) (xy 183.45834 -313.285814) (xy 183.411069 -313.299506) (xy 183.362214 -313.305438)
			(xy 183.313039 -313.303457) (xy 183.26482 -313.293613) (xy 183.218804 -313.276161) (xy 183.176183 -313.251554)
			(xy 183.138062 -313.220429) (xy 183.105427 -313.183592) (xy 183.079124 -313.141996) (xy 183.059833 -313.09672)
			(xy 183.048056 -313.048936) (xy 183.044096 -312.999882) (xy 181.777132 -312.999882) (xy 181.776628 -313.02559)
			(xy 181.768585 -313.076372) (xy 181.752697 -313.125271) (xy 181.729354 -313.171083) (xy 181.699133 -313.212679)
			(xy 181.662777 -313.249035) (xy 181.621181 -313.279256) (xy 181.575369 -313.302599) (xy 181.52647 -313.318487)
			(xy 181.475688 -313.32653) (xy 181.424272 -313.32653) (xy 181.37349 -313.318487) (xy 181.324591 -313.302599)
			(xy 181.278779 -313.279256) (xy 181.237183 -313.249035) (xy 181.200827 -313.212679) (xy 181.170606 -313.171083)
			(xy 181.147263 -313.125271) (xy 181.131375 -313.076372) (xy 181.123332 -313.02559) (xy 179.876708 -313.02559)
			(xy 179.868665 -313.076372) (xy 179.852777 -313.125271) (xy 179.829434 -313.171083) (xy 179.799213 -313.212679)
			(xy 179.762857 -313.249035) (xy 179.721261 -313.279256) (xy 179.675449 -313.302599) (xy 179.62655 -313.318487)
			(xy 179.575768 -313.32653) (xy 179.524352 -313.32653) (xy 179.47357 -313.318487) (xy 179.424671 -313.302599)
			(xy 179.378859 -313.279256) (xy 179.337263 -313.249035) (xy 179.300907 -313.212679) (xy 179.270686 -313.171083)
			(xy 179.247343 -313.125271) (xy 179.231455 -313.076372) (xy 179.223412 -313.02559) (xy 177.976534 -313.02559)
			(xy 177.968491 -313.076372) (xy 177.952603 -313.125271) (xy 177.92926 -313.171083) (xy 177.899039 -313.212679)
			(xy 177.862683 -313.249035) (xy 177.821087 -313.279256) (xy 177.775275 -313.302599) (xy 177.726376 -313.318487)
			(xy 177.675594 -313.32653) (xy 177.624178 -313.32653) (xy 177.573396 -313.318487) (xy 177.524497 -313.302599)
			(xy 177.478685 -313.279256) (xy 177.437089 -313.249035) (xy 177.400733 -313.212679) (xy 177.370512 -313.171083)
			(xy 177.347169 -313.125271) (xy 177.331281 -313.076372) (xy 177.323238 -313.02559) (xy 176.076614 -313.02559)
			(xy 176.068571 -313.076372) (xy 176.052683 -313.125271) (xy 176.02934 -313.171083) (xy 175.999119 -313.212679)
			(xy 175.962763 -313.249035) (xy 175.921167 -313.279256) (xy 175.875355 -313.302599) (xy 175.826456 -313.318487)
			(xy 175.775674 -313.32653) (xy 175.724258 -313.32653) (xy 175.673476 -313.318487) (xy 175.624577 -313.302599)
			(xy 175.578765 -313.279256) (xy 175.537169 -313.249035) (xy 175.500813 -313.212679) (xy 175.470592 -313.171083)
			(xy 175.447249 -313.125271) (xy 175.431361 -313.076372) (xy 175.423318 -313.02559) (xy 174.176694 -313.02559)
			(xy 174.168651 -313.076372) (xy 174.152763 -313.125271) (xy 174.12942 -313.171083) (xy 174.099199 -313.212679)
			(xy 174.062843 -313.249035) (xy 174.021247 -313.279256) (xy 173.975435 -313.302599) (xy 173.926536 -313.318487)
			(xy 173.875754 -313.32653) (xy 173.824338 -313.32653) (xy 173.773556 -313.318487) (xy 173.724657 -313.302599)
			(xy 173.678845 -313.279256) (xy 173.637249 -313.249035) (xy 173.600893 -313.212679) (xy 173.570672 -313.171083)
			(xy 173.547329 -313.125271) (xy 173.531441 -313.076372) (xy 173.523398 -313.02559) (xy 172.27652 -313.02559)
			(xy 172.268477 -313.076372) (xy 172.252589 -313.125271) (xy 172.229246 -313.171083) (xy 172.199025 -313.212679)
			(xy 172.162669 -313.249035) (xy 172.121073 -313.279256) (xy 172.075261 -313.302599) (xy 172.026362 -313.318487)
			(xy 171.97558 -313.32653) (xy 171.924164 -313.32653) (xy 171.873382 -313.318487) (xy 171.824483 -313.302599)
			(xy 171.778671 -313.279256) (xy 171.737075 -313.249035) (xy 171.700719 -313.212679) (xy 171.670498 -313.171083)
			(xy 171.647155 -313.125271) (xy 171.631267 -313.076372) (xy 171.623224 -313.02559) (xy 170.3766 -313.02559)
			(xy 170.368557 -313.076372) (xy 170.352669 -313.125271) (xy 170.329326 -313.171083) (xy 170.299105 -313.212679)
			(xy 170.262749 -313.249035) (xy 170.221153 -313.279256) (xy 170.175341 -313.302599) (xy 170.126442 -313.318487)
			(xy 170.07566 -313.32653) (xy 170.024244 -313.32653) (xy 169.973462 -313.318487) (xy 169.924563 -313.302599)
			(xy 169.878751 -313.279256) (xy 169.837155 -313.249035) (xy 169.800799 -313.212679) (xy 169.770578 -313.171083)
			(xy 169.747235 -313.125271) (xy 169.731347 -313.076372) (xy 169.723304 -313.02559) (xy 168.47668 -313.02559)
			(xy 168.468637 -313.076372) (xy 168.452749 -313.125271) (xy 168.429406 -313.171083) (xy 168.399185 -313.212679)
			(xy 168.362829 -313.249035) (xy 168.321233 -313.279256) (xy 168.275421 -313.302599) (xy 168.226522 -313.318487)
			(xy 168.17574 -313.32653) (xy 168.124324 -313.32653) (xy 168.073542 -313.318487) (xy 168.024643 -313.302599)
			(xy 167.978831 -313.279256) (xy 167.937235 -313.249035) (xy 167.900879 -313.212679) (xy 167.870658 -313.171083)
			(xy 167.847315 -313.125271) (xy 167.831427 -313.076372) (xy 167.823384 -313.02559) (xy 166.554492 -313.02559)
			(xy 166.546776 -313.073066) (xy 166.531192 -313.119747) (xy 166.508321 -313.163324) (xy 166.478756 -313.202668)
			(xy 166.443263 -313.23676) (xy 166.40276 -313.264716) (xy 166.358298 -313.285814) (xy 166.311027 -313.299506)
			(xy 166.262172 -313.305438) (xy 166.212997 -313.303457) (xy 166.164778 -313.293613) (xy 166.118762 -313.276161)
			(xy 166.076141 -313.251554) (xy 166.03802 -313.220429) (xy 166.005385 -313.183592) (xy 165.979082 -313.141996)
			(xy 165.959791 -313.09672) (xy 165.948014 -313.048936) (xy 165.944054 -312.999882) (xy 164.655246 -312.999882)
			(xy 164.654751 -313.024489) (xy 164.646856 -313.073066) (xy 164.631272 -313.119747) (xy 164.608401 -313.163324)
			(xy 164.578836 -313.202668) (xy 164.543343 -313.23676) (xy 164.50284 -313.264716) (xy 164.458378 -313.285814)
			(xy 164.411107 -313.299506) (xy 164.362252 -313.305438) (xy 164.313077 -313.303457) (xy 164.264858 -313.293613)
			(xy 164.218842 -313.276161) (xy 164.176221 -313.251554) (xy 164.1381 -313.220429) (xy 164.105465 -313.183592)
			(xy 164.079162 -313.141996) (xy 164.059871 -313.09672) (xy 164.048094 -313.048936) (xy 164.044134 -312.999882)
			(xy 162.755326 -312.999882) (xy 162.754831 -313.024489) (xy 162.746936 -313.073066) (xy 162.731352 -313.119747)
			(xy 162.708481 -313.163324) (xy 162.678916 -313.202668) (xy 162.643423 -313.23676) (xy 162.60292 -313.264716)
			(xy 162.558458 -313.285814) (xy 162.511187 -313.299506) (xy 162.462332 -313.305438) (xy 162.413157 -313.303457)
			(xy 162.364938 -313.293613) (xy 162.318922 -313.276161) (xy 162.276301 -313.251554) (xy 162.23818 -313.220429)
			(xy 162.205545 -313.183592) (xy 162.179242 -313.141996) (xy 162.159951 -313.09672) (xy 162.148174 -313.048936)
			(xy 162.144214 -312.999882) (xy 160.855152 -312.999882) (xy 160.854657 -313.024489) (xy 160.846762 -313.073066)
			(xy 160.831178 -313.119747) (xy 160.808307 -313.163324) (xy 160.778742 -313.202668) (xy 160.743249 -313.23676)
			(xy 160.702746 -313.264716) (xy 160.658284 -313.285814) (xy 160.611013 -313.299506) (xy 160.562158 -313.305438)
			(xy 160.512983 -313.303457) (xy 160.464764 -313.293613) (xy 160.418748 -313.276161) (xy 160.376127 -313.251554)
			(xy 160.338006 -313.220429) (xy 160.305371 -313.183592) (xy 160.279068 -313.141996) (xy 160.259777 -313.09672)
			(xy 160.248 -313.048936) (xy 160.24404 -312.999882) (xy 158.9557 -312.999882) (xy 158.951923 -313.04787)
			(xy 158.940619 -313.094774) (xy 158.92208 -313.139317) (xy 158.896765 -313.180389) (xy 158.865306 -313.216969)
			(xy 158.828485 -313.248146) (xy 158.78722 -313.273144) (xy 158.742536 -313.29134) (xy 158.695546 -313.302283)
			(xy 158.671514 -313.304428) (xy 158.671006 -313.304428) (xy 158.661577 -313.30553) (xy 158.644481 -313.313753)
			(xy 158.637732 -313.32043) (xy 158.590488 -313.370976) (xy 158.584195 -313.378263) (xy 158.577125 -313.396154)
			(xy 158.576772 -313.405774) (xy 158.576772 -313.54395) (xy 158.57718 -313.553562) (xy 158.584218 -313.571452)
			(xy 158.590488 -313.578748) (xy 158.637732 -313.629294) (xy 158.64448 -313.635975) (xy 158.661574 -313.644212)
			(xy 158.671006 -313.645296) (xy 158.67126 -313.645296) (xy 158.695296 -313.647439) (xy 158.742301 -313.658343)
			(xy 158.787006 -313.676504) (xy 158.828298 -313.70147) (xy 158.86515 -313.73262) (xy 158.896645 -313.769178)
			(xy 158.921997 -313.810234) (xy 158.940577 -313.854767) (xy 158.951921 -313.901668) (xy 158.955748 -313.949769)
			(xy 158.955742 -313.949842) (xy 160.24404 -313.949842) (xy 160.248 -313.900788) (xy 160.259777 -313.853004)
			(xy 160.279068 -313.807728) (xy 160.305371 -313.766132) (xy 160.338006 -313.729295) (xy 160.376127 -313.69817)
			(xy 160.418748 -313.673563) (xy 160.464764 -313.656111) (xy 160.512983 -313.646267) (xy 160.562158 -313.644286)
			(xy 160.611013 -313.650218) (xy 160.658284 -313.66391) (xy 160.702746 -313.685008) (xy 160.743249 -313.712964)
			(xy 160.778742 -313.747056) (xy 160.808307 -313.7864) (xy 160.831178 -313.829977) (xy 160.846762 -313.876658)
			(xy 160.854657 -313.925235) (xy 160.855152 -313.949842) (xy 162.144214 -313.949842) (xy 162.148174 -313.900788)
			(xy 162.159951 -313.853004) (xy 162.179242 -313.807728) (xy 162.205545 -313.766132) (xy 162.23818 -313.729295)
			(xy 162.276301 -313.69817) (xy 162.318922 -313.673563) (xy 162.364938 -313.656111) (xy 162.413157 -313.646267)
			(xy 162.462332 -313.644286) (xy 162.511187 -313.650218) (xy 162.558458 -313.66391) (xy 162.60292 -313.685008)
			(xy 162.643423 -313.712964) (xy 162.678916 -313.747056) (xy 162.708481 -313.7864) (xy 162.731352 -313.829977)
			(xy 162.746936 -313.876658) (xy 162.754831 -313.925235) (xy 162.755326 -313.949842) (xy 164.044134 -313.949842)
			(xy 164.048094 -313.900788) (xy 164.059871 -313.853004) (xy 164.079162 -313.807728) (xy 164.105465 -313.766132)
			(xy 164.1381 -313.729295) (xy 164.176221 -313.69817) (xy 164.218842 -313.673563) (xy 164.264858 -313.656111)
			(xy 164.313077 -313.646267) (xy 164.362252 -313.644286) (xy 164.411107 -313.650218) (xy 164.458378 -313.66391)
			(xy 164.50284 -313.685008) (xy 164.543343 -313.712964) (xy 164.578836 -313.747056) (xy 164.608401 -313.7864)
			(xy 164.631272 -313.829977) (xy 164.646856 -313.876658) (xy 164.654751 -313.925235) (xy 164.655246 -313.949842)
			(xy 165.944054 -313.949842) (xy 165.948014 -313.900788) (xy 165.959791 -313.853004) (xy 165.979082 -313.807728)
			(xy 166.005385 -313.766132) (xy 166.03802 -313.729295) (xy 166.076141 -313.69817) (xy 166.118762 -313.673563)
			(xy 166.164778 -313.656111) (xy 166.212997 -313.646267) (xy 166.262172 -313.644286) (xy 166.311027 -313.650218)
			(xy 166.358298 -313.66391) (xy 166.40276 -313.685008) (xy 166.443263 -313.712964) (xy 166.478756 -313.747056)
			(xy 166.508321 -313.7864) (xy 166.531192 -313.829977) (xy 166.546776 -313.876658) (xy 166.554671 -313.925235)
			(xy 166.555166 -313.949842) (xy 166.554671 -313.974449) (xy 166.554492 -313.97555) (xy 167.823384 -313.97555)
			(xy 167.823384 -313.924134) (xy 167.831427 -313.873352) (xy 167.847315 -313.824453) (xy 167.870658 -313.778641)
			(xy 167.900879 -313.737045) (xy 167.937235 -313.700689) (xy 167.978831 -313.670468) (xy 168.024643 -313.647125)
			(xy 168.073542 -313.631237) (xy 168.124324 -313.623194) (xy 168.17574 -313.623194) (xy 168.226522 -313.631237)
			(xy 168.275421 -313.647125) (xy 168.321233 -313.670468) (xy 168.362829 -313.700689) (xy 168.399185 -313.737045)
			(xy 168.429406 -313.778641) (xy 168.452749 -313.824453) (xy 168.468637 -313.873352) (xy 168.47668 -313.924134)
			(xy 168.477184 -313.949842) (xy 168.47668 -313.97555) (xy 169.723304 -313.97555) (xy 169.723304 -313.924134)
			(xy 169.731347 -313.873352) (xy 169.747235 -313.824453) (xy 169.770578 -313.778641) (xy 169.800799 -313.737045)
			(xy 169.837155 -313.700689) (xy 169.878751 -313.670468) (xy 169.924563 -313.647125) (xy 169.973462 -313.631237)
			(xy 170.024244 -313.623194) (xy 170.07566 -313.623194) (xy 170.126442 -313.631237) (xy 170.175341 -313.647125)
			(xy 170.221153 -313.670468) (xy 170.262749 -313.700689) (xy 170.299105 -313.737045) (xy 170.329326 -313.778641)
			(xy 170.352669 -313.824453) (xy 170.368557 -313.873352) (xy 170.3766 -313.924134) (xy 170.377104 -313.949842)
			(xy 170.3766 -313.97555) (xy 171.623224 -313.97555) (xy 171.623224 -313.924134) (xy 171.631267 -313.873352)
			(xy 171.647155 -313.824453) (xy 171.670498 -313.778641) (xy 171.700719 -313.737045) (xy 171.737075 -313.700689)
			(xy 171.778671 -313.670468) (xy 171.824483 -313.647125) (xy 171.873382 -313.631237) (xy 171.924164 -313.623194)
			(xy 171.97558 -313.623194) (xy 172.026362 -313.631237) (xy 172.075261 -313.647125) (xy 172.121073 -313.670468)
			(xy 172.162669 -313.700689) (xy 172.199025 -313.737045) (xy 172.229246 -313.778641) (xy 172.252589 -313.824453)
			(xy 172.268477 -313.873352) (xy 172.27652 -313.924134) (xy 172.277024 -313.949842) (xy 172.27652 -313.97555)
			(xy 173.523398 -313.97555) (xy 173.523398 -313.924134) (xy 173.531441 -313.873352) (xy 173.547329 -313.824453)
			(xy 173.570672 -313.778641) (xy 173.600893 -313.737045) (xy 173.637249 -313.700689) (xy 173.678845 -313.670468)
			(xy 173.724657 -313.647125) (xy 173.773556 -313.631237) (xy 173.824338 -313.623194) (xy 173.875754 -313.623194)
			(xy 173.926536 -313.631237) (xy 173.975435 -313.647125) (xy 174.021247 -313.670468) (xy 174.062843 -313.700689)
			(xy 174.099199 -313.737045) (xy 174.12942 -313.778641) (xy 174.152763 -313.824453) (xy 174.168651 -313.873352)
			(xy 174.176694 -313.924134) (xy 174.177198 -313.949842) (xy 174.176694 -313.97555) (xy 175.423318 -313.97555)
			(xy 175.423318 -313.924134) (xy 175.431361 -313.873352) (xy 175.447249 -313.824453) (xy 175.470592 -313.778641)
			(xy 175.500813 -313.737045) (xy 175.537169 -313.700689) (xy 175.578765 -313.670468) (xy 175.624577 -313.647125)
			(xy 175.673476 -313.631237) (xy 175.724258 -313.623194) (xy 175.775674 -313.623194) (xy 175.826456 -313.631237)
			(xy 175.875355 -313.647125) (xy 175.921167 -313.670468) (xy 175.962763 -313.700689) (xy 175.999119 -313.737045)
			(xy 176.02934 -313.778641) (xy 176.052683 -313.824453) (xy 176.068571 -313.873352) (xy 176.076614 -313.924134)
			(xy 176.077118 -313.949842) (xy 176.076614 -313.97555) (xy 177.323238 -313.97555) (xy 177.323238 -313.924134)
			(xy 177.331281 -313.873352) (xy 177.347169 -313.824453) (xy 177.370512 -313.778641) (xy 177.400733 -313.737045)
			(xy 177.437089 -313.700689) (xy 177.478685 -313.670468) (xy 177.524497 -313.647125) (xy 177.573396 -313.631237)
			(xy 177.624178 -313.623194) (xy 177.675594 -313.623194) (xy 177.726376 -313.631237) (xy 177.775275 -313.647125)
			(xy 177.821087 -313.670468) (xy 177.862683 -313.700689) (xy 177.899039 -313.737045) (xy 177.92926 -313.778641)
			(xy 177.952603 -313.824453) (xy 177.968491 -313.873352) (xy 177.976534 -313.924134) (xy 177.977038 -313.949842)
			(xy 177.976534 -313.97555) (xy 179.223412 -313.97555) (xy 179.223412 -313.924134) (xy 179.231455 -313.873352)
			(xy 179.247343 -313.824453) (xy 179.270686 -313.778641) (xy 179.300907 -313.737045) (xy 179.337263 -313.700689)
			(xy 179.378859 -313.670468) (xy 179.424671 -313.647125) (xy 179.47357 -313.631237) (xy 179.524352 -313.623194)
			(xy 179.575768 -313.623194) (xy 179.62655 -313.631237) (xy 179.675449 -313.647125) (xy 179.721261 -313.670468)
			(xy 179.762857 -313.700689) (xy 179.799213 -313.737045) (xy 179.829434 -313.778641) (xy 179.852777 -313.824453)
			(xy 179.868665 -313.873352) (xy 179.876708 -313.924134) (xy 179.877212 -313.949842) (xy 179.876708 -313.97555)
			(xy 181.123332 -313.97555) (xy 181.123332 -313.924134) (xy 181.131375 -313.873352) (xy 181.147263 -313.824453)
			(xy 181.170606 -313.778641) (xy 181.200827 -313.737045) (xy 181.237183 -313.700689) (xy 181.278779 -313.670468)
			(xy 181.324591 -313.647125) (xy 181.37349 -313.631237) (xy 181.424272 -313.623194) (xy 181.475688 -313.623194)
			(xy 181.52647 -313.631237) (xy 181.575369 -313.647125) (xy 181.621181 -313.670468) (xy 181.662777 -313.700689)
			(xy 181.699133 -313.737045) (xy 181.729354 -313.778641) (xy 181.752697 -313.824453) (xy 181.768585 -313.873352)
			(xy 181.776628 -313.924134) (xy 181.777132 -313.949842) (xy 183.044096 -313.949842) (xy 183.048056 -313.900788)
			(xy 183.059833 -313.853004) (xy 183.079124 -313.807728) (xy 183.105427 -313.766132) (xy 183.138062 -313.729295)
			(xy 183.176183 -313.69817) (xy 183.218804 -313.673563) (xy 183.26482 -313.656111) (xy 183.313039 -313.646267)
			(xy 183.362214 -313.644286) (xy 183.411069 -313.650218) (xy 183.45834 -313.66391) (xy 183.502802 -313.685008)
			(xy 183.543305 -313.712964) (xy 183.578798 -313.747056) (xy 183.608363 -313.7864) (xy 183.631234 -313.829977)
			(xy 183.646818 -313.876658) (xy 183.654713 -313.925235) (xy 183.655208 -313.949842) (xy 184.94427 -313.949842)
			(xy 184.94823 -313.900788) (xy 184.960007 -313.853004) (xy 184.979298 -313.807728) (xy 185.005601 -313.766132)
			(xy 185.038236 -313.729295) (xy 185.076357 -313.69817) (xy 185.118978 -313.673563) (xy 185.164994 -313.656111)
			(xy 185.213213 -313.646267) (xy 185.262388 -313.644286) (xy 185.311243 -313.650218) (xy 185.358514 -313.66391)
			(xy 185.402976 -313.685008) (xy 185.443479 -313.712964) (xy 185.478972 -313.747056) (xy 185.508537 -313.7864)
			(xy 185.531408 -313.829977) (xy 185.546992 -313.876658) (xy 185.554887 -313.925235) (xy 185.555382 -313.949842)
			(xy 186.84419 -313.949842) (xy 186.84815 -313.900788) (xy 186.859927 -313.853004) (xy 186.879218 -313.807728)
			(xy 186.905521 -313.766132) (xy 186.938156 -313.729295) (xy 186.976277 -313.69817) (xy 187.018898 -313.673563)
			(xy 187.064914 -313.656111) (xy 187.113133 -313.646267) (xy 187.162308 -313.644286) (xy 187.211163 -313.650218)
			(xy 187.258434 -313.66391) (xy 187.302896 -313.685008) (xy 187.343399 -313.712964) (xy 187.378892 -313.747056)
			(xy 187.408457 -313.7864) (xy 187.431328 -313.829977) (xy 187.446912 -313.876658) (xy 187.454807 -313.925235)
			(xy 187.455302 -313.949842) (xy 188.74411 -313.949842) (xy 188.74807 -313.900788) (xy 188.759847 -313.853004)
			(xy 188.779138 -313.807728) (xy 188.805441 -313.766132) (xy 188.838076 -313.729295) (xy 188.876197 -313.69817)
			(xy 188.918818 -313.673563) (xy 188.964834 -313.656111) (xy 189.013053 -313.646267) (xy 189.062228 -313.644286)
			(xy 189.111083 -313.650218) (xy 189.158354 -313.66391) (xy 189.202816 -313.685008) (xy 189.243319 -313.712964)
			(xy 189.278812 -313.747056) (xy 189.308377 -313.7864) (xy 189.331248 -313.829977) (xy 189.346832 -313.876658)
			(xy 189.354727 -313.925235) (xy 189.355222 -313.949842) (xy 189.354727 -313.974449) (xy 189.354548 -313.97555)
			(xy 190.62344 -313.97555) (xy 190.62344 -313.924134) (xy 190.631483 -313.873352) (xy 190.647371 -313.824453)
			(xy 190.670714 -313.778641) (xy 190.700935 -313.737045) (xy 190.737291 -313.700689) (xy 190.778887 -313.670468)
			(xy 190.824699 -313.647125) (xy 190.873598 -313.631237) (xy 190.92438 -313.623194) (xy 190.975796 -313.623194)
			(xy 191.026578 -313.631237) (xy 191.075477 -313.647125) (xy 191.121289 -313.670468) (xy 191.162885 -313.700689)
			(xy 191.199241 -313.737045) (xy 191.229462 -313.778641) (xy 191.252805 -313.824453) (xy 191.268693 -313.873352)
			(xy 191.276736 -313.924134) (xy 191.27724 -313.949842) (xy 191.276736 -313.97555) (xy 192.52336 -313.97555)
			(xy 192.52336 -313.924134) (xy 192.531403 -313.873352) (xy 192.547291 -313.824453) (xy 192.570634 -313.778641)
			(xy 192.600855 -313.737045) (xy 192.637211 -313.700689) (xy 192.678807 -313.670468) (xy 192.724619 -313.647125)
			(xy 192.773518 -313.631237) (xy 192.8243 -313.623194) (xy 192.875716 -313.623194) (xy 192.926498 -313.631237)
			(xy 192.975397 -313.647125) (xy 193.021209 -313.670468) (xy 193.062805 -313.700689) (xy 193.099161 -313.737045)
			(xy 193.129382 -313.778641) (xy 193.152725 -313.824453) (xy 193.168613 -313.873352) (xy 193.176656 -313.924134)
			(xy 193.17716 -313.949842) (xy 193.176656 -313.97555) (xy 194.42328 -313.97555) (xy 194.42328 -313.924134)
			(xy 194.431323 -313.873352) (xy 194.447211 -313.824453) (xy 194.470554 -313.778641) (xy 194.500775 -313.737045)
			(xy 194.537131 -313.700689) (xy 194.578727 -313.670468) (xy 194.624539 -313.647125) (xy 194.673438 -313.631237)
			(xy 194.72422 -313.623194) (xy 194.775636 -313.623194) (xy 194.826418 -313.631237) (xy 194.875317 -313.647125)
			(xy 194.921129 -313.670468) (xy 194.962725 -313.700689) (xy 194.999081 -313.737045) (xy 195.029302 -313.778641)
			(xy 195.052645 -313.824453) (xy 195.068533 -313.873352) (xy 195.076576 -313.924134) (xy 195.07708 -313.949842)
			(xy 195.076576 -313.97555) (xy 196.3232 -313.97555) (xy 196.3232 -313.924134) (xy 196.331243 -313.873352)
			(xy 196.347131 -313.824453) (xy 196.370474 -313.778641) (xy 196.400695 -313.737045) (xy 196.437051 -313.700689)
			(xy 196.478647 -313.670468) (xy 196.524459 -313.647125) (xy 196.573358 -313.631237) (xy 196.62414 -313.623194)
			(xy 196.675556 -313.623194) (xy 196.726338 -313.631237) (xy 196.775237 -313.647125) (xy 196.821049 -313.670468)
			(xy 196.862645 -313.700689) (xy 196.899001 -313.737045) (xy 196.929222 -313.778641) (xy 196.952565 -313.824453)
			(xy 196.968453 -313.873352) (xy 196.976496 -313.924134) (xy 196.977 -313.949842) (xy 196.976496 -313.97555)
			(xy 196.968453 -314.026332) (xy 196.952565 -314.075231) (xy 196.929222 -314.121043) (xy 196.899001 -314.162639)
			(xy 196.862645 -314.198995) (xy 196.821049 -314.229216) (xy 196.775237 -314.252559) (xy 196.726338 -314.268447)
			(xy 196.675556 -314.27649) (xy 196.62414 -314.27649) (xy 196.573358 -314.268447) (xy 196.524459 -314.252559)
			(xy 196.478647 -314.229216) (xy 196.437051 -314.198995) (xy 196.400695 -314.162639) (xy 196.370474 -314.121043)
			(xy 196.347131 -314.075231) (xy 196.331243 -314.026332) (xy 196.3232 -313.97555) (xy 195.076576 -313.97555)
			(xy 195.068533 -314.026332) (xy 195.052645 -314.075231) (xy 195.029302 -314.121043) (xy 194.999081 -314.162639)
			(xy 194.962725 -314.198995) (xy 194.921129 -314.229216) (xy 194.875317 -314.252559) (xy 194.826418 -314.268447)
			(xy 194.775636 -314.27649) (xy 194.72422 -314.27649) (xy 194.673438 -314.268447) (xy 194.624539 -314.252559)
			(xy 194.578727 -314.229216) (xy 194.537131 -314.198995) (xy 194.500775 -314.162639) (xy 194.470554 -314.121043)
			(xy 194.447211 -314.075231) (xy 194.431323 -314.026332) (xy 194.42328 -313.97555) (xy 193.176656 -313.97555)
			(xy 193.168613 -314.026332) (xy 193.152725 -314.075231) (xy 193.129382 -314.121043) (xy 193.099161 -314.162639)
			(xy 193.062805 -314.198995) (xy 193.021209 -314.229216) (xy 192.975397 -314.252559) (xy 192.926498 -314.268447)
			(xy 192.875716 -314.27649) (xy 192.8243 -314.27649) (xy 192.773518 -314.268447) (xy 192.724619 -314.252559)
			(xy 192.678807 -314.229216) (xy 192.637211 -314.198995) (xy 192.600855 -314.162639) (xy 192.570634 -314.121043)
			(xy 192.547291 -314.075231) (xy 192.531403 -314.026332) (xy 192.52336 -313.97555) (xy 191.276736 -313.97555)
			(xy 191.268693 -314.026332) (xy 191.252805 -314.075231) (xy 191.229462 -314.121043) (xy 191.199241 -314.162639)
			(xy 191.162885 -314.198995) (xy 191.121289 -314.229216) (xy 191.075477 -314.252559) (xy 191.026578 -314.268447)
			(xy 190.975796 -314.27649) (xy 190.92438 -314.27649) (xy 190.873598 -314.268447) (xy 190.824699 -314.252559)
			(xy 190.778887 -314.229216) (xy 190.737291 -314.198995) (xy 190.700935 -314.162639) (xy 190.670714 -314.121043)
			(xy 190.647371 -314.075231) (xy 190.631483 -314.026332) (xy 190.62344 -313.97555) (xy 189.354548 -313.97555)
			(xy 189.346832 -314.023026) (xy 189.331248 -314.069707) (xy 189.308377 -314.113284) (xy 189.278812 -314.152628)
			(xy 189.243319 -314.18672) (xy 189.202816 -314.214676) (xy 189.158354 -314.235774) (xy 189.111083 -314.249466)
			(xy 189.062228 -314.255398) (xy 189.013053 -314.253417) (xy 188.964834 -314.243573) (xy 188.918818 -314.226121)
			(xy 188.876197 -314.201514) (xy 188.838076 -314.170389) (xy 188.805441 -314.133552) (xy 188.779138 -314.091956)
			(xy 188.759847 -314.04668) (xy 188.74807 -313.998896) (xy 188.74411 -313.949842) (xy 187.455302 -313.949842)
			(xy 187.454807 -313.974449) (xy 187.446912 -314.023026) (xy 187.431328 -314.069707) (xy 187.408457 -314.113284)
			(xy 187.378892 -314.152628) (xy 187.343399 -314.18672) (xy 187.302896 -314.214676) (xy 187.258434 -314.235774)
			(xy 187.211163 -314.249466) (xy 187.162308 -314.255398) (xy 187.113133 -314.253417) (xy 187.064914 -314.243573)
			(xy 187.018898 -314.226121) (xy 186.976277 -314.201514) (xy 186.938156 -314.170389) (xy 186.905521 -314.133552)
			(xy 186.879218 -314.091956) (xy 186.859927 -314.04668) (xy 186.84815 -313.998896) (xy 186.84419 -313.949842)
			(xy 185.555382 -313.949842) (xy 185.554887 -313.974449) (xy 185.546992 -314.023026) (xy 185.531408 -314.069707)
			(xy 185.508537 -314.113284) (xy 185.478972 -314.152628) (xy 185.443479 -314.18672) (xy 185.402976 -314.214676)
			(xy 185.358514 -314.235774) (xy 185.311243 -314.249466) (xy 185.262388 -314.255398) (xy 185.213213 -314.253417)
			(xy 185.164994 -314.243573) (xy 185.118978 -314.226121) (xy 185.076357 -314.201514) (xy 185.038236 -314.170389)
			(xy 185.005601 -314.133552) (xy 184.979298 -314.091956) (xy 184.960007 -314.04668) (xy 184.94823 -313.998896)
			(xy 184.94427 -313.949842) (xy 183.655208 -313.949842) (xy 183.654713 -313.974449) (xy 183.646818 -314.023026)
			(xy 183.631234 -314.069707) (xy 183.608363 -314.113284) (xy 183.578798 -314.152628) (xy 183.543305 -314.18672)
			(xy 183.502802 -314.214676) (xy 183.45834 -314.235774) (xy 183.411069 -314.249466) (xy 183.362214 -314.255398)
			(xy 183.313039 -314.253417) (xy 183.26482 -314.243573) (xy 183.218804 -314.226121) (xy 183.176183 -314.201514)
			(xy 183.138062 -314.170389) (xy 183.105427 -314.133552) (xy 183.079124 -314.091956) (xy 183.059833 -314.04668)
			(xy 183.048056 -313.998896) (xy 183.044096 -313.949842) (xy 181.777132 -313.949842) (xy 181.776628 -313.97555)
			(xy 181.768585 -314.026332) (xy 181.752697 -314.075231) (xy 181.729354 -314.121043) (xy 181.699133 -314.162639)
			(xy 181.662777 -314.198995) (xy 181.621181 -314.229216) (xy 181.575369 -314.252559) (xy 181.52647 -314.268447)
			(xy 181.475688 -314.27649) (xy 181.424272 -314.27649) (xy 181.37349 -314.268447) (xy 181.324591 -314.252559)
			(xy 181.278779 -314.229216) (xy 181.237183 -314.198995) (xy 181.200827 -314.162639) (xy 181.170606 -314.121043)
			(xy 181.147263 -314.075231) (xy 181.131375 -314.026332) (xy 181.123332 -313.97555) (xy 179.876708 -313.97555)
			(xy 179.868665 -314.026332) (xy 179.852777 -314.075231) (xy 179.829434 -314.121043) (xy 179.799213 -314.162639)
			(xy 179.762857 -314.198995) (xy 179.721261 -314.229216) (xy 179.675449 -314.252559) (xy 179.62655 -314.268447)
			(xy 179.575768 -314.27649) (xy 179.524352 -314.27649) (xy 179.47357 -314.268447) (xy 179.424671 -314.252559)
			(xy 179.378859 -314.229216) (xy 179.337263 -314.198995) (xy 179.300907 -314.162639) (xy 179.270686 -314.121043)
			(xy 179.247343 -314.075231) (xy 179.231455 -314.026332) (xy 179.223412 -313.97555) (xy 177.976534 -313.97555)
			(xy 177.968491 -314.026332) (xy 177.952603 -314.075231) (xy 177.92926 -314.121043) (xy 177.899039 -314.162639)
			(xy 177.862683 -314.198995) (xy 177.821087 -314.229216) (xy 177.775275 -314.252559) (xy 177.726376 -314.268447)
			(xy 177.675594 -314.27649) (xy 177.624178 -314.27649) (xy 177.573396 -314.268447) (xy 177.524497 -314.252559)
			(xy 177.478685 -314.229216) (xy 177.437089 -314.198995) (xy 177.400733 -314.162639) (xy 177.370512 -314.121043)
			(xy 177.347169 -314.075231) (xy 177.331281 -314.026332) (xy 177.323238 -313.97555) (xy 176.076614 -313.97555)
			(xy 176.068571 -314.026332) (xy 176.052683 -314.075231) (xy 176.02934 -314.121043) (xy 175.999119 -314.162639)
			(xy 175.962763 -314.198995) (xy 175.921167 -314.229216) (xy 175.875355 -314.252559) (xy 175.826456 -314.268447)
			(xy 175.775674 -314.27649) (xy 175.724258 -314.27649) (xy 175.673476 -314.268447) (xy 175.624577 -314.252559)
			(xy 175.578765 -314.229216) (xy 175.537169 -314.198995) (xy 175.500813 -314.162639) (xy 175.470592 -314.121043)
			(xy 175.447249 -314.075231) (xy 175.431361 -314.026332) (xy 175.423318 -313.97555) (xy 174.176694 -313.97555)
			(xy 174.168651 -314.026332) (xy 174.152763 -314.075231) (xy 174.12942 -314.121043) (xy 174.099199 -314.162639)
			(xy 174.062843 -314.198995) (xy 174.021247 -314.229216) (xy 173.975435 -314.252559) (xy 173.926536 -314.268447)
			(xy 173.875754 -314.27649) (xy 173.824338 -314.27649) (xy 173.773556 -314.268447) (xy 173.724657 -314.252559)
			(xy 173.678845 -314.229216) (xy 173.637249 -314.198995) (xy 173.600893 -314.162639) (xy 173.570672 -314.121043)
			(xy 173.547329 -314.075231) (xy 173.531441 -314.026332) (xy 173.523398 -313.97555) (xy 172.27652 -313.97555)
			(xy 172.268477 -314.026332) (xy 172.252589 -314.075231) (xy 172.229246 -314.121043) (xy 172.199025 -314.162639)
			(xy 172.162669 -314.198995) (xy 172.121073 -314.229216) (xy 172.075261 -314.252559) (xy 172.026362 -314.268447)
			(xy 171.97558 -314.27649) (xy 171.924164 -314.27649) (xy 171.873382 -314.268447) (xy 171.824483 -314.252559)
			(xy 171.778671 -314.229216) (xy 171.737075 -314.198995) (xy 171.700719 -314.162639) (xy 171.670498 -314.121043)
			(xy 171.647155 -314.075231) (xy 171.631267 -314.026332) (xy 171.623224 -313.97555) (xy 170.3766 -313.97555)
			(xy 170.368557 -314.026332) (xy 170.352669 -314.075231) (xy 170.329326 -314.121043) (xy 170.299105 -314.162639)
			(xy 170.262749 -314.198995) (xy 170.221153 -314.229216) (xy 170.175341 -314.252559) (xy 170.126442 -314.268447)
			(xy 170.07566 -314.27649) (xy 170.024244 -314.27649) (xy 169.973462 -314.268447) (xy 169.924563 -314.252559)
			(xy 169.878751 -314.229216) (xy 169.837155 -314.198995) (xy 169.800799 -314.162639) (xy 169.770578 -314.121043)
			(xy 169.747235 -314.075231) (xy 169.731347 -314.026332) (xy 169.723304 -313.97555) (xy 168.47668 -313.97555)
			(xy 168.468637 -314.026332) (xy 168.452749 -314.075231) (xy 168.429406 -314.121043) (xy 168.399185 -314.162639)
			(xy 168.362829 -314.198995) (xy 168.321233 -314.229216) (xy 168.275421 -314.252559) (xy 168.226522 -314.268447)
			(xy 168.17574 -314.27649) (xy 168.124324 -314.27649) (xy 168.073542 -314.268447) (xy 168.024643 -314.252559)
			(xy 167.978831 -314.229216) (xy 167.937235 -314.198995) (xy 167.900879 -314.162639) (xy 167.870658 -314.121043)
			(xy 167.847315 -314.075231) (xy 167.831427 -314.026332) (xy 167.823384 -313.97555) (xy 166.554492 -313.97555)
			(xy 166.546776 -314.023026) (xy 166.531192 -314.069707) (xy 166.508321 -314.113284) (xy 166.478756 -314.152628)
			(xy 166.443263 -314.18672) (xy 166.40276 -314.214676) (xy 166.358298 -314.235774) (xy 166.311027 -314.249466)
			(xy 166.262172 -314.255398) (xy 166.212997 -314.253417) (xy 166.164778 -314.243573) (xy 166.118762 -314.226121)
			(xy 166.076141 -314.201514) (xy 166.03802 -314.170389) (xy 166.005385 -314.133552) (xy 165.979082 -314.091956)
			(xy 165.959791 -314.04668) (xy 165.948014 -313.998896) (xy 165.944054 -313.949842) (xy 164.655246 -313.949842)
			(xy 164.654751 -313.974449) (xy 164.646856 -314.023026) (xy 164.631272 -314.069707) (xy 164.608401 -314.113284)
			(xy 164.578836 -314.152628) (xy 164.543343 -314.18672) (xy 164.50284 -314.214676) (xy 164.458378 -314.235774)
			(xy 164.411107 -314.249466) (xy 164.362252 -314.255398) (xy 164.313077 -314.253417) (xy 164.264858 -314.243573)
			(xy 164.218842 -314.226121) (xy 164.176221 -314.201514) (xy 164.1381 -314.170389) (xy 164.105465 -314.133552)
			(xy 164.079162 -314.091956) (xy 164.059871 -314.04668) (xy 164.048094 -313.998896) (xy 164.044134 -313.949842)
			(xy 162.755326 -313.949842) (xy 162.754831 -313.974449) (xy 162.746936 -314.023026) (xy 162.731352 -314.069707)
			(xy 162.708481 -314.113284) (xy 162.678916 -314.152628) (xy 162.643423 -314.18672) (xy 162.60292 -314.214676)
			(xy 162.558458 -314.235774) (xy 162.511187 -314.249466) (xy 162.462332 -314.255398) (xy 162.413157 -314.253417)
			(xy 162.364938 -314.243573) (xy 162.318922 -314.226121) (xy 162.276301 -314.201514) (xy 162.23818 -314.170389)
			(xy 162.205545 -314.133552) (xy 162.179242 -314.091956) (xy 162.159951 -314.04668) (xy 162.148174 -313.998896)
			(xy 162.144214 -313.949842) (xy 160.855152 -313.949842) (xy 160.854657 -313.974449) (xy 160.846762 -314.023026)
			(xy 160.831178 -314.069707) (xy 160.808307 -314.113284) (xy 160.778742 -314.152628) (xy 160.743249 -314.18672)
			(xy 160.702746 -314.214676) (xy 160.658284 -314.235774) (xy 160.611013 -314.249466) (xy 160.562158 -314.255398)
			(xy 160.512983 -314.253417) (xy 160.464764 -314.243573) (xy 160.418748 -314.226121) (xy 160.376127 -314.201514)
			(xy 160.338006 -314.170389) (xy 160.305371 -314.133552) (xy 160.279068 -314.091956) (xy 160.259777 -314.04668)
			(xy 160.248 -313.998896) (xy 160.24404 -313.949842) (xy 158.955742 -313.949842) (xy 158.951963 -313.997873)
			(xy 158.940658 -314.044784) (xy 158.922117 -314.089333) (xy 158.896799 -314.130411) (xy 158.865336 -314.166996)
			(xy 158.828511 -314.198177) (xy 158.78724 -314.223178) (xy 158.74255 -314.241378) (xy 158.695555 -314.252322)
			(xy 158.671514 -314.254388) (xy 158.671006 -314.254388) (xy 158.661576 -314.255489) (xy 158.644476 -314.263708)
			(xy 158.637732 -314.27039) (xy 158.590488 -314.320936) (xy 158.584204 -314.328226) (xy 158.577155 -314.346117)
			(xy 158.576772 -314.355734) (xy 158.576772 -314.92551) (xy 197.273414 -314.92551) (xy 197.273414 -314.874094)
			(xy 197.281457 -314.823312) (xy 197.297345 -314.774413) (xy 197.320688 -314.728601) (xy 197.350909 -314.687005)
			(xy 197.387265 -314.650649) (xy 197.428861 -314.620428) (xy 197.474673 -314.597085) (xy 197.523572 -314.581197)
			(xy 197.574354 -314.573154) (xy 197.62577 -314.573154) (xy 197.676552 -314.581197) (xy 197.725451 -314.597085)
			(xy 197.771263 -314.620428) (xy 197.812859 -314.650649) (xy 197.849215 -314.687005) (xy 197.879436 -314.728601)
			(xy 197.902779 -314.774413) (xy 197.918667 -314.823312) (xy 197.92671 -314.874094) (xy 197.927214 -314.899802)
			(xy 197.92671 -314.92551) (xy 198.223374 -314.92551) (xy 198.223374 -314.874094) (xy 198.231417 -314.823312)
			(xy 198.247305 -314.774413) (xy 198.270648 -314.728601) (xy 198.300869 -314.687005) (xy 198.337225 -314.650649)
			(xy 198.378821 -314.620428) (xy 198.424633 -314.597085) (xy 198.473532 -314.581197) (xy 198.524314 -314.573154)
			(xy 198.57573 -314.573154) (xy 198.626512 -314.581197) (xy 198.675411 -314.597085) (xy 198.721223 -314.620428)
			(xy 198.762819 -314.650649) (xy 198.799175 -314.687005) (xy 198.829396 -314.728601) (xy 198.852739 -314.774413)
			(xy 198.868627 -314.823312) (xy 198.87667 -314.874094) (xy 198.877174 -314.899802) (xy 198.87667 -314.92551)
			(xy 198.868627 -314.976292) (xy 198.852739 -315.025191) (xy 198.829396 -315.071003) (xy 198.799175 -315.112599)
			(xy 198.762819 -315.148955) (xy 198.721223 -315.179176) (xy 198.675411 -315.202519) (xy 198.626512 -315.218407)
			(xy 198.57573 -315.22645) (xy 198.524314 -315.22645) (xy 198.473532 -315.218407) (xy 198.424633 -315.202519)
			(xy 198.378821 -315.179176) (xy 198.337225 -315.148955) (xy 198.300869 -315.112599) (xy 198.270648 -315.071003)
			(xy 198.247305 -315.025191) (xy 198.231417 -314.976292) (xy 198.223374 -314.92551) (xy 197.92671 -314.92551)
			(xy 197.918667 -314.976292) (xy 197.902779 -315.025191) (xy 197.879436 -315.071003) (xy 197.849215 -315.112599)
			(xy 197.812859 -315.148955) (xy 197.771263 -315.179176) (xy 197.725451 -315.202519) (xy 197.676552 -315.218407)
			(xy 197.62577 -315.22645) (xy 197.574354 -315.22645) (xy 197.523572 -315.218407) (xy 197.474673 -315.202519)
			(xy 197.428861 -315.179176) (xy 197.387265 -315.148955) (xy 197.350909 -315.112599) (xy 197.320688 -315.071003)
			(xy 197.297345 -315.025191) (xy 197.281457 -314.976292) (xy 197.273414 -314.92551) (xy 158.576772 -314.92551)
			(xy 158.576772 -315.418724) (xy 158.576922 -315.424305) (xy 158.579366 -315.435196) (xy 158.581598 -315.440314)
			(xy 158.601918 -315.487304) (xy 158.606101 -315.496528) (xy 158.620337 -315.51091) (xy 158.639041 -315.518635)
			(xy 158.649162 -315.519054) (xy 158.649924 -315.519054) (xy 158.675911 -315.519565) (xy 158.727245 -315.527699)
			(xy 158.776675 -315.543761) (xy 158.822984 -315.567358) (xy 158.865032 -315.597907) (xy 158.901784 -315.634658)
			(xy 158.932335 -315.676705) (xy 158.955933 -315.723012) (xy 158.971998 -315.772442) (xy 158.980134 -315.823775)
			(xy 158.980632 -315.849762) (xy 158.980163 -315.875258) (xy 158.97234 -315.925647) (xy 158.956873 -315.974237)
			(xy 158.934129 -316.019877) (xy 158.904648 -316.061484) (xy 158.869129 -316.098071) (xy 158.828413 -316.12877)
			(xy 158.783467 -316.152855) (xy 158.735356 -316.169753) (xy 158.710376 -316.174882) (xy 158.699553 -316.177425)
			(xy 158.68144 -316.190273) (xy 158.670473 -316.209583) (xy 158.668974 -316.220602) (xy 158.666834 -316.244478)
			(xy 158.660482 -316.291998) (xy 158.656274 -316.315598) (xy 158.655548 -316.320141) (xy 158.655556 -316.329341)
			(xy 158.656274 -316.333886) (xy 158.660466 -316.357488) (xy 158.666817 -316.405008) (xy 158.668974 -316.428882)
			(xy 158.670493 -316.439878) (xy 158.681518 -316.459117) (xy 158.699591 -316.471964) (xy 158.710376 -316.474602)
			(xy 158.730442 -316.47892) (xy 158.739526 -316.4808) (xy 158.757938 -316.478654) (xy 158.77438 -316.470094)
			(xy 158.786697 -316.456242) (xy 158.793276 -316.438913) (xy 158.793688 -316.429644) (xy 158.793688 -316.324742)
			(xy 158.794168 -316.29875) (xy 158.802294 -316.247407) (xy 158.818352 -316.197966) (xy 158.841948 -316.151647)
			(xy 158.872499 -316.109589) (xy 158.909254 -316.072829) (xy 158.951308 -316.042272) (xy 158.997624 -316.01867)
			(xy 159.047062 -316.002605) (xy 159.098405 -315.994472) (xy 159.124396 -315.994034) (xy 159.138824 -315.994198)
			(xy 159.167567 -315.996744) (xy 159.1818 -315.999114) (xy 159.182562 -315.999114) (xy 159.191198 -316.000638)
			(xy 159.213804 -315.993526) (xy 159.290258 -315.920882) (xy 159.298386 -315.898022) (xy 159.296862 -315.886338)
			(xy 159.295807 -315.877231) (xy 159.294661 -315.85893) (xy 159.294576 -315.849762) (xy 159.295065 -315.82494)
			(xy 159.303102 -315.775952) (xy 159.318959 -315.728909) (xy 159.342218 -315.685051) (xy 159.372265 -315.645533)
			(xy 159.40831 -315.611398) (xy 159.449403 -315.583543) (xy 159.49446 -315.562703) (xy 159.542296 -315.549427)
			(xy 159.591649 -315.544064) (xy 159.641219 -315.546757) (xy 159.689701 -315.557434) (xy 159.735817 -315.575813)
			(xy 159.778352 -315.601411) (xy 159.816186 -315.633553) (xy 159.848321 -315.671392) (xy 159.873911 -315.713931)
			(xy 159.892282 -315.760051) (xy 159.90295 -315.808534) (xy 159.905182 -315.849762) (xy 161.194254 -315.849762)
			(xy 161.198214 -315.800708) (xy 161.209991 -315.752924) (xy 161.229282 -315.707648) (xy 161.255585 -315.666052)
			(xy 161.28822 -315.629215) (xy 161.326341 -315.59809) (xy 161.368962 -315.573483) (xy 161.414978 -315.556031)
			(xy 161.463197 -315.546187) (xy 161.512372 -315.544206) (xy 161.561227 -315.550138) (xy 161.608498 -315.56383)
			(xy 161.65296 -315.584928) (xy 161.693463 -315.612884) (xy 161.728956 -315.646976) (xy 161.758521 -315.68632)
			(xy 161.781392 -315.729897) (xy 161.796976 -315.776578) (xy 161.804871 -315.825155) (xy 161.805366 -315.849762)
			(xy 163.094174 -315.849762) (xy 163.098134 -315.800708) (xy 163.109911 -315.752924) (xy 163.129202 -315.707648)
			(xy 163.155505 -315.666052) (xy 163.18814 -315.629215) (xy 163.226261 -315.59809) (xy 163.268882 -315.573483)
			(xy 163.314898 -315.556031) (xy 163.363117 -315.546187) (xy 163.412292 -315.544206) (xy 163.461147 -315.550138)
			(xy 163.508418 -315.56383) (xy 163.55288 -315.584928) (xy 163.593383 -315.612884) (xy 163.628876 -315.646976)
			(xy 163.658441 -315.68632) (xy 163.681312 -315.729897) (xy 163.696896 -315.776578) (xy 163.704791 -315.825155)
			(xy 163.705286 -315.849762) (xy 164.994094 -315.849762) (xy 164.998054 -315.800708) (xy 165.009831 -315.752924)
			(xy 165.029122 -315.707648) (xy 165.055425 -315.666052) (xy 165.08806 -315.629215) (xy 165.126181 -315.59809)
			(xy 165.168802 -315.573483) (xy 165.214818 -315.556031) (xy 165.263037 -315.546187) (xy 165.312212 -315.544206)
			(xy 165.361067 -315.550138) (xy 165.408338 -315.56383) (xy 165.4528 -315.584928) (xy 165.493303 -315.612884)
			(xy 165.528796 -315.646976) (xy 165.558361 -315.68632) (xy 165.581232 -315.729897) (xy 165.596816 -315.776578)
			(xy 165.604711 -315.825155) (xy 165.605206 -315.849762) (xy 165.604711 -315.874369) (xy 165.604532 -315.87547)
			(xy 166.873424 -315.87547) (xy 166.873424 -315.824054) (xy 166.881467 -315.773272) (xy 166.897355 -315.724373)
			(xy 166.920698 -315.678561) (xy 166.950919 -315.636965) (xy 166.987275 -315.600609) (xy 167.028871 -315.570388)
			(xy 167.074683 -315.547045) (xy 167.123582 -315.531157) (xy 167.174364 -315.523114) (xy 167.22578 -315.523114)
			(xy 167.276562 -315.531157) (xy 167.325461 -315.547045) (xy 167.371273 -315.570388) (xy 167.412869 -315.600609)
			(xy 167.449225 -315.636965) (xy 167.479446 -315.678561) (xy 167.502789 -315.724373) (xy 167.518677 -315.773272)
			(xy 167.52672 -315.824054) (xy 167.527224 -315.849762) (xy 167.52672 -315.87547) (xy 168.773344 -315.87547)
			(xy 168.773344 -315.824054) (xy 168.781387 -315.773272) (xy 168.797275 -315.724373) (xy 168.820618 -315.678561)
			(xy 168.850839 -315.636965) (xy 168.887195 -315.600609) (xy 168.928791 -315.570388) (xy 168.974603 -315.547045)
			(xy 169.023502 -315.531157) (xy 169.074284 -315.523114) (xy 169.1257 -315.523114) (xy 169.176482 -315.531157)
			(xy 169.225381 -315.547045) (xy 169.271193 -315.570388) (xy 169.312789 -315.600609) (xy 169.349145 -315.636965)
			(xy 169.379366 -315.678561) (xy 169.402709 -315.724373) (xy 169.418597 -315.773272) (xy 169.42664 -315.824054)
			(xy 169.427144 -315.849762) (xy 169.42664 -315.87547) (xy 170.673264 -315.87547) (xy 170.673264 -315.824054)
			(xy 170.681307 -315.773272) (xy 170.697195 -315.724373) (xy 170.720538 -315.678561) (xy 170.750759 -315.636965)
			(xy 170.787115 -315.600609) (xy 170.828711 -315.570388) (xy 170.874523 -315.547045) (xy 170.923422 -315.531157)
			(xy 170.974204 -315.523114) (xy 171.02562 -315.523114) (xy 171.076402 -315.531157) (xy 171.125301 -315.547045)
			(xy 171.171113 -315.570388) (xy 171.212709 -315.600609) (xy 171.249065 -315.636965) (xy 171.279286 -315.678561)
			(xy 171.302629 -315.724373) (xy 171.318517 -315.773272) (xy 171.32656 -315.824054) (xy 171.327064 -315.849762)
			(xy 171.32656 -315.87547) (xy 172.573438 -315.87547) (xy 172.573438 -315.824054) (xy 172.581481 -315.773272)
			(xy 172.597369 -315.724373) (xy 172.620712 -315.678561) (xy 172.650933 -315.636965) (xy 172.687289 -315.600609)
			(xy 172.728885 -315.570388) (xy 172.774697 -315.547045) (xy 172.823596 -315.531157) (xy 172.874378 -315.523114)
			(xy 172.925794 -315.523114) (xy 172.976576 -315.531157) (xy 173.025475 -315.547045) (xy 173.071287 -315.570388)
			(xy 173.112883 -315.600609) (xy 173.149239 -315.636965) (xy 173.17946 -315.678561) (xy 173.202803 -315.724373)
			(xy 173.218691 -315.773272) (xy 173.226734 -315.824054) (xy 173.227238 -315.849762) (xy 173.226734 -315.87547)
			(xy 174.473358 -315.87547) (xy 174.473358 -315.824054) (xy 174.481401 -315.773272) (xy 174.497289 -315.724373)
			(xy 174.520632 -315.678561) (xy 174.550853 -315.636965) (xy 174.587209 -315.600609) (xy 174.628805 -315.570388)
			(xy 174.674617 -315.547045) (xy 174.723516 -315.531157) (xy 174.774298 -315.523114) (xy 174.825714 -315.523114)
			(xy 174.876496 -315.531157) (xy 174.925395 -315.547045) (xy 174.971207 -315.570388) (xy 175.012803 -315.600609)
			(xy 175.049159 -315.636965) (xy 175.07938 -315.678561) (xy 175.102723 -315.724373) (xy 175.118611 -315.773272)
			(xy 175.126654 -315.824054) (xy 175.127158 -315.849762) (xy 175.126654 -315.87547) (xy 176.373278 -315.87547)
			(xy 176.373278 -315.824054) (xy 176.381321 -315.773272) (xy 176.397209 -315.724373) (xy 176.420552 -315.678561)
			(xy 176.450773 -315.636965) (xy 176.487129 -315.600609) (xy 176.528725 -315.570388) (xy 176.574537 -315.547045)
			(xy 176.623436 -315.531157) (xy 176.674218 -315.523114) (xy 176.725634 -315.523114) (xy 176.776416 -315.531157)
			(xy 176.825315 -315.547045) (xy 176.871127 -315.570388) (xy 176.912723 -315.600609) (xy 176.949079 -315.636965)
			(xy 176.9793 -315.678561) (xy 177.002643 -315.724373) (xy 177.018531 -315.773272) (xy 177.026574 -315.824054)
			(xy 177.027078 -315.849762) (xy 177.026574 -315.87547) (xy 178.273198 -315.87547) (xy 178.273198 -315.824054)
			(xy 178.281241 -315.773272) (xy 178.297129 -315.724373) (xy 178.320472 -315.678561) (xy 178.350693 -315.636965)
			(xy 178.387049 -315.600609) (xy 178.428645 -315.570388) (xy 178.474457 -315.547045) (xy 178.523356 -315.531157)
			(xy 178.574138 -315.523114) (xy 178.625554 -315.523114) (xy 178.676336 -315.531157) (xy 178.725235 -315.547045)
			(xy 178.771047 -315.570388) (xy 178.812643 -315.600609) (xy 178.848999 -315.636965) (xy 178.87922 -315.678561)
			(xy 178.902563 -315.724373) (xy 178.918451 -315.773272) (xy 178.926494 -315.824054) (xy 178.926998 -315.849762)
			(xy 178.926494 -315.87547) (xy 180.173372 -315.87547) (xy 180.173372 -315.824054) (xy 180.181415 -315.773272)
			(xy 180.197303 -315.724373) (xy 180.220646 -315.678561) (xy 180.250867 -315.636965) (xy 180.287223 -315.600609)
			(xy 180.328819 -315.570388) (xy 180.374631 -315.547045) (xy 180.42353 -315.531157) (xy 180.474312 -315.523114)
			(xy 180.525728 -315.523114) (xy 180.57651 -315.531157) (xy 180.625409 -315.547045) (xy 180.671221 -315.570388)
			(xy 180.712817 -315.600609) (xy 180.749173 -315.636965) (xy 180.779394 -315.678561) (xy 180.802737 -315.724373)
			(xy 180.818625 -315.773272) (xy 180.826668 -315.824054) (xy 180.827172 -315.849762) (xy 182.094136 -315.849762)
			(xy 182.098096 -315.800708) (xy 182.109873 -315.752924) (xy 182.129164 -315.707648) (xy 182.155467 -315.666052)
			(xy 182.188102 -315.629215) (xy 182.226223 -315.59809) (xy 182.268844 -315.573483) (xy 182.31486 -315.556031)
			(xy 182.363079 -315.546187) (xy 182.412254 -315.544206) (xy 182.461109 -315.550138) (xy 182.50838 -315.56383)
			(xy 182.552842 -315.584928) (xy 182.593345 -315.612884) (xy 182.628838 -315.646976) (xy 182.658403 -315.68632)
			(xy 182.681274 -315.729897) (xy 182.696858 -315.776578) (xy 182.704753 -315.825155) (xy 182.705248 -315.849762)
			(xy 183.994056 -315.849762) (xy 183.998016 -315.800708) (xy 184.009793 -315.752924) (xy 184.029084 -315.707648)
			(xy 184.055387 -315.666052) (xy 184.088022 -315.629215) (xy 184.126143 -315.59809) (xy 184.168764 -315.573483)
			(xy 184.21478 -315.556031) (xy 184.262999 -315.546187) (xy 184.312174 -315.544206) (xy 184.361029 -315.550138)
			(xy 184.4083 -315.56383) (xy 184.452762 -315.584928) (xy 184.493265 -315.612884) (xy 184.528758 -315.646976)
			(xy 184.558323 -315.68632) (xy 184.581194 -315.729897) (xy 184.596778 -315.776578) (xy 184.604673 -315.825155)
			(xy 184.605168 -315.849762) (xy 185.89423 -315.849762) (xy 185.89819 -315.800708) (xy 185.909967 -315.752924)
			(xy 185.929258 -315.707648) (xy 185.955561 -315.666052) (xy 185.988196 -315.629215) (xy 186.026317 -315.59809)
			(xy 186.068938 -315.573483) (xy 186.114954 -315.556031) (xy 186.163173 -315.546187) (xy 186.212348 -315.544206)
			(xy 186.261203 -315.550138) (xy 186.308474 -315.56383) (xy 186.352936 -315.584928) (xy 186.393439 -315.612884)
			(xy 186.428932 -315.646976) (xy 186.458497 -315.68632) (xy 186.481368 -315.729897) (xy 186.496952 -315.776578)
			(xy 186.504847 -315.825155) (xy 186.505342 -315.849762) (xy 187.79415 -315.849762) (xy 187.79811 -315.800708)
			(xy 187.809887 -315.752924) (xy 187.829178 -315.707648) (xy 187.855481 -315.666052) (xy 187.888116 -315.629215)
			(xy 187.926237 -315.59809) (xy 187.968858 -315.573483) (xy 188.014874 -315.556031) (xy 188.063093 -315.546187)
			(xy 188.112268 -315.544206) (xy 188.161123 -315.550138) (xy 188.208394 -315.56383) (xy 188.252856 -315.584928)
			(xy 188.293359 -315.612884) (xy 188.328852 -315.646976) (xy 188.358417 -315.68632) (xy 188.381288 -315.729897)
			(xy 188.396872 -315.776578) (xy 188.404767 -315.825155) (xy 188.405262 -315.849762) (xy 188.404767 -315.874369)
			(xy 188.404588 -315.87547) (xy 189.673226 -315.87547) (xy 189.673226 -315.824054) (xy 189.681269 -315.773272)
			(xy 189.697157 -315.724373) (xy 189.7205 -315.678561) (xy 189.750721 -315.636965) (xy 189.787077 -315.600609)
			(xy 189.828673 -315.570388) (xy 189.874485 -315.547045) (xy 189.923384 -315.531157) (xy 189.974166 -315.523114)
			(xy 190.025582 -315.523114) (xy 190.076364 -315.531157) (xy 190.125263 -315.547045) (xy 190.171075 -315.570388)
			(xy 190.212671 -315.600609) (xy 190.249027 -315.636965) (xy 190.279248 -315.678561) (xy 190.302591 -315.724373)
			(xy 190.318479 -315.773272) (xy 190.326522 -315.824054) (xy 190.327026 -315.849762) (xy 190.326522 -315.87547)
			(xy 191.5734 -315.87547) (xy 191.5734 -315.824054) (xy 191.581443 -315.773272) (xy 191.597331 -315.724373)
			(xy 191.620674 -315.678561) (xy 191.650895 -315.636965) (xy 191.687251 -315.600609) (xy 191.728847 -315.570388)
			(xy 191.774659 -315.547045) (xy 191.823558 -315.531157) (xy 191.87434 -315.523114) (xy 191.925756 -315.523114)
			(xy 191.976538 -315.531157) (xy 192.025437 -315.547045) (xy 192.071249 -315.570388) (xy 192.112845 -315.600609)
			(xy 192.149201 -315.636965) (xy 192.179422 -315.678561) (xy 192.202765 -315.724373) (xy 192.218653 -315.773272)
			(xy 192.226696 -315.824054) (xy 192.2272 -315.849762) (xy 192.226696 -315.87547) (xy 193.47332 -315.87547)
			(xy 193.47332 -315.824054) (xy 193.481363 -315.773272) (xy 193.497251 -315.724373) (xy 193.520594 -315.678561)
			(xy 193.550815 -315.636965) (xy 193.587171 -315.600609) (xy 193.628767 -315.570388) (xy 193.674579 -315.547045)
			(xy 193.723478 -315.531157) (xy 193.77426 -315.523114) (xy 193.825676 -315.523114) (xy 193.876458 -315.531157)
			(xy 193.925357 -315.547045) (xy 193.971169 -315.570388) (xy 194.012765 -315.600609) (xy 194.049121 -315.636965)
			(xy 194.079342 -315.678561) (xy 194.102685 -315.724373) (xy 194.118573 -315.773272) (xy 194.126616 -315.824054)
			(xy 194.12712 -315.849762) (xy 194.126616 -315.87547) (xy 195.37324 -315.87547) (xy 195.37324 -315.824054)
			(xy 195.381283 -315.773272) (xy 195.397171 -315.724373) (xy 195.420514 -315.678561) (xy 195.450735 -315.636965)
			(xy 195.487091 -315.600609) (xy 195.528687 -315.570388) (xy 195.574499 -315.547045) (xy 195.623398 -315.531157)
			(xy 195.67418 -315.523114) (xy 195.725596 -315.523114) (xy 195.776378 -315.531157) (xy 195.825277 -315.547045)
			(xy 195.871089 -315.570388) (xy 195.912685 -315.600609) (xy 195.949041 -315.636965) (xy 195.979262 -315.678561)
			(xy 196.002605 -315.724373) (xy 196.018493 -315.773272) (xy 196.026536 -315.824054) (xy 196.02704 -315.849762)
			(xy 196.026536 -315.87547) (xy 196.018493 -315.926252) (xy 196.002605 -315.975151) (xy 195.979262 -316.020963)
			(xy 195.949041 -316.062559) (xy 195.912685 -316.098915) (xy 195.871089 -316.129136) (xy 195.825277 -316.152479)
			(xy 195.776378 -316.168367) (xy 195.725596 -316.17641) (xy 195.67418 -316.17641) (xy 195.623398 -316.168367)
			(xy 195.574499 -316.152479) (xy 195.528687 -316.129136) (xy 195.487091 -316.098915) (xy 195.450735 -316.062559)
			(xy 195.420514 -316.020963) (xy 195.397171 -315.975151) (xy 195.381283 -315.926252) (xy 195.37324 -315.87547)
			(xy 194.126616 -315.87547) (xy 194.118573 -315.926252) (xy 194.102685 -315.975151) (xy 194.079342 -316.020963)
			(xy 194.049121 -316.062559) (xy 194.012765 -316.098915) (xy 193.971169 -316.129136) (xy 193.925357 -316.152479)
			(xy 193.876458 -316.168367) (xy 193.825676 -316.17641) (xy 193.77426 -316.17641) (xy 193.723478 -316.168367)
			(xy 193.674579 -316.152479) (xy 193.628767 -316.129136) (xy 193.587171 -316.098915) (xy 193.550815 -316.062559)
			(xy 193.520594 -316.020963) (xy 193.497251 -315.975151) (xy 193.481363 -315.926252) (xy 193.47332 -315.87547)
			(xy 192.226696 -315.87547) (xy 192.218653 -315.926252) (xy 192.202765 -315.975151) (xy 192.179422 -316.020963)
			(xy 192.149201 -316.062559) (xy 192.112845 -316.098915) (xy 192.071249 -316.129136) (xy 192.025437 -316.152479)
			(xy 191.976538 -316.168367) (xy 191.925756 -316.17641) (xy 191.87434 -316.17641) (xy 191.823558 -316.168367)
			(xy 191.774659 -316.152479) (xy 191.728847 -316.129136) (xy 191.687251 -316.098915) (xy 191.650895 -316.062559)
			(xy 191.620674 -316.020963) (xy 191.597331 -315.975151) (xy 191.581443 -315.926252) (xy 191.5734 -315.87547)
			(xy 190.326522 -315.87547) (xy 190.318479 -315.926252) (xy 190.302591 -315.975151) (xy 190.279248 -316.020963)
			(xy 190.249027 -316.062559) (xy 190.212671 -316.098915) (xy 190.171075 -316.129136) (xy 190.125263 -316.152479)
			(xy 190.076364 -316.168367) (xy 190.025582 -316.17641) (xy 189.974166 -316.17641) (xy 189.923384 -316.168367)
			(xy 189.874485 -316.152479) (xy 189.828673 -316.129136) (xy 189.787077 -316.098915) (xy 189.750721 -316.062559)
			(xy 189.7205 -316.020963) (xy 189.697157 -315.975151) (xy 189.681269 -315.926252) (xy 189.673226 -315.87547)
			(xy 188.404588 -315.87547) (xy 188.396872 -315.922946) (xy 188.381288 -315.969627) (xy 188.358417 -316.013204)
			(xy 188.328852 -316.052548) (xy 188.293359 -316.08664) (xy 188.252856 -316.114596) (xy 188.208394 -316.135694)
			(xy 188.161123 -316.149386) (xy 188.112268 -316.155318) (xy 188.063093 -316.153337) (xy 188.014874 -316.143493)
			(xy 187.968858 -316.126041) (xy 187.926237 -316.101434) (xy 187.888116 -316.070309) (xy 187.855481 -316.033472)
			(xy 187.829178 -315.991876) (xy 187.809887 -315.9466) (xy 187.79811 -315.898816) (xy 187.79415 -315.849762)
			(xy 186.505342 -315.849762) (xy 186.504847 -315.874369) (xy 186.496952 -315.922946) (xy 186.481368 -315.969627)
			(xy 186.458497 -316.013204) (xy 186.428932 -316.052548) (xy 186.393439 -316.08664) (xy 186.352936 -316.114596)
			(xy 186.308474 -316.135694) (xy 186.261203 -316.149386) (xy 186.212348 -316.155318) (xy 186.163173 -316.153337)
			(xy 186.114954 -316.143493) (xy 186.068938 -316.126041) (xy 186.026317 -316.101434) (xy 185.988196 -316.070309)
			(xy 185.955561 -316.033472) (xy 185.929258 -315.991876) (xy 185.909967 -315.9466) (xy 185.89819 -315.898816)
			(xy 185.89423 -315.849762) (xy 184.605168 -315.849762) (xy 184.604673 -315.874369) (xy 184.596778 -315.922946)
			(xy 184.581194 -315.969627) (xy 184.558323 -316.013204) (xy 184.528758 -316.052548) (xy 184.493265 -316.08664)
			(xy 184.452762 -316.114596) (xy 184.4083 -316.135694) (xy 184.361029 -316.149386) (xy 184.312174 -316.155318)
			(xy 184.262999 -316.153337) (xy 184.21478 -316.143493) (xy 184.168764 -316.126041) (xy 184.126143 -316.101434)
			(xy 184.088022 -316.070309) (xy 184.055387 -316.033472) (xy 184.029084 -315.991876) (xy 184.009793 -315.9466)
			(xy 183.998016 -315.898816) (xy 183.994056 -315.849762) (xy 182.705248 -315.849762) (xy 182.704753 -315.874369)
			(xy 182.696858 -315.922946) (xy 182.681274 -315.969627) (xy 182.658403 -316.013204) (xy 182.628838 -316.052548)
			(xy 182.593345 -316.08664) (xy 182.552842 -316.114596) (xy 182.50838 -316.135694) (xy 182.461109 -316.149386)
			(xy 182.412254 -316.155318) (xy 182.363079 -316.153337) (xy 182.31486 -316.143493) (xy 182.268844 -316.126041)
			(xy 182.226223 -316.101434) (xy 182.188102 -316.070309) (xy 182.155467 -316.033472) (xy 182.129164 -315.991876)
			(xy 182.109873 -315.9466) (xy 182.098096 -315.898816) (xy 182.094136 -315.849762) (xy 180.827172 -315.849762)
			(xy 180.826668 -315.87547) (xy 180.818625 -315.926252) (xy 180.802737 -315.975151) (xy 180.779394 -316.020963)
			(xy 180.749173 -316.062559) (xy 180.712817 -316.098915) (xy 180.671221 -316.129136) (xy 180.625409 -316.152479)
			(xy 180.57651 -316.168367) (xy 180.525728 -316.17641) (xy 180.474312 -316.17641) (xy 180.42353 -316.168367)
			(xy 180.374631 -316.152479) (xy 180.328819 -316.129136) (xy 180.287223 -316.098915) (xy 180.250867 -316.062559)
			(xy 180.220646 -316.020963) (xy 180.197303 -315.975151) (xy 180.181415 -315.926252) (xy 180.173372 -315.87547)
			(xy 178.926494 -315.87547) (xy 178.918451 -315.926252) (xy 178.902563 -315.975151) (xy 178.87922 -316.020963)
			(xy 178.848999 -316.062559) (xy 178.812643 -316.098915) (xy 178.771047 -316.129136) (xy 178.725235 -316.152479)
			(xy 178.676336 -316.168367) (xy 178.625554 -316.17641) (xy 178.574138 -316.17641) (xy 178.523356 -316.168367)
			(xy 178.474457 -316.152479) (xy 178.428645 -316.129136) (xy 178.387049 -316.098915) (xy 178.350693 -316.062559)
			(xy 178.320472 -316.020963) (xy 178.297129 -315.975151) (xy 178.281241 -315.926252) (xy 178.273198 -315.87547)
			(xy 177.026574 -315.87547) (xy 177.018531 -315.926252) (xy 177.002643 -315.975151) (xy 176.9793 -316.020963)
			(xy 176.949079 -316.062559) (xy 176.912723 -316.098915) (xy 176.871127 -316.129136) (xy 176.825315 -316.152479)
			(xy 176.776416 -316.168367) (xy 176.725634 -316.17641) (xy 176.674218 -316.17641) (xy 176.623436 -316.168367)
			(xy 176.574537 -316.152479) (xy 176.528725 -316.129136) (xy 176.487129 -316.098915) (xy 176.450773 -316.062559)
			(xy 176.420552 -316.020963) (xy 176.397209 -315.975151) (xy 176.381321 -315.926252) (xy 176.373278 -315.87547)
			(xy 175.126654 -315.87547) (xy 175.118611 -315.926252) (xy 175.102723 -315.975151) (xy 175.07938 -316.020963)
			(xy 175.049159 -316.062559) (xy 175.012803 -316.098915) (xy 174.971207 -316.129136) (xy 174.925395 -316.152479)
			(xy 174.876496 -316.168367) (xy 174.825714 -316.17641) (xy 174.774298 -316.17641) (xy 174.723516 -316.168367)
			(xy 174.674617 -316.152479) (xy 174.628805 -316.129136) (xy 174.587209 -316.098915) (xy 174.550853 -316.062559)
			(xy 174.520632 -316.020963) (xy 174.497289 -315.975151) (xy 174.481401 -315.926252) (xy 174.473358 -315.87547)
			(xy 173.226734 -315.87547) (xy 173.218691 -315.926252) (xy 173.202803 -315.975151) (xy 173.17946 -316.020963)
			(xy 173.149239 -316.062559) (xy 173.112883 -316.098915) (xy 173.071287 -316.129136) (xy 173.025475 -316.152479)
			(xy 172.976576 -316.168367) (xy 172.925794 -316.17641) (xy 172.874378 -316.17641) (xy 172.823596 -316.168367)
			(xy 172.774697 -316.152479) (xy 172.728885 -316.129136) (xy 172.687289 -316.098915) (xy 172.650933 -316.062559)
			(xy 172.620712 -316.020963) (xy 172.597369 -315.975151) (xy 172.581481 -315.926252) (xy 172.573438 -315.87547)
			(xy 171.32656 -315.87547) (xy 171.318517 -315.926252) (xy 171.302629 -315.975151) (xy 171.279286 -316.020963)
			(xy 171.249065 -316.062559) (xy 171.212709 -316.098915) (xy 171.171113 -316.129136) (xy 171.125301 -316.152479)
			(xy 171.076402 -316.168367) (xy 171.02562 -316.17641) (xy 170.974204 -316.17641) (xy 170.923422 -316.168367)
			(xy 170.874523 -316.152479) (xy 170.828711 -316.129136) (xy 170.787115 -316.098915) (xy 170.750759 -316.062559)
			(xy 170.720538 -316.020963) (xy 170.697195 -315.975151) (xy 170.681307 -315.926252) (xy 170.673264 -315.87547)
			(xy 169.42664 -315.87547) (xy 169.418597 -315.926252) (xy 169.402709 -315.975151) (xy 169.379366 -316.020963)
			(xy 169.349145 -316.062559) (xy 169.312789 -316.098915) (xy 169.271193 -316.129136) (xy 169.225381 -316.152479)
			(xy 169.176482 -316.168367) (xy 169.1257 -316.17641) (xy 169.074284 -316.17641) (xy 169.023502 -316.168367)
			(xy 168.974603 -316.152479) (xy 168.928791 -316.129136) (xy 168.887195 -316.098915) (xy 168.850839 -316.062559)
			(xy 168.820618 -316.020963) (xy 168.797275 -315.975151) (xy 168.781387 -315.926252) (xy 168.773344 -315.87547)
			(xy 167.52672 -315.87547) (xy 167.518677 -315.926252) (xy 167.502789 -315.975151) (xy 167.479446 -316.020963)
			(xy 167.449225 -316.062559) (xy 167.412869 -316.098915) (xy 167.371273 -316.129136) (xy 167.325461 -316.152479)
			(xy 167.276562 -316.168367) (xy 167.22578 -316.17641) (xy 167.174364 -316.17641) (xy 167.123582 -316.168367)
			(xy 167.074683 -316.152479) (xy 167.028871 -316.129136) (xy 166.987275 -316.098915) (xy 166.950919 -316.062559)
			(xy 166.920698 -316.020963) (xy 166.897355 -315.975151) (xy 166.881467 -315.926252) (xy 166.873424 -315.87547)
			(xy 165.604532 -315.87547) (xy 165.596816 -315.922946) (xy 165.581232 -315.969627) (xy 165.558361 -316.013204)
			(xy 165.528796 -316.052548) (xy 165.493303 -316.08664) (xy 165.4528 -316.114596) (xy 165.408338 -316.135694)
			(xy 165.361067 -316.149386) (xy 165.312212 -316.155318) (xy 165.263037 -316.153337) (xy 165.214818 -316.143493)
			(xy 165.168802 -316.126041) (xy 165.126181 -316.101434) (xy 165.08806 -316.070309) (xy 165.055425 -316.033472)
			(xy 165.029122 -315.991876) (xy 165.009831 -315.9466) (xy 164.998054 -315.898816) (xy 164.994094 -315.849762)
			(xy 163.705286 -315.849762) (xy 163.704791 -315.874369) (xy 163.696896 -315.922946) (xy 163.681312 -315.969627)
			(xy 163.658441 -316.013204) (xy 163.628876 -316.052548) (xy 163.593383 -316.08664) (xy 163.55288 -316.114596)
			(xy 163.508418 -316.135694) (xy 163.461147 -316.149386) (xy 163.412292 -316.155318) (xy 163.363117 -316.153337)
			(xy 163.314898 -316.143493) (xy 163.268882 -316.126041) (xy 163.226261 -316.101434) (xy 163.18814 -316.070309)
			(xy 163.155505 -316.033472) (xy 163.129202 -315.991876) (xy 163.109911 -315.9466) (xy 163.098134 -315.898816)
			(xy 163.094174 -315.849762) (xy 161.805366 -315.849762) (xy 161.804871 -315.874369) (xy 161.796976 -315.922946)
			(xy 161.781392 -315.969627) (xy 161.758521 -316.013204) (xy 161.728956 -316.052548) (xy 161.693463 -316.08664)
			(xy 161.65296 -316.114596) (xy 161.608498 -316.135694) (xy 161.561227 -316.149386) (xy 161.512372 -316.155318)
			(xy 161.463197 -316.153337) (xy 161.414978 -316.143493) (xy 161.368962 -316.126041) (xy 161.326341 -316.101434)
			(xy 161.28822 -316.070309) (xy 161.255585 -316.033472) (xy 161.229282 -315.991876) (xy 161.209991 -315.9466)
			(xy 161.198214 -315.898816) (xy 161.194254 -315.849762) (xy 159.905182 -315.849762) (xy 159.905634 -315.858105)
			(xy 159.900263 -315.907458) (xy 159.886979 -315.955291) (xy 159.866131 -316.000344) (xy 159.838269 -316.041432)
			(xy 159.804126 -316.077471) (xy 159.764604 -316.107511) (xy 159.720742 -316.130762) (xy 159.673696 -316.146611)
			(xy 159.624706 -316.154639) (xy 159.599884 -316.15507) (xy 159.590653 -316.154986) (xy 159.572225 -316.153845)
			(xy 159.563054 -316.152784) (xy 159.551116 -316.15126) (xy 159.528764 -316.159388) (xy 159.455612 -316.235588)
			(xy 159.448754 -316.258194) (xy 159.44977 -316.265052) (xy 159.452291 -316.279845) (xy 159.454965 -316.309736)
			(xy 159.455104 -316.324742) (xy 159.455104 -316.3951) (xy 159.455663 -316.405794) (xy 159.464316 -316.425355)
			(xy 159.471868 -316.432946) (xy 159.536384 -316.490604) (xy 159.556704 -316.497208) (xy 159.567372 -316.496192)
			(xy 159.599884 -316.494414) (xy 159.625141 -316.494905) (xy 159.674966 -316.503217) (xy 159.722743 -316.519617)
			(xy 159.767169 -316.543657) (xy 159.807032 -316.574682) (xy 159.841245 -316.611845) (xy 159.868874 -316.654133)
			(xy 159.889166 -316.700391) (xy 159.901566 -316.749359) (xy 159.905738 -316.7997) (xy 159.905736 -316.799722)
			(xy 161.194254 -316.799722) (xy 161.198214 -316.750668) (xy 161.209991 -316.702884) (xy 161.229282 -316.657608)
			(xy 161.255585 -316.616012) (xy 161.28822 -316.579175) (xy 161.326341 -316.54805) (xy 161.368962 -316.523443)
			(xy 161.414978 -316.505991) (xy 161.463197 -316.496147) (xy 161.512372 -316.494166) (xy 161.561227 -316.500098)
			(xy 161.608498 -316.51379) (xy 161.65296 -316.534888) (xy 161.693463 -316.562844) (xy 161.728956 -316.596936)
			(xy 161.758521 -316.63628) (xy 161.781392 -316.679857) (xy 161.796976 -316.726538) (xy 161.804871 -316.775115)
			(xy 161.805366 -316.799722) (xy 163.094174 -316.799722) (xy 163.098134 -316.750668) (xy 163.109911 -316.702884)
			(xy 163.129202 -316.657608) (xy 163.155505 -316.616012) (xy 163.18814 -316.579175) (xy 163.226261 -316.54805)
			(xy 163.268882 -316.523443) (xy 163.314898 -316.505991) (xy 163.363117 -316.496147) (xy 163.412292 -316.494166)
			(xy 163.461147 -316.500098) (xy 163.508418 -316.51379) (xy 163.55288 -316.534888) (xy 163.593383 -316.562844)
			(xy 163.628876 -316.596936) (xy 163.658441 -316.63628) (xy 163.681312 -316.679857) (xy 163.696896 -316.726538)
			(xy 163.704791 -316.775115) (xy 163.705286 -316.799722) (xy 164.994094 -316.799722) (xy 164.998054 -316.750668)
			(xy 165.009831 -316.702884) (xy 165.029122 -316.657608) (xy 165.055425 -316.616012) (xy 165.08806 -316.579175)
			(xy 165.126181 -316.54805) (xy 165.168802 -316.523443) (xy 165.214818 -316.505991) (xy 165.263037 -316.496147)
			(xy 165.312212 -316.494166) (xy 165.361067 -316.500098) (xy 165.408338 -316.51379) (xy 165.4528 -316.534888)
			(xy 165.493303 -316.562844) (xy 165.528796 -316.596936) (xy 165.558361 -316.63628) (xy 165.581232 -316.679857)
			(xy 165.596816 -316.726538) (xy 165.604711 -316.775115) (xy 165.605206 -316.799722) (xy 165.604711 -316.824329)
			(xy 165.604532 -316.82543) (xy 166.873424 -316.82543) (xy 166.873424 -316.774014) (xy 166.881467 -316.723232)
			(xy 166.897355 -316.674333) (xy 166.920698 -316.628521) (xy 166.950919 -316.586925) (xy 166.987275 -316.550569)
			(xy 167.028871 -316.520348) (xy 167.074683 -316.497005) (xy 167.123582 -316.481117) (xy 167.174364 -316.473074)
			(xy 167.22578 -316.473074) (xy 167.276562 -316.481117) (xy 167.325461 -316.497005) (xy 167.371273 -316.520348)
			(xy 167.412869 -316.550569) (xy 167.449225 -316.586925) (xy 167.479446 -316.628521) (xy 167.502789 -316.674333)
			(xy 167.518677 -316.723232) (xy 167.52672 -316.774014) (xy 167.527224 -316.799722) (xy 167.52672 -316.82543)
			(xy 168.773344 -316.82543) (xy 168.773344 -316.774014) (xy 168.781387 -316.723232) (xy 168.797275 -316.674333)
			(xy 168.820618 -316.628521) (xy 168.850839 -316.586925) (xy 168.887195 -316.550569) (xy 168.928791 -316.520348)
			(xy 168.974603 -316.497005) (xy 169.023502 -316.481117) (xy 169.074284 -316.473074) (xy 169.1257 -316.473074)
			(xy 169.176482 -316.481117) (xy 169.225381 -316.497005) (xy 169.271193 -316.520348) (xy 169.312789 -316.550569)
			(xy 169.349145 -316.586925) (xy 169.379366 -316.628521) (xy 169.402709 -316.674333) (xy 169.418597 -316.723232)
			(xy 169.42664 -316.774014) (xy 169.427144 -316.799722) (xy 169.42664 -316.82543) (xy 170.673264 -316.82543)
			(xy 170.673264 -316.774014) (xy 170.681307 -316.723232) (xy 170.697195 -316.674333) (xy 170.720538 -316.628521)
			(xy 170.750759 -316.586925) (xy 170.787115 -316.550569) (xy 170.828711 -316.520348) (xy 170.874523 -316.497005)
			(xy 170.923422 -316.481117) (xy 170.974204 -316.473074) (xy 171.02562 -316.473074) (xy 171.076402 -316.481117)
			(xy 171.125301 -316.497005) (xy 171.171113 -316.520348) (xy 171.212709 -316.550569) (xy 171.249065 -316.586925)
			(xy 171.279286 -316.628521) (xy 171.302629 -316.674333) (xy 171.318517 -316.723232) (xy 171.32656 -316.774014)
			(xy 171.327064 -316.799722) (xy 171.32656 -316.82543) (xy 172.573438 -316.82543) (xy 172.573438 -316.774014)
			(xy 172.581481 -316.723232) (xy 172.597369 -316.674333) (xy 172.620712 -316.628521) (xy 172.650933 -316.586925)
			(xy 172.687289 -316.550569) (xy 172.728885 -316.520348) (xy 172.774697 -316.497005) (xy 172.823596 -316.481117)
			(xy 172.874378 -316.473074) (xy 172.925794 -316.473074) (xy 172.976576 -316.481117) (xy 173.025475 -316.497005)
			(xy 173.071287 -316.520348) (xy 173.112883 -316.550569) (xy 173.149239 -316.586925) (xy 173.17946 -316.628521)
			(xy 173.202803 -316.674333) (xy 173.218691 -316.723232) (xy 173.226734 -316.774014) (xy 173.227238 -316.799722)
			(xy 173.226734 -316.82543) (xy 174.473358 -316.82543) (xy 174.473358 -316.774014) (xy 174.481401 -316.723232)
			(xy 174.497289 -316.674333) (xy 174.520632 -316.628521) (xy 174.550853 -316.586925) (xy 174.587209 -316.550569)
			(xy 174.628805 -316.520348) (xy 174.674617 -316.497005) (xy 174.723516 -316.481117) (xy 174.774298 -316.473074)
			(xy 174.825714 -316.473074) (xy 174.876496 -316.481117) (xy 174.925395 -316.497005) (xy 174.971207 -316.520348)
			(xy 175.012803 -316.550569) (xy 175.049159 -316.586925) (xy 175.07938 -316.628521) (xy 175.102723 -316.674333)
			(xy 175.118611 -316.723232) (xy 175.126654 -316.774014) (xy 175.127158 -316.799722) (xy 175.126654 -316.82543)
			(xy 176.373278 -316.82543) (xy 176.373278 -316.774014) (xy 176.381321 -316.723232) (xy 176.397209 -316.674333)
			(xy 176.420552 -316.628521) (xy 176.450773 -316.586925) (xy 176.487129 -316.550569) (xy 176.528725 -316.520348)
			(xy 176.574537 -316.497005) (xy 176.623436 -316.481117) (xy 176.674218 -316.473074) (xy 176.725634 -316.473074)
			(xy 176.776416 -316.481117) (xy 176.825315 -316.497005) (xy 176.871127 -316.520348) (xy 176.912723 -316.550569)
			(xy 176.949079 -316.586925) (xy 176.9793 -316.628521) (xy 177.002643 -316.674333) (xy 177.018531 -316.723232)
			(xy 177.026574 -316.774014) (xy 177.027078 -316.799722) (xy 177.026574 -316.82543) (xy 178.273198 -316.82543)
			(xy 178.273198 -316.774014) (xy 178.281241 -316.723232) (xy 178.297129 -316.674333) (xy 178.320472 -316.628521)
			(xy 178.350693 -316.586925) (xy 178.387049 -316.550569) (xy 178.428645 -316.520348) (xy 178.474457 -316.497005)
			(xy 178.523356 -316.481117) (xy 178.574138 -316.473074) (xy 178.625554 -316.473074) (xy 178.676336 -316.481117)
			(xy 178.725235 -316.497005) (xy 178.771047 -316.520348) (xy 178.812643 -316.550569) (xy 178.848999 -316.586925)
			(xy 178.87922 -316.628521) (xy 178.902563 -316.674333) (xy 178.918451 -316.723232) (xy 178.926494 -316.774014)
			(xy 178.926998 -316.799722) (xy 178.926494 -316.82543) (xy 180.173372 -316.82543) (xy 180.173372 -316.774014)
			(xy 180.181415 -316.723232) (xy 180.197303 -316.674333) (xy 180.220646 -316.628521) (xy 180.250867 -316.586925)
			(xy 180.287223 -316.550569) (xy 180.328819 -316.520348) (xy 180.374631 -316.497005) (xy 180.42353 -316.481117)
			(xy 180.474312 -316.473074) (xy 180.525728 -316.473074) (xy 180.57651 -316.481117) (xy 180.625409 -316.497005)
			(xy 180.671221 -316.520348) (xy 180.712817 -316.550569) (xy 180.749173 -316.586925) (xy 180.779394 -316.628521)
			(xy 180.802737 -316.674333) (xy 180.818625 -316.723232) (xy 180.826668 -316.774014) (xy 180.827172 -316.799722)
			(xy 182.094136 -316.799722) (xy 182.098096 -316.750668) (xy 182.109873 -316.702884) (xy 182.129164 -316.657608)
			(xy 182.155467 -316.616012) (xy 182.188102 -316.579175) (xy 182.226223 -316.54805) (xy 182.268844 -316.523443)
			(xy 182.31486 -316.505991) (xy 182.363079 -316.496147) (xy 182.412254 -316.494166) (xy 182.461109 -316.500098)
			(xy 182.50838 -316.51379) (xy 182.552842 -316.534888) (xy 182.593345 -316.562844) (xy 182.628838 -316.596936)
			(xy 182.658403 -316.63628) (xy 182.681274 -316.679857) (xy 182.696858 -316.726538) (xy 182.704753 -316.775115)
			(xy 182.705248 -316.799722) (xy 183.994056 -316.799722) (xy 183.998016 -316.750668) (xy 184.009793 -316.702884)
			(xy 184.029084 -316.657608) (xy 184.055387 -316.616012) (xy 184.088022 -316.579175) (xy 184.126143 -316.54805)
			(xy 184.168764 -316.523443) (xy 184.21478 -316.505991) (xy 184.262999 -316.496147) (xy 184.312174 -316.494166)
			(xy 184.361029 -316.500098) (xy 184.4083 -316.51379) (xy 184.452762 -316.534888) (xy 184.493265 -316.562844)
			(xy 184.528758 -316.596936) (xy 184.558323 -316.63628) (xy 184.581194 -316.679857) (xy 184.596778 -316.726538)
			(xy 184.604673 -316.775115) (xy 184.605168 -316.799722) (xy 185.89423 -316.799722) (xy 185.89819 -316.750668)
			(xy 185.909967 -316.702884) (xy 185.929258 -316.657608) (xy 185.955561 -316.616012) (xy 185.988196 -316.579175)
			(xy 186.026317 -316.54805) (xy 186.068938 -316.523443) (xy 186.114954 -316.505991) (xy 186.163173 -316.496147)
			(xy 186.212348 -316.494166) (xy 186.261203 -316.500098) (xy 186.308474 -316.51379) (xy 186.352936 -316.534888)
			(xy 186.393439 -316.562844) (xy 186.428932 -316.596936) (xy 186.458497 -316.63628) (xy 186.481368 -316.679857)
			(xy 186.496952 -316.726538) (xy 186.504847 -316.775115) (xy 186.505342 -316.799722) (xy 187.79415 -316.799722)
			(xy 187.79811 -316.750668) (xy 187.809887 -316.702884) (xy 187.829178 -316.657608) (xy 187.855481 -316.616012)
			(xy 187.888116 -316.579175) (xy 187.926237 -316.54805) (xy 187.968858 -316.523443) (xy 188.014874 -316.505991)
			(xy 188.063093 -316.496147) (xy 188.112268 -316.494166) (xy 188.161123 -316.500098) (xy 188.208394 -316.51379)
			(xy 188.252856 -316.534888) (xy 188.293359 -316.562844) (xy 188.328852 -316.596936) (xy 188.358417 -316.63628)
			(xy 188.381288 -316.679857) (xy 188.396872 -316.726538) (xy 188.404767 -316.775115) (xy 188.405262 -316.799722)
			(xy 188.404767 -316.824329) (xy 188.404588 -316.82543) (xy 189.673226 -316.82543) (xy 189.673226 -316.774014)
			(xy 189.681269 -316.723232) (xy 189.697157 -316.674333) (xy 189.7205 -316.628521) (xy 189.750721 -316.586925)
			(xy 189.787077 -316.550569) (xy 189.828673 -316.520348) (xy 189.874485 -316.497005) (xy 189.923384 -316.481117)
			(xy 189.974166 -316.473074) (xy 190.025582 -316.473074) (xy 190.076364 -316.481117) (xy 190.125263 -316.497005)
			(xy 190.171075 -316.520348) (xy 190.212671 -316.550569) (xy 190.249027 -316.586925) (xy 190.279248 -316.628521)
			(xy 190.302591 -316.674333) (xy 190.318479 -316.723232) (xy 190.326522 -316.774014) (xy 190.327026 -316.799722)
			(xy 190.326522 -316.82543) (xy 191.5734 -316.82543) (xy 191.5734 -316.774014) (xy 191.581443 -316.723232)
			(xy 191.597331 -316.674333) (xy 191.620674 -316.628521) (xy 191.650895 -316.586925) (xy 191.687251 -316.550569)
			(xy 191.728847 -316.520348) (xy 191.774659 -316.497005) (xy 191.823558 -316.481117) (xy 191.87434 -316.473074)
			(xy 191.925756 -316.473074) (xy 191.976538 -316.481117) (xy 192.025437 -316.497005) (xy 192.071249 -316.520348)
			(xy 192.112845 -316.550569) (xy 192.149201 -316.586925) (xy 192.179422 -316.628521) (xy 192.202765 -316.674333)
			(xy 192.218653 -316.723232) (xy 192.226696 -316.774014) (xy 192.2272 -316.799722) (xy 192.226696 -316.82543)
			(xy 193.47332 -316.82543) (xy 193.47332 -316.774014) (xy 193.481363 -316.723232) (xy 193.497251 -316.674333)
			(xy 193.520594 -316.628521) (xy 193.550815 -316.586925) (xy 193.587171 -316.550569) (xy 193.628767 -316.520348)
			(xy 193.674579 -316.497005) (xy 193.723478 -316.481117) (xy 193.77426 -316.473074) (xy 193.825676 -316.473074)
			(xy 193.876458 -316.481117) (xy 193.925357 -316.497005) (xy 193.971169 -316.520348) (xy 194.012765 -316.550569)
			(xy 194.049121 -316.586925) (xy 194.079342 -316.628521) (xy 194.102685 -316.674333) (xy 194.118573 -316.723232)
			(xy 194.126616 -316.774014) (xy 194.12712 -316.799722) (xy 194.126616 -316.82543) (xy 195.37324 -316.82543)
			(xy 195.37324 -316.774014) (xy 195.381283 -316.723232) (xy 195.397171 -316.674333) (xy 195.420514 -316.628521)
			(xy 195.450735 -316.586925) (xy 195.487091 -316.550569) (xy 195.528687 -316.520348) (xy 195.574499 -316.497005)
			(xy 195.623398 -316.481117) (xy 195.67418 -316.473074) (xy 195.725596 -316.473074) (xy 195.776378 -316.481117)
			(xy 195.825277 -316.497005) (xy 195.871089 -316.520348) (xy 195.912685 -316.550569) (xy 195.949041 -316.586925)
			(xy 195.979262 -316.628521) (xy 196.002605 -316.674333) (xy 196.018493 -316.723232) (xy 196.026536 -316.774014)
			(xy 196.02704 -316.799722) (xy 196.026536 -316.82543) (xy 197.273414 -316.82543) (xy 197.273414 -316.774014)
			(xy 197.281457 -316.723232) (xy 197.297345 -316.674333) (xy 197.320688 -316.628521) (xy 197.350909 -316.586925)
			(xy 197.387265 -316.550569) (xy 197.428861 -316.520348) (xy 197.474673 -316.497005) (xy 197.523572 -316.481117)
			(xy 197.574354 -316.473074) (xy 197.62577 -316.473074) (xy 197.676552 -316.481117) (xy 197.725451 -316.497005)
			(xy 197.771263 -316.520348) (xy 197.812859 -316.550569) (xy 197.849215 -316.586925) (xy 197.879436 -316.628521)
			(xy 197.902779 -316.674333) (xy 197.918667 -316.723232) (xy 197.92671 -316.774014) (xy 197.927214 -316.799722)
			(xy 197.92671 -316.82543) (xy 198.223374 -316.82543) (xy 198.223374 -316.774014) (xy 198.231417 -316.723232)
			(xy 198.247305 -316.674333) (xy 198.270648 -316.628521) (xy 198.300869 -316.586925) (xy 198.337225 -316.550569)
			(xy 198.378821 -316.520348) (xy 198.424633 -316.497005) (xy 198.473532 -316.481117) (xy 198.524314 -316.473074)
			(xy 198.57573 -316.473074) (xy 198.626512 -316.481117) (xy 198.675411 -316.497005) (xy 198.721223 -316.520348)
			(xy 198.762819 -316.550569) (xy 198.799175 -316.586925) (xy 198.829396 -316.628521) (xy 198.852739 -316.674333)
			(xy 198.868627 -316.723232) (xy 198.87667 -316.774014) (xy 198.877174 -316.799722) (xy 198.87667 -316.82543)
			(xy 198.868627 -316.876212) (xy 198.852739 -316.925111) (xy 198.829396 -316.970923) (xy 198.799175 -317.012519)
			(xy 198.762819 -317.048875) (xy 198.721223 -317.079096) (xy 198.675411 -317.102439) (xy 198.626512 -317.118327)
			(xy 198.57573 -317.12637) (xy 198.524314 -317.12637) (xy 198.473532 -317.118327) (xy 198.424633 -317.102439)
			(xy 198.378821 -317.079096) (xy 198.337225 -317.048875) (xy 198.300869 -317.012519) (xy 198.270648 -316.970923)
			(xy 198.247305 -316.925111) (xy 198.231417 -316.876212) (xy 198.223374 -316.82543) (xy 197.92671 -316.82543)
			(xy 197.918667 -316.876212) (xy 197.902779 -316.925111) (xy 197.879436 -316.970923) (xy 197.849215 -317.012519)
			(xy 197.812859 -317.048875) (xy 197.771263 -317.079096) (xy 197.725451 -317.102439) (xy 197.676552 -317.118327)
			(xy 197.62577 -317.12637) (xy 197.574354 -317.12637) (xy 197.523572 -317.118327) (xy 197.474673 -317.102439)
			(xy 197.428861 -317.079096) (xy 197.387265 -317.048875) (xy 197.350909 -317.012519) (xy 197.320688 -316.970923)
			(xy 197.297345 -316.925111) (xy 197.281457 -316.876212) (xy 197.273414 -316.82543) (xy 196.026536 -316.82543)
			(xy 196.018493 -316.876212) (xy 196.002605 -316.925111) (xy 195.979262 -316.970923) (xy 195.949041 -317.012519)
			(xy 195.912685 -317.048875) (xy 195.871089 -317.079096) (xy 195.825277 -317.102439) (xy 195.776378 -317.118327)
			(xy 195.725596 -317.12637) (xy 195.67418 -317.12637) (xy 195.623398 -317.118327) (xy 195.574499 -317.102439)
			(xy 195.528687 -317.079096) (xy 195.487091 -317.048875) (xy 195.450735 -317.012519) (xy 195.420514 -316.970923)
			(xy 195.397171 -316.925111) (xy 195.381283 -316.876212) (xy 195.37324 -316.82543) (xy 194.126616 -316.82543)
			(xy 194.118573 -316.876212) (xy 194.102685 -316.925111) (xy 194.079342 -316.970923) (xy 194.049121 -317.012519)
			(xy 194.012765 -317.048875) (xy 193.971169 -317.079096) (xy 193.925357 -317.102439) (xy 193.876458 -317.118327)
			(xy 193.825676 -317.12637) (xy 193.77426 -317.12637) (xy 193.723478 -317.118327) (xy 193.674579 -317.102439)
			(xy 193.628767 -317.079096) (xy 193.587171 -317.048875) (xy 193.550815 -317.012519) (xy 193.520594 -316.970923)
			(xy 193.497251 -316.925111) (xy 193.481363 -316.876212) (xy 193.47332 -316.82543) (xy 192.226696 -316.82543)
			(xy 192.218653 -316.876212) (xy 192.202765 -316.925111) (xy 192.179422 -316.970923) (xy 192.149201 -317.012519)
			(xy 192.112845 -317.048875) (xy 192.071249 -317.079096) (xy 192.025437 -317.102439) (xy 191.976538 -317.118327)
			(xy 191.925756 -317.12637) (xy 191.87434 -317.12637) (xy 191.823558 -317.118327) (xy 191.774659 -317.102439)
			(xy 191.728847 -317.079096) (xy 191.687251 -317.048875) (xy 191.650895 -317.012519) (xy 191.620674 -316.970923)
			(xy 191.597331 -316.925111) (xy 191.581443 -316.876212) (xy 191.5734 -316.82543) (xy 190.326522 -316.82543)
			(xy 190.318479 -316.876212) (xy 190.302591 -316.925111) (xy 190.279248 -316.970923) (xy 190.249027 -317.012519)
			(xy 190.212671 -317.048875) (xy 190.171075 -317.079096) (xy 190.125263 -317.102439) (xy 190.076364 -317.118327)
			(xy 190.025582 -317.12637) (xy 189.974166 -317.12637) (xy 189.923384 -317.118327) (xy 189.874485 -317.102439)
			(xy 189.828673 -317.079096) (xy 189.787077 -317.048875) (xy 189.750721 -317.012519) (xy 189.7205 -316.970923)
			(xy 189.697157 -316.925111) (xy 189.681269 -316.876212) (xy 189.673226 -316.82543) (xy 188.404588 -316.82543)
			(xy 188.396872 -316.872906) (xy 188.381288 -316.919587) (xy 188.358417 -316.963164) (xy 188.328852 -317.002508)
			(xy 188.293359 -317.0366) (xy 188.252856 -317.064556) (xy 188.208394 -317.085654) (xy 188.161123 -317.099346)
			(xy 188.112268 -317.105278) (xy 188.063093 -317.103297) (xy 188.014874 -317.093453) (xy 187.968858 -317.076001)
			(xy 187.926237 -317.051394) (xy 187.888116 -317.020269) (xy 187.855481 -316.983432) (xy 187.829178 -316.941836)
			(xy 187.809887 -316.89656) (xy 187.79811 -316.848776) (xy 187.79415 -316.799722) (xy 186.505342 -316.799722)
			(xy 186.504847 -316.824329) (xy 186.496952 -316.872906) (xy 186.481368 -316.919587) (xy 186.458497 -316.963164)
			(xy 186.428932 -317.002508) (xy 186.393439 -317.0366) (xy 186.352936 -317.064556) (xy 186.308474 -317.085654)
			(xy 186.261203 -317.099346) (xy 186.212348 -317.105278) (xy 186.163173 -317.103297) (xy 186.114954 -317.093453)
			(xy 186.068938 -317.076001) (xy 186.026317 -317.051394) (xy 185.988196 -317.020269) (xy 185.955561 -316.983432)
			(xy 185.929258 -316.941836) (xy 185.909967 -316.89656) (xy 185.89819 -316.848776) (xy 185.89423 -316.799722)
			(xy 184.605168 -316.799722) (xy 184.604673 -316.824329) (xy 184.596778 -316.872906) (xy 184.581194 -316.919587)
			(xy 184.558323 -316.963164) (xy 184.528758 -317.002508) (xy 184.493265 -317.0366) (xy 184.452762 -317.064556)
			(xy 184.4083 -317.085654) (xy 184.361029 -317.099346) (xy 184.312174 -317.105278) (xy 184.262999 -317.103297)
			(xy 184.21478 -317.093453) (xy 184.168764 -317.076001) (xy 184.126143 -317.051394) (xy 184.088022 -317.020269)
			(xy 184.055387 -316.983432) (xy 184.029084 -316.941836) (xy 184.009793 -316.89656) (xy 183.998016 -316.848776)
			(xy 183.994056 -316.799722) (xy 182.705248 -316.799722) (xy 182.704753 -316.824329) (xy 182.696858 -316.872906)
			(xy 182.681274 -316.919587) (xy 182.658403 -316.963164) (xy 182.628838 -317.002508) (xy 182.593345 -317.0366)
			(xy 182.552842 -317.064556) (xy 182.50838 -317.085654) (xy 182.461109 -317.099346) (xy 182.412254 -317.105278)
			(xy 182.363079 -317.103297) (xy 182.31486 -317.093453) (xy 182.268844 -317.076001) (xy 182.226223 -317.051394)
			(xy 182.188102 -317.020269) (xy 182.155467 -316.983432) (xy 182.129164 -316.941836) (xy 182.109873 -316.89656)
			(xy 182.098096 -316.848776) (xy 182.094136 -316.799722) (xy 180.827172 -316.799722) (xy 180.826668 -316.82543)
			(xy 180.818625 -316.876212) (xy 180.802737 -316.925111) (xy 180.779394 -316.970923) (xy 180.749173 -317.012519)
			(xy 180.712817 -317.048875) (xy 180.671221 -317.079096) (xy 180.625409 -317.102439) (xy 180.57651 -317.118327)
			(xy 180.525728 -317.12637) (xy 180.474312 -317.12637) (xy 180.42353 -317.118327) (xy 180.374631 -317.102439)
			(xy 180.328819 -317.079096) (xy 180.287223 -317.048875) (xy 180.250867 -317.012519) (xy 180.220646 -316.970923)
			(xy 180.197303 -316.925111) (xy 180.181415 -316.876212) (xy 180.173372 -316.82543) (xy 178.926494 -316.82543)
			(xy 178.918451 -316.876212) (xy 178.902563 -316.925111) (xy 178.87922 -316.970923) (xy 178.848999 -317.012519)
			(xy 178.812643 -317.048875) (xy 178.771047 -317.079096) (xy 178.725235 -317.102439) (xy 178.676336 -317.118327)
			(xy 178.625554 -317.12637) (xy 178.574138 -317.12637) (xy 178.523356 -317.118327) (xy 178.474457 -317.102439)
			(xy 178.428645 -317.079096) (xy 178.387049 -317.048875) (xy 178.350693 -317.012519) (xy 178.320472 -316.970923)
			(xy 178.297129 -316.925111) (xy 178.281241 -316.876212) (xy 178.273198 -316.82543) (xy 177.026574 -316.82543)
			(xy 177.018531 -316.876212) (xy 177.002643 -316.925111) (xy 176.9793 -316.970923) (xy 176.949079 -317.012519)
			(xy 176.912723 -317.048875) (xy 176.871127 -317.079096) (xy 176.825315 -317.102439) (xy 176.776416 -317.118327)
			(xy 176.725634 -317.12637) (xy 176.674218 -317.12637) (xy 176.623436 -317.118327) (xy 176.574537 -317.102439)
			(xy 176.528725 -317.079096) (xy 176.487129 -317.048875) (xy 176.450773 -317.012519) (xy 176.420552 -316.970923)
			(xy 176.397209 -316.925111) (xy 176.381321 -316.876212) (xy 176.373278 -316.82543) (xy 175.126654 -316.82543)
			(xy 175.118611 -316.876212) (xy 175.102723 -316.925111) (xy 175.07938 -316.970923) (xy 175.049159 -317.012519)
			(xy 175.012803 -317.048875) (xy 174.971207 -317.079096) (xy 174.925395 -317.102439) (xy 174.876496 -317.118327)
			(xy 174.825714 -317.12637) (xy 174.774298 -317.12637) (xy 174.723516 -317.118327) (xy 174.674617 -317.102439)
			(xy 174.628805 -317.079096) (xy 174.587209 -317.048875) (xy 174.550853 -317.012519) (xy 174.520632 -316.970923)
			(xy 174.497289 -316.925111) (xy 174.481401 -316.876212) (xy 174.473358 -316.82543) (xy 173.226734 -316.82543)
			(xy 173.218691 -316.876212) (xy 173.202803 -316.925111) (xy 173.17946 -316.970923) (xy 173.149239 -317.012519)
			(xy 173.112883 -317.048875) (xy 173.071287 -317.079096) (xy 173.025475 -317.102439) (xy 172.976576 -317.118327)
			(xy 172.925794 -317.12637) (xy 172.874378 -317.12637) (xy 172.823596 -317.118327) (xy 172.774697 -317.102439)
			(xy 172.728885 -317.079096) (xy 172.687289 -317.048875) (xy 172.650933 -317.012519) (xy 172.620712 -316.970923)
			(xy 172.597369 -316.925111) (xy 172.581481 -316.876212) (xy 172.573438 -316.82543) (xy 171.32656 -316.82543)
			(xy 171.318517 -316.876212) (xy 171.302629 -316.925111) (xy 171.279286 -316.970923) (xy 171.249065 -317.012519)
			(xy 171.212709 -317.048875) (xy 171.171113 -317.079096) (xy 171.125301 -317.102439) (xy 171.076402 -317.118327)
			(xy 171.02562 -317.12637) (xy 170.974204 -317.12637) (xy 170.923422 -317.118327) (xy 170.874523 -317.102439)
			(xy 170.828711 -317.079096) (xy 170.787115 -317.048875) (xy 170.750759 -317.012519) (xy 170.720538 -316.970923)
			(xy 170.697195 -316.925111) (xy 170.681307 -316.876212) (xy 170.673264 -316.82543) (xy 169.42664 -316.82543)
			(xy 169.418597 -316.876212) (xy 169.402709 -316.925111) (xy 169.379366 -316.970923) (xy 169.349145 -317.012519)
			(xy 169.312789 -317.048875) (xy 169.271193 -317.079096) (xy 169.225381 -317.102439) (xy 169.176482 -317.118327)
			(xy 169.1257 -317.12637) (xy 169.074284 -317.12637) (xy 169.023502 -317.118327) (xy 168.974603 -317.102439)
			(xy 168.928791 -317.079096) (xy 168.887195 -317.048875) (xy 168.850839 -317.012519) (xy 168.820618 -316.970923)
			(xy 168.797275 -316.925111) (xy 168.781387 -316.876212) (xy 168.773344 -316.82543) (xy 167.52672 -316.82543)
			(xy 167.518677 -316.876212) (xy 167.502789 -316.925111) (xy 167.479446 -316.970923) (xy 167.449225 -317.012519)
			(xy 167.412869 -317.048875) (xy 167.371273 -317.079096) (xy 167.325461 -317.102439) (xy 167.276562 -317.118327)
			(xy 167.22578 -317.12637) (xy 167.174364 -317.12637) (xy 167.123582 -317.118327) (xy 167.074683 -317.102439)
			(xy 167.028871 -317.079096) (xy 166.987275 -317.048875) (xy 166.950919 -317.012519) (xy 166.920698 -316.970923)
			(xy 166.897355 -316.925111) (xy 166.881467 -316.876212) (xy 166.873424 -316.82543) (xy 165.604532 -316.82543)
			(xy 165.596816 -316.872906) (xy 165.581232 -316.919587) (xy 165.558361 -316.963164) (xy 165.528796 -317.002508)
			(xy 165.493303 -317.0366) (xy 165.4528 -317.064556) (xy 165.408338 -317.085654) (xy 165.361067 -317.099346)
			(xy 165.312212 -317.105278) (xy 165.263037 -317.103297) (xy 165.214818 -317.093453) (xy 165.168802 -317.076001)
			(xy 165.126181 -317.051394) (xy 165.08806 -317.020269) (xy 165.055425 -316.983432) (xy 165.029122 -316.941836)
			(xy 165.009831 -316.89656) (xy 164.998054 -316.848776) (xy 164.994094 -316.799722) (xy 163.705286 -316.799722)
			(xy 163.704791 -316.824329) (xy 163.696896 -316.872906) (xy 163.681312 -316.919587) (xy 163.658441 -316.963164)
			(xy 163.628876 -317.002508) (xy 163.593383 -317.0366) (xy 163.55288 -317.064556) (xy 163.508418 -317.085654)
			(xy 163.461147 -317.099346) (xy 163.412292 -317.105278) (xy 163.363117 -317.103297) (xy 163.314898 -317.093453)
			(xy 163.268882 -317.076001) (xy 163.226261 -317.051394) (xy 163.18814 -317.020269) (xy 163.155505 -316.983432)
			(xy 163.129202 -316.941836) (xy 163.109911 -316.89656) (xy 163.098134 -316.848776) (xy 163.094174 -316.799722)
			(xy 161.805366 -316.799722) (xy 161.804871 -316.824329) (xy 161.796976 -316.872906) (xy 161.781392 -316.919587)
			(xy 161.758521 -316.963164) (xy 161.728956 -317.002508) (xy 161.693463 -317.0366) (xy 161.65296 -317.064556)
			(xy 161.608498 -317.085654) (xy 161.561227 -317.099346) (xy 161.512372 -317.105278) (xy 161.463197 -317.103297)
			(xy 161.414978 -317.093453) (xy 161.368962 -317.076001) (xy 161.326341 -317.051394) (xy 161.28822 -317.020269)
			(xy 161.255585 -316.983432) (xy 161.229282 -316.941836) (xy 161.209991 -316.89656) (xy 161.198214 -316.848776)
			(xy 161.194254 -316.799722) (xy 159.905736 -316.799722) (xy 159.901566 -316.850041) (xy 159.889166 -316.899009)
			(xy 159.868874 -316.945267) (xy 159.841245 -316.987555) (xy 159.807032 -317.024718) (xy 159.767169 -317.055743)
			(xy 159.722743 -317.079783) (xy 159.674966 -317.096183) (xy 159.625141 -317.104495) (xy 159.599884 -317.10503)
			(xy 159.57951 -317.104724) (xy 159.539117 -317.099369) (xy 159.519366 -317.094362) (xy 159.512762 -317.09233)
			(xy 159.505904 -317.09233) (xy 159.495938 -317.092869) (xy 159.477552 -317.100582) (xy 159.463499 -317.114726)
			(xy 159.455904 -317.133161) (xy 159.455358 -317.14313) (xy 159.455358 -317.190628) (xy 159.455594 -317.197896)
			(xy 159.459736 -317.211828) (xy 159.463486 -317.21806) (xy 159.463486 -317.218314) (xy 159.489078 -317.258625)
			(xy 159.533103 -317.343362) (xy 159.55137 -317.387478) (xy 159.555571 -317.396747) (xy 159.569886 -317.411186)
			(xy 159.588697 -317.418902) (xy 159.598868 -317.419228) (xy 159.599884 -317.419228) (xy 159.625873 -317.41971)
			(xy 159.677211 -317.427839) (xy 159.726646 -317.443901) (xy 159.772959 -317.467498) (xy 159.815009 -317.498051)
			(xy 159.851762 -317.534806) (xy 159.882312 -317.576858) (xy 159.905907 -317.623173) (xy 159.921965 -317.672608)
			(xy 159.930092 -317.723947) (xy 159.930592 -317.749936) (xy 160.24404 -317.749936) (xy 160.248 -317.700882)
			(xy 160.259777 -317.653098) (xy 160.279068 -317.607822) (xy 160.305371 -317.566226) (xy 160.338006 -317.529389)
			(xy 160.376127 -317.498264) (xy 160.418748 -317.473657) (xy 160.464764 -317.456205) (xy 160.512983 -317.446361)
			(xy 160.562158 -317.44438) (xy 160.611013 -317.450312) (xy 160.658284 -317.464004) (xy 160.702746 -317.485102)
			(xy 160.743249 -317.513058) (xy 160.778742 -317.54715) (xy 160.808307 -317.586494) (xy 160.831178 -317.630071)
			(xy 160.846762 -317.676752) (xy 160.854657 -317.725329) (xy 160.855152 -317.749936) (xy 162.144214 -317.749936)
			(xy 162.148174 -317.700882) (xy 162.159951 -317.653098) (xy 162.179242 -317.607822) (xy 162.205545 -317.566226)
			(xy 162.23818 -317.529389) (xy 162.276301 -317.498264) (xy 162.318922 -317.473657) (xy 162.364938 -317.456205)
			(xy 162.413157 -317.446361) (xy 162.462332 -317.44438) (xy 162.511187 -317.450312) (xy 162.558458 -317.464004)
			(xy 162.60292 -317.485102) (xy 162.643423 -317.513058) (xy 162.678916 -317.54715) (xy 162.708481 -317.586494)
			(xy 162.731352 -317.630071) (xy 162.746936 -317.676752) (xy 162.754831 -317.725329) (xy 162.755326 -317.749936)
			(xy 164.044134 -317.749936) (xy 164.048094 -317.700882) (xy 164.059871 -317.653098) (xy 164.079162 -317.607822)
			(xy 164.105465 -317.566226) (xy 164.1381 -317.529389) (xy 164.176221 -317.498264) (xy 164.218842 -317.473657)
			(xy 164.264858 -317.456205) (xy 164.313077 -317.446361) (xy 164.362252 -317.44438) (xy 164.411107 -317.450312)
			(xy 164.458378 -317.464004) (xy 164.50284 -317.485102) (xy 164.543343 -317.513058) (xy 164.578836 -317.54715)
			(xy 164.608401 -317.586494) (xy 164.631272 -317.630071) (xy 164.646856 -317.676752) (xy 164.654751 -317.725329)
			(xy 164.655246 -317.749936) (xy 165.944054 -317.749936) (xy 165.948014 -317.700882) (xy 165.959791 -317.653098)
			(xy 165.979082 -317.607822) (xy 166.005385 -317.566226) (xy 166.03802 -317.529389) (xy 166.076141 -317.498264)
			(xy 166.118762 -317.473657) (xy 166.164778 -317.456205) (xy 166.212997 -317.446361) (xy 166.262172 -317.44438)
			(xy 166.311027 -317.450312) (xy 166.358298 -317.464004) (xy 166.40276 -317.485102) (xy 166.443263 -317.513058)
			(xy 166.478756 -317.54715) (xy 166.508321 -317.586494) (xy 166.531192 -317.630071) (xy 166.546776 -317.676752)
			(xy 166.554671 -317.725329) (xy 166.555166 -317.749936) (xy 166.554671 -317.774543) (xy 166.554492 -317.775644)
			(xy 167.823384 -317.775644) (xy 167.823384 -317.724228) (xy 167.831427 -317.673446) (xy 167.847315 -317.624547)
			(xy 167.870658 -317.578735) (xy 167.900879 -317.537139) (xy 167.937235 -317.500783) (xy 167.978831 -317.470562)
			(xy 168.024643 -317.447219) (xy 168.073542 -317.431331) (xy 168.124324 -317.423288) (xy 168.17574 -317.423288)
			(xy 168.226522 -317.431331) (xy 168.275421 -317.447219) (xy 168.321233 -317.470562) (xy 168.362829 -317.500783)
			(xy 168.399185 -317.537139) (xy 168.429406 -317.578735) (xy 168.452749 -317.624547) (xy 168.468637 -317.673446)
			(xy 168.47668 -317.724228) (xy 168.477184 -317.749936) (xy 168.47668 -317.775644) (xy 169.723304 -317.775644)
			(xy 169.723304 -317.724228) (xy 169.731347 -317.673446) (xy 169.747235 -317.624547) (xy 169.770578 -317.578735)
			(xy 169.800799 -317.537139) (xy 169.837155 -317.500783) (xy 169.878751 -317.470562) (xy 169.924563 -317.447219)
			(xy 169.973462 -317.431331) (xy 170.024244 -317.423288) (xy 170.07566 -317.423288) (xy 170.126442 -317.431331)
			(xy 170.175341 -317.447219) (xy 170.221153 -317.470562) (xy 170.262749 -317.500783) (xy 170.299105 -317.537139)
			(xy 170.329326 -317.578735) (xy 170.352669 -317.624547) (xy 170.368557 -317.673446) (xy 170.3766 -317.724228)
			(xy 170.377104 -317.749936) (xy 170.3766 -317.775644) (xy 171.623224 -317.775644) (xy 171.623224 -317.724228)
			(xy 171.631267 -317.673446) (xy 171.647155 -317.624547) (xy 171.670498 -317.578735) (xy 171.700719 -317.537139)
			(xy 171.737075 -317.500783) (xy 171.778671 -317.470562) (xy 171.824483 -317.447219) (xy 171.873382 -317.431331)
			(xy 171.924164 -317.423288) (xy 171.97558 -317.423288) (xy 172.026362 -317.431331) (xy 172.075261 -317.447219)
			(xy 172.121073 -317.470562) (xy 172.162669 -317.500783) (xy 172.199025 -317.537139) (xy 172.229246 -317.578735)
			(xy 172.252589 -317.624547) (xy 172.268477 -317.673446) (xy 172.27652 -317.724228) (xy 172.277024 -317.749936)
			(xy 172.27652 -317.775644) (xy 173.523398 -317.775644) (xy 173.523398 -317.724228) (xy 173.531441 -317.673446)
			(xy 173.547329 -317.624547) (xy 173.570672 -317.578735) (xy 173.600893 -317.537139) (xy 173.637249 -317.500783)
			(xy 173.678845 -317.470562) (xy 173.724657 -317.447219) (xy 173.773556 -317.431331) (xy 173.824338 -317.423288)
			(xy 173.875754 -317.423288) (xy 173.926536 -317.431331) (xy 173.975435 -317.447219) (xy 174.021247 -317.470562)
			(xy 174.062843 -317.500783) (xy 174.099199 -317.537139) (xy 174.12942 -317.578735) (xy 174.152763 -317.624547)
			(xy 174.168651 -317.673446) (xy 174.176694 -317.724228) (xy 174.177198 -317.749936) (xy 174.176694 -317.775644)
			(xy 175.423318 -317.775644) (xy 175.423318 -317.724228) (xy 175.431361 -317.673446) (xy 175.447249 -317.624547)
			(xy 175.470592 -317.578735) (xy 175.500813 -317.537139) (xy 175.537169 -317.500783) (xy 175.578765 -317.470562)
			(xy 175.624577 -317.447219) (xy 175.673476 -317.431331) (xy 175.724258 -317.423288) (xy 175.775674 -317.423288)
			(xy 175.826456 -317.431331) (xy 175.875355 -317.447219) (xy 175.921167 -317.470562) (xy 175.962763 -317.500783)
			(xy 175.999119 -317.537139) (xy 176.02934 -317.578735) (xy 176.052683 -317.624547) (xy 176.068571 -317.673446)
			(xy 176.076614 -317.724228) (xy 176.077118 -317.749936) (xy 176.076614 -317.775644) (xy 177.323238 -317.775644)
			(xy 177.323238 -317.724228) (xy 177.331281 -317.673446) (xy 177.347169 -317.624547) (xy 177.370512 -317.578735)
			(xy 177.400733 -317.537139) (xy 177.437089 -317.500783) (xy 177.478685 -317.470562) (xy 177.524497 -317.447219)
			(xy 177.573396 -317.431331) (xy 177.624178 -317.423288) (xy 177.675594 -317.423288) (xy 177.726376 -317.431331)
			(xy 177.775275 -317.447219) (xy 177.821087 -317.470562) (xy 177.862683 -317.500783) (xy 177.899039 -317.537139)
			(xy 177.92926 -317.578735) (xy 177.952603 -317.624547) (xy 177.968491 -317.673446) (xy 177.976534 -317.724228)
			(xy 177.977038 -317.749936) (xy 177.976534 -317.775644) (xy 179.223412 -317.775644) (xy 179.223412 -317.724228)
			(xy 179.231455 -317.673446) (xy 179.247343 -317.624547) (xy 179.270686 -317.578735) (xy 179.300907 -317.537139)
			(xy 179.337263 -317.500783) (xy 179.378859 -317.470562) (xy 179.424671 -317.447219) (xy 179.47357 -317.431331)
			(xy 179.524352 -317.423288) (xy 179.575768 -317.423288) (xy 179.62655 -317.431331) (xy 179.675449 -317.447219)
			(xy 179.721261 -317.470562) (xy 179.762857 -317.500783) (xy 179.799213 -317.537139) (xy 179.829434 -317.578735)
			(xy 179.852777 -317.624547) (xy 179.868665 -317.673446) (xy 179.876708 -317.724228) (xy 179.877212 -317.749936)
			(xy 179.876708 -317.775644) (xy 181.123332 -317.775644) (xy 181.123332 -317.724228) (xy 181.131375 -317.673446)
			(xy 181.147263 -317.624547) (xy 181.170606 -317.578735) (xy 181.200827 -317.537139) (xy 181.237183 -317.500783)
			(xy 181.278779 -317.470562) (xy 181.324591 -317.447219) (xy 181.37349 -317.431331) (xy 181.424272 -317.423288)
			(xy 181.475688 -317.423288) (xy 181.52647 -317.431331) (xy 181.575369 -317.447219) (xy 181.621181 -317.470562)
			(xy 181.662777 -317.500783) (xy 181.699133 -317.537139) (xy 181.729354 -317.578735) (xy 181.752697 -317.624547)
			(xy 181.768585 -317.673446) (xy 181.776628 -317.724228) (xy 181.777132 -317.749936) (xy 183.044096 -317.749936)
			(xy 183.048056 -317.700882) (xy 183.059833 -317.653098) (xy 183.079124 -317.607822) (xy 183.105427 -317.566226)
			(xy 183.138062 -317.529389) (xy 183.176183 -317.498264) (xy 183.218804 -317.473657) (xy 183.26482 -317.456205)
			(xy 183.313039 -317.446361) (xy 183.362214 -317.44438) (xy 183.411069 -317.450312) (xy 183.45834 -317.464004)
			(xy 183.502802 -317.485102) (xy 183.543305 -317.513058) (xy 183.578798 -317.54715) (xy 183.608363 -317.586494)
			(xy 183.631234 -317.630071) (xy 183.646818 -317.676752) (xy 183.654713 -317.725329) (xy 183.655208 -317.749936)
			(xy 184.94427 -317.749936) (xy 184.94823 -317.700882) (xy 184.960007 -317.653098) (xy 184.979298 -317.607822)
			(xy 185.005601 -317.566226) (xy 185.038236 -317.529389) (xy 185.076357 -317.498264) (xy 185.118978 -317.473657)
			(xy 185.164994 -317.456205) (xy 185.213213 -317.446361) (xy 185.262388 -317.44438) (xy 185.311243 -317.450312)
			(xy 185.358514 -317.464004) (xy 185.402976 -317.485102) (xy 185.443479 -317.513058) (xy 185.478972 -317.54715)
			(xy 185.508537 -317.586494) (xy 185.531408 -317.630071) (xy 185.546992 -317.676752) (xy 185.554887 -317.725329)
			(xy 185.555382 -317.749936) (xy 186.84419 -317.749936) (xy 186.84815 -317.700882) (xy 186.859927 -317.653098)
			(xy 186.879218 -317.607822) (xy 186.905521 -317.566226) (xy 186.938156 -317.529389) (xy 186.976277 -317.498264)
			(xy 187.018898 -317.473657) (xy 187.064914 -317.456205) (xy 187.113133 -317.446361) (xy 187.162308 -317.44438)
			(xy 187.211163 -317.450312) (xy 187.258434 -317.464004) (xy 187.302896 -317.485102) (xy 187.343399 -317.513058)
			(xy 187.378892 -317.54715) (xy 187.408457 -317.586494) (xy 187.431328 -317.630071) (xy 187.446912 -317.676752)
			(xy 187.454807 -317.725329) (xy 187.455302 -317.749936) (xy 188.74411 -317.749936) (xy 188.74807 -317.700882)
			(xy 188.759847 -317.653098) (xy 188.779138 -317.607822) (xy 188.805441 -317.566226) (xy 188.838076 -317.529389)
			(xy 188.876197 -317.498264) (xy 188.918818 -317.473657) (xy 188.964834 -317.456205) (xy 189.013053 -317.446361)
			(xy 189.062228 -317.44438) (xy 189.111083 -317.450312) (xy 189.158354 -317.464004) (xy 189.202816 -317.485102)
			(xy 189.243319 -317.513058) (xy 189.278812 -317.54715) (xy 189.308377 -317.586494) (xy 189.331248 -317.630071)
			(xy 189.346832 -317.676752) (xy 189.354727 -317.725329) (xy 189.355222 -317.749936) (xy 189.354727 -317.774543)
			(xy 189.354548 -317.775644) (xy 190.62344 -317.775644) (xy 190.62344 -317.724228) (xy 190.631483 -317.673446)
			(xy 190.647371 -317.624547) (xy 190.670714 -317.578735) (xy 190.700935 -317.537139) (xy 190.737291 -317.500783)
			(xy 190.778887 -317.470562) (xy 190.824699 -317.447219) (xy 190.873598 -317.431331) (xy 190.92438 -317.423288)
			(xy 190.975796 -317.423288) (xy 191.026578 -317.431331) (xy 191.075477 -317.447219) (xy 191.121289 -317.470562)
			(xy 191.162885 -317.500783) (xy 191.199241 -317.537139) (xy 191.229462 -317.578735) (xy 191.252805 -317.624547)
			(xy 191.268693 -317.673446) (xy 191.276736 -317.724228) (xy 191.27724 -317.749936) (xy 191.276736 -317.775644)
			(xy 192.52336 -317.775644) (xy 192.52336 -317.724228) (xy 192.531403 -317.673446) (xy 192.547291 -317.624547)
			(xy 192.570634 -317.578735) (xy 192.600855 -317.537139) (xy 192.637211 -317.500783) (xy 192.678807 -317.470562)
			(xy 192.724619 -317.447219) (xy 192.773518 -317.431331) (xy 192.8243 -317.423288) (xy 192.875716 -317.423288)
			(xy 192.926498 -317.431331) (xy 192.975397 -317.447219) (xy 193.021209 -317.470562) (xy 193.062805 -317.500783)
			(xy 193.099161 -317.537139) (xy 193.129382 -317.578735) (xy 193.152725 -317.624547) (xy 193.168613 -317.673446)
			(xy 193.176656 -317.724228) (xy 193.17716 -317.749936) (xy 193.176656 -317.775644) (xy 194.42328 -317.775644)
			(xy 194.42328 -317.724228) (xy 194.431323 -317.673446) (xy 194.447211 -317.624547) (xy 194.470554 -317.578735)
			(xy 194.500775 -317.537139) (xy 194.537131 -317.500783) (xy 194.578727 -317.470562) (xy 194.624539 -317.447219)
			(xy 194.673438 -317.431331) (xy 194.72422 -317.423288) (xy 194.775636 -317.423288) (xy 194.826418 -317.431331)
			(xy 194.875317 -317.447219) (xy 194.921129 -317.470562) (xy 194.962725 -317.500783) (xy 194.999081 -317.537139)
			(xy 195.029302 -317.578735) (xy 195.052645 -317.624547) (xy 195.068533 -317.673446) (xy 195.076576 -317.724228)
			(xy 195.07708 -317.749936) (xy 195.076576 -317.775644) (xy 196.3232 -317.775644) (xy 196.3232 -317.724228)
			(xy 196.331243 -317.673446) (xy 196.347131 -317.624547) (xy 196.370474 -317.578735) (xy 196.400695 -317.537139)
			(xy 196.437051 -317.500783) (xy 196.478647 -317.470562) (xy 196.524459 -317.447219) (xy 196.573358 -317.431331)
			(xy 196.62414 -317.423288) (xy 196.675556 -317.423288) (xy 196.726338 -317.431331) (xy 196.775237 -317.447219)
			(xy 196.821049 -317.470562) (xy 196.862645 -317.500783) (xy 196.899001 -317.537139) (xy 196.929222 -317.578735)
			(xy 196.952565 -317.624547) (xy 196.968453 -317.673446) (xy 196.976496 -317.724228) (xy 196.977 -317.749936)
			(xy 196.976496 -317.775644) (xy 196.968453 -317.826426) (xy 196.952565 -317.875325) (xy 196.929222 -317.921137)
			(xy 196.899001 -317.962733) (xy 196.862645 -317.999089) (xy 196.821049 -318.02931) (xy 196.775237 -318.052653)
			(xy 196.726338 -318.068541) (xy 196.675556 -318.076584) (xy 196.62414 -318.076584) (xy 196.573358 -318.068541)
			(xy 196.524459 -318.052653) (xy 196.478647 -318.02931) (xy 196.437051 -317.999089) (xy 196.400695 -317.962733)
			(xy 196.370474 -317.921137) (xy 196.347131 -317.875325) (xy 196.331243 -317.826426) (xy 196.3232 -317.775644)
			(xy 195.076576 -317.775644) (xy 195.068533 -317.826426) (xy 195.052645 -317.875325) (xy 195.029302 -317.921137)
			(xy 194.999081 -317.962733) (xy 194.962725 -317.999089) (xy 194.921129 -318.02931) (xy 194.875317 -318.052653)
			(xy 194.826418 -318.068541) (xy 194.775636 -318.076584) (xy 194.72422 -318.076584) (xy 194.673438 -318.068541)
			(xy 194.624539 -318.052653) (xy 194.578727 -318.02931) (xy 194.537131 -317.999089) (xy 194.500775 -317.962733)
			(xy 194.470554 -317.921137) (xy 194.447211 -317.875325) (xy 194.431323 -317.826426) (xy 194.42328 -317.775644)
			(xy 193.176656 -317.775644) (xy 193.168613 -317.826426) (xy 193.152725 -317.875325) (xy 193.129382 -317.921137)
			(xy 193.099161 -317.962733) (xy 193.062805 -317.999089) (xy 193.021209 -318.02931) (xy 192.975397 -318.052653)
			(xy 192.926498 -318.068541) (xy 192.875716 -318.076584) (xy 192.8243 -318.076584) (xy 192.773518 -318.068541)
			(xy 192.724619 -318.052653) (xy 192.678807 -318.02931) (xy 192.637211 -317.999089) (xy 192.600855 -317.962733)
			(xy 192.570634 -317.921137) (xy 192.547291 -317.875325) (xy 192.531403 -317.826426) (xy 192.52336 -317.775644)
			(xy 191.276736 -317.775644) (xy 191.268693 -317.826426) (xy 191.252805 -317.875325) (xy 191.229462 -317.921137)
			(xy 191.199241 -317.962733) (xy 191.162885 -317.999089) (xy 191.121289 -318.02931) (xy 191.075477 -318.052653)
			(xy 191.026578 -318.068541) (xy 190.975796 -318.076584) (xy 190.92438 -318.076584) (xy 190.873598 -318.068541)
			(xy 190.824699 -318.052653) (xy 190.778887 -318.02931) (xy 190.737291 -317.999089) (xy 190.700935 -317.962733)
			(xy 190.670714 -317.921137) (xy 190.647371 -317.875325) (xy 190.631483 -317.826426) (xy 190.62344 -317.775644)
			(xy 189.354548 -317.775644) (xy 189.346832 -317.82312) (xy 189.331248 -317.869801) (xy 189.308377 -317.913378)
			(xy 189.278812 -317.952722) (xy 189.243319 -317.986814) (xy 189.202816 -318.01477) (xy 189.158354 -318.035868)
			(xy 189.111083 -318.04956) (xy 189.062228 -318.055492) (xy 189.013053 -318.053511) (xy 188.964834 -318.043667)
			(xy 188.918818 -318.026215) (xy 188.876197 -318.001608) (xy 188.838076 -317.970483) (xy 188.805441 -317.933646)
			(xy 188.779138 -317.89205) (xy 188.759847 -317.846774) (xy 188.74807 -317.79899) (xy 188.74411 -317.749936)
			(xy 187.455302 -317.749936) (xy 187.454807 -317.774543) (xy 187.446912 -317.82312) (xy 187.431328 -317.869801)
			(xy 187.408457 -317.913378) (xy 187.378892 -317.952722) (xy 187.343399 -317.986814) (xy 187.302896 -318.01477)
			(xy 187.258434 -318.035868) (xy 187.211163 -318.04956) (xy 187.162308 -318.055492) (xy 187.113133 -318.053511)
			(xy 187.064914 -318.043667) (xy 187.018898 -318.026215) (xy 186.976277 -318.001608) (xy 186.938156 -317.970483)
			(xy 186.905521 -317.933646) (xy 186.879218 -317.89205) (xy 186.859927 -317.846774) (xy 186.84815 -317.79899)
			(xy 186.84419 -317.749936) (xy 185.555382 -317.749936) (xy 185.554887 -317.774543) (xy 185.546992 -317.82312)
			(xy 185.531408 -317.869801) (xy 185.508537 -317.913378) (xy 185.478972 -317.952722) (xy 185.443479 -317.986814)
			(xy 185.402976 -318.01477) (xy 185.358514 -318.035868) (xy 185.311243 -318.04956) (xy 185.262388 -318.055492)
			(xy 185.213213 -318.053511) (xy 185.164994 -318.043667) (xy 185.118978 -318.026215) (xy 185.076357 -318.001608)
			(xy 185.038236 -317.970483) (xy 185.005601 -317.933646) (xy 184.979298 -317.89205) (xy 184.960007 -317.846774)
			(xy 184.94823 -317.79899) (xy 184.94427 -317.749936) (xy 183.655208 -317.749936) (xy 183.654713 -317.774543)
			(xy 183.646818 -317.82312) (xy 183.631234 -317.869801) (xy 183.608363 -317.913378) (xy 183.578798 -317.952722)
			(xy 183.543305 -317.986814) (xy 183.502802 -318.01477) (xy 183.45834 -318.035868) (xy 183.411069 -318.04956)
			(xy 183.362214 -318.055492) (xy 183.313039 -318.053511) (xy 183.26482 -318.043667) (xy 183.218804 -318.026215)
			(xy 183.176183 -318.001608) (xy 183.138062 -317.970483) (xy 183.105427 -317.933646) (xy 183.079124 -317.89205)
			(xy 183.059833 -317.846774) (xy 183.048056 -317.79899) (xy 183.044096 -317.749936) (xy 181.777132 -317.749936)
			(xy 181.776628 -317.775644) (xy 181.768585 -317.826426) (xy 181.752697 -317.875325) (xy 181.729354 -317.921137)
			(xy 181.699133 -317.962733) (xy 181.662777 -317.999089) (xy 181.621181 -318.02931) (xy 181.575369 -318.052653)
			(xy 181.52647 -318.068541) (xy 181.475688 -318.076584) (xy 181.424272 -318.076584) (xy 181.37349 -318.068541)
			(xy 181.324591 -318.052653) (xy 181.278779 -318.02931) (xy 181.237183 -317.999089) (xy 181.200827 -317.962733)
			(xy 181.170606 -317.921137) (xy 181.147263 -317.875325) (xy 181.131375 -317.826426) (xy 181.123332 -317.775644)
			(xy 179.876708 -317.775644) (xy 179.868665 -317.826426) (xy 179.852777 -317.875325) (xy 179.829434 -317.921137)
			(xy 179.799213 -317.962733) (xy 179.762857 -317.999089) (xy 179.721261 -318.02931) (xy 179.675449 -318.052653)
			(xy 179.62655 -318.068541) (xy 179.575768 -318.076584) (xy 179.524352 -318.076584) (xy 179.47357 -318.068541)
			(xy 179.424671 -318.052653) (xy 179.378859 -318.02931) (xy 179.337263 -317.999089) (xy 179.300907 -317.962733)
			(xy 179.270686 -317.921137) (xy 179.247343 -317.875325) (xy 179.231455 -317.826426) (xy 179.223412 -317.775644)
			(xy 177.976534 -317.775644) (xy 177.968491 -317.826426) (xy 177.952603 -317.875325) (xy 177.92926 -317.921137)
			(xy 177.899039 -317.962733) (xy 177.862683 -317.999089) (xy 177.821087 -318.02931) (xy 177.775275 -318.052653)
			(xy 177.726376 -318.068541) (xy 177.675594 -318.076584) (xy 177.624178 -318.076584) (xy 177.573396 -318.068541)
			(xy 177.524497 -318.052653) (xy 177.478685 -318.02931) (xy 177.437089 -317.999089) (xy 177.400733 -317.962733)
			(xy 177.370512 -317.921137) (xy 177.347169 -317.875325) (xy 177.331281 -317.826426) (xy 177.323238 -317.775644)
			(xy 176.076614 -317.775644) (xy 176.068571 -317.826426) (xy 176.052683 -317.875325) (xy 176.02934 -317.921137)
			(xy 175.999119 -317.962733) (xy 175.962763 -317.999089) (xy 175.921167 -318.02931) (xy 175.875355 -318.052653)
			(xy 175.826456 -318.068541) (xy 175.775674 -318.076584) (xy 175.724258 -318.076584) (xy 175.673476 -318.068541)
			(xy 175.624577 -318.052653) (xy 175.578765 -318.02931) (xy 175.537169 -317.999089) (xy 175.500813 -317.962733)
			(xy 175.470592 -317.921137) (xy 175.447249 -317.875325) (xy 175.431361 -317.826426) (xy 175.423318 -317.775644)
			(xy 174.176694 -317.775644) (xy 174.168651 -317.826426) (xy 174.152763 -317.875325) (xy 174.12942 -317.921137)
			(xy 174.099199 -317.962733) (xy 174.062843 -317.999089) (xy 174.021247 -318.02931) (xy 173.975435 -318.052653)
			(xy 173.926536 -318.068541) (xy 173.875754 -318.076584) (xy 173.824338 -318.076584) (xy 173.773556 -318.068541)
			(xy 173.724657 -318.052653) (xy 173.678845 -318.02931) (xy 173.637249 -317.999089) (xy 173.600893 -317.962733)
			(xy 173.570672 -317.921137) (xy 173.547329 -317.875325) (xy 173.531441 -317.826426) (xy 173.523398 -317.775644)
			(xy 172.27652 -317.775644) (xy 172.268477 -317.826426) (xy 172.252589 -317.875325) (xy 172.229246 -317.921137)
			(xy 172.199025 -317.962733) (xy 172.162669 -317.999089) (xy 172.121073 -318.02931) (xy 172.075261 -318.052653)
			(xy 172.026362 -318.068541) (xy 171.97558 -318.076584) (xy 171.924164 -318.076584) (xy 171.873382 -318.068541)
			(xy 171.824483 -318.052653) (xy 171.778671 -318.02931) (xy 171.737075 -317.999089) (xy 171.700719 -317.962733)
			(xy 171.670498 -317.921137) (xy 171.647155 -317.875325) (xy 171.631267 -317.826426) (xy 171.623224 -317.775644)
			(xy 170.3766 -317.775644) (xy 170.368557 -317.826426) (xy 170.352669 -317.875325) (xy 170.329326 -317.921137)
			(xy 170.299105 -317.962733) (xy 170.262749 -317.999089) (xy 170.221153 -318.02931) (xy 170.175341 -318.052653)
			(xy 170.126442 -318.068541) (xy 170.07566 -318.076584) (xy 170.024244 -318.076584) (xy 169.973462 -318.068541)
			(xy 169.924563 -318.052653) (xy 169.878751 -318.02931) (xy 169.837155 -317.999089) (xy 169.800799 -317.962733)
			(xy 169.770578 -317.921137) (xy 169.747235 -317.875325) (xy 169.731347 -317.826426) (xy 169.723304 -317.775644)
			(xy 168.47668 -317.775644) (xy 168.468637 -317.826426) (xy 168.452749 -317.875325) (xy 168.429406 -317.921137)
			(xy 168.399185 -317.962733) (xy 168.362829 -317.999089) (xy 168.321233 -318.02931) (xy 168.275421 -318.052653)
			(xy 168.226522 -318.068541) (xy 168.17574 -318.076584) (xy 168.124324 -318.076584) (xy 168.073542 -318.068541)
			(xy 168.024643 -318.052653) (xy 167.978831 -318.02931) (xy 167.937235 -317.999089) (xy 167.900879 -317.962733)
			(xy 167.870658 -317.921137) (xy 167.847315 -317.875325) (xy 167.831427 -317.826426) (xy 167.823384 -317.775644)
			(xy 166.554492 -317.775644) (xy 166.546776 -317.82312) (xy 166.531192 -317.869801) (xy 166.508321 -317.913378)
			(xy 166.478756 -317.952722) (xy 166.443263 -317.986814) (xy 166.40276 -318.01477) (xy 166.358298 -318.035868)
			(xy 166.311027 -318.04956) (xy 166.262172 -318.055492) (xy 166.212997 -318.053511) (xy 166.164778 -318.043667)
			(xy 166.118762 -318.026215) (xy 166.076141 -318.001608) (xy 166.03802 -317.970483) (xy 166.005385 -317.933646)
			(xy 165.979082 -317.89205) (xy 165.959791 -317.846774) (xy 165.948014 -317.79899) (xy 165.944054 -317.749936)
			(xy 164.655246 -317.749936) (xy 164.654751 -317.774543) (xy 164.646856 -317.82312) (xy 164.631272 -317.869801)
			(xy 164.608401 -317.913378) (xy 164.578836 -317.952722) (xy 164.543343 -317.986814) (xy 164.50284 -318.01477)
			(xy 164.458378 -318.035868) (xy 164.411107 -318.04956) (xy 164.362252 -318.055492) (xy 164.313077 -318.053511)
			(xy 164.264858 -318.043667) (xy 164.218842 -318.026215) (xy 164.176221 -318.001608) (xy 164.1381 -317.970483)
			(xy 164.105465 -317.933646) (xy 164.079162 -317.89205) (xy 164.059871 -317.846774) (xy 164.048094 -317.79899)
			(xy 164.044134 -317.749936) (xy 162.755326 -317.749936) (xy 162.754831 -317.774543) (xy 162.746936 -317.82312)
			(xy 162.731352 -317.869801) (xy 162.708481 -317.913378) (xy 162.678916 -317.952722) (xy 162.643423 -317.986814)
			(xy 162.60292 -318.01477) (xy 162.558458 -318.035868) (xy 162.511187 -318.04956) (xy 162.462332 -318.055492)
			(xy 162.413157 -318.053511) (xy 162.364938 -318.043667) (xy 162.318922 -318.026215) (xy 162.276301 -318.001608)
			(xy 162.23818 -317.970483) (xy 162.205545 -317.933646) (xy 162.179242 -317.89205) (xy 162.159951 -317.846774)
			(xy 162.148174 -317.79899) (xy 162.144214 -317.749936) (xy 160.855152 -317.749936) (xy 160.854657 -317.774543)
			(xy 160.846762 -317.82312) (xy 160.831178 -317.869801) (xy 160.808307 -317.913378) (xy 160.778742 -317.952722)
			(xy 160.743249 -317.986814) (xy 160.702746 -318.01477) (xy 160.658284 -318.035868) (xy 160.611013 -318.04956)
			(xy 160.562158 -318.055492) (xy 160.512983 -318.053511) (xy 160.464764 -318.043667) (xy 160.418748 -318.026215)
			(xy 160.376127 -318.001608) (xy 160.338006 -317.970483) (xy 160.305371 -317.933646) (xy 160.279068 -317.89205)
			(xy 160.259777 -317.846774) (xy 160.248 -317.79899) (xy 160.24404 -317.749936) (xy 159.930592 -317.749936)
			(xy 159.930116 -317.775458) (xy 159.922267 -317.825895) (xy 159.906761 -317.874527) (xy 159.883967 -317.920199)
			(xy 159.854426 -317.961826) (xy 159.818839 -317.998419) (xy 159.778052 -318.029109) (xy 159.733033 -318.053168)
			(xy 159.684852 -318.070023) (xy 159.659828 -318.075056) (xy 159.648994 -318.077589) (xy 159.630856 -318.090429)
			(xy 159.619867 -318.109744) (xy 159.618426 -318.120776) (xy 159.616348 -318.144649) (xy 159.610123 -318.192169)
			(xy 159.60598 -318.215772) (xy 159.60525 -318.220315) (xy 159.605253 -318.229516) (xy 159.60598 -318.23406)
			(xy 159.610109 -318.257665) (xy 159.616333 -318.305184) (xy 159.618426 -318.329056) (xy 159.619939 -318.340059)
			(xy 159.630956 -318.359317) (xy 159.649028 -318.372187) (xy 159.659828 -318.374776) (xy 159.684851 -318.379844)
			(xy 159.733055 -318.396661) (xy 159.778098 -318.420693) (xy 159.818907 -318.45137) (xy 159.85451 -318.48796)
			(xy 159.88406 -318.529591) (xy 159.906853 -318.575274) (xy 159.922347 -318.623919) (xy 159.930171 -318.674369)
			(xy 159.930592 -318.699896) (xy 160.24404 -318.699896) (xy 160.248 -318.650842) (xy 160.259777 -318.603058)
			(xy 160.279068 -318.557782) (xy 160.305371 -318.516186) (xy 160.338006 -318.479349) (xy 160.376127 -318.448224)
			(xy 160.418748 -318.423617) (xy 160.464764 -318.406165) (xy 160.512983 -318.396321) (xy 160.562158 -318.39434)
			(xy 160.611013 -318.400272) (xy 160.658284 -318.413964) (xy 160.702746 -318.435062) (xy 160.743249 -318.463018)
			(xy 160.778742 -318.49711) (xy 160.808307 -318.536454) (xy 160.831178 -318.580031) (xy 160.846762 -318.626712)
			(xy 160.854657 -318.675289) (xy 160.855152 -318.699896) (xy 162.144214 -318.699896) (xy 162.148174 -318.650842)
			(xy 162.159951 -318.603058) (xy 162.179242 -318.557782) (xy 162.205545 -318.516186) (xy 162.23818 -318.479349)
			(xy 162.276301 -318.448224) (xy 162.318922 -318.423617) (xy 162.364938 -318.406165) (xy 162.413157 -318.396321)
			(xy 162.462332 -318.39434) (xy 162.511187 -318.400272) (xy 162.558458 -318.413964) (xy 162.60292 -318.435062)
			(xy 162.643423 -318.463018) (xy 162.678916 -318.49711) (xy 162.708481 -318.536454) (xy 162.731352 -318.580031)
			(xy 162.746936 -318.626712) (xy 162.754831 -318.675289) (xy 162.755326 -318.699896) (xy 164.044134 -318.699896)
			(xy 164.048094 -318.650842) (xy 164.059871 -318.603058) (xy 164.079162 -318.557782) (xy 164.105465 -318.516186)
			(xy 164.1381 -318.479349) (xy 164.176221 -318.448224) (xy 164.218842 -318.423617) (xy 164.264858 -318.406165)
			(xy 164.313077 -318.396321) (xy 164.362252 -318.39434) (xy 164.411107 -318.400272) (xy 164.458378 -318.413964)
			(xy 164.50284 -318.435062) (xy 164.543343 -318.463018) (xy 164.578836 -318.49711) (xy 164.608401 -318.536454)
			(xy 164.631272 -318.580031) (xy 164.646856 -318.626712) (xy 164.654751 -318.675289) (xy 164.655246 -318.699896)
			(xy 165.944054 -318.699896) (xy 165.948014 -318.650842) (xy 165.959791 -318.603058) (xy 165.979082 -318.557782)
			(xy 166.005385 -318.516186) (xy 166.03802 -318.479349) (xy 166.076141 -318.448224) (xy 166.118762 -318.423617)
			(xy 166.164778 -318.406165) (xy 166.212997 -318.396321) (xy 166.262172 -318.39434) (xy 166.311027 -318.400272)
			(xy 166.358298 -318.413964) (xy 166.40276 -318.435062) (xy 166.443263 -318.463018) (xy 166.478756 -318.49711)
			(xy 166.508321 -318.536454) (xy 166.531192 -318.580031) (xy 166.546776 -318.626712) (xy 166.554671 -318.675289)
			(xy 166.555166 -318.699896) (xy 166.554671 -318.724503) (xy 166.554492 -318.725604) (xy 167.823384 -318.725604)
			(xy 167.823384 -318.674188) (xy 167.831427 -318.623406) (xy 167.847315 -318.574507) (xy 167.870658 -318.528695)
			(xy 167.900879 -318.487099) (xy 167.937235 -318.450743) (xy 167.978831 -318.420522) (xy 168.024643 -318.397179)
			(xy 168.073542 -318.381291) (xy 168.124324 -318.373248) (xy 168.17574 -318.373248) (xy 168.226522 -318.381291)
			(xy 168.275421 -318.397179) (xy 168.321233 -318.420522) (xy 168.362829 -318.450743) (xy 168.399185 -318.487099)
			(xy 168.429406 -318.528695) (xy 168.452749 -318.574507) (xy 168.468637 -318.623406) (xy 168.47668 -318.674188)
			(xy 168.477184 -318.699896) (xy 168.47668 -318.725604) (xy 169.723304 -318.725604) (xy 169.723304 -318.674188)
			(xy 169.731347 -318.623406) (xy 169.747235 -318.574507) (xy 169.770578 -318.528695) (xy 169.800799 -318.487099)
			(xy 169.837155 -318.450743) (xy 169.878751 -318.420522) (xy 169.924563 -318.397179) (xy 169.973462 -318.381291)
			(xy 170.024244 -318.373248) (xy 170.07566 -318.373248) (xy 170.126442 -318.381291) (xy 170.175341 -318.397179)
			(xy 170.221153 -318.420522) (xy 170.262749 -318.450743) (xy 170.299105 -318.487099) (xy 170.329326 -318.528695)
			(xy 170.352669 -318.574507) (xy 170.368557 -318.623406) (xy 170.3766 -318.674188) (xy 170.377104 -318.699896)
			(xy 170.3766 -318.725604) (xy 171.623224 -318.725604) (xy 171.623224 -318.674188) (xy 171.631267 -318.623406)
			(xy 171.647155 -318.574507) (xy 171.670498 -318.528695) (xy 171.700719 -318.487099) (xy 171.737075 -318.450743)
			(xy 171.778671 -318.420522) (xy 171.824483 -318.397179) (xy 171.873382 -318.381291) (xy 171.924164 -318.373248)
			(xy 171.97558 -318.373248) (xy 172.026362 -318.381291) (xy 172.075261 -318.397179) (xy 172.121073 -318.420522)
			(xy 172.162669 -318.450743) (xy 172.199025 -318.487099) (xy 172.229246 -318.528695) (xy 172.252589 -318.574507)
			(xy 172.268477 -318.623406) (xy 172.27652 -318.674188) (xy 172.277024 -318.699896) (xy 172.27652 -318.725604)
			(xy 173.523398 -318.725604) (xy 173.523398 -318.674188) (xy 173.531441 -318.623406) (xy 173.547329 -318.574507)
			(xy 173.570672 -318.528695) (xy 173.600893 -318.487099) (xy 173.637249 -318.450743) (xy 173.678845 -318.420522)
			(xy 173.724657 -318.397179) (xy 173.773556 -318.381291) (xy 173.824338 -318.373248) (xy 173.875754 -318.373248)
			(xy 173.926536 -318.381291) (xy 173.975435 -318.397179) (xy 174.021247 -318.420522) (xy 174.062843 -318.450743)
			(xy 174.099199 -318.487099) (xy 174.12942 -318.528695) (xy 174.152763 -318.574507) (xy 174.168651 -318.623406)
			(xy 174.176694 -318.674188) (xy 174.177198 -318.699896) (xy 174.176694 -318.725604) (xy 175.423318 -318.725604)
			(xy 175.423318 -318.674188) (xy 175.431361 -318.623406) (xy 175.447249 -318.574507) (xy 175.470592 -318.528695)
			(xy 175.500813 -318.487099) (xy 175.537169 -318.450743) (xy 175.578765 -318.420522) (xy 175.624577 -318.397179)
			(xy 175.673476 -318.381291) (xy 175.724258 -318.373248) (xy 175.775674 -318.373248) (xy 175.826456 -318.381291)
			(xy 175.875355 -318.397179) (xy 175.921167 -318.420522) (xy 175.962763 -318.450743) (xy 175.999119 -318.487099)
			(xy 176.02934 -318.528695) (xy 176.052683 -318.574507) (xy 176.068571 -318.623406) (xy 176.076614 -318.674188)
			(xy 176.077118 -318.699896) (xy 176.076614 -318.725604) (xy 177.323238 -318.725604) (xy 177.323238 -318.674188)
			(xy 177.331281 -318.623406) (xy 177.347169 -318.574507) (xy 177.370512 -318.528695) (xy 177.400733 -318.487099)
			(xy 177.437089 -318.450743) (xy 177.478685 -318.420522) (xy 177.524497 -318.397179) (xy 177.573396 -318.381291)
			(xy 177.624178 -318.373248) (xy 177.675594 -318.373248) (xy 177.726376 -318.381291) (xy 177.775275 -318.397179)
			(xy 177.821087 -318.420522) (xy 177.862683 -318.450743) (xy 177.899039 -318.487099) (xy 177.92926 -318.528695)
			(xy 177.952603 -318.574507) (xy 177.968491 -318.623406) (xy 177.976534 -318.674188) (xy 177.977038 -318.699896)
			(xy 177.976534 -318.725604) (xy 179.223412 -318.725604) (xy 179.223412 -318.674188) (xy 179.231455 -318.623406)
			(xy 179.247343 -318.574507) (xy 179.270686 -318.528695) (xy 179.300907 -318.487099) (xy 179.337263 -318.450743)
			(xy 179.378859 -318.420522) (xy 179.424671 -318.397179) (xy 179.47357 -318.381291) (xy 179.524352 -318.373248)
			(xy 179.575768 -318.373248) (xy 179.62655 -318.381291) (xy 179.675449 -318.397179) (xy 179.721261 -318.420522)
			(xy 179.762857 -318.450743) (xy 179.799213 -318.487099) (xy 179.829434 -318.528695) (xy 179.852777 -318.574507)
			(xy 179.868665 -318.623406) (xy 179.876708 -318.674188) (xy 179.877212 -318.699896) (xy 179.876708 -318.725604)
			(xy 181.123332 -318.725604) (xy 181.123332 -318.674188) (xy 181.131375 -318.623406) (xy 181.147263 -318.574507)
			(xy 181.170606 -318.528695) (xy 181.200827 -318.487099) (xy 181.237183 -318.450743) (xy 181.278779 -318.420522)
			(xy 181.324591 -318.397179) (xy 181.37349 -318.381291) (xy 181.424272 -318.373248) (xy 181.475688 -318.373248)
			(xy 181.52647 -318.381291) (xy 181.575369 -318.397179) (xy 181.621181 -318.420522) (xy 181.662777 -318.450743)
			(xy 181.699133 -318.487099) (xy 181.729354 -318.528695) (xy 181.752697 -318.574507) (xy 181.768585 -318.623406)
			(xy 181.776628 -318.674188) (xy 181.777132 -318.699896) (xy 183.044096 -318.699896) (xy 183.048056 -318.650842)
			(xy 183.059833 -318.603058) (xy 183.079124 -318.557782) (xy 183.105427 -318.516186) (xy 183.138062 -318.479349)
			(xy 183.176183 -318.448224) (xy 183.218804 -318.423617) (xy 183.26482 -318.406165) (xy 183.313039 -318.396321)
			(xy 183.362214 -318.39434) (xy 183.411069 -318.400272) (xy 183.45834 -318.413964) (xy 183.502802 -318.435062)
			(xy 183.543305 -318.463018) (xy 183.578798 -318.49711) (xy 183.608363 -318.536454) (xy 183.631234 -318.580031)
			(xy 183.646818 -318.626712) (xy 183.654713 -318.675289) (xy 183.655208 -318.699896) (xy 184.94427 -318.699896)
			(xy 184.94823 -318.650842) (xy 184.960007 -318.603058) (xy 184.979298 -318.557782) (xy 185.005601 -318.516186)
			(xy 185.038236 -318.479349) (xy 185.076357 -318.448224) (xy 185.118978 -318.423617) (xy 185.164994 -318.406165)
			(xy 185.213213 -318.396321) (xy 185.262388 -318.39434) (xy 185.311243 -318.400272) (xy 185.358514 -318.413964)
			(xy 185.402976 -318.435062) (xy 185.443479 -318.463018) (xy 185.478972 -318.49711) (xy 185.508537 -318.536454)
			(xy 185.531408 -318.580031) (xy 185.546992 -318.626712) (xy 185.554887 -318.675289) (xy 185.555382 -318.699896)
			(xy 186.84419 -318.699896) (xy 186.84815 -318.650842) (xy 186.859927 -318.603058) (xy 186.879218 -318.557782)
			(xy 186.905521 -318.516186) (xy 186.938156 -318.479349) (xy 186.976277 -318.448224) (xy 187.018898 -318.423617)
			(xy 187.064914 -318.406165) (xy 187.113133 -318.396321) (xy 187.162308 -318.39434) (xy 187.211163 -318.400272)
			(xy 187.258434 -318.413964) (xy 187.302896 -318.435062) (xy 187.343399 -318.463018) (xy 187.378892 -318.49711)
			(xy 187.408457 -318.536454) (xy 187.431328 -318.580031) (xy 187.446912 -318.626712) (xy 187.454807 -318.675289)
			(xy 187.455302 -318.699896) (xy 188.74411 -318.699896) (xy 188.74807 -318.650842) (xy 188.759847 -318.603058)
			(xy 188.779138 -318.557782) (xy 188.805441 -318.516186) (xy 188.838076 -318.479349) (xy 188.876197 -318.448224)
			(xy 188.918818 -318.423617) (xy 188.964834 -318.406165) (xy 189.013053 -318.396321) (xy 189.062228 -318.39434)
			(xy 189.111083 -318.400272) (xy 189.158354 -318.413964) (xy 189.202816 -318.435062) (xy 189.243319 -318.463018)
			(xy 189.278812 -318.49711) (xy 189.308377 -318.536454) (xy 189.331248 -318.580031) (xy 189.346832 -318.626712)
			(xy 189.354727 -318.675289) (xy 189.355222 -318.699896) (xy 189.354727 -318.724503) (xy 189.354548 -318.725604)
			(xy 190.62344 -318.725604) (xy 190.62344 -318.674188) (xy 190.631483 -318.623406) (xy 190.647371 -318.574507)
			(xy 190.670714 -318.528695) (xy 190.700935 -318.487099) (xy 190.737291 -318.450743) (xy 190.778887 -318.420522)
			(xy 190.824699 -318.397179) (xy 190.873598 -318.381291) (xy 190.92438 -318.373248) (xy 190.975796 -318.373248)
			(xy 191.026578 -318.381291) (xy 191.075477 -318.397179) (xy 191.121289 -318.420522) (xy 191.162885 -318.450743)
			(xy 191.199241 -318.487099) (xy 191.229462 -318.528695) (xy 191.252805 -318.574507) (xy 191.268693 -318.623406)
			(xy 191.276736 -318.674188) (xy 191.27724 -318.699896) (xy 191.276736 -318.725604) (xy 192.52336 -318.725604)
			(xy 192.52336 -318.674188) (xy 192.531403 -318.623406) (xy 192.547291 -318.574507) (xy 192.570634 -318.528695)
			(xy 192.600855 -318.487099) (xy 192.637211 -318.450743) (xy 192.678807 -318.420522) (xy 192.724619 -318.397179)
			(xy 192.773518 -318.381291) (xy 192.8243 -318.373248) (xy 192.875716 -318.373248) (xy 192.926498 -318.381291)
			(xy 192.975397 -318.397179) (xy 193.021209 -318.420522) (xy 193.062805 -318.450743) (xy 193.099161 -318.487099)
			(xy 193.129382 -318.528695) (xy 193.152725 -318.574507) (xy 193.168613 -318.623406) (xy 193.176656 -318.674188)
			(xy 193.17716 -318.699896) (xy 193.176656 -318.725604) (xy 194.42328 -318.725604) (xy 194.42328 -318.674188)
			(xy 194.431323 -318.623406) (xy 194.447211 -318.574507) (xy 194.470554 -318.528695) (xy 194.500775 -318.487099)
			(xy 194.537131 -318.450743) (xy 194.578727 -318.420522) (xy 194.624539 -318.397179) (xy 194.673438 -318.381291)
			(xy 194.72422 -318.373248) (xy 194.775636 -318.373248) (xy 194.826418 -318.381291) (xy 194.875317 -318.397179)
			(xy 194.921129 -318.420522) (xy 194.962725 -318.450743) (xy 194.999081 -318.487099) (xy 195.029302 -318.528695)
			(xy 195.052645 -318.574507) (xy 195.068533 -318.623406) (xy 195.076576 -318.674188) (xy 195.07708 -318.699896)
			(xy 195.076576 -318.725604) (xy 196.3232 -318.725604) (xy 196.3232 -318.674188) (xy 196.331243 -318.623406)
			(xy 196.347131 -318.574507) (xy 196.370474 -318.528695) (xy 196.400695 -318.487099) (xy 196.437051 -318.450743)
			(xy 196.478647 -318.420522) (xy 196.524459 -318.397179) (xy 196.573358 -318.381291) (xy 196.62414 -318.373248)
			(xy 196.675556 -318.373248) (xy 196.726338 -318.381291) (xy 196.775237 -318.397179) (xy 196.821049 -318.420522)
			(xy 196.862645 -318.450743) (xy 196.899001 -318.487099) (xy 196.929222 -318.528695) (xy 196.952565 -318.574507)
			(xy 196.968453 -318.623406) (xy 196.976496 -318.674188) (xy 196.977 -318.699896) (xy 196.976496 -318.725604)
			(xy 196.968453 -318.776386) (xy 196.952565 -318.825285) (xy 196.929222 -318.871097) (xy 196.899001 -318.912693)
			(xy 196.862645 -318.949049) (xy 196.821049 -318.97927) (xy 196.775237 -319.002613) (xy 196.726338 -319.018501)
			(xy 196.675556 -319.026544) (xy 196.62414 -319.026544) (xy 196.573358 -319.018501) (xy 196.524459 -319.002613)
			(xy 196.478647 -318.97927) (xy 196.437051 -318.949049) (xy 196.400695 -318.912693) (xy 196.370474 -318.871097)
			(xy 196.347131 -318.825285) (xy 196.331243 -318.776386) (xy 196.3232 -318.725604) (xy 195.076576 -318.725604)
			(xy 195.068533 -318.776386) (xy 195.052645 -318.825285) (xy 195.029302 -318.871097) (xy 194.999081 -318.912693)
			(xy 194.962725 -318.949049) (xy 194.921129 -318.97927) (xy 194.875317 -319.002613) (xy 194.826418 -319.018501)
			(xy 194.775636 -319.026544) (xy 194.72422 -319.026544) (xy 194.673438 -319.018501) (xy 194.624539 -319.002613)
			(xy 194.578727 -318.97927) (xy 194.537131 -318.949049) (xy 194.500775 -318.912693) (xy 194.470554 -318.871097)
			(xy 194.447211 -318.825285) (xy 194.431323 -318.776386) (xy 194.42328 -318.725604) (xy 193.176656 -318.725604)
			(xy 193.168613 -318.776386) (xy 193.152725 -318.825285) (xy 193.129382 -318.871097) (xy 193.099161 -318.912693)
			(xy 193.062805 -318.949049) (xy 193.021209 -318.97927) (xy 192.975397 -319.002613) (xy 192.926498 -319.018501)
			(xy 192.875716 -319.026544) (xy 192.8243 -319.026544) (xy 192.773518 -319.018501) (xy 192.724619 -319.002613)
			(xy 192.678807 -318.97927) (xy 192.637211 -318.949049) (xy 192.600855 -318.912693) (xy 192.570634 -318.871097)
			(xy 192.547291 -318.825285) (xy 192.531403 -318.776386) (xy 192.52336 -318.725604) (xy 191.276736 -318.725604)
			(xy 191.268693 -318.776386) (xy 191.252805 -318.825285) (xy 191.229462 -318.871097) (xy 191.199241 -318.912693)
			(xy 191.162885 -318.949049) (xy 191.121289 -318.97927) (xy 191.075477 -319.002613) (xy 191.026578 -319.018501)
			(xy 190.975796 -319.026544) (xy 190.92438 -319.026544) (xy 190.873598 -319.018501) (xy 190.824699 -319.002613)
			(xy 190.778887 -318.97927) (xy 190.737291 -318.949049) (xy 190.700935 -318.912693) (xy 190.670714 -318.871097)
			(xy 190.647371 -318.825285) (xy 190.631483 -318.776386) (xy 190.62344 -318.725604) (xy 189.354548 -318.725604)
			(xy 189.346832 -318.77308) (xy 189.331248 -318.819761) (xy 189.308377 -318.863338) (xy 189.278812 -318.902682)
			(xy 189.243319 -318.936774) (xy 189.202816 -318.96473) (xy 189.158354 -318.985828) (xy 189.111083 -318.99952)
			(xy 189.062228 -319.005452) (xy 189.013053 -319.003471) (xy 188.964834 -318.993627) (xy 188.918818 -318.976175)
			(xy 188.876197 -318.951568) (xy 188.838076 -318.920443) (xy 188.805441 -318.883606) (xy 188.779138 -318.84201)
			(xy 188.759847 -318.796734) (xy 188.74807 -318.74895) (xy 188.74411 -318.699896) (xy 187.455302 -318.699896)
			(xy 187.454807 -318.724503) (xy 187.446912 -318.77308) (xy 187.431328 -318.819761) (xy 187.408457 -318.863338)
			(xy 187.378892 -318.902682) (xy 187.343399 -318.936774) (xy 187.302896 -318.96473) (xy 187.258434 -318.985828)
			(xy 187.211163 -318.99952) (xy 187.162308 -319.005452) (xy 187.113133 -319.003471) (xy 187.064914 -318.993627)
			(xy 187.018898 -318.976175) (xy 186.976277 -318.951568) (xy 186.938156 -318.920443) (xy 186.905521 -318.883606)
			(xy 186.879218 -318.84201) (xy 186.859927 -318.796734) (xy 186.84815 -318.74895) (xy 186.84419 -318.699896)
			(xy 185.555382 -318.699896) (xy 185.554887 -318.724503) (xy 185.546992 -318.77308) (xy 185.531408 -318.819761)
			(xy 185.508537 -318.863338) (xy 185.478972 -318.902682) (xy 185.443479 -318.936774) (xy 185.402976 -318.96473)
			(xy 185.358514 -318.985828) (xy 185.311243 -318.99952) (xy 185.262388 -319.005452) (xy 185.213213 -319.003471)
			(xy 185.164994 -318.993627) (xy 185.118978 -318.976175) (xy 185.076357 -318.951568) (xy 185.038236 -318.920443)
			(xy 185.005601 -318.883606) (xy 184.979298 -318.84201) (xy 184.960007 -318.796734) (xy 184.94823 -318.74895)
			(xy 184.94427 -318.699896) (xy 183.655208 -318.699896) (xy 183.654713 -318.724503) (xy 183.646818 -318.77308)
			(xy 183.631234 -318.819761) (xy 183.608363 -318.863338) (xy 183.578798 -318.902682) (xy 183.543305 -318.936774)
			(xy 183.502802 -318.96473) (xy 183.45834 -318.985828) (xy 183.411069 -318.99952) (xy 183.362214 -319.005452)
			(xy 183.313039 -319.003471) (xy 183.26482 -318.993627) (xy 183.218804 -318.976175) (xy 183.176183 -318.951568)
			(xy 183.138062 -318.920443) (xy 183.105427 -318.883606) (xy 183.079124 -318.84201) (xy 183.059833 -318.796734)
			(xy 183.048056 -318.74895) (xy 183.044096 -318.699896) (xy 181.777132 -318.699896) (xy 181.776628 -318.725604)
			(xy 181.768585 -318.776386) (xy 181.752697 -318.825285) (xy 181.729354 -318.871097) (xy 181.699133 -318.912693)
			(xy 181.662777 -318.949049) (xy 181.621181 -318.97927) (xy 181.575369 -319.002613) (xy 181.52647 -319.018501)
			(xy 181.475688 -319.026544) (xy 181.424272 -319.026544) (xy 181.37349 -319.018501) (xy 181.324591 -319.002613)
			(xy 181.278779 -318.97927) (xy 181.237183 -318.949049) (xy 181.200827 -318.912693) (xy 181.170606 -318.871097)
			(xy 181.147263 -318.825285) (xy 181.131375 -318.776386) (xy 181.123332 -318.725604) (xy 179.876708 -318.725604)
			(xy 179.868665 -318.776386) (xy 179.852777 -318.825285) (xy 179.829434 -318.871097) (xy 179.799213 -318.912693)
			(xy 179.762857 -318.949049) (xy 179.721261 -318.97927) (xy 179.675449 -319.002613) (xy 179.62655 -319.018501)
			(xy 179.575768 -319.026544) (xy 179.524352 -319.026544) (xy 179.47357 -319.018501) (xy 179.424671 -319.002613)
			(xy 179.378859 -318.97927) (xy 179.337263 -318.949049) (xy 179.300907 -318.912693) (xy 179.270686 -318.871097)
			(xy 179.247343 -318.825285) (xy 179.231455 -318.776386) (xy 179.223412 -318.725604) (xy 177.976534 -318.725604)
			(xy 177.968491 -318.776386) (xy 177.952603 -318.825285) (xy 177.92926 -318.871097) (xy 177.899039 -318.912693)
			(xy 177.862683 -318.949049) (xy 177.821087 -318.97927) (xy 177.775275 -319.002613) (xy 177.726376 -319.018501)
			(xy 177.675594 -319.026544) (xy 177.624178 -319.026544) (xy 177.573396 -319.018501) (xy 177.524497 -319.002613)
			(xy 177.478685 -318.97927) (xy 177.437089 -318.949049) (xy 177.400733 -318.912693) (xy 177.370512 -318.871097)
			(xy 177.347169 -318.825285) (xy 177.331281 -318.776386) (xy 177.323238 -318.725604) (xy 176.076614 -318.725604)
			(xy 176.068571 -318.776386) (xy 176.052683 -318.825285) (xy 176.02934 -318.871097) (xy 175.999119 -318.912693)
			(xy 175.962763 -318.949049) (xy 175.921167 -318.97927) (xy 175.875355 -319.002613) (xy 175.826456 -319.018501)
			(xy 175.775674 -319.026544) (xy 175.724258 -319.026544) (xy 175.673476 -319.018501) (xy 175.624577 -319.002613)
			(xy 175.578765 -318.97927) (xy 175.537169 -318.949049) (xy 175.500813 -318.912693) (xy 175.470592 -318.871097)
			(xy 175.447249 -318.825285) (xy 175.431361 -318.776386) (xy 175.423318 -318.725604) (xy 174.176694 -318.725604)
			(xy 174.168651 -318.776386) (xy 174.152763 -318.825285) (xy 174.12942 -318.871097) (xy 174.099199 -318.912693)
			(xy 174.062843 -318.949049) (xy 174.021247 -318.97927) (xy 173.975435 -319.002613) (xy 173.926536 -319.018501)
			(xy 173.875754 -319.026544) (xy 173.824338 -319.026544) (xy 173.773556 -319.018501) (xy 173.724657 -319.002613)
			(xy 173.678845 -318.97927) (xy 173.637249 -318.949049) (xy 173.600893 -318.912693) (xy 173.570672 -318.871097)
			(xy 173.547329 -318.825285) (xy 173.531441 -318.776386) (xy 173.523398 -318.725604) (xy 172.27652 -318.725604)
			(xy 172.268477 -318.776386) (xy 172.252589 -318.825285) (xy 172.229246 -318.871097) (xy 172.199025 -318.912693)
			(xy 172.162669 -318.949049) (xy 172.121073 -318.97927) (xy 172.075261 -319.002613) (xy 172.026362 -319.018501)
			(xy 171.97558 -319.026544) (xy 171.924164 -319.026544) (xy 171.873382 -319.018501) (xy 171.824483 -319.002613)
			(xy 171.778671 -318.97927) (xy 171.737075 -318.949049) (xy 171.700719 -318.912693) (xy 171.670498 -318.871097)
			(xy 171.647155 -318.825285) (xy 171.631267 -318.776386) (xy 171.623224 -318.725604) (xy 170.3766 -318.725604)
			(xy 170.368557 -318.776386) (xy 170.352669 -318.825285) (xy 170.329326 -318.871097) (xy 170.299105 -318.912693)
			(xy 170.262749 -318.949049) (xy 170.221153 -318.97927) (xy 170.175341 -319.002613) (xy 170.126442 -319.018501)
			(xy 170.07566 -319.026544) (xy 170.024244 -319.026544) (xy 169.973462 -319.018501) (xy 169.924563 -319.002613)
			(xy 169.878751 -318.97927) (xy 169.837155 -318.949049) (xy 169.800799 -318.912693) (xy 169.770578 -318.871097)
			(xy 169.747235 -318.825285) (xy 169.731347 -318.776386) (xy 169.723304 -318.725604) (xy 168.47668 -318.725604)
			(xy 168.468637 -318.776386) (xy 168.452749 -318.825285) (xy 168.429406 -318.871097) (xy 168.399185 -318.912693)
			(xy 168.362829 -318.949049) (xy 168.321233 -318.97927) (xy 168.275421 -319.002613) (xy 168.226522 -319.018501)
			(xy 168.17574 -319.026544) (xy 168.124324 -319.026544) (xy 168.073542 -319.018501) (xy 168.024643 -319.002613)
			(xy 167.978831 -318.97927) (xy 167.937235 -318.949049) (xy 167.900879 -318.912693) (xy 167.870658 -318.871097)
			(xy 167.847315 -318.825285) (xy 167.831427 -318.776386) (xy 167.823384 -318.725604) (xy 166.554492 -318.725604)
			(xy 166.546776 -318.77308) (xy 166.531192 -318.819761) (xy 166.508321 -318.863338) (xy 166.478756 -318.902682)
			(xy 166.443263 -318.936774) (xy 166.40276 -318.96473) (xy 166.358298 -318.985828) (xy 166.311027 -318.99952)
			(xy 166.262172 -319.005452) (xy 166.212997 -319.003471) (xy 166.164778 -318.993627) (xy 166.118762 -318.976175)
			(xy 166.076141 -318.951568) (xy 166.03802 -318.920443) (xy 166.005385 -318.883606) (xy 165.979082 -318.84201)
			(xy 165.959791 -318.796734) (xy 165.948014 -318.74895) (xy 165.944054 -318.699896) (xy 164.655246 -318.699896)
			(xy 164.654751 -318.724503) (xy 164.646856 -318.77308) (xy 164.631272 -318.819761) (xy 164.608401 -318.863338)
			(xy 164.578836 -318.902682) (xy 164.543343 -318.936774) (xy 164.50284 -318.96473) (xy 164.458378 -318.985828)
			(xy 164.411107 -318.99952) (xy 164.362252 -319.005452) (xy 164.313077 -319.003471) (xy 164.264858 -318.993627)
			(xy 164.218842 -318.976175) (xy 164.176221 -318.951568) (xy 164.1381 -318.920443) (xy 164.105465 -318.883606)
			(xy 164.079162 -318.84201) (xy 164.059871 -318.796734) (xy 164.048094 -318.74895) (xy 164.044134 -318.699896)
			(xy 162.755326 -318.699896) (xy 162.754831 -318.724503) (xy 162.746936 -318.77308) (xy 162.731352 -318.819761)
			(xy 162.708481 -318.863338) (xy 162.678916 -318.902682) (xy 162.643423 -318.936774) (xy 162.60292 -318.96473)
			(xy 162.558458 -318.985828) (xy 162.511187 -318.99952) (xy 162.462332 -319.005452) (xy 162.413157 -319.003471)
			(xy 162.364938 -318.993627) (xy 162.318922 -318.976175) (xy 162.276301 -318.951568) (xy 162.23818 -318.920443)
			(xy 162.205545 -318.883606) (xy 162.179242 -318.84201) (xy 162.159951 -318.796734) (xy 162.148174 -318.74895)
			(xy 162.144214 -318.699896) (xy 160.855152 -318.699896) (xy 160.854657 -318.724503) (xy 160.846762 -318.77308)
			(xy 160.831178 -318.819761) (xy 160.808307 -318.863338) (xy 160.778742 -318.902682) (xy 160.743249 -318.936774)
			(xy 160.702746 -318.96473) (xy 160.658284 -318.985828) (xy 160.611013 -318.99952) (xy 160.562158 -319.005452)
			(xy 160.512983 -319.003471) (xy 160.464764 -318.993627) (xy 160.418748 -318.976175) (xy 160.376127 -318.951568)
			(xy 160.338006 -318.920443) (xy 160.305371 -318.883606) (xy 160.279068 -318.84201) (xy 160.259777 -318.796734)
			(xy 160.248 -318.74895) (xy 160.24404 -318.699896) (xy 159.930592 -318.699896) (xy 159.930109 -318.725885)
			(xy 159.921978 -318.777223) (xy 159.905916 -318.826657) (xy 159.882318 -318.87297) (xy 159.851766 -318.91502)
			(xy 159.815011 -318.951774) (xy 159.77296 -318.982325) (xy 159.726646 -319.005921) (xy 159.677211 -319.021981)
			(xy 159.625873 -319.03011) (xy 159.599884 -319.030604) (xy 159.598868 -319.030604) (xy 159.58869 -319.031018)
			(xy 159.569902 -319.038847) (xy 159.555619 -319.053346) (xy 159.55137 -319.062608) (xy 159.530651 -319.112347)
			(xy 159.479737 -319.207313) (xy 159.44977 -319.252092) (xy 159.447543 -319.255515) (xy 159.444093 -319.262915)
			(xy 159.442912 -319.266824) (xy 159.435502 -319.290629) (xy 159.414537 -319.335862) (xy 159.387035 -319.377446)
			(xy 159.353618 -319.414444) (xy 159.315038 -319.446022) (xy 159.293814 -319.459102) (xy 159.286701 -319.463721)
			(xy 159.275798 -319.476698) (xy 159.272478 -319.484502) (xy 159.26181 -319.511934) (xy 159.258861 -319.520359)
			(xy 159.258459 -319.538191) (xy 159.261048 -319.546732) (xy 159.273611 -319.585269) (xy 159.293193 -319.663932)
			(xy 159.30633 -319.743923) (xy 159.312934 -319.824717) (xy 159.313372 -319.865248) (xy 159.313372 -320.374518)
			(xy 159.313457 -320.378929) (xy 159.314987 -320.387618) (xy 159.31642 -320.39179) (xy 159.380936 -320.571876)
			(xy 159.383005 -320.577098) (xy 159.389034 -320.586572) (xy 159.392874 -320.590672) (xy 159.702246 -320.900044)
			(xy 202.982331 -320.900044) (xy 202.98632 -320.751504) (xy 202.998277 -320.603391) (xy 203.018167 -320.456134)
			(xy 203.045932 -320.310158) (xy 203.081493 -320.165881) (xy 203.124747 -320.023722) (xy 203.175569 -319.884089)
			(xy 203.233813 -319.747386) (xy 203.299311 -319.614006) (xy 203.371874 -319.484334) (xy 203.451292 -319.358744)
			(xy 203.537337 -319.237597) (xy 203.629761 -319.121244) (xy 203.728297 -319.01002) (xy 203.832661 -318.904245)
			(xy 203.942553 -318.804225) (xy 204.057654 -318.710247) (xy 204.177634 -318.622583) (xy 204.302147 -318.541486)
			(xy 204.430833 -318.467189) (xy 204.563322 -318.399907) (xy 204.699231 -318.339833) (xy 204.838169 -318.287141)
			(xy 204.979735 -318.241982) (xy 205.123521 -318.204487) (xy 205.269112 -318.174765) (xy 205.416088 -318.1529)
			(xy 205.564027 -318.138956) (xy 205.7125 -318.132972) (xy 205.861081 -318.134967) (xy 206.00934 -318.144935)
			(xy 206.156851 -318.162846) (xy 206.303187 -318.188649) (xy 206.447928 -318.222269) (xy 206.590655 -318.263611)
			(xy 206.730958 -318.312554) (xy 206.868431 -318.368957) (xy 207.002678 -318.432658) (xy 207.133313 -318.503474)
			(xy 207.259958 -318.581199) (xy 207.382248 -318.66561) (xy 207.499831 -318.756463) (xy 207.612368 -318.853497)
			(xy 207.719535 -318.956432) (xy 207.821022 -319.064971) (xy 207.916536 -319.1788) (xy 208.005803 -319.297593)
			(xy 208.088564 -319.421005) (xy 208.164582 -319.548683) (xy 208.233637 -319.680256) (xy 208.29553 -319.815347)
			(xy 208.350083 -319.953564) (xy 208.397138 -320.094511) (xy 208.43656 -320.237781) (xy 208.468234 -320.38296)
			(xy 208.49207 -320.529629) (xy 208.507999 -320.677367) (xy 208.515975 -320.825747) (xy 208.516474 -320.900044)
			(xy 208.515975 -320.974341) (xy 208.507999 -321.122721) (xy 208.49207 -321.270459) (xy 208.468234 -321.417128)
			(xy 208.43656 -321.562307) (xy 208.397138 -321.705577) (xy 208.350083 -321.846524) (xy 208.29553 -321.984741)
			(xy 208.233637 -322.119832) (xy 208.164582 -322.251405) (xy 208.088564 -322.379083) (xy 208.005803 -322.502495)
			(xy 207.916536 -322.621288) (xy 207.821022 -322.735117) (xy 207.719535 -322.843656) (xy 207.612368 -322.946591)
			(xy 207.499831 -323.043625) (xy 207.382248 -323.134478) (xy 207.259958 -323.218889) (xy 207.133313 -323.296614)
			(xy 207.002678 -323.36743) (xy 206.868431 -323.431131) (xy 206.730958 -323.487534) (xy 206.590655 -323.536477)
			(xy 206.447928 -323.577819) (xy 206.303187 -323.611439) (xy 206.156851 -323.637242) (xy 206.00934 -323.655153)
			(xy 205.861081 -323.665121) (xy 205.7125 -323.667116) (xy 205.564027 -323.661132) (xy 205.416088 -323.647188)
			(xy 205.269112 -323.625323) (xy 205.123521 -323.595601) (xy 204.979735 -323.558106) (xy 204.838169 -323.512947)
			(xy 204.699231 -323.460255) (xy 204.563322 -323.400181) (xy 204.430833 -323.332899) (xy 204.302147 -323.258602)
			(xy 204.177634 -323.177505) (xy 204.057654 -323.089841) (xy 203.942553 -322.995863) (xy 203.832661 -322.895843)
			(xy 203.728297 -322.790068) (xy 203.629761 -322.678844) (xy 203.537337 -322.562491) (xy 203.451292 -322.441344)
			(xy 203.371874 -322.315754) (xy 203.299311 -322.186082) (xy 203.233813 -322.052702) (xy 203.175569 -321.915999)
			(xy 203.124747 -321.776366) (xy 203.081493 -321.634207) (xy 203.045932 -321.48993) (xy 203.018167 -321.343954)
			(xy 202.998277 -321.196697) (xy 202.98632 -321.048584) (xy 202.982331 -320.900044) (xy 159.702246 -320.900044)
			(xy 169.213784 -330.411582) (xy 221.258892 -330.411582) (xy 221.259349 -330.384211) (xy 221.26717 -330.330032)
			(xy 221.282661 -330.277529) (xy 221.305504 -330.227782) (xy 221.33523 -330.181816) (xy 221.352872 -330.160884)
			(xy 221.353126 -330.16063) (xy 221.358709 -330.153541) (xy 221.364957 -330.136626) (xy 221.365318 -330.12761)
			(xy 221.365318 -330.060554) (xy 221.364931 -330.05154) (xy 221.358704 -330.034623) (xy 221.353126 -330.027534)
			(xy 221.352872 -330.027534) (xy 221.352872 -330.02728) (xy 221.335253 -330.006332) (xy 221.305539 -329.960363)
			(xy 221.282699 -329.91062) (xy 221.267204 -329.858123) (xy 221.259369 -329.80395) (xy 221.258892 -329.776582)
			(xy 221.259378 -329.749331) (xy 221.267134 -329.695383) (xy 221.282489 -329.643088) (xy 221.305131 -329.593511)
			(xy 221.334597 -329.547661) (xy 221.370288 -329.50647) (xy 221.411479 -329.470779) (xy 221.457329 -329.441313)
			(xy 221.506906 -329.418671) (xy 221.559201 -329.403316) (xy 221.613149 -329.39556) (xy 221.667651 -329.39556)
			(xy 221.721599 -329.403316) (xy 221.773894 -329.418671) (xy 221.823471 -329.441313) (xy 221.869321 -329.470779)
			(xy 221.910512 -329.50647) (xy 221.946203 -329.547661) (xy 221.975669 -329.593511) (xy 221.998311 -329.643088)
			(xy 222.013666 -329.695383) (xy 222.021422 -329.749331) (xy 222.021908 -329.776582) (xy 222.021429 -329.803952)
			(xy 222.013614 -329.85813) (xy 221.998128 -329.910633) (xy 221.975289 -329.96038) (xy 221.945568 -330.006348)
			(xy 221.927928 -330.02728) (xy 221.927674 -330.027534) (xy 221.922106 -330.034633) (xy 221.915849 -330.05154)
			(xy 221.915482 -330.060554) (xy 221.915482 -330.12761) (xy 221.915838 -330.136627) (xy 221.922087 -330.153544)
			(xy 221.927674 -330.16063) (xy 221.927928 -330.16063) (xy 221.927928 -330.160884) (xy 221.945577 -330.181808)
			(xy 221.975287 -330.227783) (xy 221.99812 -330.277533) (xy 222.013609 -330.330035) (xy 222.021435 -330.384212)
			(xy 222.021908 -330.411582) (xy 222.021422 -330.438833) (xy 222.013666 -330.492781) (xy 221.998311 -330.545076)
			(xy 221.975669 -330.594653) (xy 221.946203 -330.640503) (xy 221.910512 -330.681694) (xy 221.869321 -330.717385)
			(xy 221.823471 -330.746851) (xy 221.773894 -330.769493) (xy 221.721599 -330.784848) (xy 221.667651 -330.792604)
			(xy 221.613149 -330.792604) (xy 221.559201 -330.784848) (xy 221.506906 -330.769493) (xy 221.457329 -330.746851)
			(xy 221.411479 -330.717385) (xy 221.370288 -330.681694) (xy 221.334597 -330.640503) (xy 221.305131 -330.594653)
			(xy 221.282489 -330.545076) (xy 221.267134 -330.492781) (xy 221.259378 -330.438833) (xy 221.258892 -330.411582)
			(xy 169.213784 -330.411582) (xy 174.200312 -335.39811) (xy 174.207166 -335.405505) (xy 174.214911 -335.424104)
			(xy 174.215298 -335.434178) (xy 174.215298 -338.84362) (xy 201.544174 -338.84362) (xy 201.544663 -338.817307)
			(xy 201.551895 -338.76518) (xy 201.56621 -338.714538) (xy 201.587339 -338.666339) (xy 201.61488 -338.621495)
			(xy 201.648315 -338.580854) (xy 201.667364 -338.562696) (xy 201.674764 -338.555173) (xy 201.683291 -338.535894)
			(xy 201.683874 -338.525358) (xy 201.683874 -338.450682) (xy 201.683322 -338.440135) (xy 201.674804 -338.420839)
			(xy 201.667364 -338.413344) (xy 201.648281 -338.395216) (xy 201.614828 -338.354579) (xy 201.587274 -338.309733)
			(xy 201.56614 -338.261527) (xy 201.551828 -338.210875) (xy 201.544609 -338.158738) (xy 201.544174 -338.13242)
			(xy 201.54466 -338.105169) (xy 201.552416 -338.051221) (xy 201.567771 -337.998926) (xy 201.590413 -337.949349)
			(xy 201.619879 -337.903499) (xy 201.65557 -337.862308) (xy 201.696761 -337.826617) (xy 201.742611 -337.797151)
			(xy 201.792188 -337.774509) (xy 201.844483 -337.759154) (xy 201.898431 -337.751398) (xy 201.952933 -337.751398)
			(xy 202.006881 -337.759154) (xy 202.059176 -337.774509) (xy 202.108753 -337.797151) (xy 202.154603 -337.826617)
			(xy 202.195794 -337.862308) (xy 202.231485 -337.903499) (xy 202.260951 -337.949349) (xy 202.283593 -337.998926)
			(xy 202.298948 -338.051221) (xy 202.306704 -338.105169) (xy 202.30719 -338.13242) (xy 202.306739 -338.158735)
			(xy 202.299501 -338.210864) (xy 202.285179 -338.261507) (xy 202.264044 -338.309706) (xy 202.236495 -338.354549)
			(xy 202.203053 -338.395188) (xy 202.184 -338.413344) (xy 202.176577 -338.420847) (xy 202.168065 -338.440141)
			(xy 202.16749 -338.450682) (xy 202.16749 -338.525358) (xy 202.168031 -338.535906) (xy 202.176558 -338.555202)
			(xy 202.184 -338.562696) (xy 202.203047 -338.580861) (xy 202.236505 -338.621488) (xy 202.264065 -338.666327)
			(xy 202.285205 -338.714526) (xy 202.299524 -338.765172) (xy 202.30675 -338.817304) (xy 202.30719 -338.84362)
			(xy 202.306704 -338.870871) (xy 202.298948 -338.924819) (xy 202.283593 -338.977114) (xy 202.260951 -339.026691)
			(xy 202.231485 -339.072541) (xy 202.195794 -339.113732) (xy 202.154603 -339.149423) (xy 202.108753 -339.178889)
			(xy 202.059176 -339.201531) (xy 202.006881 -339.216886) (xy 201.952933 -339.224642) (xy 201.898431 -339.224642)
			(xy 201.844483 -339.216886) (xy 201.792188 -339.201531) (xy 201.742611 -339.178889) (xy 201.696761 -339.149423)
			(xy 201.65557 -339.113732) (xy 201.619879 -339.072541) (xy 201.590413 -339.026691) (xy 201.567771 -338.977114)
			(xy 201.552416 -338.924819) (xy 201.54466 -338.870871) (xy 201.544174 -338.84362) (xy 174.215298 -338.84362)
			(xy 174.215298 -340.77402) (xy 174.215495 -340.780687) (xy 174.218975 -340.793557) (xy 174.222156 -340.79942)
			(xy 174.267114 -340.864952) (xy 174.637446 -341.404956) (xy 174.643796 -341.414354) (xy 174.644558 -341.41537)
			(xy 174.648114 -341.420958) (xy 174.64913 -341.421974) (xy 174.649892 -341.42299) (xy 174.651416 -341.42553)
			(xy 174.654718 -341.43061) (xy 174.657512 -341.434928) (xy 174.659798 -341.438484) (xy 174.68977 -341.460074)
			(xy 174.69612 -341.461852) (xy 174.720891 -341.469119) (xy 174.768185 -341.48981) (xy 174.811998 -341.517108)
			(xy 174.851414 -341.550443) (xy 174.885607 -341.589117) (xy 174.913861 -341.63232) (xy 174.935586 -341.679148)
			(xy 174.950326 -341.728621) (xy 174.957773 -341.779703) (xy 174.958248 -341.805514) (xy 174.957639 -341.835362)
			(xy 174.947681 -341.894221) (xy 174.938436 -341.922608) (xy 174.938436 -341.922862) (xy 174.935183 -341.934231)
			(xy 174.938236 -341.957654) (xy 174.944278 -341.96782) (xy 174.992792 -342.036146) (xy 174.997364 -342.041988)
			(xy 175.004787 -342.049109) (xy 175.023665 -342.05723) (xy 175.03394 -342.057736) (xy 175.485552 -342.057736)
			(xy 175.517338 -342.058416) (xy 175.580021 -342.069018) (xy 175.610266 -342.078818) (xy 175.618394 -342.081612)
			(xy 175.663352 -342.081612) (xy 175.690627 -342.082072) (xy 175.744623 -342.089829) (xy 175.796965 -342.105193)
			(xy 175.846587 -342.127849) (xy 175.89248 -342.157337) (xy 175.933709 -342.193057) (xy 175.969434 -342.234281)
			(xy 175.998928 -342.28017) (xy 176.021591 -342.32979) (xy 176.03696 -342.38213) (xy 176.044724 -342.436125)
			(xy 176.044724 -342.466772) (xy 177.3496 -342.466772) (xy 177.3496 -342.412228) (xy 177.357362 -342.35824)
			(xy 177.372729 -342.305906) (xy 177.395388 -342.256292) (xy 177.424876 -342.210407) (xy 177.460595 -342.169187)
			(xy 177.501817 -342.133469) (xy 177.547703 -342.103982) (xy 177.597317 -342.081325) (xy 177.649652 -342.065959)
			(xy 177.70364 -342.058199) (xy 177.730912 -342.057736) (xy 178.594512 -342.057736) (xy 178.621781 -342.058227)
			(xy 178.675763 -342.06599) (xy 178.728091 -342.081357) (xy 178.777699 -342.104013) (xy 178.823578 -342.133499)
			(xy 178.864794 -342.169214) (xy 178.900508 -342.210432) (xy 178.929992 -342.256312) (xy 178.952648 -342.305921)
			(xy 178.968012 -342.358249) (xy 178.975774 -342.412231) (xy 178.975774 -342.466768) (xy 180.458622 -342.466768)
			(xy 180.458622 -342.412232) (xy 180.466383 -342.35825) (xy 180.481747 -342.305923) (xy 180.504402 -342.256314)
			(xy 180.533885 -342.210434) (xy 180.569597 -342.169217) (xy 180.610812 -342.133502) (xy 180.65669 -342.104015)
			(xy 180.706296 -342.081357) (xy 180.758623 -342.065989) (xy 180.812604 -342.058224) (xy 180.839872 -342.057736)
			(xy 181.703472 -342.057736) (xy 181.730744 -342.058202) (xy 181.784734 -342.06596) (xy 181.83707 -342.081324)
			(xy 181.886686 -342.10398) (xy 181.932573 -342.133467) (xy 181.973796 -342.169184) (xy 182.009516 -342.210405)
			(xy 182.039007 -342.256289) (xy 182.061666 -342.305904) (xy 182.077034 -342.358239) (xy 182.084796 -342.412228)
			(xy 182.084796 -342.466772) (xy 182.084796 -342.466773) (xy 183.5675 -342.466773) (xy 183.5675 -342.412227)
			(xy 183.575263 -342.358237) (xy 183.590631 -342.305902) (xy 183.613291 -342.256286) (xy 183.642781 -342.210401)
			(xy 183.678502 -342.16918) (xy 183.719727 -342.133462) (xy 183.765615 -342.103975) (xy 183.815232 -342.081319)
			(xy 183.867569 -342.065956) (xy 183.921559 -342.058197) (xy 183.948832 -342.057736) (xy 184.812432 -342.057736)
			(xy 184.8397 -342.058229) (xy 184.89368 -342.065994) (xy 184.946005 -342.081362) (xy 184.995611 -342.10402)
			(xy 185.041488 -342.133506) (xy 185.082701 -342.169222) (xy 185.118413 -342.210438) (xy 185.147895 -342.256317)
			(xy 185.170549 -342.305925) (xy 185.185913 -342.358252) (xy 185.193674 -342.412232) (xy 185.193674 -342.466768)
			(xy 185.193674 -342.466769) (xy 186.676522 -342.466769) (xy 186.676522 -342.412231) (xy 186.684284 -342.358248)
			(xy 186.699649 -342.305918) (xy 186.722305 -342.256309) (xy 186.75179 -342.210428) (xy 186.787505 -342.16921)
			(xy 186.828721 -342.133495) (xy 186.874602 -342.104009) (xy 186.924211 -342.081352) (xy 186.97654 -342.065986)
			(xy 187.030523 -342.058223) (xy 187.057792 -342.057736) (xy 187.921392 -342.057736) (xy 187.948663 -342.058203)
			(xy 188.002651 -342.065964) (xy 188.054984 -342.08133) (xy 188.104598 -342.103987) (xy 188.150482 -342.133474)
			(xy 188.191703 -342.169191) (xy 188.227421 -342.210411) (xy 188.25691 -342.256295) (xy 188.279568 -342.305908)
			(xy 188.294934 -342.358241) (xy 188.302696 -342.412229) (xy 188.302696 -342.466767) (xy 189.785522 -342.466767)
			(xy 189.785522 -342.412233) (xy 189.793283 -342.358253) (xy 189.808646 -342.305927) (xy 189.831299 -342.25632)
			(xy 189.86078 -342.210441) (xy 189.89649 -342.169224) (xy 189.937702 -342.133509) (xy 189.983578 -342.104022)
			(xy 190.033182 -342.081363) (xy 190.085506 -342.065993) (xy 190.139485 -342.058226) (xy 190.166752 -342.057736)
			(xy 191.030352 -342.057736) (xy 191.057625 -342.0582) (xy 191.111617 -342.065957) (xy 191.163955 -342.081319)
			(xy 191.213574 -342.103974) (xy 191.259463 -342.13346) (xy 191.300689 -342.169177) (xy 191.336412 -342.210398)
			(xy 191.365903 -342.256284) (xy 191.388564 -342.3059) (xy 191.403933 -342.358236) (xy 191.411696 -342.412227)
			(xy 191.411696 -342.466772) (xy 192.8944 -342.466772) (xy 192.8944 -342.412228) (xy 192.902162 -342.35824)
			(xy 192.917529 -342.305906) (xy 192.940188 -342.256292) (xy 192.969676 -342.210407) (xy 193.005395 -342.169187)
			(xy 193.046617 -342.133469) (xy 193.092503 -342.103982) (xy 193.142117 -342.081325) (xy 193.194452 -342.065959)
			(xy 193.24844 -342.058199) (xy 193.275712 -342.057736) (xy 194.139312 -342.057736) (xy 194.166581 -342.058227)
			(xy 194.220563 -342.06599) (xy 194.272891 -342.081357) (xy 194.322499 -342.104013) (xy 194.368378 -342.133499)
			(xy 194.409594 -342.169214) (xy 194.445308 -342.210432) (xy 194.474792 -342.256312) (xy 194.497448 -342.305921)
			(xy 194.512812 -342.358249) (xy 194.520574 -342.412231) (xy 194.520574 -342.466768) (xy 196.003422 -342.466768)
			(xy 196.003422 -342.412232) (xy 196.011183 -342.35825) (xy 196.026547 -342.305923) (xy 196.049202 -342.256314)
			(xy 196.078685 -342.210434) (xy 196.114397 -342.169217) (xy 196.155612 -342.133502) (xy 196.20149 -342.104015)
			(xy 196.251096 -342.081357) (xy 196.303423 -342.065989) (xy 196.357404 -342.058224) (xy 196.384672 -342.057736)
			(xy 197.248272 -342.057736) (xy 197.275544 -342.058202) (xy 197.329534 -342.06596) (xy 197.38187 -342.081324)
			(xy 197.431486 -342.10398) (xy 197.477373 -342.133467) (xy 197.518596 -342.169184) (xy 197.554316 -342.210405)
			(xy 197.583807 -342.256289) (xy 197.606466 -342.305904) (xy 197.621834 -342.358239) (xy 197.629596 -342.412228)
			(xy 197.629596 -342.466772) (xy 197.621834 -342.520761) (xy 197.606466 -342.573096) (xy 197.583807 -342.622711)
			(xy 197.554316 -342.668595) (xy 197.518596 -342.709816) (xy 197.477373 -342.745533) (xy 197.431486 -342.77502)
			(xy 197.38187 -342.797676) (xy 197.329534 -342.81304) (xy 197.275544 -342.820798) (xy 197.248272 -342.82126)
			(xy 196.384672 -342.82126) (xy 196.357404 -342.820776) (xy 196.303423 -342.813011) (xy 196.251096 -342.797643)
			(xy 196.20149 -342.774985) (xy 196.155612 -342.745498) (xy 196.114397 -342.709783) (xy 196.078685 -342.668566)
			(xy 196.049202 -342.622686) (xy 196.026547 -342.573077) (xy 196.011183 -342.52075) (xy 196.003422 -342.466768)
			(xy 194.520574 -342.466768) (xy 194.520574 -342.466769) (xy 194.512812 -342.520751) (xy 194.497448 -342.573079)
			(xy 194.474792 -342.622688) (xy 194.445308 -342.668568) (xy 194.409594 -342.709786) (xy 194.368378 -342.745501)
			(xy 194.322499 -342.774987) (xy 194.272891 -342.797643) (xy 194.220563 -342.81301) (xy 194.166581 -342.820773)
			(xy 194.139312 -342.82126) (xy 193.275712 -342.82126) (xy 193.24844 -342.820801) (xy 193.194452 -342.813041)
			(xy 193.142117 -342.797675) (xy 193.092503 -342.775018) (xy 193.046617 -342.745531) (xy 193.005395 -342.709813)
			(xy 192.969676 -342.668593) (xy 192.940188 -342.622708) (xy 192.917529 -342.573094) (xy 192.902162 -342.52076)
			(xy 192.8944 -342.466772) (xy 191.411696 -342.466772) (xy 191.411696 -342.466773) (xy 191.403933 -342.520764)
			(xy 191.388564 -342.5731) (xy 191.365903 -342.622716) (xy 191.336412 -342.668602) (xy 191.300689 -342.709823)
			(xy 191.259463 -342.74554) (xy 191.213574 -342.775026) (xy 191.163955 -342.797681) (xy 191.111617 -342.813043)
			(xy 191.057625 -342.8208) (xy 191.030352 -342.82126) (xy 190.166752 -342.82126) (xy 190.139485 -342.820774)
			(xy 190.085506 -342.813007) (xy 190.033182 -342.797637) (xy 189.983578 -342.774978) (xy 189.937702 -342.745491)
			(xy 189.89649 -342.709776) (xy 189.86078 -342.668559) (xy 189.831299 -342.62268) (xy 189.808646 -342.573073)
			(xy 189.793283 -342.520747) (xy 189.785522 -342.466767) (xy 188.302696 -342.466767) (xy 188.302696 -342.466771)
			(xy 188.294934 -342.520759) (xy 188.279568 -342.573092) (xy 188.25691 -342.622705) (xy 188.227421 -342.668589)
			(xy 188.191703 -342.709809) (xy 188.150482 -342.745526) (xy 188.104598 -342.775013) (xy 188.054984 -342.79767)
			(xy 188.002651 -342.813036) (xy 187.948663 -342.820797) (xy 187.921392 -342.82126) (xy 187.057792 -342.82126)
			(xy 187.030523 -342.820777) (xy 186.97654 -342.813014) (xy 186.924211 -342.797648) (xy 186.874602 -342.774991)
			(xy 186.828721 -342.745505) (xy 186.787505 -342.70979) (xy 186.75179 -342.668572) (xy 186.722305 -342.622691)
			(xy 186.699649 -342.573082) (xy 186.684284 -342.520752) (xy 186.676522 -342.466769) (xy 185.193674 -342.466769)
			(xy 185.185913 -342.520748) (xy 185.170549 -342.573075) (xy 185.147895 -342.622683) (xy 185.118413 -342.668562)
			(xy 185.082701 -342.709778) (xy 185.041488 -342.745494) (xy 184.995611 -342.77498) (xy 184.946005 -342.797638)
			(xy 184.89368 -342.813006) (xy 184.8397 -342.820771) (xy 184.812432 -342.82126) (xy 183.948832 -342.82126)
			(xy 183.921559 -342.820803) (xy 183.867569 -342.813044) (xy 183.815232 -342.797681) (xy 183.765615 -342.775025)
			(xy 183.719727 -342.745538) (xy 183.678502 -342.70982) (xy 183.642781 -342.668599) (xy 183.613291 -342.622714)
			(xy 183.590631 -342.573098) (xy 183.575263 -342.520763) (xy 183.5675 -342.466773) (xy 182.084796 -342.466773)
			(xy 182.077034 -342.520761) (xy 182.061666 -342.573096) (xy 182.039007 -342.622711) (xy 182.009516 -342.668595)
			(xy 181.973796 -342.709816) (xy 181.932573 -342.745533) (xy 181.886686 -342.77502) (xy 181.83707 -342.797676)
			(xy 181.784734 -342.81304) (xy 181.730744 -342.820798) (xy 181.703472 -342.82126) (xy 180.839872 -342.82126)
			(xy 180.812604 -342.820776) (xy 180.758623 -342.813011) (xy 180.706296 -342.797643) (xy 180.65669 -342.774985)
			(xy 180.610812 -342.745498) (xy 180.569597 -342.709783) (xy 180.533885 -342.668566) (xy 180.504402 -342.622686)
			(xy 180.481747 -342.573077) (xy 180.466383 -342.52075) (xy 180.458622 -342.466768) (xy 178.975774 -342.466768)
			(xy 178.975774 -342.466769) (xy 178.968012 -342.520751) (xy 178.952648 -342.573079) (xy 178.929992 -342.622688)
			(xy 178.900508 -342.668568) (xy 178.864794 -342.709786) (xy 178.823578 -342.745501) (xy 178.777699 -342.774987)
			(xy 178.728091 -342.797643) (xy 178.675763 -342.81301) (xy 178.621781 -342.820773) (xy 178.594512 -342.82126)
			(xy 177.730912 -342.82126) (xy 177.70364 -342.820801) (xy 177.649652 -342.813041) (xy 177.597317 -342.797675)
			(xy 177.547703 -342.775018) (xy 177.501817 -342.745531) (xy 177.460595 -342.709813) (xy 177.424876 -342.668593)
			(xy 177.395388 -342.622708) (xy 177.372729 -342.573094) (xy 177.357362 -342.52076) (xy 177.3496 -342.466772)
			(xy 176.044724 -342.466772) (xy 176.044724 -342.490675) (xy 176.03696 -342.54467) (xy 176.021591 -342.59701)
			(xy 175.998928 -342.64663) (xy 175.969434 -342.692519) (xy 175.933709 -342.733743) (xy 175.89248 -342.769463)
			(xy 175.846587 -342.798951) (xy 175.796965 -342.821607) (xy 175.744623 -342.836971) (xy 175.690627 -342.844728)
			(xy 175.663352 -342.845136) (xy 175.041814 -342.845136) (xy 175.030677 -342.845752) (xy 175.010507 -342.855221)
			(xy 175.002952 -342.863424) (xy 174.946564 -342.9381) (xy 174.945294 -342.939624) (xy 174.940976 -342.963246)
			(xy 174.942246 -342.96731) (xy 174.949742 -342.99308) (xy 174.957783 -343.04614) (xy 174.958248 -343.072974)
			(xy 174.958248 -343.073482) (xy 174.957801 -343.099156) (xy 174.950434 -343.149972) (xy 174.935849 -343.199204)
			(xy 174.91435 -343.245834) (xy 174.88638 -343.288894) (xy 174.85252 -343.327495) (xy 174.83328 -343.3445)
			(xy 174.828178 -343.349167) (xy 174.820446 -343.360624) (xy 174.81804 -343.367106) (xy 174.81686 -343.371001)
			(xy 174.815583 -343.379039) (xy 174.8155 -343.383108) (xy 174.8155 -344.521536) (xy 174.815553 -344.525608)
			(xy 174.816829 -344.53365) (xy 174.81804 -344.537538) (xy 174.820411 -344.544039) (xy 174.82814 -344.555512)
			(xy 174.83328 -344.560144) (xy 174.852516 -344.577154) (xy 174.886382 -344.615752) (xy 174.914358 -344.658811)
			(xy 174.935864 -344.705439) (xy 174.950456 -344.754671) (xy 174.957831 -344.805488) (xy 174.958248 -344.831162)
			(xy 174.957635 -344.861009) (xy 174.94767 -344.919866) (xy 174.938436 -344.948256) (xy 174.938436 -344.94851)
			(xy 174.935171 -344.959881) (xy 174.938205 -344.983317) (xy 174.944278 -344.993468) (xy 174.992792 -345.061794)
			(xy 174.997364 -345.067636) (xy 175.00479 -345.074751) (xy 175.023667 -345.082864) (xy 175.03394 -345.083384)
			(xy 175.485552 -345.083384) (xy 175.517338 -345.084064) (xy 175.580021 -345.094665) (xy 175.610266 -345.104466)
			(xy 175.618394 -345.10726) (xy 175.663352 -345.10726) (xy 175.690624 -345.10772) (xy 175.744613 -345.115476)
			(xy 175.796948 -345.130838) (xy 175.846564 -345.153491) (xy 175.892451 -345.182976) (xy 175.933675 -345.218691)
			(xy 175.969396 -345.25991) (xy 175.998886 -345.305793) (xy 176.021546 -345.355407) (xy 176.036913 -345.40774)
			(xy 176.044676 -345.461728) (xy 176.044676 -345.492368) (xy 177.349647 -345.492368) (xy 177.349647 -345.437832)
			(xy 177.357409 -345.38385) (xy 177.372774 -345.331523) (xy 177.39543 -345.281915) (xy 177.424915 -345.236036)
			(xy 177.460629 -345.194821) (xy 177.501846 -345.159108) (xy 177.547726 -345.129624) (xy 177.597334 -345.10697)
			(xy 177.649662 -345.091606) (xy 177.703644 -345.083847) (xy 177.730912 -345.083384) (xy 178.594512 -345.083384)
			(xy 178.621784 -345.083779) (xy 178.675773 -345.091543) (xy 178.728107 -345.106912) (xy 178.777722 -345.129571)
			(xy 178.823607 -345.159061) (xy 178.864828 -345.194781) (xy 178.900546 -345.236003) (xy 178.930035 -345.281889)
			(xy 178.952693 -345.331504) (xy 178.968059 -345.383839) (xy 178.975821 -345.437828) (xy 178.975821 -345.492365)
			(xy 180.45867 -345.492365) (xy 180.45867 -345.437835) (xy 180.46643 -345.383861) (xy 180.481792 -345.33154)
			(xy 180.504444 -345.281937) (xy 180.533923 -345.236063) (xy 180.569631 -345.194851) (xy 180.610841 -345.15914)
			(xy 180.656713 -345.129657) (xy 180.706313 -345.107002) (xy 180.758633 -345.091636) (xy 180.812607 -345.083872)
			(xy 180.839872 -345.083384) (xy 181.703472 -345.083384) (xy 181.730748 -345.083754) (xy 181.784744 -345.091514)
			(xy 181.837086 -345.106879) (xy 181.886709 -345.129538) (xy 181.932602 -345.159028) (xy 181.97383 -345.19475)
			(xy 182.009555 -345.235976) (xy 182.039049 -345.281866) (xy 182.061711 -345.331487) (xy 182.077081 -345.383829)
			(xy 182.084844 -345.437824) (xy 182.084844 -345.492369) (xy 183.567547 -345.492369) (xy 183.567547 -345.437831)
			(xy 183.57531 -345.383848) (xy 183.590676 -345.331519) (xy 183.613333 -345.281909) (xy 183.64282 -345.23603)
			(xy 183.678536 -345.194814) (xy 183.719755 -345.159101) (xy 183.765638 -345.129617) (xy 183.815249 -345.106964)
			(xy 183.867579 -345.091603) (xy 183.921563 -345.083845) (xy 183.948832 -345.083384) (xy 184.812432 -345.083384)
			(xy 184.839703 -345.083781) (xy 184.89369 -345.091547) (xy 184.946022 -345.106917) (xy 184.995634 -345.129578)
			(xy 185.041516 -345.159068) (xy 185.082735 -345.194788) (xy 185.118451 -345.236009) (xy 185.147938 -345.281894)
			(xy 185.170594 -345.331508) (xy 185.18596 -345.383842) (xy 185.193722 -345.437829) (xy 185.193722 -345.492366)
			(xy 186.67657 -345.492366) (xy 186.67657 -345.437834) (xy 186.684331 -345.383858) (xy 186.699694 -345.331535)
			(xy 186.722347 -345.281932) (xy 186.751828 -345.236057) (xy 186.787538 -345.194844) (xy 186.82875 -345.159133)
			(xy 186.874625 -345.129651) (xy 186.924228 -345.106997) (xy 186.97655 -345.091633) (xy 187.030526 -345.083871)
			(xy 187.057792 -345.083384) (xy 187.921392 -345.083384) (xy 187.948667 -345.083755) (xy 188.002661 -345.091517)
			(xy 188.055001 -345.106885) (xy 188.104621 -345.129544) (xy 188.150511 -345.159035) (xy 188.191737 -345.194757)
			(xy 188.22746 -345.235982) (xy 188.256952 -345.281872) (xy 188.279613 -345.331492) (xy 188.294981 -345.383831)
			(xy 188.302744 -345.437825) (xy 188.302744 -345.492364) (xy 189.78557 -345.492364) (xy 189.78557 -345.437836)
			(xy 189.79333 -345.383863) (xy 189.808691 -345.331544) (xy 189.831341 -345.281943) (xy 189.860819 -345.23607)
			(xy 189.896524 -345.194858) (xy 189.937731 -345.159147) (xy 189.983601 -345.129664) (xy 190.033199 -345.107008)
			(xy 190.085516 -345.09164) (xy 190.139488 -345.083874) (xy 190.166752 -345.083384) (xy 191.030352 -345.083384)
			(xy 191.057629 -345.083752) (xy 191.111627 -345.09151) (xy 191.163972 -345.106874) (xy 191.213597 -345.129531)
			(xy 191.259492 -345.159021) (xy 191.300723 -345.194743) (xy 191.33645 -345.235969) (xy 191.365946 -345.281861)
			(xy 191.388609 -345.331483) (xy 191.40398 -345.383826) (xy 191.411744 -345.437824) (xy 191.411744 -345.492368)
			(xy 192.894447 -345.492368) (xy 192.894447 -345.437832) (xy 192.902209 -345.38385) (xy 192.917574 -345.331523)
			(xy 192.94023 -345.281915) (xy 192.969715 -345.236036) (xy 193.005429 -345.194821) (xy 193.046646 -345.159108)
			(xy 193.092526 -345.129624) (xy 193.142134 -345.10697) (xy 193.194462 -345.091606) (xy 193.248444 -345.083847)
			(xy 193.275712 -345.083384) (xy 194.139312 -345.083384) (xy 194.166584 -345.083779) (xy 194.220573 -345.091543)
			(xy 194.272907 -345.106912) (xy 194.322522 -345.129571) (xy 194.368407 -345.159061) (xy 194.409628 -345.194781)
			(xy 194.445346 -345.236003) (xy 194.474835 -345.281889) (xy 194.497493 -345.331504) (xy 194.512859 -345.383839)
			(xy 194.520621 -345.437828) (xy 194.520621 -345.492365) (xy 196.00347 -345.492365) (xy 196.00347 -345.437835)
			(xy 196.01123 -345.383861) (xy 196.026592 -345.33154) (xy 196.049244 -345.281937) (xy 196.078723 -345.236063)
			(xy 196.114431 -345.194851) (xy 196.155641 -345.15914) (xy 196.201513 -345.129657) (xy 196.251113 -345.107002)
			(xy 196.303433 -345.091636) (xy 196.357407 -345.083872) (xy 196.384672 -345.083384) (xy 197.248272 -345.083384)
			(xy 197.275548 -345.083754) (xy 197.329544 -345.091514) (xy 197.381886 -345.106879) (xy 197.431509 -345.129538)
			(xy 197.477402 -345.159028) (xy 197.51863 -345.19475) (xy 197.554355 -345.235976) (xy 197.583849 -345.281866)
			(xy 197.606511 -345.331487) (xy 197.621881 -345.383829) (xy 197.628314 -345.42857) (xy 229.27894 -345.42857)
			(xy 229.283011 -345.372948) (xy 229.295137 -345.318511) (xy 229.31506 -345.26642) (xy 229.342356 -345.217785)
			(xy 229.376442 -345.173642) (xy 229.416591 -345.134933) (xy 229.461949 -345.102482) (xy 229.511549 -345.076981)
			(xy 229.564333 -345.058974) (xy 229.619176 -345.048844) (xy 229.67491 -345.046807) (xy 229.730347 -345.052907)
			(xy 229.784304 -345.067013) (xy 229.835633 -345.088825) (xy 229.883239 -345.117879) (xy 229.926107 -345.153554)
			(xy 229.963324 -345.195091) (xy 229.994097 -345.241604) (xy 230.017769 -345.292101) (xy 230.033837 -345.345508)
			(xy 230.041957 -345.400684) (xy 230.042466 -345.42857) (xy 230.041957 -345.456456) (xy 230.033837 -345.511632)
			(xy 230.017769 -345.565039) (xy 229.994097 -345.615536) (xy 229.963324 -345.662049) (xy 229.926107 -345.703586)
			(xy 229.883239 -345.739261) (xy 229.835633 -345.768315) (xy 229.784304 -345.790127) (xy 229.730347 -345.804233)
			(xy 229.67491 -345.810333) (xy 229.619176 -345.808296) (xy 229.564333 -345.798166) (xy 229.511549 -345.780159)
			(xy 229.461949 -345.754658) (xy 229.416591 -345.722207) (xy 229.376442 -345.683498) (xy 229.342356 -345.639355)
			(xy 229.31506 -345.59072) (xy 229.295137 -345.538629) (xy 229.283011 -345.484192) (xy 229.27894 -345.42857)
			(xy 197.628314 -345.42857) (xy 197.629644 -345.437824) (xy 197.629644 -345.492376) (xy 197.621881 -345.546371)
			(xy 197.606511 -345.598713) (xy 197.583849 -345.648334) (xy 197.554355 -345.694224) (xy 197.51863 -345.73545)
			(xy 197.477402 -345.771172) (xy 197.431509 -345.800662) (xy 197.381886 -345.823321) (xy 197.349125 -345.832938)
			(xy 235.125004 -345.832938) (xy 235.129075 -345.777316) (xy 235.141201 -345.722879) (xy 235.161124 -345.670788)
			(xy 235.18842 -345.622153) (xy 235.222506 -345.57801) (xy 235.262655 -345.539301) (xy 235.308013 -345.50685)
			(xy 235.357613 -345.481349) (xy 235.410397 -345.463342) (xy 235.46524 -345.453212) (xy 235.520974 -345.451175)
			(xy 235.576411 -345.457275) (xy 235.630368 -345.471381) (xy 235.681697 -345.493193) (xy 235.729303 -345.522247)
			(xy 235.772171 -345.557922) (xy 235.809388 -345.599459) (xy 235.840161 -345.645972) (xy 235.863833 -345.696469)
			(xy 235.879901 -345.749876) (xy 235.888021 -345.805052) (xy 235.88853 -345.832938) (xy 235.888021 -345.860824)
			(xy 235.879901 -345.916) (xy 235.87226 -345.941396) (xy 250.769118 -345.941396) (xy 250.773189 -345.885774)
			(xy 250.785315 -345.831337) (xy 250.805238 -345.779246) (xy 250.832534 -345.730611) (xy 250.86662 -345.686468)
			(xy 250.906769 -345.647759) (xy 250.952127 -345.615308) (xy 251.001727 -345.589807) (xy 251.054511 -345.5718)
			(xy 251.109354 -345.56167) (xy 251.165088 -345.559633) (xy 251.220525 -345.565733) (xy 251.274482 -345.579839)
			(xy 251.325811 -345.601651) (xy 251.373417 -345.630705) (xy 251.416285 -345.66638) (xy 251.453502 -345.707917)
			(xy 251.484275 -345.75443) (xy 251.507947 -345.804927) (xy 251.524015 -345.858334) (xy 251.532135 -345.91351)
			(xy 251.532644 -345.941396) (xy 251.532135 -345.969282) (xy 251.524015 -346.024458) (xy 251.507947 -346.077865)
			(xy 251.484275 -346.128362) (xy 251.453502 -346.174875) (xy 251.416285 -346.216412) (xy 251.373417 -346.252087)
			(xy 251.325811 -346.281141) (xy 251.274482 -346.302953) (xy 251.220525 -346.317059) (xy 251.165088 -346.323159)
			(xy 251.109354 -346.321122) (xy 251.054511 -346.310992) (xy 251.001727 -346.292985) (xy 250.952127 -346.267484)
			(xy 250.906769 -346.235033) (xy 250.86662 -346.196324) (xy 250.832534 -346.152181) (xy 250.805238 -346.103546)
			(xy 250.785315 -346.051455) (xy 250.773189 -345.997018) (xy 250.769118 -345.941396) (xy 235.87226 -345.941396)
			(xy 235.863833 -345.969407) (xy 235.840161 -346.019904) (xy 235.809388 -346.066417) (xy 235.772171 -346.107954)
			(xy 235.729303 -346.143629) (xy 235.681697 -346.172683) (xy 235.630368 -346.194495) (xy 235.576411 -346.208601)
			(xy 235.520974 -346.214701) (xy 235.46524 -346.212664) (xy 235.410397 -346.202534) (xy 235.357613 -346.184527)
			(xy 235.308013 -346.159026) (xy 235.262655 -346.126575) (xy 235.222506 -346.087866) (xy 235.18842 -346.043723)
			(xy 235.161124 -345.995088) (xy 235.141201 -345.942997) (xy 235.129075 -345.88856) (xy 235.125004 -345.832938)
			(xy 197.349125 -345.832938) (xy 197.329544 -345.838686) (xy 197.275548 -345.846446) (xy 197.248272 -345.846908)
			(xy 196.384672 -345.846908) (xy 196.357407 -345.846328) (xy 196.303433 -345.838564) (xy 196.251113 -345.823198)
			(xy 196.201513 -345.800543) (xy 196.155641 -345.77106) (xy 196.114431 -345.735349) (xy 196.078723 -345.694137)
			(xy 196.049244 -345.648263) (xy 196.026592 -345.59866) (xy 196.01123 -345.546339) (xy 196.00347 -345.492365)
			(xy 194.520621 -345.492365) (xy 194.520621 -345.492372) (xy 194.512859 -345.546361) (xy 194.497493 -345.598696)
			(xy 194.474835 -345.648311) (xy 194.445346 -345.694197) (xy 194.409628 -345.735419) (xy 194.368407 -345.771139)
			(xy 194.322522 -345.800629) (xy 194.272907 -345.823288) (xy 194.220573 -345.838657) (xy 194.166584 -345.846421)
			(xy 194.139312 -345.846908) (xy 193.275712 -345.846908) (xy 193.248444 -345.846353) (xy 193.194462 -345.838594)
			(xy 193.142134 -345.82323) (xy 193.092526 -345.800576) (xy 193.046646 -345.771092) (xy 193.005429 -345.735379)
			(xy 192.969715 -345.694164) (xy 192.94023 -345.648285) (xy 192.917574 -345.598677) (xy 192.902209 -345.54635)
			(xy 192.894447 -345.492368) (xy 191.411744 -345.492368) (xy 191.411744 -345.492376) (xy 191.40398 -345.546374)
			(xy 191.388609 -345.598717) (xy 191.365946 -345.648339) (xy 191.33645 -345.694231) (xy 191.300723 -345.735457)
			(xy 191.259492 -345.771179) (xy 191.213597 -345.800669) (xy 191.163972 -345.823326) (xy 191.111627 -345.83869)
			(xy 191.057629 -345.846448) (xy 191.030352 -345.846908) (xy 190.166752 -345.846908) (xy 190.139488 -345.846326)
			(xy 190.085516 -345.83856) (xy 190.033199 -345.823192) (xy 189.983601 -345.800536) (xy 189.937731 -345.771053)
			(xy 189.896524 -345.735342) (xy 189.860819 -345.69413) (xy 189.831341 -345.648257) (xy 189.808691 -345.598656)
			(xy 189.79333 -345.546337) (xy 189.78557 -345.492364) (xy 188.302744 -345.492364) (xy 188.302744 -345.492375)
			(xy 188.294981 -345.546369) (xy 188.279613 -345.598708) (xy 188.256952 -345.648328) (xy 188.22746 -345.694218)
			(xy 188.191737 -345.735443) (xy 188.150511 -345.771165) (xy 188.104621 -345.800656) (xy 188.055001 -345.823315)
			(xy 188.002661 -345.838683) (xy 187.948667 -345.846445) (xy 187.921392 -345.846908) (xy 187.057792 -345.846908)
			(xy 187.030526 -345.846329) (xy 186.97655 -345.838567) (xy 186.924228 -345.823203) (xy 186.874625 -345.800549)
			(xy 186.82875 -345.771067) (xy 186.787538 -345.735356) (xy 186.751828 -345.694143) (xy 186.722347 -345.648268)
			(xy 186.699694 -345.598665) (xy 186.684331 -345.546342) (xy 186.67657 -345.492366) (xy 185.193722 -345.492366)
			(xy 185.193722 -345.492371) (xy 185.18596 -345.546358) (xy 185.170594 -345.598692) (xy 185.147938 -345.648306)
			(xy 185.118451 -345.694191) (xy 185.082735 -345.735412) (xy 185.041516 -345.771132) (xy 184.995634 -345.800622)
			(xy 184.946022 -345.823283) (xy 184.89369 -345.838653) (xy 184.839703 -345.846419) (xy 184.812432 -345.846908)
			(xy 183.948832 -345.846908) (xy 183.921563 -345.846355) (xy 183.867579 -345.838597) (xy 183.815249 -345.823236)
			(xy 183.765638 -345.800583) (xy 183.719755 -345.771099) (xy 183.678536 -345.735386) (xy 183.64282 -345.69417)
			(xy 183.613333 -345.648291) (xy 183.590676 -345.598681) (xy 183.57531 -345.546352) (xy 183.567547 -345.492369)
			(xy 182.084844 -345.492369) (xy 182.084844 -345.492376) (xy 182.077081 -345.546371) (xy 182.061711 -345.598713)
			(xy 182.039049 -345.648334) (xy 182.009555 -345.694224) (xy 181.97383 -345.73545) (xy 181.932602 -345.771172)
			(xy 181.886709 -345.800662) (xy 181.837086 -345.823321) (xy 181.784744 -345.838686) (xy 181.730748 -345.846446)
			(xy 181.703472 -345.846908) (xy 180.839872 -345.846908) (xy 180.812607 -345.846328) (xy 180.758633 -345.838564)
			(xy 180.706313 -345.823198) (xy 180.656713 -345.800543) (xy 180.610841 -345.77106) (xy 180.569631 -345.735349)
			(xy 180.533923 -345.694137) (xy 180.504444 -345.648263) (xy 180.481792 -345.59866) (xy 180.46643 -345.546339)
			(xy 180.45867 -345.492365) (xy 178.975821 -345.492365) (xy 178.975821 -345.492372) (xy 178.968059 -345.546361)
			(xy 178.952693 -345.598696) (xy 178.930035 -345.648311) (xy 178.900546 -345.694197) (xy 178.864828 -345.735419)
			(xy 178.823607 -345.771139) (xy 178.777722 -345.800629) (xy 178.728107 -345.823288) (xy 178.675773 -345.838657)
			(xy 178.621784 -345.846421) (xy 178.594512 -345.846908) (xy 177.730912 -345.846908) (xy 177.703644 -345.846353)
			(xy 177.649662 -345.838594) (xy 177.597334 -345.82323) (xy 177.547726 -345.800576) (xy 177.501846 -345.771092)
			(xy 177.460629 -345.735379) (xy 177.424915 -345.694164) (xy 177.39543 -345.648285) (xy 177.372774 -345.598677)
			(xy 177.357409 -345.54635) (xy 177.349647 -345.492368) (xy 176.044676 -345.492368) (xy 176.044676 -345.516272)
			(xy 176.036913 -345.57026) (xy 176.021546 -345.622593) (xy 175.998886 -345.672207) (xy 175.969396 -345.71809)
			(xy 175.933675 -345.759309) (xy 175.892451 -345.795024) (xy 175.846564 -345.824509) (xy 175.796948 -345.847162)
			(xy 175.744613 -345.862524) (xy 175.690624 -345.87028) (xy 175.663352 -345.870784) (xy 175.041814 -345.870784)
			(xy 175.030678 -345.871401) (xy 175.010515 -345.880876) (xy 175.002952 -345.889072) (xy 174.946564 -345.963748)
			(xy 174.945294 -345.965272) (xy 174.940976 -345.988894) (xy 174.942246 -345.992958) (xy 174.949738 -346.018728)
			(xy 174.957773 -346.071789) (xy 174.958248 -346.098622) (xy 174.958248 -346.09913) (xy 174.957595 -346.129887)
			(xy 174.947014 -346.190484) (xy 174.92617 -346.248358) (xy 174.911512 -346.275406) (xy 174.904908 -346.28709)
			(xy 174.902876 -346.290392) (xy 174.905162 -346.306902) (xy 174.906623 -346.315091) (xy 174.914017 -346.32998)
			(xy 174.91964 -346.336112) (xy 175.501484 -346.917956) (xy 245.50903 -346.917956) (xy 245.50903 -346.83326)
			(xy 245.517081 -346.748946) (xy 245.53311 -346.66578) (xy 245.556971 -346.584513) (xy 245.58845 -346.505883)
			(xy 245.627261 -346.430602) (xy 245.673051 -346.35935) (xy 245.725407 -346.292774) (xy 245.783855 -346.231476)
			(xy 245.847865 -346.176011) (xy 245.916857 -346.126882) (xy 245.990207 -346.084533) (xy 246.06725 -346.049349)
			(xy 246.147289 -346.021647) (xy 246.229598 -346.001679) (xy 246.313433 -345.989626) (xy 246.398034 -345.985596)
			(xy 246.482635 -345.989626) (xy 246.56647 -346.001679) (xy 246.648779 -346.021647) (xy 246.728818 -346.049349)
			(xy 246.805861 -346.084533) (xy 246.879211 -346.126882) (xy 246.948203 -346.176011) (xy 247.012213 -346.231476)
			(xy 247.070661 -346.292774) (xy 247.123017 -346.35935) (xy 247.168807 -346.430602) (xy 247.207618 -346.505883)
			(xy 247.239097 -346.584513) (xy 247.262958 -346.66578) (xy 247.278987 -346.748946) (xy 247.287038 -346.83326)
			(xy 247.287542 -346.875608) (xy 247.287038 -346.917956) (xy 247.278987 -347.00227) (xy 247.262958 -347.085436)
			(xy 247.239097 -347.166703) (xy 247.207618 -347.245333) (xy 247.168807 -347.320614) (xy 247.123017 -347.391866)
			(xy 247.070661 -347.458442) (xy 247.012213 -347.51974) (xy 246.948203 -347.575205) (xy 246.879211 -347.624334)
			(xy 246.805861 -347.666683) (xy 246.728818 -347.701867) (xy 246.648779 -347.729569) (xy 246.56647 -347.749537)
			(xy 246.482635 -347.76159) (xy 246.398034 -347.765621) (xy 246.313433 -347.76159) (xy 246.229598 -347.749537)
			(xy 246.147289 -347.729569) (xy 246.06725 -347.701867) (xy 245.990207 -347.666683) (xy 245.916857 -347.624334)
			(xy 245.847865 -347.575205) (xy 245.783855 -347.51974) (xy 245.725407 -347.458442) (xy 245.673051 -347.391866)
			(xy 245.627261 -347.320614) (xy 245.58845 -347.245333) (xy 245.556971 -347.166703) (xy 245.53311 -347.085436)
			(xy 245.517081 -347.00227) (xy 245.50903 -346.917956) (xy 175.501484 -346.917956) (xy 175.867568 -347.28404)
			(xy 175.900893 -347.318183) (xy 175.961544 -347.39184) (xy 176.014826 -347.470991) (xy 176.060243 -347.554903)
			(xy 176.097375 -347.642796) (xy 176.11217 -347.688154) (xy 176.113694 -347.693234) (xy 176.124616 -347.712284)
			(xy 176.126902 -347.714824) (xy 176.146718 -347.738106) (xy 176.170671 -347.7768) (xy 253.262382 -347.7768)
			(xy 253.266453 -347.721178) (xy 253.278579 -347.666741) (xy 253.298502 -347.61465) (xy 253.325798 -347.566015)
			(xy 253.359884 -347.521872) (xy 253.400033 -347.483163) (xy 253.445391 -347.450712) (xy 253.494991 -347.425211)
			(xy 253.547775 -347.407204) (xy 253.602618 -347.397074) (xy 253.658352 -347.395037) (xy 253.713789 -347.401137)
			(xy 253.767746 -347.415243) (xy 253.819075 -347.437055) (xy 253.866681 -347.466109) (xy 253.909549 -347.501784)
			(xy 253.946766 -347.543321) (xy 253.977539 -347.589834) (xy 254.001211 -347.640331) (xy 254.014376 -347.68409)
			(xy 255.611882 -347.68409) (xy 255.615953 -347.628468) (xy 255.628079 -347.574031) (xy 255.648002 -347.52194)
			(xy 255.675298 -347.473305) (xy 255.709384 -347.429162) (xy 255.749533 -347.390453) (xy 255.794891 -347.358002)
			(xy 255.844491 -347.332501) (xy 255.897275 -347.314494) (xy 255.952118 -347.304364) (xy 256.007852 -347.302327)
			(xy 256.063289 -347.308427) (xy 256.117246 -347.322533) (xy 256.168575 -347.344345) (xy 256.216181 -347.373399)
			(xy 256.259049 -347.409074) (xy 256.296266 -347.450611) (xy 256.327039 -347.497124) (xy 256.350711 -347.547621)
			(xy 256.366779 -347.601028) (xy 256.374899 -347.656204) (xy 256.375408 -347.68409) (xy 256.374899 -347.711976)
			(xy 256.366779 -347.767152) (xy 256.350711 -347.820559) (xy 256.327039 -347.871056) (xy 256.296266 -347.917569)
			(xy 256.259049 -347.959106) (xy 256.216181 -347.994781) (xy 256.168575 -348.023835) (xy 256.117246 -348.045647)
			(xy 256.063289 -348.059753) (xy 256.007852 -348.065853) (xy 255.952118 -348.063816) (xy 255.897275 -348.053686)
			(xy 255.844491 -348.035679) (xy 255.794891 -348.010178) (xy 255.749533 -347.977727) (xy 255.709384 -347.939018)
			(xy 255.675298 -347.894875) (xy 255.648002 -347.84624) (xy 255.628079 -347.794149) (xy 255.615953 -347.739712)
			(xy 255.611882 -347.68409) (xy 254.014376 -347.68409) (xy 254.017279 -347.693738) (xy 254.025399 -347.748914)
			(xy 254.025908 -347.7768) (xy 254.025399 -347.804686) (xy 254.017279 -347.859862) (xy 254.001211 -347.913269)
			(xy 253.977539 -347.963766) (xy 253.946766 -348.010279) (xy 253.909549 -348.051816) (xy 253.866681 -348.087491)
			(xy 253.819075 -348.116545) (xy 253.767746 -348.138357) (xy 253.713789 -348.152463) (xy 253.658352 -348.158563)
			(xy 253.602618 -348.156526) (xy 253.547775 -348.146396) (xy 253.494991 -348.128389) (xy 253.445391 -348.102888)
			(xy 253.400033 -348.070437) (xy 253.359884 -348.031728) (xy 253.325798 -347.987585) (xy 253.298502 -347.93895)
			(xy 253.278579 -347.886859) (xy 253.266453 -347.832422) (xy 253.262382 -347.7768) (xy 176.170671 -347.7768)
			(xy 176.178896 -347.790087) (xy 176.19091 -347.818202) (xy 176.194974 -347.8276) (xy 176.55667 -348.189296)
			(xy 176.559673 -348.192178) (xy 176.566439 -348.197027) (xy 176.570132 -348.198948) (xy 176.574196 -348.200726)
			(xy 176.577752 -348.201996) (xy 176.591468 -348.204028) (xy 176.63922 -348.204028) (xy 176.666483 -348.204494)
			(xy 176.720452 -348.21226) (xy 176.772765 -348.227631) (xy 176.822358 -348.250293) (xy 176.868218 -348.279786)
			(xy 176.909412 -348.315508) (xy 176.9451 -348.356731) (xy 176.974555 -348.402615) (xy 176.997178 -348.452225)
			(xy 177.012506 -348.504552) (xy 177.020228 -348.558527) (xy 177.020728 -348.58579) (xy 177.020662 -348.59565)
			(xy 177.019645 -348.615345) (xy 177.018696 -348.62516) (xy 177.018696 -348.625414) (xy 177.018214 -348.636606)
			(xy 177.025728 -348.657683) (xy 177.033174 -348.666054) (xy 177.2793 -348.91218) (xy 177.287772 -348.919969)
			(xy 177.309455 -348.927607) (xy 177.332295 -348.924993) (xy 177.342292 -348.919292) (xy 177.342546 -348.919038)
			(xy 177.358548 -348.909386) (xy 177.367184 -348.90456) (xy 177.379884 -348.888812) (xy 177.404776 -348.800166)
			(xy 177.40249 -348.780354) (xy 177.39741 -348.771464) (xy 177.382341 -348.742995) (xy 177.360948 -348.682243)
			(xy 177.350092 -348.618756) (xy 177.349404 -348.586552) (xy 177.349404 -348.58579) (xy 177.34989 -348.558532)
			(xy 177.357646 -348.50457) (xy 177.372999 -348.45226) (xy 177.395637 -348.402666) (xy 177.425099 -348.356796)
			(xy 177.460786 -348.315583) (xy 177.501973 -348.279866) (xy 177.547821 -348.250371) (xy 177.597399 -348.227697)
			(xy 177.649698 -348.212306) (xy 177.703654 -348.20451) (xy 177.730912 -348.204028) (xy 178.594512 -348.204028)
			(xy 178.621782 -348.204515) (xy 178.675765 -348.212279) (xy 178.728095 -348.227645) (xy 178.777705 -348.250303)
			(xy 178.823585 -348.27979) (xy 178.864803 -348.315506) (xy 178.900517 -348.356724) (xy 178.930003 -348.402606)
			(xy 178.952659 -348.452217) (xy 178.968024 -348.504546) (xy 178.975786 -348.55853) (xy 178.975786 -348.613069)
			(xy 180.458614 -348.613069) (xy 180.458614 -348.558531) (xy 180.466376 -348.504549) (xy 180.48174 -348.45222)
			(xy 180.504395 -348.40261) (xy 180.533879 -348.35673) (xy 180.569592 -348.315512) (xy 180.610807 -348.279795)
			(xy 180.656686 -348.250308) (xy 180.706294 -348.22765) (xy 180.758621 -348.212281) (xy 180.812603 -348.204516)
			(xy 180.839872 -348.204028) (xy 181.703472 -348.204028) (xy 181.730744 -348.20451) (xy 181.784732 -348.212268)
			(xy 181.837067 -348.227632) (xy 181.886682 -348.250287) (xy 181.932568 -348.279773) (xy 181.97379 -348.31549)
			(xy 182.00951 -348.356709) (xy 182.038999 -348.402593) (xy 182.061659 -348.452207) (xy 182.077026 -348.504541)
			(xy 182.084788 -348.558528) (xy 182.084788 -348.613072) (xy 182.084788 -348.613073) (xy 183.567492 -348.613073)
			(xy 183.567492 -348.558527) (xy 183.575255 -348.504536) (xy 183.590623 -348.452199) (xy 183.613284 -348.402583)
			(xy 183.642775 -348.356696) (xy 183.678497 -348.315474) (xy 183.719722 -348.279756) (xy 183.765611 -348.250268)
			(xy 183.815229 -348.227612) (xy 183.867567 -348.212248) (xy 183.921559 -348.204489) (xy 183.948832 -348.204028)
			(xy 184.812432 -348.204028) (xy 184.839699 -348.204537) (xy 184.893678 -348.212302) (xy 184.946002 -348.227669)
			(xy 184.995607 -348.250327) (xy 185.041483 -348.279813) (xy 185.082695 -348.315527) (xy 185.118406 -348.356743)
			(xy 185.147888 -348.402621) (xy 185.170542 -348.452228) (xy 185.185905 -348.504553) (xy 185.193666 -348.558533)
			(xy 185.193666 -348.613067) (xy 185.193666 -348.61307) (xy 186.676514 -348.61307) (xy 186.676514 -348.55853)
			(xy 186.684276 -348.504546) (xy 186.699641 -348.452216) (xy 186.722298 -348.402605) (xy 186.751784 -348.356723)
			(xy 186.787499 -348.315505) (xy 186.828717 -348.279788) (xy 186.874598 -348.250301) (xy 186.924208 -348.227644)
			(xy 186.976538 -348.212278) (xy 187.030522 -348.204515) (xy 187.057792 -348.204028) (xy 187.921392 -348.204028)
			(xy 187.948663 -348.204511) (xy 188.002649 -348.212272) (xy 188.054981 -348.227637) (xy 188.104594 -348.250294)
			(xy 188.150478 -348.27978) (xy 188.191698 -348.315497) (xy 188.227415 -348.356716) (xy 188.256903 -348.402599)
			(xy 188.27956 -348.452211) (xy 188.294926 -348.504543) (xy 188.302689 -348.558529) (xy 188.302689 -348.613068)
			(xy 189.785514 -348.613068) (xy 189.785514 -348.558532) (xy 189.793275 -348.504551) (xy 189.808638 -348.452224)
			(xy 189.831292 -348.402616) (xy 189.860774 -348.356736) (xy 189.896485 -348.315519) (xy 189.937698 -348.279803)
			(xy 189.983574 -348.250315) (xy 190.033179 -348.227655) (xy 190.085504 -348.212285) (xy 190.139484 -348.204518)
			(xy 190.166752 -348.204028) (xy 191.030352 -348.204028) (xy 191.057625 -348.204508) (xy 191.111615 -348.212265)
			(xy 191.163952 -348.227626) (xy 191.21357 -348.250281) (xy 191.259459 -348.279766) (xy 191.300683 -348.315483)
			(xy 191.336405 -348.356703) (xy 191.365896 -348.402588) (xy 191.388557 -348.452203) (xy 191.403925 -348.504538)
			(xy 191.411688 -348.558528) (xy 191.411688 -348.613072) (xy 192.894392 -348.613072) (xy 192.894392 -348.558528)
			(xy 192.902154 -348.504538) (xy 192.917521 -348.452203) (xy 192.940181 -348.402588) (xy 192.96967 -348.356703)
			(xy 193.00539 -348.315481) (xy 193.046612 -348.279763) (xy 193.092499 -348.250275) (xy 193.142115 -348.227617)
			(xy 193.19445 -348.212252) (xy 193.24844 -348.204491) (xy 193.275712 -348.204028) (xy 194.139312 -348.204028)
			(xy 194.16658 -348.204535) (xy 194.220561 -348.212298) (xy 194.272888 -348.227664) (xy 194.322495 -348.25032)
			(xy 194.368373 -348.279806) (xy 194.409588 -348.31552) (xy 194.445301 -348.356736) (xy 194.474785 -348.402615)
			(xy 194.49744 -348.452224) (xy 194.50429 -348.475554) (xy 236.142528 -348.475554) (xy 236.146599 -348.419932)
			(xy 236.158725 -348.365495) (xy 236.178648 -348.313404) (xy 236.205944 -348.264769) (xy 236.24003 -348.220626)
			(xy 236.280179 -348.181917) (xy 236.325537 -348.149466) (xy 236.375137 -348.123965) (xy 236.427921 -348.105958)
			(xy 236.482764 -348.095828) (xy 236.538498 -348.093791) (xy 236.593935 -348.099891) (xy 236.647892 -348.113997)
			(xy 236.699221 -348.135809) (xy 236.746827 -348.164863) (xy 236.789695 -348.200538) (xy 236.826912 -348.242075)
			(xy 236.857685 -348.288588) (xy 236.881357 -348.339085) (xy 236.897425 -348.392492) (xy 236.902555 -348.427353)
			(xy 240.622271 -348.427353) (xy 240.622271 -348.372847) (xy 240.630029 -348.318896) (xy 240.645386 -348.266598)
			(xy 240.668029 -348.217018) (xy 240.697499 -348.171166) (xy 240.733194 -348.129974) (xy 240.774388 -348.094282)
			(xy 240.820243 -348.064816) (xy 240.869824 -348.042176) (xy 240.922123 -348.026823) (xy 240.976075 -348.019069)
			(xy 241.003328 -348.018608) (xy 241.032243 -348.019175) (xy 241.089412 -348.027893) (xy 241.14461 -348.045141)
			(xy 241.196572 -348.070524) (xy 241.244107 -348.103459) (xy 241.286126 -348.143192) (xy 241.304318 -348.165674)
			(xy 241.311914 -348.174492) (xy 241.332824 -348.184666) (xy 241.34445 -348.185232) (xy 241.424206 -348.185232)
			(xy 241.43584 -348.184706) (xy 241.456751 -348.17451) (xy 241.464338 -348.165674) (xy 241.482501 -348.143167)
			(xy 241.524527 -348.103434) (xy 241.572068 -348.070499) (xy 241.624035 -348.045115) (xy 241.679237 -348.027863)
			(xy 241.73641 -348.01914) (xy 241.765328 -348.018608) (xy 241.792579 -348.019064) (xy 241.846526 -348.026824)
			(xy 241.89882 -348.042182) (xy 241.948395 -348.064826) (xy 241.994244 -348.094294) (xy 242.035433 -348.129987)
			(xy 242.071123 -348.171178) (xy 242.100588 -348.217029) (xy 242.123228 -348.266607) (xy 242.138582 -348.318901)
			(xy 242.146338 -348.372849) (xy 242.146338 -348.427351) (xy 242.138582 -348.481299) (xy 242.123228 -348.533593)
			(xy 242.100588 -348.583171) (xy 242.071123 -348.629022) (xy 242.035433 -348.670213) (xy 241.994244 -348.705906)
			(xy 241.948395 -348.735374) (xy 241.89882 -348.758018) (xy 241.846526 -348.773376) (xy 241.792579 -348.781136)
			(xy 241.765328 -348.781624) (xy 241.73641 -348.781115) (xy 241.679237 -348.772388) (xy 241.624037 -348.75513)
			(xy 241.572075 -348.729737) (xy 241.524541 -348.69679) (xy 241.482527 -348.657046) (xy 241.464338 -348.634558)
			(xy 241.456712 -348.625771) (xy 241.435825 -348.615578) (xy 241.424206 -348.615) (xy 241.34445 -348.615)
			(xy 241.332816 -348.615525) (xy 241.311907 -348.625724) (xy 241.304318 -348.634558) (xy 241.286106 -348.657024)
			(xy 241.244092 -348.696762) (xy 241.196562 -348.729705) (xy 241.144604 -348.755096) (xy 241.08941 -348.772356)
			(xy 241.032243 -348.781088) (xy 241.003328 -348.781624) (xy 240.976075 -348.781131) (xy 240.922123 -348.773377)
			(xy 240.869824 -348.758024) (xy 240.820243 -348.735384) (xy 240.774388 -348.705918) (xy 240.733194 -348.670226)
			(xy 240.697499 -348.629034) (xy 240.668029 -348.583182) (xy 240.645386 -348.533602) (xy 240.630029 -348.481304)
			(xy 240.622271 -348.427353) (xy 236.902555 -348.427353) (xy 236.905545 -348.447668) (xy 236.906054 -348.475554)
			(xy 236.905545 -348.50344) (xy 236.897425 -348.558616) (xy 236.881357 -348.612023) (xy 236.857685 -348.66252)
			(xy 236.826912 -348.709033) (xy 236.789695 -348.75057) (xy 236.746827 -348.786245) (xy 236.699221 -348.815299)
			(xy 236.647892 -348.837111) (xy 236.593935 -348.851217) (xy 236.538498 -348.857317) (xy 236.482764 -348.85528)
			(xy 236.427921 -348.84515) (xy 236.375137 -348.827143) (xy 236.325537 -348.801642) (xy 236.280179 -348.769191)
			(xy 236.24003 -348.730482) (xy 236.205944 -348.686339) (xy 236.178648 -348.637704) (xy 236.158725 -348.585613)
			(xy 236.146599 -348.531176) (xy 236.142528 -348.475554) (xy 194.50429 -348.475554) (xy 194.512804 -348.504551)
			(xy 194.520566 -348.558532) (xy 194.520566 -348.613068) (xy 194.512804 -348.667049) (xy 194.49744 -348.719376)
			(xy 194.474785 -348.768985) (xy 194.445301 -348.814864) (xy 194.409588 -348.85608) (xy 194.368373 -348.891794)
			(xy 194.322495 -348.92128) (xy 194.272888 -348.943936) (xy 194.220561 -348.959302) (xy 194.16658 -348.967065)
			(xy 194.139312 -348.967552) (xy 193.275712 -348.967552) (xy 193.24844 -348.967109) (xy 193.19445 -348.959348)
			(xy 193.142115 -348.943983) (xy 193.092499 -348.921325) (xy 193.046612 -348.891837) (xy 193.00539 -348.856119)
			(xy 192.96967 -348.814897) (xy 192.940181 -348.769012) (xy 192.917521 -348.719397) (xy 192.902154 -348.667062)
			(xy 192.894392 -348.613072) (xy 191.411688 -348.613072) (xy 191.403925 -348.667062) (xy 191.388557 -348.719397)
			(xy 191.365896 -348.769012) (xy 191.336405 -348.814897) (xy 191.300683 -348.856117) (xy 191.259459 -348.891834)
			(xy 191.21357 -348.921319) (xy 191.163952 -348.943974) (xy 191.111615 -348.959335) (xy 191.057625 -348.967092)
			(xy 191.030352 -348.967552) (xy 190.166752 -348.967552) (xy 190.139484 -348.967082) (xy 190.085504 -348.959315)
			(xy 190.033179 -348.943945) (xy 189.983574 -348.921285) (xy 189.937698 -348.891797) (xy 189.896485 -348.856081)
			(xy 189.860774 -348.814864) (xy 189.831292 -348.768984) (xy 189.808638 -348.719376) (xy 189.793275 -348.667049)
			(xy 189.785514 -348.613068) (xy 188.302689 -348.613068) (xy 188.302689 -348.613071) (xy 188.294926 -348.667057)
			(xy 188.27956 -348.719389) (xy 188.256903 -348.769001) (xy 188.227415 -348.814884) (xy 188.191698 -348.856103)
			(xy 188.150478 -348.89182) (xy 188.104594 -348.921306) (xy 188.054981 -348.943963) (xy 188.002649 -348.959328)
			(xy 187.948663 -348.967089) (xy 187.921392 -348.967552) (xy 187.057792 -348.967552) (xy 187.030522 -348.967085)
			(xy 186.976538 -348.959322) (xy 186.924208 -348.943956) (xy 186.874598 -348.921299) (xy 186.828717 -348.891812)
			(xy 186.787499 -348.856095) (xy 186.751784 -348.814877) (xy 186.722298 -348.768995) (xy 186.699641 -348.719384)
			(xy 186.684276 -348.667054) (xy 186.676514 -348.61307) (xy 185.193666 -348.61307) (xy 185.185905 -348.667047)
			(xy 185.170542 -348.719372) (xy 185.147888 -348.768979) (xy 185.118406 -348.814857) (xy 185.082695 -348.856073)
			(xy 185.041483 -348.891787) (xy 184.995607 -348.921273) (xy 184.946002 -348.943931) (xy 184.893678 -348.959298)
			(xy 184.839699 -348.967063) (xy 184.812432 -348.967552) (xy 183.948832 -348.967552) (xy 183.921559 -348.967111)
			(xy 183.867567 -348.959352) (xy 183.815229 -348.943988) (xy 183.765611 -348.921332) (xy 183.719722 -348.891844)
			(xy 183.678497 -348.856126) (xy 183.642775 -348.814904) (xy 183.613284 -348.769017) (xy 183.590623 -348.719401)
			(xy 183.575255 -348.667064) (xy 183.567492 -348.613073) (xy 182.084788 -348.613073) (xy 182.077026 -348.667059)
			(xy 182.061659 -348.719393) (xy 182.038999 -348.769007) (xy 182.00951 -348.814891) (xy 181.97379 -348.85611)
			(xy 181.932568 -348.891827) (xy 181.886682 -348.921313) (xy 181.837067 -348.943968) (xy 181.784732 -348.959332)
			(xy 181.730744 -348.96709) (xy 181.703472 -348.967552) (xy 180.839872 -348.967552) (xy 180.812603 -348.967084)
			(xy 180.758621 -348.959319) (xy 180.706294 -348.94395) (xy 180.656686 -348.921292) (xy 180.610807 -348.891805)
			(xy 180.569592 -348.856088) (xy 180.533879 -348.81487) (xy 180.504395 -348.76899) (xy 180.48174 -348.71938)
			(xy 180.466376 -348.667051) (xy 180.458614 -348.613069) (xy 178.975786 -348.613069) (xy 178.975786 -348.61307)
			(xy 178.968024 -348.667053) (xy 178.952659 -348.719383) (xy 178.930003 -348.768994) (xy 178.900517 -348.814876)
			(xy 178.864803 -348.856094) (xy 178.823585 -348.89181) (xy 178.777705 -348.921297) (xy 178.728095 -348.943955)
			(xy 178.675765 -348.959321) (xy 178.621782 -348.967085) (xy 178.594512 -348.967552) (xy 177.965354 -348.967552)
			(xy 177.953198 -348.968254) (xy 177.931593 -348.979405) (xy 177.923952 -348.988888) (xy 177.868834 -349.066612)
			(xy 177.865532 -349.090742) (xy 177.869596 -349.102426) (xy 177.878821 -349.130752) (xy 177.88878 -349.189482)
			(xy 177.889408 -349.219266) (xy 177.889408 -349.219774) (xy 177.888975 -349.244947) (xy 177.881888 -349.294792)
			(xy 177.879554 -349.302832) (xy 204.379574 -349.302832) (xy 204.383645 -349.24721) (xy 204.395771 -349.192773)
			(xy 204.415694 -349.140682) (xy 204.44299 -349.092047) (xy 204.477076 -349.047904) (xy 204.517225 -349.009195)
			(xy 204.562583 -348.976744) (xy 204.612183 -348.951243) (xy 204.664967 -348.933236) (xy 204.71981 -348.923106)
			(xy 204.775544 -348.921069) (xy 204.830981 -348.927169) (xy 204.884938 -348.941275) (xy 204.936267 -348.963087)
			(xy 204.983873 -348.992141) (xy 205.026741 -349.027816) (xy 205.063958 -349.069353) (xy 205.094731 -349.115866)
			(xy 205.118403 -349.166363) (xy 205.134471 -349.21977) (xy 205.134584 -349.220536) (xy 205.395574 -349.220536)
			(xy 205.399645 -349.164914) (xy 205.411771 -349.110477) (xy 205.431694 -349.058386) (xy 205.45899 -349.009751)
			(xy 205.493076 -348.965608) (xy 205.533225 -348.926899) (xy 205.578583 -348.894448) (xy 205.628183 -348.868947)
			(xy 205.680967 -348.85094) (xy 205.73581 -348.84081) (xy 205.791544 -348.838773) (xy 205.846981 -348.844873)
			(xy 205.900938 -348.858979) (xy 205.952267 -348.880791) (xy 205.983722 -348.899988) (xy 248.580146 -348.899988)
			(xy 248.584217 -348.844366) (xy 248.596343 -348.789929) (xy 248.616266 -348.737838) (xy 248.643562 -348.689203)
			(xy 248.677648 -348.64506) (xy 248.717797 -348.606351) (xy 248.763155 -348.5739) (xy 248.812755 -348.548399)
			(xy 248.865539 -348.530392) (xy 248.920382 -348.520262) (xy 248.976116 -348.518225) (xy 249.031553 -348.524325)
			(xy 249.08551 -348.538431) (xy 249.136839 -348.560243) (xy 249.184445 -348.589297) (xy 249.227313 -348.624972)
			(xy 249.26453 -348.666509) (xy 249.295303 -348.713022) (xy 249.318975 -348.763519) (xy 249.335043 -348.816926)
			(xy 249.338968 -348.8436) (xy 253.262382 -348.8436) (xy 253.266453 -348.787978) (xy 253.278579 -348.733541)
			(xy 253.298502 -348.68145) (xy 253.325798 -348.632815) (xy 253.359884 -348.588672) (xy 253.400033 -348.549963)
			(xy 253.445391 -348.517512) (xy 253.494991 -348.492011) (xy 253.547775 -348.474004) (xy 253.602618 -348.463874)
			(xy 253.658352 -348.461837) (xy 253.713789 -348.467937) (xy 253.767746 -348.482043) (xy 253.819075 -348.503855)
			(xy 253.866681 -348.532909) (xy 253.909549 -348.568584) (xy 253.946766 -348.610121) (xy 253.977539 -348.656634)
			(xy 254.001211 -348.707131) (xy 254.017279 -348.760538) (xy 254.025399 -348.815714) (xy 254.025908 -348.8436)
			(xy 254.025399 -348.871486) (xy 254.017279 -348.926662) (xy 254.001211 -348.980069) (xy 253.977539 -349.030566)
			(xy 253.946766 -349.077079) (xy 253.909549 -349.118616) (xy 253.866681 -349.154291) (xy 253.819075 -349.183345)
			(xy 253.767746 -349.205157) (xy 253.713789 -349.219263) (xy 253.658352 -349.225363) (xy 253.602618 -349.223326)
			(xy 253.547775 -349.213196) (xy 253.494991 -349.195189) (xy 253.445391 -349.169688) (xy 253.400033 -349.137237)
			(xy 253.359884 -349.098528) (xy 253.325798 -349.054385) (xy 253.298502 -349.00575) (xy 253.278579 -348.953659)
			(xy 253.266453 -348.899222) (xy 253.262382 -348.8436) (xy 249.338968 -348.8436) (xy 249.343163 -348.872102)
			(xy 249.343672 -348.899988) (xy 249.343163 -348.927874) (xy 249.335043 -348.98305) (xy 249.318975 -349.036457)
			(xy 249.295303 -349.086954) (xy 249.26453 -349.133467) (xy 249.227313 -349.175004) (xy 249.184445 -349.210679)
			(xy 249.136839 -349.239733) (xy 249.08551 -349.261545) (xy 249.031553 -349.275651) (xy 248.976116 -349.281751)
			(xy 248.920382 -349.279714) (xy 248.865539 -349.269584) (xy 248.812755 -349.251577) (xy 248.763155 -349.226076)
			(xy 248.717797 -349.193625) (xy 248.677648 -349.154916) (xy 248.643562 -349.110773) (xy 248.616266 -349.062138)
			(xy 248.596343 -349.010047) (xy 248.584217 -348.95561) (xy 248.580146 -348.899988) (xy 205.983722 -348.899988)
			(xy 205.999873 -348.909845) (xy 206.042741 -348.94552) (xy 206.079958 -348.987057) (xy 206.110731 -349.03357)
			(xy 206.134403 -349.084067) (xy 206.150471 -349.137474) (xy 206.158591 -349.19265) (xy 206.1591 -349.220536)
			(xy 206.158591 -349.248422) (xy 206.150471 -349.303598) (xy 206.134403 -349.357005) (xy 206.110731 -349.407502)
			(xy 206.079958 -349.454015) (xy 206.062937 -349.473012) (xy 236.12678 -349.473012) (xy 236.130851 -349.41739)
			(xy 236.142977 -349.362953) (xy 236.1629 -349.310862) (xy 236.190196 -349.262227) (xy 236.224282 -349.218084)
			(xy 236.264431 -349.179375) (xy 236.309789 -349.146924) (xy 236.359389 -349.121423) (xy 236.412173 -349.103416)
			(xy 236.467016 -349.093286) (xy 236.52275 -349.091249) (xy 236.578187 -349.097349) (xy 236.632144 -349.111455)
			(xy 236.683473 -349.133267) (xy 236.731079 -349.162321) (xy 236.773947 -349.197996) (xy 236.811164 -349.239533)
			(xy 236.841937 -349.286046) (xy 236.865609 -349.336543) (xy 236.881677 -349.38995) (xy 236.887181 -349.42735)
			(xy 240.762792 -349.42735) (xy 240.762792 -349.37285) (xy 240.770548 -349.318905) (xy 240.785902 -349.266613)
			(xy 240.808542 -349.217039) (xy 240.838006 -349.171191) (xy 240.873695 -349.130002) (xy 240.914883 -349.094312)
			(xy 240.96073 -349.064847) (xy 241.010304 -349.042206) (xy 241.062596 -349.02685) (xy 241.11654 -349.019093)
			(xy 241.14379 -349.018606) (xy 241.172707 -349.019129) (xy 241.229878 -349.027857) (xy 241.285077 -349.045114)
			(xy 241.337038 -349.070505) (xy 241.384572 -349.103447) (xy 241.42659 -349.143187) (xy 241.44478 -349.165672)
			(xy 241.452393 -349.174472) (xy 241.47329 -349.184657) (xy 241.484912 -349.18523) (xy 241.564668 -349.18523)
			(xy 241.5763 -349.184683) (xy 241.597211 -349.174502) (xy 241.6048 -349.165672) (xy 241.622984 -349.143183)
			(xy 241.665006 -349.103449) (xy 241.712543 -349.070512) (xy 241.764505 -349.045125) (xy 241.819704 -349.027869)
			(xy 241.876874 -349.019141) (xy 241.90579 -349.018606) (xy 241.933044 -349.01904) (xy 241.986998 -349.026796)
			(xy 242.039299 -349.042152) (xy 242.088883 -349.064795) (xy 242.134739 -349.094264) (xy 242.175934 -349.129959)
			(xy 242.21163 -349.171153) (xy 242.2411 -349.217009) (xy 242.263744 -349.266591) (xy 242.279102 -349.318892)
			(xy 242.286859 -349.372846) (xy 242.286859 -349.427354) (xy 242.279102 -349.481308) (xy 242.263744 -349.533609)
			(xy 242.2411 -349.583191) (xy 242.21163 -349.629047) (xy 242.175934 -349.670241) (xy 242.134739 -349.705936)
			(xy 242.088883 -349.735405) (xy 242.039299 -349.758048) (xy 241.986998 -349.773404) (xy 241.933044 -349.78116)
			(xy 241.90579 -349.781622) (xy 241.876874 -349.781069) (xy 241.819703 -349.772351) (xy 241.764504 -349.755102)
			(xy 241.712541 -349.729717) (xy 241.665007 -349.696778) (xy 241.62299 -349.65704) (xy 241.6048 -349.634556)
			(xy 241.597191 -349.625752) (xy 241.576291 -349.615568) (xy 241.564668 -349.614998) (xy 241.484912 -349.614998)
			(xy 241.473283 -349.615559) (xy 241.452373 -349.625733) (xy 241.44478 -349.634556) (xy 241.426589 -349.65704)
			(xy 241.384571 -349.696777) (xy 241.337036 -349.729717) (xy 241.285075 -349.755106) (xy 241.229876 -349.772362)
			(xy 241.172706 -349.781088) (xy 241.14379 -349.781622) (xy 241.11654 -349.781107) (xy 241.062596 -349.77335)
			(xy 241.010304 -349.757994) (xy 240.96073 -349.735353) (xy 240.914883 -349.705888) (xy 240.873695 -349.670198)
			(xy 240.838006 -349.629009) (xy 240.808542 -349.583161) (xy 240.785902 -349.533587) (xy 240.770548 -349.481295)
			(xy 240.762792 -349.42735) (xy 236.887181 -349.42735) (xy 236.889797 -349.445126) (xy 236.890306 -349.473012)
			(xy 236.889797 -349.500898) (xy 236.881677 -349.556074) (xy 236.865609 -349.609481) (xy 236.841937 -349.659978)
			(xy 236.811164 -349.706491) (xy 236.773947 -349.748028) (xy 236.731079 -349.783703) (xy 236.683473 -349.812757)
			(xy 236.632144 -349.834569) (xy 236.578187 -349.848675) (xy 236.52275 -349.854775) (xy 236.467016 -349.852738)
			(xy 236.412173 -349.842608) (xy 236.359389 -349.824601) (xy 236.309789 -349.7991) (xy 236.264431 -349.766649)
			(xy 236.224282 -349.72794) (xy 236.190196 -349.683797) (xy 236.1629 -349.635162) (xy 236.142977 -349.583071)
			(xy 236.130851 -349.528634) (xy 236.12678 -349.473012) (xy 206.062937 -349.473012) (xy 206.042741 -349.495552)
			(xy 205.999873 -349.531227) (xy 205.952267 -349.560281) (xy 205.900938 -349.582093) (xy 205.846981 -349.596199)
			(xy 205.791544 -349.602299) (xy 205.73581 -349.600262) (xy 205.680967 -349.590132) (xy 205.628183 -349.572125)
			(xy 205.578583 -349.546624) (xy 205.533225 -349.514173) (xy 205.493076 -349.475464) (xy 205.45899 -349.431321)
			(xy 205.431694 -349.382686) (xy 205.411771 -349.330595) (xy 205.399645 -349.276158) (xy 205.395574 -349.220536)
			(xy 205.134584 -349.220536) (xy 205.142591 -349.274946) (xy 205.1431 -349.302832) (xy 205.142591 -349.330718)
			(xy 205.134471 -349.385894) (xy 205.118403 -349.439301) (xy 205.094731 -349.489798) (xy 205.063958 -349.536311)
			(xy 205.026741 -349.577848) (xy 204.983873 -349.613523) (xy 204.936267 -349.642577) (xy 204.884938 -349.664389)
			(xy 204.830981 -349.678495) (xy 204.775544 -349.684595) (xy 204.71981 -349.682558) (xy 204.664967 -349.672428)
			(xy 204.612183 -349.654421) (xy 204.562583 -349.62892) (xy 204.517225 -349.596469) (xy 204.477076 -349.55776)
			(xy 204.44299 -349.513617) (xy 204.415694 -349.464982) (xy 204.395771 -349.412891) (xy 204.383645 -349.358454)
			(xy 204.379574 -349.302832) (xy 177.879554 -349.302832) (xy 177.867851 -349.343141) (xy 177.847143 -349.389032)
			(xy 177.834036 -349.410528) (xy 177.833782 -349.410782) (xy 177.828254 -349.420831) (xy 177.825716 -349.443592)
			(xy 177.833258 -349.465218) (xy 177.840894 -349.473774) (xy 178.267106 -349.899986) (xy 248.589544 -349.899986)
			(xy 248.593615 -349.844364) (xy 248.605741 -349.789927) (xy 248.625664 -349.737836) (xy 248.65296 -349.689201)
			(xy 248.687046 -349.645058) (xy 248.727195 -349.606349) (xy 248.772553 -349.573898) (xy 248.822153 -349.548397)
			(xy 248.874937 -349.53039) (xy 248.92978 -349.52026) (xy 248.985514 -349.518223) (xy 249.040951 -349.524323)
			(xy 249.094908 -349.538429) (xy 249.146237 -349.560241) (xy 249.193843 -349.589295) (xy 249.236711 -349.62497)
			(xy 249.273928 -349.666507) (xy 249.304701 -349.71302) (xy 249.328373 -349.763517) (xy 249.344441 -349.816924)
			(xy 249.350721 -349.8596) (xy 253.435864 -349.8596) (xy 253.439935 -349.803978) (xy 253.452061 -349.749541)
			(xy 253.471984 -349.69745) (xy 253.49928 -349.648815) (xy 253.533366 -349.604672) (xy 253.573515 -349.565963)
			(xy 253.618873 -349.533512) (xy 253.668473 -349.508011) (xy 253.721257 -349.490004) (xy 253.7761 -349.479874)
			(xy 253.831834 -349.477837) (xy 253.887271 -349.483937) (xy 253.941228 -349.498043) (xy 253.992557 -349.519855)
			(xy 254.040163 -349.548909) (xy 254.083031 -349.584584) (xy 254.120248 -349.626121) (xy 254.151021 -349.672634)
			(xy 254.174693 -349.723131) (xy 254.189845 -349.773494) (xy 258.543296 -349.773494) (xy 258.547367 -349.717872)
			(xy 258.559493 -349.663435) (xy 258.579416 -349.611344) (xy 258.606712 -349.562709) (xy 258.640798 -349.518566)
			(xy 258.680947 -349.479857) (xy 258.726305 -349.447406) (xy 258.775905 -349.421905) (xy 258.828689 -349.403898)
			(xy 258.883532 -349.393768) (xy 258.939266 -349.391731) (xy 258.994703 -349.397831) (xy 259.04866 -349.411937)
			(xy 259.099989 -349.433749) (xy 259.147595 -349.462803) (xy 259.190463 -349.498478) (xy 259.22768 -349.540015)
			(xy 259.258453 -349.586528) (xy 259.282125 -349.637025) (xy 259.298193 -349.690432) (xy 259.306313 -349.745608)
			(xy 259.306822 -349.773494) (xy 259.306313 -349.80138) (xy 259.298193 -349.856556) (xy 259.282125 -349.909963)
			(xy 259.258453 -349.96046) (xy 259.22768 -350.006973) (xy 259.190463 -350.04851) (xy 259.147595 -350.084185)
			(xy 259.099989 -350.113239) (xy 259.04866 -350.135051) (xy 258.994703 -350.149157) (xy 258.939266 -350.155257)
			(xy 258.883532 -350.15322) (xy 258.828689 -350.14309) (xy 258.775905 -350.125083) (xy 258.726305 -350.099582)
			(xy 258.680947 -350.067131) (xy 258.640798 -350.028422) (xy 258.606712 -349.984279) (xy 258.579416 -349.935644)
			(xy 258.559493 -349.883553) (xy 258.547367 -349.829116) (xy 258.543296 -349.773494) (xy 254.189845 -349.773494)
			(xy 254.190761 -349.776538) (xy 254.198881 -349.831714) (xy 254.19939 -349.8596) (xy 254.198881 -349.887486)
			(xy 254.190761 -349.942662) (xy 254.174693 -349.996069) (xy 254.151021 -350.046566) (xy 254.120248 -350.093079)
			(xy 254.083031 -350.134616) (xy 254.040163 -350.170291) (xy 253.992557 -350.199345) (xy 253.941228 -350.221157)
			(xy 253.887271 -350.235263) (xy 253.831834 -350.241363) (xy 253.7761 -350.239326) (xy 253.721257 -350.229196)
			(xy 253.668473 -350.211189) (xy 253.618873 -350.185688) (xy 253.573515 -350.153237) (xy 253.533366 -350.114528)
			(xy 253.49928 -350.070385) (xy 253.471984 -350.02175) (xy 253.452061 -349.969659) (xy 253.439935 -349.915222)
			(xy 253.435864 -349.8596) (xy 249.350721 -349.8596) (xy 249.352561 -349.8721) (xy 249.35307 -349.899986)
			(xy 249.352561 -349.927872) (xy 249.344441 -349.983048) (xy 249.328373 -350.036455) (xy 249.304701 -350.086952)
			(xy 249.273928 -350.133465) (xy 249.236711 -350.175002) (xy 249.193843 -350.210677) (xy 249.146237 -350.239731)
			(xy 249.094908 -350.261543) (xy 249.040951 -350.275649) (xy 248.985514 -350.281749) (xy 248.92978 -350.279712)
			(xy 248.874937 -350.269582) (xy 248.822153 -350.251575) (xy 248.772553 -350.226074) (xy 248.727195 -350.193623)
			(xy 248.687046 -350.154914) (xy 248.65296 -350.110771) (xy 248.625664 -350.062136) (xy 248.605741 -350.010045)
			(xy 248.593615 -349.955608) (xy 248.589544 -349.899986) (xy 178.267106 -349.899986) (xy 178.568858 -350.201738)
			(xy 178.575703 -350.209137) (xy 178.58343 -350.227735) (xy 178.583844 -350.237806) (xy 178.583844 -350.712532)
			(xy 207.046574 -350.712532) (xy 207.050645 -350.65691) (xy 207.062771 -350.602473) (xy 207.082694 -350.550382)
			(xy 207.10999 -350.501747) (xy 207.144076 -350.457604) (xy 207.184225 -350.418895) (xy 207.229583 -350.386444)
			(xy 207.279183 -350.360943) (xy 207.331967 -350.342936) (xy 207.38681 -350.332806) (xy 207.442544 -350.330769)
			(xy 207.497981 -350.336869) (xy 207.551938 -350.350975) (xy 207.603267 -350.372787) (xy 207.606005 -350.374458)
			(xy 236.132368 -350.374458) (xy 236.136439 -350.318836) (xy 236.148565 -350.264399) (xy 236.168488 -350.212308)
			(xy 236.195784 -350.163673) (xy 236.22987 -350.11953) (xy 236.270019 -350.080821) (xy 236.315377 -350.04837)
			(xy 236.364977 -350.022869) (xy 236.417761 -350.004862) (xy 236.472604 -349.994732) (xy 236.528338 -349.992695)
			(xy 236.583775 -349.998795) (xy 236.637732 -350.012901) (xy 236.689061 -350.034713) (xy 236.736667 -350.063767)
			(xy 236.779535 -350.099442) (xy 236.816752 -350.140979) (xy 236.847525 -350.187492) (xy 236.871197 -350.237989)
			(xy 236.887265 -350.291396) (xy 236.895385 -350.346572) (xy 236.895894 -350.374458) (xy 236.895385 -350.402344)
			(xy 236.891705 -350.427353) (xy 240.784067 -350.427353) (xy 240.784067 -350.372847) (xy 240.791825 -350.318895)
			(xy 240.807182 -350.266597) (xy 240.829825 -350.217017) (xy 240.859295 -350.171164) (xy 240.89499 -350.129972)
			(xy 240.936185 -350.094279) (xy 240.98204 -350.064813) (xy 241.031621 -350.042173) (xy 241.083921 -350.026819)
			(xy 241.137873 -350.019066) (xy 241.165126 -350.018604) (xy 241.193321 -350.019079) (xy 241.249098 -350.027377)
			(xy 241.303047 -350.043788) (xy 241.353997 -350.067955) (xy 241.400838 -350.099352) (xy 241.442551 -350.137298)
			(xy 241.460782 -350.158812) (xy 241.46838 -350.167237) (xy 241.488824 -350.176999) (xy 241.500152 -350.177608)
			(xy 241.578892 -350.177608) (xy 241.590208 -350.176941) (xy 241.610641 -350.167201) (xy 241.618262 -350.158812)
			(xy 241.636496 -350.137297) (xy 241.67819 -350.099327) (xy 241.725025 -350.067915) (xy 241.775978 -350.043748)
			(xy 241.829936 -350.027353) (xy 241.885721 -350.019089) (xy 241.913918 -350.018604) (xy 241.941169 -350.019067)
			(xy 241.995117 -350.026826) (xy 242.047411 -350.042183) (xy 242.096987 -350.064826) (xy 242.142837 -350.094294)
			(xy 242.184026 -350.129986) (xy 242.219717 -350.171177) (xy 242.249183 -350.217028) (xy 242.271823 -350.266606)
			(xy 242.287178 -350.318901) (xy 242.294934 -350.372849) (xy 242.294934 -350.427351) (xy 242.287178 -350.481299)
			(xy 242.271823 -350.533594) (xy 242.249183 -350.583172) (xy 242.219717 -350.629023) (xy 242.184026 -350.670214)
			(xy 242.142837 -350.705906) (xy 242.096987 -350.735374) (xy 242.047411 -350.758017) (xy 241.995117 -350.773374)
			(xy 241.941169 -350.781133) (xy 241.913918 -350.78162) (xy 241.885724 -350.781105) (xy 241.82995 -350.772814)
			(xy 241.776001 -350.756411) (xy 241.725052 -350.732251) (xy 241.67821 -350.700861) (xy 241.636494 -350.662923)
			(xy 241.618262 -350.641412) (xy 241.610684 -350.632966) (xy 241.590225 -350.623214) (xy 241.578892 -350.622616)
			(xy 241.500152 -350.622616) (xy 241.488831 -350.623244) (xy 241.468398 -350.633011) (xy 241.460782 -350.641412)
			(xy 241.442585 -350.662958) (xy 241.400882 -350.700926) (xy 241.354039 -350.732333) (xy 241.303079 -350.756495)
			(xy 241.249115 -350.772883) (xy 241.193325 -350.781139) (xy 241.165126 -350.78162) (xy 241.137873 -350.781134)
			(xy 241.083921 -350.773381) (xy 241.031621 -350.758027) (xy 240.98204 -350.735387) (xy 240.936185 -350.705921)
			(xy 240.89499 -350.670228) (xy 240.859295 -350.629036) (xy 240.829825 -350.583183) (xy 240.807182 -350.533603)
			(xy 240.791825 -350.481305) (xy 240.784067 -350.427353) (xy 236.891705 -350.427353) (xy 236.887265 -350.45752)
			(xy 236.871197 -350.510927) (xy 236.847525 -350.561424) (xy 236.816752 -350.607937) (xy 236.779535 -350.649474)
			(xy 236.736667 -350.685149) (xy 236.689061 -350.714203) (xy 236.637732 -350.736015) (xy 236.583775 -350.750121)
			(xy 236.528338 -350.756221) (xy 236.472604 -350.754184) (xy 236.417761 -350.744054) (xy 236.364977 -350.726047)
			(xy 236.315377 -350.700546) (xy 236.270019 -350.668095) (xy 236.22987 -350.629386) (xy 236.195784 -350.585243)
			(xy 236.168488 -350.536608) (xy 236.148565 -350.484517) (xy 236.136439 -350.43008) (xy 236.132368 -350.374458)
			(xy 207.606005 -350.374458) (xy 207.650873 -350.401841) (xy 207.693741 -350.437516) (xy 207.730958 -350.479053)
			(xy 207.761731 -350.525566) (xy 207.785403 -350.576063) (xy 207.801471 -350.62947) (xy 207.809591 -350.684646)
			(xy 207.8101 -350.712532) (xy 207.809591 -350.740418) (xy 207.801471 -350.795594) (xy 207.785403 -350.849001)
			(xy 207.761731 -350.899498) (xy 207.761409 -350.899984) (xy 248.573288 -350.899984) (xy 248.577359 -350.844362)
			(xy 248.589485 -350.789925) (xy 248.609408 -350.737834) (xy 248.636704 -350.689199) (xy 248.67079 -350.645056)
			(xy 248.710939 -350.606347) (xy 248.756297 -350.573896) (xy 248.805897 -350.548395) (xy 248.858681 -350.530388)
			(xy 248.913524 -350.520258) (xy 248.969258 -350.518221) (xy 249.024695 -350.524321) (xy 249.078652 -350.538427)
			(xy 249.129981 -350.560239) (xy 249.177587 -350.589293) (xy 249.220455 -350.624968) (xy 249.257672 -350.666505)
			(xy 249.288445 -350.713018) (xy 249.312117 -350.763515) (xy 249.328185 -350.816922) (xy 249.329344 -350.8248)
			(xy 252.957836 -350.8248) (xy 252.961907 -350.769178) (xy 252.974033 -350.714741) (xy 252.993956 -350.66265)
			(xy 253.021252 -350.614015) (xy 253.055338 -350.569872) (xy 253.095487 -350.531163) (xy 253.140845 -350.498712)
			(xy 253.190445 -350.473211) (xy 253.243229 -350.455204) (xy 253.298072 -350.445074) (xy 253.353806 -350.443037)
			(xy 253.409243 -350.449137) (xy 253.4632 -350.463243) (xy 253.514529 -350.485055) (xy 253.562135 -350.514109)
			(xy 253.605003 -350.549784) (xy 253.64222 -350.591321) (xy 253.672993 -350.637834) (xy 253.696665 -350.688331)
			(xy 253.712733 -350.741738) (xy 253.720853 -350.796914) (xy 253.721362 -350.8248) (xy 253.720853 -350.852686)
			(xy 253.712733 -350.907862) (xy 253.696665 -350.961269) (xy 253.672993 -351.011766) (xy 253.64222 -351.058279)
			(xy 253.605003 -351.099816) (xy 253.562135 -351.135491) (xy 253.514529 -351.164545) (xy 253.4632 -351.186357)
			(xy 253.409243 -351.200463) (xy 253.353806 -351.206563) (xy 253.298072 -351.204526) (xy 253.243229 -351.194396)
			(xy 253.190445 -351.176389) (xy 253.140845 -351.150888) (xy 253.095487 -351.118437) (xy 253.055338 -351.079728)
			(xy 253.021252 -351.035585) (xy 252.993956 -350.98695) (xy 252.974033 -350.934859) (xy 252.961907 -350.880422)
			(xy 252.957836 -350.8248) (xy 249.329344 -350.8248) (xy 249.336305 -350.872098) (xy 249.336814 -350.899984)
			(xy 249.336305 -350.92787) (xy 249.328185 -350.983046) (xy 249.312117 -351.036453) (xy 249.288445 -351.08695)
			(xy 249.257672 -351.133463) (xy 249.220455 -351.175) (xy 249.177587 -351.210675) (xy 249.129981 -351.239729)
			(xy 249.078652 -351.261541) (xy 249.024695 -351.275647) (xy 248.969258 -351.281747) (xy 248.913524 -351.27971)
			(xy 248.858681 -351.26958) (xy 248.805897 -351.251573) (xy 248.756297 -351.226072) (xy 248.710939 -351.193621)
			(xy 248.67079 -351.154912) (xy 248.636704 -351.110769) (xy 248.609408 -351.062134) (xy 248.589485 -351.010043)
			(xy 248.577359 -350.955606) (xy 248.573288 -350.899984) (xy 207.761409 -350.899984) (xy 207.730958 -350.946011)
			(xy 207.693741 -350.987548) (xy 207.650873 -351.023223) (xy 207.603267 -351.052277) (xy 207.551938 -351.074089)
			(xy 207.497981 -351.088195) (xy 207.442544 -351.094295) (xy 207.38681 -351.092258) (xy 207.331967 -351.082128)
			(xy 207.279183 -351.064121) (xy 207.229583 -351.03862) (xy 207.184225 -351.006169) (xy 207.144076 -350.96746)
			(xy 207.10999 -350.923317) (xy 207.082694 -350.874682) (xy 207.062771 -350.822591) (xy 207.050645 -350.768154)
			(xy 207.046574 -350.712532) (xy 178.583844 -350.712532) (xy 178.583844 -350.753172) (xy 178.585114 -350.764094)
			(xy 178.586085 -350.767832) (xy 178.589023 -350.774974) (xy 178.590956 -350.778318) (xy 178.606357 -350.802123)
			(xy 178.630224 -350.853549) (xy 178.638454 -350.88068) (xy 178.644558 -350.903702) (xy 178.651307 -350.95085)
			(xy 178.651916 -350.97466) (xy 178.651916 -350.977962) (xy 178.651291 -351.007746) (xy 178.641328 -351.066475)
			(xy 178.632104 -351.094802) (xy 178.632104 -351.095056) (xy 178.630559 -351.100047) (xy 178.629272 -351.110414)
			(xy 178.629564 -351.11563) (xy 178.629818 -351.117662) (xy 178.630729 -351.124014) (xy 178.635349 -351.135982)
			(xy 178.638962 -351.141284) (xy 178.68265 -351.203006) (xy 178.687984 -351.210372) (xy 178.689254 -351.211896)
			(xy 178.694612 -351.217709) (xy 178.708065 -351.225993) (xy 178.71567 -351.228152) (xy 178.727862 -351.229676)
			(xy 179.35702 -351.229676) (xy 179.384286 -351.230164) (xy 179.438262 -351.237927) (xy 179.490584 -351.253292)
			(xy 179.540186 -351.275948) (xy 179.58606 -351.305431) (xy 179.627271 -351.341143) (xy 179.662981 -351.382356)
			(xy 179.692462 -351.428231) (xy 179.715115 -351.477835) (xy 179.730477 -351.530158) (xy 179.738238 -351.584134)
			(xy 179.738238 -351.638665) (xy 180.458662 -351.638665) (xy 180.458662 -351.584135) (xy 180.466422 -351.530159)
			(xy 180.481785 -351.477837) (xy 180.504437 -351.428233) (xy 180.533917 -351.382358) (xy 180.569626 -351.341146)
			(xy 180.610836 -351.305434) (xy 180.656709 -351.27595) (xy 180.70631 -351.253295) (xy 180.758631 -351.237928)
			(xy 180.812607 -351.230164) (xy 180.839872 -351.229676) (xy 181.703472 -351.229676) (xy 181.730747 -351.230062)
			(xy 181.784742 -351.237821) (xy 181.837084 -351.253187) (xy 181.886705 -351.275845) (xy 181.932597 -351.305335)
			(xy 181.973824 -351.341056) (xy 182.009548 -351.382281) (xy 182.039042 -351.42817) (xy 182.061703 -351.47779)
			(xy 182.077073 -351.53013) (xy 182.084836 -351.584125) (xy 182.084836 -351.63867) (xy 183.567539 -351.63867)
			(xy 183.567539 -351.58413) (xy 183.575302 -351.530146) (xy 183.590668 -351.477816) (xy 183.613326 -351.428206)
			(xy 183.642813 -351.382325) (xy 183.678531 -351.341108) (xy 183.719751 -351.305394) (xy 183.765634 -351.27591)
			(xy 183.815246 -351.253257) (xy 183.867577 -351.237895) (xy 183.921562 -351.230137) (xy 183.948832 -351.229676)
			(xy 184.812432 -351.229676) (xy 184.839703 -351.230089) (xy 184.893688 -351.237855) (xy 184.946019 -351.253224)
			(xy 184.99563 -351.275885) (xy 185.041512 -351.305374) (xy 185.082729 -351.341093) (xy 185.118445 -351.382314)
			(xy 185.147931 -351.428198) (xy 185.170587 -351.477811) (xy 185.185952 -351.530143) (xy 185.193714 -351.584129)
			(xy 185.193714 -351.638666) (xy 186.676562 -351.638666) (xy 186.676562 -351.584134) (xy 186.684323 -351.530156)
			(xy 186.699686 -351.477832) (xy 186.72234 -351.428228) (xy 186.751822 -351.382352) (xy 186.787533 -351.341138)
			(xy 186.828745 -351.305427) (xy 186.874621 -351.275944) (xy 186.924225 -351.253289) (xy 186.976548 -351.237925)
			(xy 187.030526 -351.230163) (xy 187.057792 -351.229676) (xy 187.921392 -351.229676) (xy 187.948666 -351.230063)
			(xy 188.002659 -351.237825) (xy 188.054998 -351.253192) (xy 188.104617 -351.275851) (xy 188.150506 -351.305342)
			(xy 188.191732 -351.341063) (xy 188.227453 -351.382287) (xy 188.256945 -351.428176) (xy 188.279605 -351.477794)
			(xy 188.294973 -351.530133) (xy 188.302736 -351.584126) (xy 188.302736 -351.638664) (xy 189.785562 -351.638664)
			(xy 189.785562 -351.584136) (xy 189.793322 -351.530162) (xy 189.808683 -351.477841) (xy 189.831334 -351.428239)
			(xy 189.860812 -351.382365) (xy 189.896519 -351.341153) (xy 189.937726 -351.305441) (xy 189.983597 -351.275957)
			(xy 190.033196 -351.2533) (xy 190.085515 -351.237932) (xy 190.139488 -351.230166) (xy 190.166752 -351.229676)
			(xy 191.030352 -351.229676) (xy 191.057628 -351.23006) (xy 191.111625 -351.237818) (xy 191.163969 -351.253181)
			(xy 191.213593 -351.275838) (xy 191.259487 -351.305328) (xy 191.300717 -351.341049) (xy 191.336444 -351.382274)
			(xy 191.365939 -351.428165) (xy 191.388602 -351.477786) (xy 191.403972 -351.530128) (xy 191.411736 -351.584124)
			(xy 191.411736 -351.638669) (xy 192.894439 -351.638669) (xy 192.894439 -351.584131) (xy 192.902201 -351.530149)
			(xy 192.917566 -351.47782) (xy 192.940223 -351.428211) (xy 192.969708 -351.382331) (xy 193.005424 -351.341115)
			(xy 193.046641 -351.305401) (xy 193.092522 -351.275917) (xy 193.142131 -351.253262) (xy 193.19446 -351.237899)
			(xy 193.248443 -351.230139) (xy 193.275712 -351.229676) (xy 194.139312 -351.229676) (xy 194.166584 -351.230087)
			(xy 194.220571 -351.237851) (xy 194.272904 -351.253219) (xy 194.322518 -351.275878) (xy 194.368402 -351.305367)
			(xy 194.409622 -351.341086) (xy 194.44534 -351.382308) (xy 194.474828 -351.428192) (xy 194.491002 -351.46361)
			(xy 204.379574 -351.46361) (xy 204.383645 -351.407988) (xy 204.395771 -351.353551) (xy 204.415694 -351.30146)
			(xy 204.44299 -351.252825) (xy 204.477076 -351.208682) (xy 204.517225 -351.169973) (xy 204.562583 -351.137522)
			(xy 204.612183 -351.112021) (xy 204.664967 -351.094014) (xy 204.71981 -351.083884) (xy 204.775544 -351.081847)
			(xy 204.830981 -351.087947) (xy 204.884938 -351.102053) (xy 204.936267 -351.123865) (xy 204.983873 -351.152919)
			(xy 205.026741 -351.188594) (xy 205.063958 -351.230131) (xy 205.094731 -351.276644) (xy 205.118403 -351.327141)
			(xy 205.124996 -351.349056) (xy 233.362752 -351.349056) (xy 233.366823 -351.293434) (xy 233.378949 -351.238997)
			(xy 233.398872 -351.186906) (xy 233.426168 -351.138271) (xy 233.460254 -351.094128) (xy 233.500403 -351.055419)
			(xy 233.545761 -351.022968) (xy 233.595361 -350.997467) (xy 233.648145 -350.97946) (xy 233.702988 -350.96933)
			(xy 233.758722 -350.967293) (xy 233.814159 -350.973393) (xy 233.868116 -350.987499) (xy 233.919445 -351.009311)
			(xy 233.967051 -351.038365) (xy 234.009919 -351.07404) (xy 234.047136 -351.115577) (xy 234.077909 -351.16209)
			(xy 234.101581 -351.212587) (xy 234.117649 -351.265994) (xy 234.125769 -351.32117) (xy 234.126106 -351.339658)
			(xy 236.132368 -351.339658) (xy 236.136439 -351.284036) (xy 236.148565 -351.229599) (xy 236.168488 -351.177508)
			(xy 236.195784 -351.128873) (xy 236.22987 -351.08473) (xy 236.270019 -351.046021) (xy 236.315377 -351.01357)
			(xy 236.364977 -350.988069) (xy 236.417761 -350.970062) (xy 236.472604 -350.959932) (xy 236.528338 -350.957895)
			(xy 236.583775 -350.963995) (xy 236.637732 -350.978101) (xy 236.689061 -350.999913) (xy 236.736667 -351.028967)
			(xy 236.779535 -351.064642) (xy 236.816752 -351.106179) (xy 236.847525 -351.152692) (xy 236.871197 -351.203189)
			(xy 236.887265 -351.256596) (xy 236.895385 -351.311772) (xy 236.895894 -351.339658) (xy 236.895385 -351.367544)
			(xy 236.890592 -351.40011) (xy 241.568476 -351.40011) (xy 241.572547 -351.344488) (xy 241.584673 -351.290051)
			(xy 241.604596 -351.23796) (xy 241.631892 -351.189325) (xy 241.665978 -351.145182) (xy 241.706127 -351.106473)
			(xy 241.751485 -351.074022) (xy 241.801085 -351.048521) (xy 241.853869 -351.030514) (xy 241.908712 -351.020384)
			(xy 241.964446 -351.018347) (xy 242.019883 -351.024447) (xy 242.07384 -351.038553) (xy 242.125169 -351.060365)
			(xy 242.172775 -351.089419) (xy 242.215643 -351.125094) (xy 242.25286 -351.166631) (xy 242.283633 -351.213144)
			(xy 242.307305 -351.263641) (xy 242.323373 -351.317048) (xy 242.331493 -351.372224) (xy 242.332002 -351.40011)
			(xy 242.331493 -351.427996) (xy 242.323373 -351.483172) (xy 242.307305 -351.536579) (xy 242.283633 -351.587076)
			(xy 242.25286 -351.633589) (xy 242.215643 -351.675126) (xy 242.172775 -351.710801) (xy 242.125169 -351.739855)
			(xy 242.07384 -351.761667) (xy 242.019883 -351.775773) (xy 241.964446 -351.781873) (xy 241.908712 -351.779836)
			(xy 241.853869 -351.769706) (xy 241.801085 -351.751699) (xy 241.751485 -351.726198) (xy 241.706127 -351.693747)
			(xy 241.665978 -351.655038) (xy 241.631892 -351.610895) (xy 241.604596 -351.56226) (xy 241.584673 -351.510169)
			(xy 241.572547 -351.455732) (xy 241.568476 -351.40011) (xy 236.890592 -351.40011) (xy 236.887265 -351.42272)
			(xy 236.871197 -351.476127) (xy 236.847525 -351.526624) (xy 236.816752 -351.573137) (xy 236.779535 -351.614674)
			(xy 236.736667 -351.650349) (xy 236.689061 -351.679403) (xy 236.637732 -351.701215) (xy 236.583775 -351.715321)
			(xy 236.528338 -351.721421) (xy 236.472604 -351.719384) (xy 236.417761 -351.709254) (xy 236.364977 -351.691247)
			(xy 236.315377 -351.665746) (xy 236.270019 -351.633295) (xy 236.22987 -351.594586) (xy 236.195784 -351.550443)
			(xy 236.168488 -351.501808) (xy 236.148565 -351.449717) (xy 236.136439 -351.39528) (xy 236.132368 -351.339658)
			(xy 234.126106 -351.339658) (xy 234.126278 -351.349056) (xy 234.125769 -351.376942) (xy 234.117649 -351.432118)
			(xy 234.101581 -351.485525) (xy 234.077909 -351.536022) (xy 234.047136 -351.582535) (xy 234.009919 -351.624072)
			(xy 233.967051 -351.659747) (xy 233.919445 -351.688801) (xy 233.868116 -351.710613) (xy 233.814159 -351.724719)
			(xy 233.758722 -351.730819) (xy 233.702988 -351.728782) (xy 233.648145 -351.718652) (xy 233.595361 -351.700645)
			(xy 233.545761 -351.675144) (xy 233.500403 -351.642693) (xy 233.460254 -351.603984) (xy 233.426168 -351.559841)
			(xy 233.398872 -351.511206) (xy 233.378949 -351.459115) (xy 233.366823 -351.404678) (xy 233.362752 -351.349056)
			(xy 205.124996 -351.349056) (xy 205.134471 -351.380548) (xy 205.142591 -351.435724) (xy 205.1431 -351.46361)
			(xy 205.142591 -351.491496) (xy 205.134471 -351.546672) (xy 205.118403 -351.600079) (xy 205.094731 -351.650576)
			(xy 205.063958 -351.697089) (xy 205.026741 -351.738626) (xy 204.983873 -351.774301) (xy 204.936267 -351.803355)
			(xy 204.884938 -351.825167) (xy 204.830981 -351.839273) (xy 204.775544 -351.845373) (xy 204.71981 -351.843336)
			(xy 204.664967 -351.833206) (xy 204.612183 -351.815199) (xy 204.562583 -351.789698) (xy 204.517225 -351.757247)
			(xy 204.477076 -351.718538) (xy 204.44299 -351.674395) (xy 204.415694 -351.62576) (xy 204.395771 -351.573669)
			(xy 204.383645 -351.519232) (xy 204.379574 -351.46361) (xy 194.491002 -351.46361) (xy 194.497485 -351.477807)
			(xy 194.512851 -351.530141) (xy 194.520614 -351.584128) (xy 194.520614 -351.638672) (xy 194.512851 -351.692659)
			(xy 194.497485 -351.744993) (xy 194.474828 -351.794608) (xy 194.44534 -351.840492) (xy 194.409622 -351.881714)
			(xy 194.368402 -351.917433) (xy 194.322518 -351.946922) (xy 194.272904 -351.969581) (xy 194.220571 -351.984949)
			(xy 194.166584 -351.992713) (xy 194.139312 -351.9932) (xy 193.275712 -351.9932) (xy 193.248443 -351.992661)
			(xy 193.19446 -351.984901) (xy 193.142131 -351.969538) (xy 193.092522 -351.946883) (xy 193.046641 -351.917399)
			(xy 193.005424 -351.881685) (xy 192.969708 -351.840469) (xy 192.940223 -351.794589) (xy 192.917566 -351.74498)
			(xy 192.902201 -351.692651) (xy 192.894439 -351.638669) (xy 191.411736 -351.638669) (xy 191.411736 -351.638676)
			(xy 191.403972 -351.692672) (xy 191.388602 -351.745014) (xy 191.365939 -351.794635) (xy 191.336444 -351.840526)
			(xy 191.300717 -351.881751) (xy 191.259487 -351.917472) (xy 191.213593 -351.946962) (xy 191.163969 -351.969619)
			(xy 191.111625 -351.984982) (xy 191.057628 -351.99274) (xy 191.030352 -351.9932) (xy 190.166752 -351.9932)
			(xy 190.139488 -351.992634) (xy 190.085515 -351.984868) (xy 190.033196 -351.9695) (xy 189.983597 -351.946843)
			(xy 189.937726 -351.917359) (xy 189.896519 -351.881647) (xy 189.860812 -351.840435) (xy 189.831334 -351.794561)
			(xy 189.808683 -351.744959) (xy 189.793322 -351.692639) (xy 189.785562 -351.638664) (xy 188.302736 -351.638664)
			(xy 188.302736 -351.638674) (xy 188.294973 -351.692667) (xy 188.279605 -351.745006) (xy 188.256945 -351.794624)
			(xy 188.227453 -351.840513) (xy 188.191732 -351.881737) (xy 188.150506 -351.917458) (xy 188.104617 -351.946949)
			(xy 188.054998 -351.969608) (xy 188.002659 -351.984975) (xy 187.948666 -351.992737) (xy 187.921392 -351.9932)
			(xy 187.057792 -351.9932) (xy 187.030526 -351.992637) (xy 186.976548 -351.984875) (xy 186.924225 -351.969511)
			(xy 186.874621 -351.946856) (xy 186.828745 -351.917373) (xy 186.787533 -351.881662) (xy 186.751822 -351.840448)
			(xy 186.72234 -351.794572) (xy 186.699686 -351.744968) (xy 186.684323 -351.692644) (xy 186.676562 -351.638666)
			(xy 185.193714 -351.638666) (xy 185.193714 -351.638671) (xy 185.185952 -351.692657) (xy 185.170587 -351.744989)
			(xy 185.147931 -351.794602) (xy 185.118445 -351.840486) (xy 185.082729 -351.881707) (xy 185.041512 -351.917426)
			(xy 184.99563 -351.946915) (xy 184.946019 -351.969576) (xy 184.893688 -351.984945) (xy 184.839703 -351.992711)
			(xy 184.812432 -351.9932) (xy 183.948832 -351.9932) (xy 183.921562 -351.992663) (xy 183.867577 -351.984905)
			(xy 183.815246 -351.969543) (xy 183.765634 -351.94689) (xy 183.719751 -351.917406) (xy 183.678531 -351.881692)
			(xy 183.642813 -351.840475) (xy 183.613326 -351.794594) (xy 183.590668 -351.744984) (xy 183.575302 -351.692654)
			(xy 183.567539 -351.63867) (xy 182.084836 -351.63867) (xy 182.084836 -351.638675) (xy 182.077073 -351.69267)
			(xy 182.061703 -351.74501) (xy 182.039042 -351.79463) (xy 182.009548 -351.840519) (xy 181.973824 -351.881744)
			(xy 181.932597 -351.917465) (xy 181.886705 -351.946955) (xy 181.837084 -351.969613) (xy 181.784742 -351.984979)
			(xy 181.730747 -351.992738) (xy 181.703472 -351.9932) (xy 180.839872 -351.9932) (xy 180.812607 -351.992636)
			(xy 180.758631 -351.984872) (xy 180.70631 -351.969505) (xy 180.656709 -351.94685) (xy 180.610836 -351.917366)
			(xy 180.569626 -351.881654) (xy 180.533917 -351.840442) (xy 180.504437 -351.794567) (xy 180.481785 -351.744963)
			(xy 180.466422 -351.692641) (xy 180.458662 -351.638665) (xy 179.738238 -351.638665) (xy 179.738238 -351.638666)
			(xy 179.730477 -351.692642) (xy 179.715115 -351.744965) (xy 179.692462 -351.794569) (xy 179.662981 -351.840444)
			(xy 179.627271 -351.881657) (xy 179.58606 -351.917369) (xy 179.540186 -351.946852) (xy 179.490584 -351.969508)
			(xy 179.438262 -351.984873) (xy 179.384286 -351.992636) (xy 179.35702 -351.9932) (xy 178.892454 -351.9932)
			(xy 178.883818 -351.993962) (xy 178.871626 -351.995994) (xy 178.841389 -352.005827) (xy 178.778701 -352.01643)
			(xy 178.746912 -352.017076) (xy 178.710844 -352.017076) (xy 178.698774 -352.017746) (xy 178.677288 -352.028751)
			(xy 178.669696 -352.038158) (xy 178.667664 -352.040952) (xy 178.637946 -352.082862) (xy 178.634735 -352.087828)
			(xy 178.630504 -352.098867) (xy 178.629564 -352.104706) (xy 178.62804 -352.11639) (xy 178.632104 -352.128074)
			(xy 178.636709 -352.14177) (xy 178.643959 -352.169744) (xy 178.646582 -352.183954) (xy 178.64899 -352.198569)
			(xy 178.651662 -352.228072) (xy 178.651916 -352.242882) (xy 178.651916 -352.248216) (xy 178.649884 -352.28403)
			(xy 178.646843 -352.307906) (xy 233.389422 -352.307906) (xy 233.393493 -352.252284) (xy 233.405619 -352.197847)
			(xy 233.425542 -352.145756) (xy 233.452838 -352.097121) (xy 233.486924 -352.052978) (xy 233.527073 -352.014269)
			(xy 233.572431 -351.981818) (xy 233.622031 -351.956317) (xy 233.674815 -351.93831) (xy 233.729658 -351.92818)
			(xy 233.785392 -351.926143) (xy 233.840829 -351.932243) (xy 233.894786 -351.946349) (xy 233.946115 -351.968161)
			(xy 233.993721 -351.997215) (xy 234.036589 -352.03289) (xy 234.073806 -352.074427) (xy 234.104579 -352.12094)
			(xy 234.128251 -352.171437) (xy 234.144319 -352.224844) (xy 234.152439 -352.28002) (xy 234.152892 -352.304858)
			(xy 236.132368 -352.304858) (xy 236.136439 -352.249236) (xy 236.148565 -352.194799) (xy 236.168488 -352.142708)
			(xy 236.195784 -352.094073) (xy 236.22987 -352.04993) (xy 236.270019 -352.011221) (xy 236.315377 -351.97877)
			(xy 236.364977 -351.953269) (xy 236.417761 -351.935262) (xy 236.472604 -351.925132) (xy 236.528338 -351.923095)
			(xy 236.583775 -351.929195) (xy 236.637732 -351.943301) (xy 236.689061 -351.965113) (xy 236.736667 -351.994167)
			(xy 236.779535 -352.029842) (xy 236.816752 -352.071379) (xy 236.847525 -352.117892) (xy 236.871197 -352.168389)
			(xy 236.887265 -352.221796) (xy 236.895385 -352.276972) (xy 236.895894 -352.304858) (xy 236.895385 -352.332744)
			(xy 236.887265 -352.38792) (xy 236.883598 -352.400108) (xy 241.607846 -352.400108) (xy 241.611917 -352.344486)
			(xy 241.624043 -352.290049) (xy 241.643966 -352.237958) (xy 241.671262 -352.189323) (xy 241.705348 -352.14518)
			(xy 241.745497 -352.106471) (xy 241.790855 -352.07402) (xy 241.840455 -352.048519) (xy 241.893239 -352.030512)
			(xy 241.948082 -352.020382) (xy 242.003816 -352.018345) (xy 242.059253 -352.024445) (xy 242.11321 -352.038551)
			(xy 242.164539 -352.060363) (xy 242.179346 -352.0694) (xy 248.537476 -352.0694) (xy 248.537962 -352.042149)
			(xy 248.545718 -351.988201) (xy 248.561073 -351.935906) (xy 248.583715 -351.886329) (xy 248.613181 -351.840479)
			(xy 248.648872 -351.799288) (xy 248.690063 -351.763597) (xy 248.735913 -351.734131) (xy 248.78549 -351.711489)
			(xy 248.837785 -351.696134) (xy 248.891733 -351.688378) (xy 248.946235 -351.688378) (xy 249.000183 -351.696134)
			(xy 249.052478 -351.711489) (xy 249.102055 -351.734131) (xy 249.147905 -351.763597) (xy 249.189096 -351.799288)
			(xy 249.224787 -351.840479) (xy 249.254253 -351.886329) (xy 249.276895 -351.935906) (xy 249.29225 -351.988201)
			(xy 249.300006 -352.042149) (xy 249.300492 -352.0694) (xy 249.30006 -352.09683) (xy 249.292182 -352.151123)
			(xy 249.276617 -352.20373) (xy 249.253686 -352.253569) (xy 249.223861 -352.299614) (xy 249.187754 -352.340918)
			(xy 249.146109 -352.376632) (xy 249.1232 -352.391726) (xy 249.11084 -352.400294) (xy 249.091263 -352.423097)
			(xy 249.079171 -352.45061) (xy 249.07561 -352.480453) (xy 249.080889 -352.510039) (xy 249.094552 -352.536808)
			(xy 249.115414 -352.558442) (xy 249.12828 -352.566224) (xy 249.153419 -352.580761) (xy 249.199351 -352.616288)
			(xy 249.239371 -352.658364) (xy 249.272556 -352.706016) (xy 249.29814 -352.758145) (xy 249.315532 -352.813548)
			(xy 249.324332 -352.870946) (xy 249.324876 -352.89998) (xy 249.32439 -352.927231) (xy 249.316634 -352.981179)
			(xy 249.301279 -353.033474) (xy 249.278637 -353.083051) (xy 249.249171 -353.128901) (xy 249.21348 -353.170092)
			(xy 249.172289 -353.205783) (xy 249.126439 -353.235249) (xy 249.076862 -353.257891) (xy 249.024567 -353.273246)
			(xy 248.970619 -353.281002) (xy 248.916117 -353.281002) (xy 248.862169 -353.273246) (xy 248.809874 -353.257891)
			(xy 248.760297 -353.235249) (xy 248.714447 -353.205783) (xy 248.673256 -353.170092) (xy 248.637565 -353.128901)
			(xy 248.608099 -353.083051) (xy 248.585457 -353.033474) (xy 248.570102 -352.981179) (xy 248.562346 -352.927231)
			(xy 248.56186 -352.89998) (xy 248.562376 -352.872553) (xy 248.570242 -352.818265) (xy 248.585793 -352.765661)
			(xy 248.608711 -352.715823) (xy 248.638523 -352.669777) (xy 248.674617 -352.62847) (xy 248.716249 -352.592751)
			(xy 248.739152 -352.577654) (xy 248.751525 -352.569107) (xy 248.771093 -352.546296) (xy 248.783177 -352.518779)
			(xy 248.786733 -352.488937) (xy 248.781453 -352.45935) (xy 248.767793 -352.43258) (xy 248.746936 -352.410942)
			(xy 248.734072 -352.403156) (xy 248.708914 -352.388652) (xy 248.662984 -352.353117) (xy 248.622966 -352.311035)
			(xy 248.589784 -352.263378) (xy 248.564204 -352.211244) (xy 248.546815 -352.155837) (xy 248.538019 -352.098436)
			(xy 248.537476 -352.0694) (xy 242.179346 -352.0694) (xy 242.212145 -352.089417) (xy 242.255013 -352.125092)
			(xy 242.29223 -352.166629) (xy 242.323003 -352.213142) (xy 242.346675 -352.263639) (xy 242.362743 -352.317046)
			(xy 242.370863 -352.372222) (xy 242.371372 -352.400108) (xy 242.370863 -352.427994) (xy 242.362743 -352.48317)
			(xy 242.346675 -352.536577) (xy 242.323003 -352.587074) (xy 242.29223 -352.633587) (xy 242.255013 -352.675124)
			(xy 242.212145 -352.710799) (xy 242.164539 -352.739853) (xy 242.11321 -352.761665) (xy 242.059253 -352.775771)
			(xy 242.003816 -352.781871) (xy 241.948082 -352.779834) (xy 241.893239 -352.769704) (xy 241.840455 -352.751697)
			(xy 241.790855 -352.726196) (xy 241.745497 -352.693745) (xy 241.705348 -352.655036) (xy 241.671262 -352.610893)
			(xy 241.643966 -352.562258) (xy 241.624043 -352.510167) (xy 241.611917 -352.45573) (xy 241.607846 -352.400108)
			(xy 236.883598 -352.400108) (xy 236.871197 -352.441327) (xy 236.847525 -352.491824) (xy 236.816752 -352.538337)
			(xy 236.779535 -352.579874) (xy 236.736667 -352.615549) (xy 236.689061 -352.644603) (xy 236.637732 -352.666415)
			(xy 236.583775 -352.680521) (xy 236.528338 -352.686621) (xy 236.472604 -352.684584) (xy 236.417761 -352.674454)
			(xy 236.364977 -352.656447) (xy 236.315377 -352.630946) (xy 236.270019 -352.598495) (xy 236.22987 -352.559786)
			(xy 236.195784 -352.515643) (xy 236.168488 -352.467008) (xy 236.148565 -352.414917) (xy 236.136439 -352.36048)
			(xy 236.132368 -352.304858) (xy 234.152892 -352.304858) (xy 234.152948 -352.307906) (xy 234.152439 -352.335792)
			(xy 234.144319 -352.390968) (xy 234.128251 -352.444375) (xy 234.104579 -352.494872) (xy 234.073806 -352.541385)
			(xy 234.036589 -352.582922) (xy 233.993721 -352.618597) (xy 233.946115 -352.647651) (xy 233.894786 -352.669463)
			(xy 233.840829 -352.683569) (xy 233.785392 -352.689669) (xy 233.729658 -352.687632) (xy 233.674815 -352.677502)
			(xy 233.622031 -352.659495) (xy 233.572431 -352.633994) (xy 233.527073 -352.601543) (xy 233.486924 -352.562834)
			(xy 233.452838 -352.518691) (xy 233.425542 -352.470056) (xy 233.405619 -352.417965) (xy 233.393493 -352.363528)
			(xy 233.389422 -352.307906) (xy 178.646843 -352.307906) (xy 178.646336 -352.311887) (xy 178.631584 -352.36607)
			(xy 178.608482 -352.417252) (xy 178.593496 -352.441002) (xy 178.590956 -352.445066) (xy 178.585114 -352.458782)
			(xy 178.583844 -352.469704) (xy 178.583844 -353.270058) (xy 236.132368 -353.270058) (xy 236.136439 -353.214436)
			(xy 236.148565 -353.159999) (xy 236.168488 -353.107908) (xy 236.195784 -353.059273) (xy 236.22987 -353.01513)
			(xy 236.270019 -352.976421) (xy 236.315377 -352.94397) (xy 236.364977 -352.918469) (xy 236.417761 -352.900462)
			(xy 236.472604 -352.890332) (xy 236.528338 -352.888295) (xy 236.583775 -352.894395) (xy 236.637732 -352.908501)
			(xy 236.689061 -352.930313) (xy 236.736667 -352.959367) (xy 236.779535 -352.995042) (xy 236.816752 -353.036579)
			(xy 236.847525 -353.083092) (xy 236.871197 -353.133589) (xy 236.887265 -353.186996) (xy 236.895385 -353.242172)
			(xy 236.895894 -353.270058) (xy 236.895385 -353.297944) (xy 236.887265 -353.35312) (xy 236.873129 -353.400106)
			(xy 241.556538 -353.400106) (xy 241.560609 -353.344484) (xy 241.572735 -353.290047) (xy 241.592658 -353.237956)
			(xy 241.619954 -353.189321) (xy 241.65404 -353.145178) (xy 241.694189 -353.106469) (xy 241.739547 -353.074018)
			(xy 241.789147 -353.048517) (xy 241.841931 -353.03051) (xy 241.896774 -353.02038) (xy 241.952508 -353.018343)
			(xy 242.007945 -353.024443) (xy 242.061902 -353.038549) (xy 242.113231 -353.060361) (xy 242.160837 -353.089415)
			(xy 242.203705 -353.12509) (xy 242.240922 -353.166627) (xy 242.271695 -353.21314) (xy 242.295367 -353.263637)
			(xy 242.311435 -353.317044) (xy 242.319555 -353.37222) (xy 242.320064 -353.400106) (xy 242.319555 -353.427992)
			(xy 242.311435 -353.483168) (xy 242.295367 -353.536575) (xy 242.271695 -353.587072) (xy 242.240922 -353.633585)
			(xy 242.203705 -353.675122) (xy 242.160837 -353.710797) (xy 242.113231 -353.739851) (xy 242.061902 -353.761663)
			(xy 242.007945 -353.775769) (xy 241.952508 -353.781869) (xy 241.896774 -353.779832) (xy 241.841931 -353.769702)
			(xy 241.789147 -353.751695) (xy 241.739547 -353.726194) (xy 241.694189 -353.693743) (xy 241.65404 -353.655034)
			(xy 241.619954 -353.610891) (xy 241.592658 -353.562256) (xy 241.572735 -353.510165) (xy 241.560609 -353.455728)
			(xy 241.556538 -353.400106) (xy 236.873129 -353.400106) (xy 236.871197 -353.406527) (xy 236.847525 -353.457024)
			(xy 236.816752 -353.503537) (xy 236.779535 -353.545074) (xy 236.736667 -353.580749) (xy 236.689061 -353.609803)
			(xy 236.637732 -353.631615) (xy 236.583775 -353.645721) (xy 236.528338 -353.651821) (xy 236.472604 -353.649784)
			(xy 236.417761 -353.639654) (xy 236.364977 -353.621647) (xy 236.315377 -353.596146) (xy 236.270019 -353.563695)
			(xy 236.22987 -353.524986) (xy 236.195784 -353.480843) (xy 236.168488 -353.432208) (xy 236.148565 -353.380117)
			(xy 236.136439 -353.32568) (xy 236.132368 -353.270058) (xy 178.583844 -353.270058) (xy 178.583844 -354.235258)
			(xy 236.132368 -354.235258) (xy 236.136439 -354.179636) (xy 236.148565 -354.125199) (xy 236.168488 -354.073108)
			(xy 236.195784 -354.024473) (xy 236.22987 -353.98033) (xy 236.270019 -353.941621) (xy 236.315377 -353.90917)
			(xy 236.364977 -353.883669) (xy 236.417761 -353.865662) (xy 236.472604 -353.855532) (xy 236.528338 -353.853495)
			(xy 236.583775 -353.859595) (xy 236.637732 -353.873701) (xy 236.689061 -353.895513) (xy 236.696793 -353.900232)
			(xy 248.573288 -353.900232) (xy 248.577359 -353.84461) (xy 248.589485 -353.790173) (xy 248.609408 -353.738082)
			(xy 248.636704 -353.689447) (xy 248.67079 -353.645304) (xy 248.710939 -353.606595) (xy 248.756297 -353.574144)
			(xy 248.805897 -353.548643) (xy 248.858681 -353.530636) (xy 248.913524 -353.520506) (xy 248.969258 -353.518469)
			(xy 249.024695 -353.524569) (xy 249.078652 -353.538675) (xy 249.129981 -353.560487) (xy 249.177587 -353.589541)
			(xy 249.220455 -353.625216) (xy 249.257672 -353.666753) (xy 249.288445 -353.713266) (xy 249.312117 -353.763763)
			(xy 249.328185 -353.81717) (xy 249.336305 -353.872346) (xy 249.336814 -353.900232) (xy 249.336305 -353.928118)
			(xy 249.328185 -353.983294) (xy 249.312117 -354.036701) (xy 249.288445 -354.087198) (xy 249.257672 -354.133711)
			(xy 249.220455 -354.175248) (xy 249.177587 -354.210923) (xy 249.129981 -354.239977) (xy 249.078652 -354.261789)
			(xy 249.024695 -354.275895) (xy 248.969258 -354.281995) (xy 248.913524 -354.279958) (xy 248.858681 -354.269828)
			(xy 248.805897 -354.251821) (xy 248.756297 -354.22632) (xy 248.710939 -354.193869) (xy 248.67079 -354.15516)
			(xy 248.636704 -354.111017) (xy 248.609408 -354.062382) (xy 248.589485 -354.010291) (xy 248.577359 -353.955854)
			(xy 248.573288 -353.900232) (xy 236.696793 -353.900232) (xy 236.736667 -353.924567) (xy 236.779535 -353.960242)
			(xy 236.816752 -354.001779) (xy 236.847525 -354.048292) (xy 236.871197 -354.098789) (xy 236.887265 -354.152196)
			(xy 236.895385 -354.207372) (xy 236.895894 -354.235258) (xy 236.895385 -354.263144) (xy 236.887265 -354.31832)
			(xy 236.871197 -354.371727) (xy 236.857894 -354.400104) (xy 241.526312 -354.400104) (xy 241.530383 -354.344482)
			(xy 241.542509 -354.290045) (xy 241.562432 -354.237954) (xy 241.589728 -354.189319) (xy 241.623814 -354.145176)
			(xy 241.663963 -354.106467) (xy 241.709321 -354.074016) (xy 241.758921 -354.048515) (xy 241.811705 -354.030508)
			(xy 241.866548 -354.020378) (xy 241.922282 -354.018341) (xy 241.977719 -354.024441) (xy 242.031676 -354.038547)
			(xy 242.083005 -354.060359) (xy 242.130611 -354.089413) (xy 242.173479 -354.125088) (xy 242.210696 -354.166625)
			(xy 242.241469 -354.213138) (xy 242.265141 -354.263635) (xy 242.281209 -354.317042) (xy 242.289329 -354.372218)
			(xy 242.289838 -354.400104) (xy 242.289329 -354.42799) (xy 242.281209 -354.483166) (xy 242.265141 -354.536573)
			(xy 242.241469 -354.58707) (xy 242.210696 -354.633583) (xy 242.173479 -354.67512) (xy 242.130611 -354.710795)
			(xy 242.083005 -354.739849) (xy 242.031676 -354.761661) (xy 241.977719 -354.775767) (xy 241.922282 -354.781867)
			(xy 241.866548 -354.77983) (xy 241.811705 -354.7697) (xy 241.758921 -354.751693) (xy 241.709321 -354.726192)
			(xy 241.663963 -354.693741) (xy 241.623814 -354.655032) (xy 241.589728 -354.610889) (xy 241.562432 -354.562254)
			(xy 241.542509 -354.510163) (xy 241.530383 -354.455726) (xy 241.526312 -354.400104) (xy 236.857894 -354.400104)
			(xy 236.847525 -354.422224) (xy 236.816752 -354.468737) (xy 236.779535 -354.510274) (xy 236.736667 -354.545949)
			(xy 236.689061 -354.575003) (xy 236.637732 -354.596815) (xy 236.583775 -354.610921) (xy 236.528338 -354.617021)
			(xy 236.472604 -354.614984) (xy 236.417761 -354.604854) (xy 236.364977 -354.586847) (xy 236.315377 -354.561346)
			(xy 236.270019 -354.528895) (xy 236.22987 -354.490186) (xy 236.195784 -354.446043) (xy 236.168488 -354.397408)
			(xy 236.148565 -354.345317) (xy 236.136439 -354.29088) (xy 236.132368 -354.235258) (xy 178.583844 -354.235258)
			(xy 178.583844 -354.29952) (xy 178.584268 -354.309535) (xy 178.591943 -354.328038) (xy 178.606116 -354.342193)
			(xy 178.624628 -354.349845) (xy 178.634644 -354.35032) (xy 178.746912 -354.35032) (xy 178.774182 -354.350807)
			(xy 178.828167 -354.358571) (xy 178.880497 -354.373938) (xy 178.930109 -354.396596) (xy 178.97599 -354.426083)
			(xy 179.017208 -354.4618) (xy 179.052924 -354.50302) (xy 179.08241 -354.548902) (xy 179.105066 -354.598514)
			(xy 179.120432 -354.650845) (xy 179.128194 -354.70483) (xy 179.128194 -354.759369) (xy 180.458606 -354.759369)
			(xy 180.458606 -354.704831) (xy 180.466368 -354.650847) (xy 180.481732 -354.598517) (xy 180.504388 -354.548907)
			(xy 180.533872 -354.503025) (xy 180.569586 -354.461806) (xy 180.610802 -354.426089) (xy 180.656682 -354.396601)
			(xy 180.706291 -354.373942) (xy 180.75862 -354.358574) (xy 180.812603 -354.350808) (xy 180.839872 -354.35032)
			(xy 181.703472 -354.35032) (xy 181.730743 -354.350818) (xy 181.78473 -354.358576) (xy 181.837064 -354.373939)
			(xy 181.886678 -354.396594) (xy 181.932563 -354.42608) (xy 181.973785 -354.461795) (xy 182.009504 -354.503014)
			(xy 182.038992 -354.548897) (xy 182.061651 -354.59851) (xy 182.077018 -354.650842) (xy 182.08478 -354.704829)
			(xy 182.08478 -354.735472) (xy 183.567508 -354.735472) (xy 183.567508 -354.680928) (xy 183.57527 -354.626939)
			(xy 183.590638 -354.574605) (xy 183.613298 -354.52499) (xy 183.642788 -354.479106) (xy 183.678508 -354.437885)
			(xy 183.719731 -354.402169) (xy 183.765618 -354.372682) (xy 183.815235 -354.350027) (xy 183.86757 -354.334664)
			(xy 183.92156 -354.326905) (xy 183.948832 -354.326444) (xy 184.812432 -354.326444) (xy 184.8397 -354.326921)
			(xy 184.893681 -354.334686) (xy 184.946008 -354.350054) (xy 184.995615 -354.372713) (xy 185.041492 -354.4022)
			(xy 185.082707 -354.437916) (xy 185.118419 -354.479133) (xy 185.147903 -354.525013) (xy 185.170557 -354.574622)
			(xy 185.185921 -354.62695) (xy 185.193682 -354.680932) (xy 185.193682 -354.735468) (xy 185.193682 -354.735469)
			(xy 186.67653 -354.735469) (xy 186.67653 -354.680931) (xy 186.684292 -354.626949) (xy 186.699656 -354.574621)
			(xy 186.722312 -354.525012) (xy 186.751796 -354.479133) (xy 186.78751 -354.437916) (xy 186.828726 -354.402201)
			(xy 186.874605 -354.372716) (xy 186.924214 -354.350059) (xy 186.976542 -354.334693) (xy 187.030523 -354.326931)
			(xy 187.057792 -354.326444) (xy 187.921392 -354.326444) (xy 187.948664 -354.326895) (xy 188.002652 -354.334656)
			(xy 188.054987 -354.350022) (xy 188.104602 -354.37268) (xy 188.150487 -354.402167) (xy 188.191709 -354.437885)
			(xy 188.227428 -354.479106) (xy 188.256917 -354.524991) (xy 188.279575 -354.574606) (xy 188.294942 -354.62694)
			(xy 188.302704 -354.680928) (xy 188.302704 -354.735472) (xy 188.294942 -354.78946) (xy 188.279575 -354.841794)
			(xy 188.256917 -354.891409) (xy 188.227428 -354.937294) (xy 188.191709 -354.978515) (xy 188.15161 -355.01326)
			(xy 201.179174 -355.01326) (xy 201.183245 -354.957638) (xy 201.195371 -354.903201) (xy 201.215294 -354.85111)
			(xy 201.24259 -354.802475) (xy 201.276676 -354.758332) (xy 201.316825 -354.719623) (xy 201.362183 -354.687172)
			(xy 201.411783 -354.661671) (xy 201.464567 -354.643664) (xy 201.51941 -354.633534) (xy 201.575144 -354.631497)
			(xy 201.630581 -354.637597) (xy 201.684538 -354.651703) (xy 201.735867 -354.673515) (xy 201.783473 -354.702569)
			(xy 201.826341 -354.738244) (xy 201.863558 -354.779781) (xy 201.894331 -354.826294) (xy 201.918003 -354.876791)
			(xy 201.934071 -354.930198) (xy 201.942191 -354.985374) (xy 201.9427 -355.01326) (xy 201.942191 -355.041146)
			(xy 201.934071 -355.096322) (xy 201.918003 -355.149729) (xy 201.894331 -355.200226) (xy 201.863558 -355.246739)
			(xy 201.826341 -355.288276) (xy 201.783473 -355.323951) (xy 201.735867 -355.353005) (xy 201.684538 -355.374817)
			(xy 201.630581 -355.388923) (xy 201.575144 -355.395023) (xy 201.51941 -355.392986) (xy 201.464567 -355.382856)
			(xy 201.411783 -355.364849) (xy 201.362183 -355.339348) (xy 201.316825 -355.306897) (xy 201.276676 -355.268188)
			(xy 201.24259 -355.224045) (xy 201.215294 -355.17541) (xy 201.195371 -355.123319) (xy 201.183245 -355.068882)
			(xy 201.179174 -355.01326) (xy 188.15161 -355.01326) (xy 188.150487 -355.014233) (xy 188.104602 -355.04372)
			(xy 188.054987 -355.066378) (xy 188.002652 -355.081744) (xy 187.948664 -355.089505) (xy 187.921392 -355.089968)
			(xy 187.057792 -355.089968) (xy 187.030523 -355.089469) (xy 186.976542 -355.081707) (xy 186.924214 -355.066341)
			(xy 186.874605 -355.043684) (xy 186.828726 -355.014199) (xy 186.78751 -354.978484) (xy 186.751796 -354.937267)
			(xy 186.722312 -354.891388) (xy 186.699656 -354.841779) (xy 186.684292 -354.789451) (xy 186.67653 -354.735469)
			(xy 185.193682 -354.735469) (xy 185.185921 -354.78945) (xy 185.170557 -354.841778) (xy 185.147903 -354.891387)
			(xy 185.118419 -354.937267) (xy 185.082707 -354.978484) (xy 185.041492 -355.0142) (xy 184.995615 -355.043687)
			(xy 184.946008 -355.066346) (xy 184.893681 -355.081714) (xy 184.8397 -355.089479) (xy 184.812432 -355.089968)
			(xy 183.948832 -355.089968) (xy 183.92156 -355.089495) (xy 183.86757 -355.081736) (xy 183.815235 -355.066373)
			(xy 183.765618 -355.043718) (xy 183.719731 -355.014231) (xy 183.678508 -354.978515) (xy 183.642788 -354.937294)
			(xy 183.613298 -354.89141) (xy 183.590638 -354.841795) (xy 183.57527 -354.789461) (xy 183.567508 -354.735472)
			(xy 182.08478 -354.735472) (xy 182.08478 -354.759371) (xy 182.077018 -354.813358) (xy 182.061651 -354.86569)
			(xy 182.038992 -354.915303) (xy 182.009504 -354.961186) (xy 181.973785 -355.002405) (xy 181.932563 -355.03812)
			(xy 181.886678 -355.067606) (xy 181.837064 -355.090261) (xy 181.78473 -355.105624) (xy 181.730743 -355.113382)
			(xy 181.703472 -355.113844) (xy 180.839872 -355.113844) (xy 180.812603 -355.113392) (xy 180.75862 -355.105626)
			(xy 180.706291 -355.090258) (xy 180.656682 -355.067599) (xy 180.610802 -355.038111) (xy 180.569586 -355.002394)
			(xy 180.533872 -354.961175) (xy 180.504388 -354.915293) (xy 180.481732 -354.865683) (xy 180.466368 -354.813353)
			(xy 180.458606 -354.759369) (xy 179.128194 -354.759369) (xy 179.128194 -354.75937) (xy 179.120432 -354.813355)
			(xy 179.105066 -354.865686) (xy 179.08241 -354.915298) (xy 179.052924 -354.96118) (xy 179.017208 -355.0024)
			(xy 178.97599 -355.038117) (xy 178.930109 -355.067604) (xy 178.880497 -355.090262) (xy 178.828167 -355.105629)
			(xy 178.774182 -355.113393) (xy 178.746912 -355.113844) (xy 178.634644 -355.113844) (xy 178.62462 -355.114257)
			(xy 178.606096 -355.12192) (xy 178.59192 -355.136096) (xy 178.584257 -355.15462) (xy 178.583844 -355.164644)
			(xy 178.583844 -356.021894) (xy 205.409798 -356.021894) (xy 205.413869 -355.966272) (xy 205.425995 -355.911835)
			(xy 205.445918 -355.859744) (xy 205.473214 -355.811109) (xy 205.5073 -355.766966) (xy 205.547449 -355.728257)
			(xy 205.592807 -355.695806) (xy 205.642407 -355.670305) (xy 205.695191 -355.652298) (xy 205.750034 -355.642168)
			(xy 205.805768 -355.640131) (xy 205.861205 -355.646231) (xy 205.915162 -355.660337) (xy 205.966491 -355.682149)
			(xy 206.014097 -355.711203) (xy 206.056965 -355.746878) (xy 206.094182 -355.788415) (xy 206.124955 -355.834928)
			(xy 206.148627 -355.885425) (xy 206.164695 -355.938832) (xy 206.172815 -355.994008) (xy 206.173324 -356.021894)
			(xy 206.172815 -356.04978) (xy 206.164695 -356.104956) (xy 206.148627 -356.158363) (xy 206.124955 -356.20886)
			(xy 206.094182 -356.255373) (xy 206.056965 -356.29691) (xy 206.014097 -356.332585) (xy 205.966491 -356.361639)
			(xy 205.915162 -356.383451) (xy 205.861205 -356.397557) (xy 205.805768 -356.403657) (xy 205.750034 -356.40162)
			(xy 205.695191 -356.39149) (xy 205.642407 -356.373483) (xy 205.592807 -356.347982) (xy 205.547449 -356.315531)
			(xy 205.5073 -356.276822) (xy 205.473214 -356.232679) (xy 205.445918 -356.184044) (xy 205.425995 -356.131953)
			(xy 205.413869 -356.077516) (xy 205.409798 -356.021894) (xy 178.583844 -356.021894) (xy 178.583844 -356.811326)
			(xy 204.000098 -356.811326) (xy 204.004169 -356.755704) (xy 204.016295 -356.701267) (xy 204.036218 -356.649176)
			(xy 204.063514 -356.600541) (xy 204.0976 -356.556398) (xy 204.137749 -356.517689) (xy 204.183107 -356.485238)
			(xy 204.232707 -356.459737) (xy 204.285491 -356.44173) (xy 204.340334 -356.4316) (xy 204.396068 -356.429563)
			(xy 204.451505 -356.435663) (xy 204.505462 -356.449769) (xy 204.556791 -356.471581) (xy 204.604397 -356.500635)
			(xy 204.647265 -356.53631) (xy 204.684482 -356.577847) (xy 204.715255 -356.62436) (xy 204.738927 -356.674857)
			(xy 204.754995 -356.728264) (xy 204.763115 -356.78344) (xy 204.763624 -356.811326) (xy 204.763115 -356.839212)
			(xy 204.754995 -356.894388) (xy 204.738927 -356.947795) (xy 204.715255 -356.998292) (xy 204.684482 -357.044805)
			(xy 204.647265 -357.086342) (xy 204.604397 -357.122017) (xy 204.556791 -357.151071) (xy 204.505462 -357.172883)
			(xy 204.451505 -357.186989) (xy 204.396068 -357.193089) (xy 204.340334 -357.191052) (xy 204.285491 -357.180922)
			(xy 204.232707 -357.162915) (xy 204.183107 -357.137414) (xy 204.137749 -357.104963) (xy 204.0976 -357.066254)
			(xy 204.063514 -357.022111) (xy 204.036218 -356.973476) (xy 204.016295 -356.921385) (xy 204.004169 -356.866948)
			(xy 204.000098 -356.811326) (xy 178.583844 -356.811326) (xy 178.583844 -357.325168) (xy 178.584259 -357.33519)
			(xy 178.591925 -357.353711) (xy 178.606099 -357.367882) (xy 178.624622 -357.375544) (xy 178.634644 -357.375968)
			(xy 178.746912 -357.375968) (xy 178.774179 -357.376455) (xy 178.828157 -357.384218) (xy 178.880481 -357.399583)
			(xy 178.930085 -357.422238) (xy 178.975961 -357.451722) (xy 179.017174 -357.487434) (xy 179.052885 -357.528648)
			(xy 179.082368 -357.574525) (xy 179.105021 -357.624131) (xy 179.120385 -357.676455) (xy 179.128146 -357.730433)
			(xy 179.128146 -357.784966) (xy 180.458654 -357.784966) (xy 180.458654 -357.730434) (xy 180.466415 -357.676457)
			(xy 180.481777 -357.624134) (xy 180.50443 -357.57453) (xy 180.533911 -357.528654) (xy 180.56962 -357.48744)
			(xy 180.610831 -357.451727) (xy 180.656705 -357.422243) (xy 180.706308 -357.399587) (xy 180.75863 -357.384221)
			(xy 180.812606 -357.376456) (xy 180.839872 -357.375968) (xy 181.703472 -357.375968) (xy 181.730746 -357.37637)
			(xy 181.784741 -357.384129) (xy 181.837081 -357.399494) (xy 181.886701 -357.422152) (xy 181.932592 -357.451641)
			(xy 181.973819 -357.487361) (xy 182.009542 -357.528585) (xy 182.039035 -357.574474) (xy 182.061696 -357.624093)
			(xy 182.077065 -357.676432) (xy 182.084828 -357.730426) (xy 182.084828 -357.761176) (xy 183.567456 -357.761176)
			(xy 183.567456 -357.706624) (xy 183.57522 -357.652628) (xy 183.590589 -357.600287) (xy 183.613252 -357.550665)
			(xy 183.642746 -357.504775) (xy 183.678471 -357.463549) (xy 183.7197 -357.427827) (xy 183.765593 -357.398337)
			(xy 183.815217 -357.375678) (xy 183.867559 -357.360313) (xy 183.921556 -357.352553) (xy 183.948832 -357.352092)
			(xy 184.812432 -357.352092) (xy 184.839697 -357.352672) (xy 184.89367 -357.360437) (xy 184.94599 -357.375803)
			(xy 184.99559 -357.398458) (xy 185.041461 -357.427942) (xy 185.08267 -357.463653) (xy 185.118378 -357.504864)
			(xy 185.147857 -357.550738) (xy 185.170508 -357.60034) (xy 185.18587 -357.652661) (xy 185.19363 -357.706635)
			(xy 185.19363 -357.761165) (xy 185.193629 -357.761172) (xy 186.676479 -357.761172) (xy 186.676479 -357.706628)
			(xy 186.684241 -357.652638) (xy 186.699608 -357.600303) (xy 186.722266 -357.550688) (xy 186.751755 -357.504801)
			(xy 186.787473 -357.463579) (xy 186.828695 -357.42786) (xy 186.87458 -357.39837) (xy 186.924196 -357.37571)
			(xy 186.97653 -357.360343) (xy 187.03052 -357.352579) (xy 187.057792 -357.352092) (xy 187.921392 -357.352092)
			(xy 187.94866 -357.352647) (xy 188.002641 -357.360407) (xy 188.054969 -357.375771) (xy 188.104577 -357.398425)
			(xy 188.150456 -357.427909) (xy 188.191672 -357.463622) (xy 188.227386 -357.504838) (xy 188.256871 -357.550716)
			(xy 188.279526 -357.600324) (xy 188.294891 -357.652651) (xy 188.302653 -357.706632) (xy 188.302653 -357.761168)
			(xy 188.294891 -357.815149) (xy 188.279526 -357.867476) (xy 188.256871 -357.917084) (xy 188.227386 -357.962962)
			(xy 188.191672 -358.004178) (xy 188.150456 -358.039891) (xy 188.104577 -358.069375) (xy 188.054969 -358.092029)
			(xy 188.002641 -358.107393) (xy 187.94866 -358.115153) (xy 187.921392 -358.115616) (xy 187.057792 -358.115616)
			(xy 187.03052 -358.115221) (xy 186.97653 -358.107457) (xy 186.924196 -358.092089) (xy 186.87458 -358.06943)
			(xy 186.828695 -358.03994) (xy 186.787473 -358.004221) (xy 186.751755 -357.962999) (xy 186.722266 -357.917112)
			(xy 186.699608 -357.867497) (xy 186.684241 -357.815162) (xy 186.676479 -357.761172) (xy 185.193629 -357.761172)
			(xy 185.18587 -357.815139) (xy 185.170508 -357.86746) (xy 185.147857 -357.917062) (xy 185.118378 -357.962936)
			(xy 185.08267 -358.004147) (xy 185.041461 -358.039858) (xy 184.99559 -358.069342) (xy 184.94599 -358.091997)
			(xy 184.89367 -358.107363) (xy 184.839697 -358.115128) (xy 184.812432 -358.115616) (xy 183.948832 -358.115616)
			(xy 183.921556 -358.115247) (xy 183.867559 -358.107487) (xy 183.815217 -358.092122) (xy 183.765593 -358.069463)
			(xy 183.7197 -358.039973) (xy 183.678471 -358.004251) (xy 183.642746 -357.963025) (xy 183.613252 -357.917135)
			(xy 183.590589 -357.867513) (xy 183.57522 -357.815172) (xy 183.567456 -357.761176) (xy 182.084828 -357.761176)
			(xy 182.084828 -357.784974) (xy 182.077065 -357.838968) (xy 182.061696 -357.891307) (xy 182.039035 -357.940926)
			(xy 182.009542 -357.986815) (xy 181.973819 -358.028039) (xy 181.932592 -358.063759) (xy 181.886701 -358.093248)
			(xy 181.837081 -358.115906) (xy 181.784741 -358.131271) (xy 181.730746 -358.13903) (xy 181.703472 -358.139492)
			(xy 180.839872 -358.139492) (xy 180.812606 -358.138944) (xy 180.75863 -358.131179) (xy 180.706308 -358.115813)
			(xy 180.656705 -358.093157) (xy 180.610831 -358.063673) (xy 180.56962 -358.02796) (xy 180.533911 -357.986746)
			(xy 180.50443 -357.94087) (xy 180.481777 -357.891266) (xy 180.466415 -357.838943) (xy 180.458654 -357.784966)
			(xy 179.128146 -357.784966) (xy 179.128146 -357.784967) (xy 179.120385 -357.838945) (xy 179.105021 -357.891269)
			(xy 179.082368 -357.940875) (xy 179.052885 -357.986752) (xy 179.017174 -358.027966) (xy 178.975961 -358.063678)
			(xy 178.930085 -358.093162) (xy 178.880481 -358.115817) (xy 178.828157 -358.131182) (xy 178.774179 -358.138945)
			(xy 178.746912 -358.139492) (xy 178.634644 -358.139492) (xy 178.624616 -358.139904) (xy 178.606083 -358.147566)
			(xy 178.591895 -358.161739) (xy 178.584214 -358.180265) (xy 178.583844 -358.190292) (xy 178.583844 -358.388158)
			(xy 198.676258 -358.388158) (xy 198.680329 -358.332536) (xy 198.692455 -358.278099) (xy 198.712378 -358.226008)
			(xy 198.739674 -358.177373) (xy 198.77376 -358.13323) (xy 198.813909 -358.094521) (xy 198.859267 -358.06207)
			(xy 198.908867 -358.036569) (xy 198.961651 -358.018562) (xy 199.016494 -358.008432) (xy 199.072228 -358.006395)
			(xy 199.127665 -358.012495) (xy 199.181622 -358.026601) (xy 199.232951 -358.048413) (xy 199.280557 -358.077467)
			(xy 199.323425 -358.113142) (xy 199.360642 -358.154679) (xy 199.391415 -358.201192) (xy 199.415087 -358.251689)
			(xy 199.431155 -358.305096) (xy 199.439275 -358.360272) (xy 199.439784 -358.388158) (xy 199.439275 -358.416044)
			(xy 199.431155 -358.47122) (xy 199.415087 -358.524627) (xy 199.391415 -358.575124) (xy 199.360642 -358.621637)
			(xy 199.323425 -358.663174) (xy 199.280557 -358.698849) (xy 199.232951 -358.727903) (xy 199.181622 -358.749715)
			(xy 199.127665 -358.763821) (xy 199.072228 -358.769921) (xy 199.016494 -358.767884) (xy 198.961651 -358.757754)
			(xy 198.908867 -358.739747) (xy 198.859267 -358.714246) (xy 198.813909 -358.681795) (xy 198.77376 -358.643086)
			(xy 198.739674 -358.598943) (xy 198.712378 -358.550308) (xy 198.692455 -358.498217) (xy 198.680329 -358.44378)
			(xy 198.676258 -358.388158) (xy 178.583844 -358.388158) (xy 178.583844 -358.863392) (xy 197.77913 -358.863392)
			(xy 197.783201 -358.80777) (xy 197.795327 -358.753333) (xy 197.81525 -358.701242) (xy 197.842546 -358.652607)
			(xy 197.876632 -358.608464) (xy 197.916781 -358.569755) (xy 197.962139 -358.537304) (xy 198.011739 -358.511803)
			(xy 198.064523 -358.493796) (xy 198.119366 -358.483666) (xy 198.1751 -358.481629) (xy 198.230537 -358.487729)
			(xy 198.284494 -358.501835) (xy 198.335823 -358.523647) (xy 198.383429 -358.552701) (xy 198.426297 -358.588376)
			(xy 198.463514 -358.629913) (xy 198.494287 -358.676426) (xy 198.517959 -358.726923) (xy 198.534027 -358.78033)
			(xy 198.542147 -358.835506) (xy 198.542656 -358.863392) (xy 198.542147 -358.891278) (xy 198.534027 -358.946454)
			(xy 198.517959 -358.999861) (xy 198.494287 -359.050358) (xy 198.463514 -359.096871) (xy 198.426297 -359.138408)
			(xy 198.383429 -359.174083) (xy 198.335823 -359.203137) (xy 198.284494 -359.224949) (xy 198.230537 -359.239055)
			(xy 198.1751 -359.245155) (xy 198.119366 -359.243118) (xy 198.064523 -359.232988) (xy 198.011739 -359.214981)
			(xy 197.962139 -359.18948) (xy 197.916781 -359.157029) (xy 197.876632 -359.11832) (xy 197.842546 -359.074177)
			(xy 197.81525 -359.025542) (xy 197.795327 -358.973451) (xy 197.783201 -358.919014) (xy 197.77913 -358.863392)
			(xy 178.583844 -358.863392) (xy 178.583844 -359.714292) (xy 197.403972 -359.714292) (xy 197.408043 -359.65867)
			(xy 197.420169 -359.604233) (xy 197.440092 -359.552142) (xy 197.467388 -359.503507) (xy 197.501474 -359.459364)
			(xy 197.541623 -359.420655) (xy 197.586981 -359.388204) (xy 197.636581 -359.362703) (xy 197.689365 -359.344696)
			(xy 197.744208 -359.334566) (xy 197.799942 -359.332529) (xy 197.855379 -359.338629) (xy 197.909336 -359.352735)
			(xy 197.960665 -359.374547) (xy 198.008271 -359.403601) (xy 198.051139 -359.439276) (xy 198.088356 -359.480813)
			(xy 198.119129 -359.527326) (xy 198.142801 -359.577823) (xy 198.158869 -359.63123) (xy 198.166989 -359.686406)
			(xy 198.167498 -359.714292) (xy 198.166989 -359.742178) (xy 198.158869 -359.797354) (xy 198.142801 -359.850761)
			(xy 198.119129 -359.901258) (xy 198.088356 -359.947771) (xy 198.051139 -359.989308) (xy 198.008271 -360.024983)
			(xy 197.960665 -360.054037) (xy 197.909336 -360.075849) (xy 197.855379 -360.089955) (xy 197.799942 -360.096055)
			(xy 197.744208 -360.094018) (xy 197.689365 -360.083888) (xy 197.636581 -360.065881) (xy 197.586981 -360.04038)
			(xy 197.541623 -360.007929) (xy 197.501474 -359.96922) (xy 197.467388 -359.925077) (xy 197.440092 -359.876442)
			(xy 197.420169 -359.824351) (xy 197.408043 -359.769914) (xy 197.403972 -359.714292) (xy 178.583844 -359.714292)
			(xy 178.583844 -368.990118) (xy 179.223932 -368.990118) (xy 179.227923 -368.927951) (xy 179.239832 -368.866804)
			(xy 179.259461 -368.807683) (xy 179.28649 -368.751557) (xy 179.320474 -368.699348) (xy 179.360856 -368.651913)
			(xy 179.406972 -368.610032) (xy 179.458064 -368.574392) (xy 179.513295 -368.545578) (xy 179.571757 -368.524064)
			(xy 179.632491 -368.510202) (xy 179.694498 -368.50422) (xy 179.756761 -368.506216) (xy 179.818258 -368.516159)
			(xy 179.877979 -368.533883) (xy 179.934942 -368.5591) (xy 179.988213 -368.591393) (xy 180.036918 -368.630233)
			(xy 180.080255 -368.674983) (xy 180.117515 -368.724907) (xy 180.148084 -368.779186) (xy 180.171462 -368.836929)
			(xy 180.187263 -368.897187) (xy 180.195229 -368.95897) (xy 180.195728 -368.990118) (xy 180.195229 -369.021266)
			(xy 180.187263 -369.083049) (xy 180.171462 -369.143307) (xy 180.148084 -369.20105) (xy 180.117515 -369.255329)
			(xy 180.080255 -369.305253) (xy 180.036918 -369.350003) (xy 179.988213 -369.388843) (xy 179.934942 -369.421136)
			(xy 179.877979 -369.446353) (xy 179.818258 -369.464077) (xy 179.756761 -369.47402) (xy 179.694498 -369.476016)
			(xy 179.632491 -369.470034) (xy 179.571757 -369.456172) (xy 179.513295 -369.434658) (xy 179.458064 -369.405844)
			(xy 179.406972 -369.370204) (xy 179.360856 -369.328323) (xy 179.320474 -369.280888) (xy 179.28649 -369.228679)
			(xy 179.259461 -369.172553) (xy 179.239832 -369.113432) (xy 179.227923 -369.052285) (xy 179.223932 -368.990118)
			(xy 178.583844 -368.990118) (xy 178.583844 -371.590062) (xy 179.223932 -371.590062) (xy 179.227923 -371.527895)
			(xy 179.239832 -371.466748) (xy 179.259461 -371.407627) (xy 179.28649 -371.351501) (xy 179.320474 -371.299292)
			(xy 179.360856 -371.251857) (xy 179.406972 -371.209976) (xy 179.458064 -371.174336) (xy 179.513295 -371.145522)
			(xy 179.571757 -371.124008) (xy 179.632491 -371.110146) (xy 179.694498 -371.104164) (xy 179.756761 -371.10616)
			(xy 179.818258 -371.116103) (xy 179.877979 -371.133827) (xy 179.934942 -371.159044) (xy 179.988213 -371.191337)
			(xy 180.036918 -371.230177) (xy 180.080255 -371.274927) (xy 180.117515 -371.324851) (xy 180.148084 -371.37913)
			(xy 180.171462 -371.436873) (xy 180.187263 -371.497131) (xy 180.195229 -371.558914) (xy 180.195728 -371.590062)
			(xy 180.195229 -371.62121) (xy 180.187263 -371.682993) (xy 180.171462 -371.743251) (xy 180.148084 -371.800994)
			(xy 180.117515 -371.855273) (xy 180.080255 -371.905197) (xy 180.036918 -371.949947) (xy 179.988213 -371.988787)
			(xy 179.934942 -372.02108) (xy 179.877979 -372.046297) (xy 179.818258 -372.064021) (xy 179.756761 -372.073964)
			(xy 179.694498 -372.07596) (xy 179.632491 -372.069978) (xy 179.571757 -372.056116) (xy 179.513295 -372.034602)
			(xy 179.458064 -372.005788) (xy 179.406972 -371.970148) (xy 179.360856 -371.928267) (xy 179.320474 -371.880832)
			(xy 179.28649 -371.828623) (xy 179.259461 -371.772497) (xy 179.239832 -371.713376) (xy 179.227923 -371.652229)
			(xy 179.223932 -371.590062) (xy 178.583844 -371.590062) (xy 178.583844 -372.890034) (xy 179.223932 -372.890034)
			(xy 179.227923 -372.827867) (xy 179.239832 -372.76672) (xy 179.259461 -372.707599) (xy 179.28649 -372.651473)
			(xy 179.320474 -372.599264) (xy 179.360856 -372.551829) (xy 179.406972 -372.509948) (xy 179.458064 -372.474308)
			(xy 179.513295 -372.445494) (xy 179.571757 -372.42398) (xy 179.632491 -372.410118) (xy 179.694498 -372.404136)
			(xy 179.756761 -372.406132) (xy 179.818258 -372.416075) (xy 179.877979 -372.433799) (xy 179.934942 -372.459016)
			(xy 179.988213 -372.491309) (xy 180.036918 -372.530149) (xy 180.080255 -372.574899) (xy 180.117515 -372.624823)
			(xy 180.148084 -372.679102) (xy 180.171462 -372.736845) (xy 180.187263 -372.797103) (xy 180.195229 -372.858886)
			(xy 180.195728 -372.890034) (xy 180.195229 -372.921182) (xy 180.187263 -372.982965) (xy 180.171462 -373.043223)
			(xy 180.148084 -373.100966) (xy 180.117515 -373.155245) (xy 180.080255 -373.205169) (xy 180.036918 -373.249919)
			(xy 179.988213 -373.288759) (xy 179.934942 -373.321052) (xy 179.877979 -373.346269) (xy 179.818258 -373.363993)
			(xy 179.756761 -373.373936) (xy 179.694498 -373.375932) (xy 179.632491 -373.36995) (xy 179.571757 -373.356088)
			(xy 179.513295 -373.334574) (xy 179.458064 -373.30576) (xy 179.406972 -373.27012) (xy 179.360856 -373.228239)
			(xy 179.320474 -373.180804) (xy 179.28649 -373.128595) (xy 179.259461 -373.072469) (xy 179.239832 -373.013348)
			(xy 179.227923 -372.952201) (xy 179.223932 -372.890034) (xy 178.583844 -372.890034) (xy 178.583844 -375.490232)
			(xy 179.223932 -375.490232) (xy 179.227923 -375.428065) (xy 179.239832 -375.366918) (xy 179.259461 -375.307797)
			(xy 179.28649 -375.251671) (xy 179.320474 -375.199462) (xy 179.360856 -375.152027) (xy 179.406972 -375.110146)
			(xy 179.458064 -375.074506) (xy 179.513295 -375.045692) (xy 179.571757 -375.024178) (xy 179.632491 -375.010316)
			(xy 179.694498 -375.004334) (xy 179.756761 -375.00633) (xy 179.818258 -375.016273) (xy 179.877979 -375.033997)
			(xy 179.934942 -375.059214) (xy 179.988213 -375.091507) (xy 180.036918 -375.130347) (xy 180.080255 -375.175097)
			(xy 180.117515 -375.225021) (xy 180.148084 -375.2793) (xy 180.171462 -375.337043) (xy 180.187263 -375.397301)
			(xy 180.195229 -375.459084) (xy 180.195728 -375.490232) (xy 180.195229 -375.52138) (xy 180.187263 -375.583163)
			(xy 180.171462 -375.643421) (xy 180.148084 -375.701164) (xy 180.117515 -375.755443) (xy 180.080255 -375.805367)
			(xy 180.036918 -375.850117) (xy 179.988213 -375.888957) (xy 179.934942 -375.92125) (xy 179.877979 -375.946467)
			(xy 179.818258 -375.964191) (xy 179.756761 -375.974134) (xy 179.694498 -375.97613) (xy 179.632491 -375.970148)
			(xy 179.571757 -375.956286) (xy 179.513295 -375.934772) (xy 179.458064 -375.905958) (xy 179.406972 -375.870318)
			(xy 179.360856 -375.828437) (xy 179.320474 -375.781002) (xy 179.28649 -375.728793) (xy 179.259461 -375.672667)
			(xy 179.239832 -375.613546) (xy 179.227923 -375.552399) (xy 179.223932 -375.490232) (xy 178.583844 -375.490232)
			(xy 178.583844 -376.790204) (xy 179.223932 -376.790204) (xy 179.227923 -376.728037) (xy 179.239832 -376.66689)
			(xy 179.259461 -376.607769) (xy 179.28649 -376.551643) (xy 179.320474 -376.499434) (xy 179.360856 -376.451999)
			(xy 179.406972 -376.410118) (xy 179.458064 -376.374478) (xy 179.513295 -376.345664) (xy 179.571757 -376.32415)
			(xy 179.632491 -376.310288) (xy 179.694498 -376.304306) (xy 179.756761 -376.306302) (xy 179.818258 -376.316245)
			(xy 179.877979 -376.333969) (xy 179.934942 -376.359186) (xy 179.988213 -376.391479) (xy 180.036918 -376.430319)
			(xy 180.080255 -376.475069) (xy 180.117515 -376.524993) (xy 180.148084 -376.579272) (xy 180.171462 -376.637015)
			(xy 180.187263 -376.697273) (xy 180.195229 -376.759056) (xy 180.195728 -376.790204) (xy 180.195229 -376.821352)
			(xy 180.187263 -376.883135) (xy 180.171462 -376.943393) (xy 180.148084 -377.001136) (xy 180.117515 -377.055415)
			(xy 180.080255 -377.105339) (xy 180.036918 -377.150089) (xy 179.988213 -377.188929) (xy 179.934942 -377.221222)
			(xy 179.877979 -377.246439) (xy 179.818258 -377.264163) (xy 179.756761 -377.274106) (xy 179.694498 -377.276102)
			(xy 179.632491 -377.27012) (xy 179.571757 -377.256258) (xy 179.513295 -377.234744) (xy 179.458064 -377.20593)
			(xy 179.406972 -377.17029) (xy 179.360856 -377.128409) (xy 179.320474 -377.080974) (xy 179.28649 -377.028765)
			(xy 179.259461 -376.972639) (xy 179.239832 -376.913518) (xy 179.227923 -376.852371) (xy 179.223932 -376.790204)
			(xy 178.583844 -376.790204) (xy 178.583844 -379.390148) (xy 179.223932 -379.390148) (xy 179.227923 -379.327981)
			(xy 179.239832 -379.266834) (xy 179.259461 -379.207713) (xy 179.28649 -379.151587) (xy 179.320474 -379.099378)
			(xy 179.360856 -379.051943) (xy 179.406972 -379.010062) (xy 179.458064 -378.974422) (xy 179.513295 -378.945608)
			(xy 179.571757 -378.924094) (xy 179.632491 -378.910232) (xy 179.694498 -378.90425) (xy 179.756761 -378.906246)
			(xy 179.818258 -378.916189) (xy 179.877979 -378.933913) (xy 179.934942 -378.95913) (xy 179.988213 -378.991423)
			(xy 180.036918 -379.030263) (xy 180.080255 -379.075013) (xy 180.117515 -379.124937) (xy 180.148084 -379.179216)
			(xy 180.171462 -379.236959) (xy 180.187263 -379.297217) (xy 180.195229 -379.359) (xy 180.195728 -379.390148)
			(xy 180.195229 -379.421296) (xy 180.187263 -379.483079) (xy 180.171462 -379.543337) (xy 180.148084 -379.60108)
			(xy 180.117515 -379.655359) (xy 180.080255 -379.705283) (xy 180.036918 -379.750033) (xy 179.988213 -379.788873)
			(xy 179.934942 -379.821166) (xy 179.877979 -379.846383) (xy 179.818258 -379.864107) (xy 179.756761 -379.87405)
			(xy 179.694498 -379.876046) (xy 179.632491 -379.870064) (xy 179.571757 -379.856202) (xy 179.513295 -379.834688)
			(xy 179.458064 -379.805874) (xy 179.406972 -379.770234) (xy 179.360856 -379.728353) (xy 179.320474 -379.680918)
			(xy 179.28649 -379.628709) (xy 179.259461 -379.572583) (xy 179.239832 -379.513462) (xy 179.227923 -379.452315)
			(xy 179.223932 -379.390148) (xy 178.583844 -379.390148) (xy 178.583844 -380.69012) (xy 179.223932 -380.69012)
			(xy 179.227923 -380.627953) (xy 179.239832 -380.566806) (xy 179.259461 -380.507685) (xy 179.28649 -380.451559)
			(xy 179.320474 -380.39935) (xy 179.360856 -380.351915) (xy 179.406972 -380.310034) (xy 179.458064 -380.274394)
			(xy 179.513295 -380.24558) (xy 179.571757 -380.224066) (xy 179.632491 -380.210204) (xy 179.694498 -380.204222)
			(xy 179.756761 -380.206218) (xy 179.818258 -380.216161) (xy 179.877979 -380.233885) (xy 179.934942 -380.259102)
			(xy 179.988213 -380.291395) (xy 180.036918 -380.330235) (xy 180.080255 -380.374985) (xy 180.117515 -380.424909)
			(xy 180.148084 -380.479188) (xy 180.171462 -380.536931) (xy 180.187263 -380.597189) (xy 180.195229 -380.658972)
			(xy 180.195728 -380.69012) (xy 180.195229 -380.721268) (xy 180.187263 -380.783051) (xy 180.171462 -380.843309)
			(xy 180.148084 -380.901052) (xy 180.117515 -380.955331) (xy 180.080255 -381.005255) (xy 180.036918 -381.050005)
			(xy 179.988213 -381.088845) (xy 179.934942 -381.121138) (xy 179.877979 -381.146355) (xy 179.818258 -381.164079)
			(xy 179.756761 -381.174022) (xy 179.694498 -381.176018) (xy 179.632491 -381.170036) (xy 179.571757 -381.156174)
			(xy 179.513295 -381.13466) (xy 179.458064 -381.105846) (xy 179.406972 -381.070206) (xy 179.360856 -381.028325)
			(xy 179.320474 -380.98089) (xy 179.28649 -380.928681) (xy 179.259461 -380.872555) (xy 179.239832 -380.813434)
			(xy 179.227923 -380.752287) (xy 179.223932 -380.69012) (xy 178.583844 -380.69012) (xy 178.583844 -383.290064)
			(xy 179.223932 -383.290064) (xy 179.227923 -383.227897) (xy 179.239832 -383.16675) (xy 179.259461 -383.107629)
			(xy 179.28649 -383.051503) (xy 179.320474 -382.999294) (xy 179.360856 -382.951859) (xy 179.406972 -382.909978)
			(xy 179.458064 -382.874338) (xy 179.513295 -382.845524) (xy 179.571757 -382.82401) (xy 179.632491 -382.810148)
			(xy 179.694498 -382.804166) (xy 179.756761 -382.806162) (xy 179.818258 -382.816105) (xy 179.877979 -382.833829)
			(xy 179.934942 -382.859046) (xy 179.988213 -382.891339) (xy 180.036918 -382.930179) (xy 180.080255 -382.974929)
			(xy 180.117515 -383.024853) (xy 180.148084 -383.079132) (xy 180.171462 -383.136875) (xy 180.187263 -383.197133)
			(xy 180.195229 -383.258916) (xy 180.195728 -383.290064) (xy 180.195229 -383.321212) (xy 180.187263 -383.382995)
			(xy 180.171462 -383.443253) (xy 180.148084 -383.500996) (xy 180.117515 -383.555275) (xy 180.080255 -383.605199)
			(xy 180.036918 -383.649949) (xy 179.988213 -383.688789) (xy 179.934942 -383.721082) (xy 179.877979 -383.746299)
			(xy 179.818258 -383.764023) (xy 179.756761 -383.773966) (xy 179.694498 -383.775962) (xy 179.632491 -383.76998)
			(xy 179.571757 -383.756118) (xy 179.513295 -383.734604) (xy 179.458064 -383.70579) (xy 179.406972 -383.67015)
			(xy 179.360856 -383.628269) (xy 179.320474 -383.580834) (xy 179.28649 -383.528625) (xy 179.259461 -383.472499)
			(xy 179.239832 -383.413378) (xy 179.227923 -383.352231) (xy 179.223932 -383.290064) (xy 178.583844 -383.290064)
			(xy 178.583844 -384.590036) (xy 179.223932 -384.590036) (xy 179.227923 -384.527869) (xy 179.239832 -384.466722)
			(xy 179.259461 -384.407601) (xy 179.28649 -384.351475) (xy 179.320474 -384.299266) (xy 179.360856 -384.251831)
			(xy 179.406972 -384.20995) (xy 179.458064 -384.17431) (xy 179.513295 -384.145496) (xy 179.571757 -384.123982)
			(xy 179.632491 -384.11012) (xy 179.694498 -384.104138) (xy 179.756761 -384.106134) (xy 179.818258 -384.116077)
			(xy 179.877979 -384.133801) (xy 179.934942 -384.159018) (xy 179.988213 -384.191311) (xy 180.036918 -384.230151)
			(xy 180.080255 -384.274901) (xy 180.117515 -384.324825) (xy 180.148084 -384.379104) (xy 180.171462 -384.436847)
			(xy 180.187263 -384.497105) (xy 180.195229 -384.558888) (xy 180.195728 -384.590036) (xy 180.195229 -384.621184)
			(xy 180.187263 -384.682967) (xy 180.171462 -384.743225) (xy 180.148084 -384.800968) (xy 180.117515 -384.855247)
			(xy 180.080255 -384.905171) (xy 180.036918 -384.949921) (xy 179.988213 -384.988761) (xy 179.934942 -385.021054)
			(xy 179.877979 -385.046271) (xy 179.818258 -385.063995) (xy 179.756761 -385.073938) (xy 179.694498 -385.075934)
			(xy 179.632491 -385.069952) (xy 179.571757 -385.05609) (xy 179.513295 -385.034576) (xy 179.458064 -385.005762)
			(xy 179.406972 -384.970122) (xy 179.360856 -384.928241) (xy 179.320474 -384.880806) (xy 179.28649 -384.828597)
			(xy 179.259461 -384.772471) (xy 179.239832 -384.71335) (xy 179.227923 -384.652203) (xy 179.223932 -384.590036)
			(xy 178.583844 -384.590036) (xy 178.583844 -397.59001) (xy 179.223932 -397.59001) (xy 179.227923 -397.527843)
			(xy 179.239832 -397.466696) (xy 179.259461 -397.407575) (xy 179.28649 -397.351449) (xy 179.320474 -397.29924)
			(xy 179.360856 -397.251805) (xy 179.406972 -397.209924) (xy 179.458064 -397.174284) (xy 179.513295 -397.14547)
			(xy 179.571757 -397.123956) (xy 179.632491 -397.110094) (xy 179.694498 -397.104112) (xy 179.756761 -397.106108)
			(xy 179.818258 -397.116051) (xy 179.877979 -397.133775) (xy 179.934942 -397.158992) (xy 179.988213 -397.191285)
			(xy 180.036918 -397.230125) (xy 180.080255 -397.274875) (xy 180.117515 -397.324799) (xy 180.148084 -397.379078)
			(xy 180.171462 -397.436821) (xy 180.187263 -397.497079) (xy 180.195229 -397.558862) (xy 180.195728 -397.59001)
			(xy 180.195229 -397.621158) (xy 180.187263 -397.682941) (xy 180.171462 -397.743199) (xy 180.148084 -397.800942)
			(xy 180.117515 -397.855221) (xy 180.080255 -397.905145) (xy 180.036918 -397.949895) (xy 179.988213 -397.988735)
			(xy 179.934942 -398.021028) (xy 179.877979 -398.046245) (xy 179.818258 -398.063969) (xy 179.756761 -398.073912)
			(xy 179.694498 -398.075908) (xy 179.632491 -398.069926) (xy 179.571757 -398.056064) (xy 179.513295 -398.03455)
			(xy 179.458064 -398.005736) (xy 179.406972 -397.970096) (xy 179.360856 -397.928215) (xy 179.320474 -397.88078)
			(xy 179.28649 -397.828571) (xy 179.259461 -397.772445) (xy 179.239832 -397.713324) (xy 179.227923 -397.652177)
			(xy 179.223932 -397.59001) (xy 178.583844 -397.59001) (xy 178.583844 -398.890236) (xy 179.223932 -398.890236)
			(xy 179.227923 -398.828069) (xy 179.239832 -398.766922) (xy 179.259461 -398.707801) (xy 179.28649 -398.651675)
			(xy 179.320474 -398.599466) (xy 179.360856 -398.552031) (xy 179.406972 -398.51015) (xy 179.458064 -398.47451)
			(xy 179.513295 -398.445696) (xy 179.571757 -398.424182) (xy 179.632491 -398.41032) (xy 179.694498 -398.404338)
			(xy 179.756761 -398.406334) (xy 179.818258 -398.416277) (xy 179.877979 -398.434001) (xy 179.934942 -398.459218)
			(xy 179.988213 -398.491511) (xy 180.036918 -398.530351) (xy 180.080255 -398.575101) (xy 180.117515 -398.625025)
			(xy 180.148084 -398.679304) (xy 180.171462 -398.737047) (xy 180.187263 -398.797305) (xy 180.195229 -398.859088)
			(xy 180.195728 -398.890236) (xy 180.195229 -398.921384) (xy 180.187263 -398.983167) (xy 180.171462 -399.043425)
			(xy 180.148084 -399.101168) (xy 180.117515 -399.155447) (xy 180.080255 -399.205371) (xy 180.036918 -399.250121)
			(xy 179.988213 -399.288961) (xy 179.934942 -399.321254) (xy 179.877979 -399.346471) (xy 179.818258 -399.364195)
			(xy 179.756761 -399.374138) (xy 179.694498 -399.376134) (xy 179.632491 -399.370152) (xy 179.571757 -399.35629)
			(xy 179.513295 -399.334776) (xy 179.458064 -399.305962) (xy 179.406972 -399.270322) (xy 179.360856 -399.228441)
			(xy 179.320474 -399.181006) (xy 179.28649 -399.128797) (xy 179.259461 -399.072671) (xy 179.239832 -399.01355)
			(xy 179.227923 -398.952403) (xy 179.223932 -398.890236) (xy 178.583844 -398.890236) (xy 178.583844 -401.49018)
			(xy 179.223932 -401.49018) (xy 179.227923 -401.428013) (xy 179.239832 -401.366866) (xy 179.259461 -401.307745)
			(xy 179.28649 -401.251619) (xy 179.320474 -401.19941) (xy 179.360856 -401.151975) (xy 179.406972 -401.110094)
			(xy 179.458064 -401.074454) (xy 179.513295 -401.04564) (xy 179.571757 -401.024126) (xy 179.632491 -401.010264)
			(xy 179.694498 -401.004282) (xy 179.756761 -401.006278) (xy 179.818258 -401.016221) (xy 179.877979 -401.033945)
			(xy 179.934942 -401.059162) (xy 179.988213 -401.091455) (xy 180.036918 -401.130295) (xy 180.080255 -401.175045)
			(xy 180.117515 -401.224969) (xy 180.148084 -401.279248) (xy 180.171462 -401.336991) (xy 180.187263 -401.397249)
			(xy 180.195229 -401.459032) (xy 180.195728 -401.49018) (xy 180.195229 -401.521328) (xy 180.187263 -401.583111)
			(xy 180.171462 -401.643369) (xy 180.148084 -401.701112) (xy 180.117515 -401.755391) (xy 180.080255 -401.805315)
			(xy 180.036918 -401.850065) (xy 179.988213 -401.888905) (xy 179.934942 -401.921198) (xy 179.877979 -401.946415)
			(xy 179.818258 -401.964139) (xy 179.756761 -401.974082) (xy 179.694498 -401.976078) (xy 179.632491 -401.970096)
			(xy 179.571757 -401.956234) (xy 179.513295 -401.93472) (xy 179.458064 -401.905906) (xy 179.406972 -401.870266)
			(xy 179.360856 -401.828385) (xy 179.320474 -401.78095) (xy 179.28649 -401.728741) (xy 179.259461 -401.672615)
			(xy 179.239832 -401.613494) (xy 179.227923 -401.552347) (xy 179.223932 -401.49018) (xy 178.583844 -401.49018)
			(xy 178.583844 -405.620982) (xy 178.584283 -405.631045) (xy 178.592024 -405.649623) (xy 178.59883 -405.65705)
			(xy 179.025296 -406.083516) (xy 179.043325 -406.102288) (xy 179.073899 -406.144406) (xy 179.09752 -406.190783)
			(xy 179.113607 -406.24028) (xy 179.121766 -406.291682) (xy 179.122324 -406.317704) (xy 179.122324 -412.496762)
			(xy 179.121796 -412.522785) (xy 179.113627 -412.574187) (xy 179.09753 -412.623682) (xy 179.073901 -412.670057)
			(xy 179.04332 -412.712171) (xy 179.025296 -412.73095) (xy 178.59883 -413.157416) (xy 178.591983 -413.164814)
			(xy 178.584249 -413.183412) (xy 178.583844 -413.193484) (xy 178.583844 -413.457136) (xy 178.58438 -413.467087)
			(xy 178.592044 -413.485462) (xy 178.606099 -413.499563) (xy 178.615086 -413.503872) (xy 178.624532 -413.507426)
			(xy 178.644697 -413.507541) (xy 178.66333 -413.49983) (xy 178.670712 -413.49295) (xy 180.12029 -412.043372)
			(xy 180.127133 -412.035972) (xy 180.134859 -412.017374) (xy 180.135276 -412.007304) (xy 180.135276 -411.080204)
			(xy 180.134924 -411.071027) (xy 180.128525 -411.053828) (xy 180.116473 -411.039989) (xy 180.108606 -411.035246)
			(xy 180.029612 -410.993082) (xy 180.021376 -410.989077) (xy 180.003244 -410.986605) (xy 179.985399 -410.990662)
			(xy 179.977542 -410.995368) (xy 179.953673 -411.010639) (xy 179.903063 -411.036128) (xy 179.849829 -411.055551)
			(xy 179.794696 -411.068643) (xy 179.738413 -411.075227) (xy 179.71008 -411.075632) (xy 179.678285 -411.075111)
			(xy 179.615239 -411.066808) (xy 179.553816 -411.050348) (xy 179.495067 -411.026011) (xy 179.439997 -410.994214)
			(xy 179.389549 -410.955502) (xy 179.344585 -410.910536) (xy 179.305874 -410.860086) (xy 179.27408 -410.805015)
			(xy 179.249746 -410.746265) (xy 179.233288 -410.684841) (xy 179.224988 -410.621795) (xy 179.224988 -410.558205)
			(xy 179.233288 -410.495159) (xy 179.249746 -410.433735) (xy 179.27408 -410.374985) (xy 179.305874 -410.319914)
			(xy 179.344585 -410.269464) (xy 179.389549 -410.224498) (xy 179.439997 -410.185786) (xy 179.495067 -410.153989)
			(xy 179.553816 -410.129652) (xy 179.615239 -410.113192) (xy 179.678285 -410.104889) (xy 179.71008 -410.104336)
			(xy 179.738412 -410.104739) (xy 179.79469 -410.11134) (xy 179.849819 -410.124442) (xy 179.903049 -410.143869)
			(xy 179.953657 -410.169355) (xy 179.977542 -410.1846) (xy 179.985394 -410.189318) (xy 180.003243 -410.193378)
			(xy 180.02138 -410.190904) (xy 180.029612 -410.186886) (xy 180.108606 -410.144722) (xy 180.116505 -410.140022)
			(xy 180.128561 -410.126166) (xy 180.134958 -410.108949) (xy 180.135276 -410.099764) (xy 180.135276 -409.780232)
			(xy 180.134929 -409.771052) (xy 180.128535 -409.753846) (xy 180.116485 -409.739999) (xy 180.108606 -409.735274)
			(xy 180.029612 -409.69311) (xy 180.021377 -409.689103) (xy 180.003244 -409.68663) (xy 179.985399 -409.690689)
			(xy 179.977542 -409.695396) (xy 179.953672 -409.710666) (xy 179.903062 -409.736153) (xy 179.849828 -409.755575)
			(xy 179.794695 -409.768667) (xy 179.738413 -409.775251) (xy 179.71008 -409.77566) (xy 179.678283 -409.775139)
			(xy 179.615234 -409.766836) (xy 179.553807 -409.750374) (xy 179.495055 -409.726036) (xy 179.439982 -409.694238)
			(xy 179.38953 -409.655523) (xy 179.344564 -409.610555) (xy 179.305851 -409.560101) (xy 179.274055 -409.505027)
			(xy 179.249719 -409.446274) (xy 179.23326 -409.384847) (xy 179.22496 -409.321797) (xy 179.22496 -409.258203)
			(xy 179.23326 -409.195153) (xy 179.249719 -409.133726) (xy 179.274055 -409.074973) (xy 179.305851 -409.019899)
			(xy 179.344564 -408.969445) (xy 179.38953 -408.924477) (xy 179.439982 -408.885762) (xy 179.495055 -408.853964)
			(xy 179.553807 -408.829626) (xy 179.615234 -408.813164) (xy 179.678283 -408.804861) (xy 179.71008 -408.804364)
			(xy 179.738412 -408.804767) (xy 179.79469 -408.811368) (xy 179.849818 -408.824471) (xy 179.903047 -408.843899)
			(xy 179.953655 -408.869386) (xy 179.977542 -408.884628) (xy 179.985395 -408.889343) (xy 180.003243 -408.893402)
			(xy 180.021379 -408.890929) (xy 180.029612 -408.886914) (xy 180.108606 -408.84475) (xy 180.116508 -408.840051)
			(xy 180.128572 -408.826196) (xy 180.134977 -408.808979) (xy 180.135276 -408.799792) (xy 180.135276 -407.180288)
			(xy 180.134938 -407.171103) (xy 180.128557 -407.153882) (xy 180.11651 -407.140019) (xy 180.108606 -407.13533)
			(xy 180.029612 -407.093166) (xy 180.021378 -407.089156) (xy 180.003244 -407.08668) (xy 179.985399 -407.090744)
			(xy 179.977542 -407.095452) (xy 179.953673 -407.110723) (xy 179.903063 -407.136213) (xy 179.849829 -407.155637)
			(xy 179.794696 -407.16873) (xy 179.738413 -407.175314) (xy 179.71008 -407.175716) (xy 179.678286 -407.175195)
			(xy 179.615242 -407.166893) (xy 179.553821 -407.150433) (xy 179.495074 -407.126097) (xy 179.440006 -407.094301)
			(xy 179.389559 -407.05559) (xy 179.344597 -407.010625) (xy 179.305888 -406.960177) (xy 179.274094 -406.905108)
			(xy 179.249761 -406.84636) (xy 179.233303 -406.784938) (xy 179.225004 -406.721894) (xy 179.225004 -406.658306)
			(xy 179.233303 -406.595262) (xy 179.249761 -406.53384) (xy 179.274094 -406.475092) (xy 179.305888 -406.420023)
			(xy 179.344597 -406.369575) (xy 179.389559 -406.32461) (xy 179.440006 -406.285899) (xy 179.495074 -406.254103)
			(xy 179.553821 -406.229767) (xy 179.615242 -406.213307) (xy 179.678286 -406.205005) (xy 179.71008 -406.20442)
			(xy 179.738412 -406.204823) (xy 179.79469 -406.211424) (xy 179.849819 -406.224526) (xy 179.903049 -406.243951)
			(xy 179.953659 -406.269437) (xy 179.977542 -406.284684) (xy 179.985396 -406.289395) (xy 180.003243 -406.293449)
			(xy 180.021378 -406.290979) (xy 180.029612 -406.28697) (xy 180.108606 -406.244806) (xy 180.116503 -406.240105)
			(xy 180.128555 -406.226249) (xy 180.134946 -406.209032) (xy 180.135276 -406.199848) (xy 180.135276 -405.880316)
			(xy 180.134926 -405.871138) (xy 180.128529 -405.853936) (xy 180.116478 -405.840094) (xy 180.108606 -405.835358)
			(xy 180.029612 -405.793194) (xy 180.021376 -405.789188) (xy 180.003244 -405.786716) (xy 179.985399 -405.790774)
			(xy 179.977542 -405.79548) (xy 179.953673 -405.81075) (xy 179.903062 -405.836239) (xy 179.849829 -405.855661)
			(xy 179.794696 -405.868754) (xy 179.738413 -405.875337) (xy 179.71008 -405.875744) (xy 179.678284 -405.875223)
			(xy 179.615237 -405.86692) (xy 179.553812 -405.850459) (xy 179.495062 -405.826122) (xy 179.439991 -405.794324)
			(xy 179.389541 -405.755611) (xy 179.344576 -405.710644) (xy 179.305864 -405.660193) (xy 179.274069 -405.60512)
			(xy 179.249734 -405.546369) (xy 179.233276 -405.484944) (xy 179.224976 -405.421896) (xy 179.224976 -405.358304)
			(xy 179.233276 -405.295256) (xy 179.249734 -405.233831) (xy 179.274069 -405.17508) (xy 179.305864 -405.120007)
			(xy 179.344576 -405.069556) (xy 179.389541 -405.024589) (xy 179.439991 -404.985876) (xy 179.495062 -404.954078)
			(xy 179.553812 -404.929741) (xy 179.615237 -404.91328) (xy 179.678284 -404.904977) (xy 179.71008 -404.904448)
			(xy 179.738412 -404.904851) (xy 179.79469 -404.911452) (xy 179.849818 -404.924555) (xy 179.903048 -404.943981)
			(xy 179.953657 -404.969468) (xy 179.977542 -404.984712) (xy 179.985395 -404.989429) (xy 180.003243 -404.993488)
			(xy 180.02138 -404.991015) (xy 180.029612 -404.986998) (xy 180.108606 -404.944834) (xy 180.116506 -404.940134)
			(xy 180.128566 -404.926279) (xy 180.134966 -404.909062) (xy 180.135276 -404.899876) (xy 180.135276 -403.705568)
			(xy 180.134846 -403.695501) (xy 180.127121 -403.676907) (xy 180.12029 -403.6695) (xy 179.741322 -403.290786)
			(xy 179.734045 -403.284103) (xy 179.715878 -403.276382) (xy 179.706016 -403.2758) (xy 179.705762 -403.2758)
			(xy 179.674151 -403.275009) (xy 179.611529 -403.266242) (xy 179.550574 -403.249421) (xy 179.492319 -403.224831)
			(xy 179.437747 -403.192887) (xy 179.387784 -403.15413) (xy 179.343274 -403.109216) (xy 179.30497 -403.058905)
			(xy 179.27352 -403.004047) (xy 179.249457 -402.945572) (xy 179.233187 -402.884468) (xy 179.224986 -402.821769)
			(xy 179.224432 -402.790152) (xy 179.224955 -402.758357) (xy 179.233261 -402.69531) (xy 179.249724 -402.633888)
			(xy 179.274063 -402.575139) (xy 179.305861 -402.520069) (xy 179.344575 -402.469621) (xy 179.389542 -402.424656)
			(xy 179.439992 -402.385946) (xy 179.495064 -402.35415) (xy 179.553814 -402.329815) (xy 179.615238 -402.313355)
			(xy 179.678285 -402.305053) (xy 179.71008 -402.304504) (xy 179.741699 -402.305011) (xy 179.804403 -402.313216)
			(xy 179.865512 -402.329489) (xy 179.923991 -402.353557) (xy 179.978853 -402.38501) (xy 180.029168 -402.423318)
			(xy 180.074086 -402.467832) (xy 180.112846 -402.517799) (xy 180.144794 -402.572374) (xy 180.169388 -402.630634)
			(xy 180.186213 -402.691593) (xy 180.194984 -402.75422) (xy 180.195728 -402.785834) (xy 180.195728 -402.786088)
			(xy 180.196335 -402.795946) (xy 180.204041 -402.814113) (xy 180.210714 -402.821394) (xy 180.701696 -403.312376)
			(xy 180.719728 -403.331147) (xy 180.750307 -403.373264) (xy 180.773933 -403.419641) (xy 180.790026 -403.469138)
			(xy 180.798192 -403.520541) (xy 180.798724 -403.546564) (xy 180.798724 -412.166308) (xy 180.798192 -412.19233)
			(xy 180.790017 -412.243728) (xy 180.773915 -412.293219) (xy 180.750282 -412.339588) (xy 180.719698 -412.381697)
			(xy 180.701696 -412.400496) (xy 178.59883 -414.503362) (xy 178.59199 -414.510762) (xy 178.584274 -414.529361)
			(xy 178.583844 -414.53943) (xy 178.583844 -417.20643) (xy 178.583414 -417.216497) (xy 178.575686 -417.235088)
			(xy 178.568858 -417.242498) (xy 178.113944 -417.697412) (xy 178.107095 -417.704809) (xy 178.099358 -417.723408)
			(xy 178.098958 -417.73348) (xy 178.098958 -417.865052) (xy 178.099392 -417.875117) (xy 178.107126 -417.893702)
			(xy 178.113944 -417.90112) (xy 178.17846 -417.965636) (xy 178.185859 -417.97248) (xy 178.204458 -417.980203)
			(xy 178.214528 -417.980622)
		)
		(stroke
			(width 0)
			(type solid)
		)
		(fill yes)
		(layer "In9.Cu")
		(net "GND")
	)
	(gr_poly
		(pts
			(xy 44.759118 -417.957) (xy 44.769187 -417.956573) (xy 44.787786 -417.948854) (xy 44.795186 -417.942014)
			(xy 44.942506 -417.794694) (xy 44.949351 -417.787295) (xy 44.957082 -417.768697) (xy 44.957492 -417.758626)
			(xy 44.957492 -416.418522) (xy 44.957054 -416.408458) (xy 44.949319 -416.389875) (xy 44.942506 -416.382454)
			(xy 43.993816 -415.43351) (xy 43.986413 -415.426676) (xy 43.967815 -415.41897) (xy 43.957748 -415.418524)
			(xy 30.652466 -415.418524) (xy 30.619611 -415.418067) (xy 30.554313 -415.410718) (xy 30.490248 -415.396104)
			(xy 30.428223 -415.374409) (xy 30.369016 -415.345906) (xy 30.313373 -415.310954) (xy 30.261993 -415.269991)
			(xy 30.238446 -415.247074) (xy 27.495754 -412.504382) (xy 27.472855 -412.480818) (xy 27.431898 -412.429436)
			(xy 27.396948 -412.373793) (xy 27.368442 -412.31459) (xy 27.346738 -412.25257) (xy 27.33211 -412.18851)
			(xy 27.32474 -412.123216) (xy 27.324304 -412.090362) (xy 27.324304 -412.090108) (xy 27.324817 -412.05471)
			(xy 27.33335 -411.984429) (xy 27.350292 -411.915689) (xy 27.375397 -411.849493) (xy 27.408298 -411.786806)
			(xy 27.448516 -411.728541) (xy 27.495464 -411.67555) (xy 27.548457 -411.628604) (xy 27.606723 -411.588388)
			(xy 27.669411 -411.555489) (xy 27.735608 -411.530386) (xy 27.804349 -411.513446) (xy 27.87463 -411.504915)
			(xy 27.910028 -411.504384) (xy 27.910282 -411.504384) (xy 27.943136 -411.504843) (xy 28.008431 -411.512198)
			(xy 28.072493 -411.526816) (xy 28.134515 -411.548515) (xy 28.193717 -411.577022) (xy 28.249356 -411.611977)
			(xy 28.300732 -411.652942) (xy 28.324302 -411.675834) (xy 30.720284 -414.071816) (xy 30.72765 -414.072324)
			(xy 33.714944 -414.072324) (xy 33.720462 -414.072157) (xy 33.731227 -414.06972) (xy 33.73628 -414.067498)
			(xy 33.747202 -414.041082) (xy 33.750748 -414.031637) (xy 33.750852 -414.011479) (xy 33.743138 -413.992855)
			(xy 33.73628 -413.985456) (xy 32.341312 -412.590742) (xy 32.334037 -412.584055) (xy 32.31587 -412.576328)
			(xy 32.306006 -412.575756) (xy 32.305752 -412.575756) (xy 32.27414 -412.574965) (xy 32.211516 -412.566197)
			(xy 32.15056 -412.549375) (xy 32.092302 -412.524785) (xy 32.037728 -412.492842) (xy 31.987762 -412.454085)
			(xy 31.943249 -412.409172) (xy 31.904941 -412.358862) (xy 31.873486 -412.304005) (xy 31.849417 -412.24553)
			(xy 31.833141 -412.184425) (xy 31.824933 -412.121725) (xy 31.824422 -412.090108) (xy 31.824941 -412.05831)
			(xy 31.833241 -411.995258) (xy 31.849699 -411.933828) (xy 31.874035 -411.875073) (xy 31.905831 -411.819996)
			(xy 31.944544 -411.76954) (xy 31.989512 -411.724569) (xy 32.039964 -411.685852) (xy 32.095039 -411.654052)
			(xy 32.153792 -411.629712) (xy 32.215221 -411.613249) (xy 32.278272 -411.604944) (xy 32.31007 -411.60446)
			(xy 32.341688 -411.604966) (xy 32.40439 -411.61317) (xy 32.465497 -411.629444) (xy 32.523975 -411.653511)
			(xy 32.578834 -411.684965) (xy 32.629146 -411.723273) (xy 32.674061 -411.767788) (xy 32.712817 -411.817756)
			(xy 32.74476 -411.872332) (xy 32.769349 -411.930592) (xy 32.786168 -411.991551) (xy 32.794932 -412.054177)
			(xy 32.795718 -412.08579) (xy 32.795718 -412.086044) (xy 32.796335 -412.095898) (xy 32.804054 -412.114051)
			(xy 32.810704 -412.12135) (xy 34.551112 -413.861758) (xy 34.558509 -413.868607) (xy 34.577108 -413.876344)
			(xy 34.58718 -413.876744) (xy 37.559996 -413.876744) (xy 37.569982 -413.876341) (xy 37.588439 -413.868711)
			(xy 37.602551 -413.854579) (xy 37.606732 -413.845502) (xy 37.618416 -413.817816) (xy 37.617146 -413.811466)
			(xy 36.30295 -412.49727) (xy 36.280453 -412.474129) (xy 36.240217 -412.423666) (xy 36.205882 -412.369015)
			(xy 36.177881 -412.310864) (xy 36.156567 -412.249945) (xy 36.142205 -412.187022) (xy 36.134978 -412.122887)
			(xy 36.134548 -412.090616) (xy 36.134548 -412.090108) (xy 36.135052 -412.055323) (xy 36.143437 -411.986261)
			(xy 36.160085 -411.918713) (xy 36.184754 -411.853664) (xy 36.217085 -411.792063) (xy 36.256605 -411.734809)
			(xy 36.302738 -411.682735) (xy 36.354812 -411.636602) (xy 36.412067 -411.597083) (xy 36.473668 -411.564753)
			(xy 36.538717 -411.540084) (xy 36.606265 -411.523436) (xy 36.675327 -411.515051) (xy 36.710112 -411.514544)
			(xy 36.71062 -411.514544) (xy 36.742888 -411.515012) (xy 36.807015 -411.52226) (xy 36.869931 -411.536631)
			(xy 36.930846 -411.557943) (xy 36.988998 -411.585931) (xy 37.043657 -411.620242) (xy 37.094139 -411.660447)
			(xy 37.117274 -411.682946) (xy 38.613334 -413.179006) (xy 38.618834 -413.183992) (xy 38.632001 -413.190833)
			(xy 38.639242 -413.192468) (xy 38.648894 -413.193484) (xy 41.635934 -413.193484) (xy 41.645581 -413.193067)
			(xy 41.663496 -413.185908) (xy 41.677457 -413.172593) (xy 41.681908 -413.16402) (xy 41.68267 -413.161988)
			(xy 41.685375 -413.154885) (xy 41.686921 -413.139775) (xy 41.685718 -413.13227) (xy 41.684194 -413.125158)
			(xy 41.677336 -413.112458) (xy 41.155366 -412.590488) (xy 41.151635 -412.586968) (xy 41.14306 -412.581341)
			(xy 41.138348 -412.579312) (xy 41.12895 -412.575502) (xy 41.118536 -412.575756) (xy 41.1099 -412.575756)
			(xy 41.078962 -412.575271) (xy 41.017587 -412.567411) (xy 40.957707 -412.55182) (xy 40.900293 -412.528749)
			(xy 40.846275 -412.498572) (xy 40.796527 -412.461778) (xy 40.751855 -412.418964) (xy 40.712983 -412.370822)
			(xy 40.680541 -412.318132) (xy 40.655055 -412.261749) (xy 40.636936 -412.202585) (xy 40.626479 -412.141599)
			(xy 40.623854 -412.079778) (xy 40.629101 -412.018125) (xy 40.642138 -411.957638) (xy 40.662752 -411.899297)
			(xy 40.690609 -411.844046) (xy 40.725258 -411.792781) (xy 40.766139 -411.746333) (xy 40.812588 -411.705453)
			(xy 40.863853 -411.670805) (xy 40.919104 -411.642948) (xy 40.977446 -411.622336) (xy 41.037933 -411.6093)
			(xy 41.099586 -411.604053) (xy 41.161407 -411.60668) (xy 41.222393 -411.617138) (xy 41.281556 -411.635257)
			(xy 41.337939 -411.660745) (xy 41.390628 -411.693188) (xy 41.43877 -411.73206) (xy 41.481583 -411.776733)
			(xy 41.518376 -411.826481) (xy 41.548552 -411.880501) (xy 41.571622 -411.937915) (xy 41.587213 -411.997795)
			(xy 41.595071 -412.05917) (xy 41.595548 -412.090108) (xy 41.595548 -412.098744) (xy 41.595294 -412.109158)
			(xy 41.599104 -412.118556) (xy 41.601105 -412.123283) (xy 41.60673 -412.131867) (xy 41.61028 -412.135574)
			(xy 42.441114 -412.966154) (xy 42.468546 -412.993586) (xy 42.475929 -413.000166) (xy 42.494227 -413.007614)
			(xy 42.504106 -413.008064) (xy 44.558712 -413.008064) (xy 44.56878 -413.007638) (xy 44.587378 -412.999916)
			(xy 44.59478 -412.993078) (xy 44.675552 -412.912306) (xy 44.682405 -412.90491) (xy 44.690149 -412.886312)
			(xy 44.690538 -412.876238) (xy 44.690538 -412.071058) (xy 44.69097 -412.060992) (xy 44.698699 -412.042402)
			(xy 44.705524 -412.03499) (xy 44.727368 -412.013146) (xy 44.734768 -412.006305) (xy 44.753367 -411.998588)
			(xy 44.763436 -411.99816) (xy 44.831508 -411.99816) (xy 44.841577 -411.997734) (xy 44.860175 -411.990013)
			(xy 44.867576 -411.983174) (xy 44.958254 -411.892496) (xy 44.962318 -411.882336) (xy 44.975371 -411.849432)
			(xy 45.008273 -411.786754) (xy 45.048489 -411.728498) (xy 45.095432 -411.675513) (xy 45.148419 -411.628572)
			(xy 45.206677 -411.588359) (xy 45.269357 -411.55546) (xy 45.335544 -411.530355) (xy 45.404275 -411.51341)
			(xy 45.474548 -411.504872) (xy 45.509942 -411.504384) (xy 45.510704 -411.504384) (xy 45.536884 -411.504682)
			(xy 45.589034 -411.509385) (xy 45.614844 -411.513782) (xy 45.619416 -411.514544) (xy 45.663358 -411.514544)
			(xy 45.673422 -411.514109) (xy 45.692006 -411.506373) (xy 45.699426 -411.499558) (xy 45.743368 -411.455616)
			(xy 45.750205 -411.448215) (xy 45.757914 -411.429616) (xy 45.758354 -411.419548) (xy 45.758354 -410.245306)
			(xy 45.757931 -410.235236) (xy 45.750213 -410.216635) (xy 45.743368 -410.209238) (xy 45.51045 -409.97632)
			(xy 45.496988 -409.975558) (xy 45.465758 -409.974236) (xy 45.404004 -409.96456) (xy 45.344001 -409.947041)
			(xy 45.286741 -409.92197) (xy 45.233171 -409.88976) (xy 45.184175 -409.850944) (xy 45.140564 -409.806163)
			(xy 45.103058 -409.756158) (xy 45.072276 -409.701755) (xy 45.048728 -409.643852) (xy 45.032802 -409.583407)
			(xy 45.024763 -409.521418) (xy 45.024294 -409.490164) (xy 45.024817 -409.457571) (xy 45.033532 -409.392971)
			(xy 45.050815 -409.330118) (xy 45.076354 -409.270144) (xy 45.109689 -409.214127) (xy 45.150222 -409.163075)
			(xy 45.197222 -409.117907) (xy 45.249845 -409.079436) (xy 45.307142 -409.048353) (xy 45.368085 -409.025218)
			(xy 45.431575 -409.010448) (xy 45.463968 -409.006802) (xy 45.473324 -409.005524) (xy 45.490185 -408.997052)
			(xy 45.502846 -408.98306) (xy 45.509595 -408.965438) (xy 45.509942 -408.956002) (xy 45.509942 -408.808682)
			(xy 45.509514 -408.798615) (xy 45.501789 -408.78002) (xy 45.494956 -408.772614) (xy 45.38091 -408.658568)
			(xy 45.374814 -408.656536) (xy 45.343634 -408.646944) (xy 45.283976 -408.620552) (xy 45.228385 -408.586417)
			(xy 45.17786 -408.545151) (xy 45.13331 -408.497498) (xy 45.095535 -408.444313) (xy 45.065214 -408.386553)
			(xy 45.042893 -408.325255) (xy 45.028972 -408.261523) (xy 45.025818 -408.229054) (xy 45.024294 -408.190192)
			(xy 45.024793 -408.158374) (xy 45.033107 -408.095283) (xy 45.049589 -408.033818) (xy 45.073959 -407.975032)
			(xy 45.105799 -407.919934) (xy 45.144563 -407.869466) (xy 45.189586 -407.824494) (xy 45.240098 -407.785789)
			(xy 45.295234 -407.754012) (xy 45.354047 -407.72971) (xy 45.41553 -407.713298) (xy 45.478631 -407.705057)
			(xy 45.51045 -407.704544) (xy 45.518578 -407.704544) (xy 45.528992 -407.704798) (xy 45.53839 -407.700988)
			(xy 45.542947 -407.699051) (xy 45.551265 -407.693682) (xy 45.5549 -407.69032) (xy 45.922946 -407.32202)
			(xy 45.929786 -407.31462) (xy 45.9375 -407.296021) (xy 45.937932 -407.285952) (xy 45.937932 -406.580086)
			(xy 45.937507 -406.570016) (xy 45.929793 -406.551412) (xy 45.922946 -406.544018) (xy 45.451268 -406.07234)
			(xy 45.442378 -406.07107) (xy 45.412279 -406.06637) (xy 45.353481 -406.050427) (xy 45.297143 -406.027246)
			(xy 45.244151 -405.997193) (xy 45.19534 -405.960741) (xy 45.151477 -405.918464) (xy 45.13199 -405.895048)
			(xy 45.111707 -405.86902) (xy 45.077613 -405.812525) (xy 45.051478 -405.751935) (xy 45.033783 -405.688366)
			(xy 45.024854 -405.622987) (xy 45.024294 -405.589994) (xy 45.024777 -405.558997) (xy 45.032654 -405.497505)
			(xy 45.048291 -405.437515) (xy 45.071435 -405.380003) (xy 45.101709 -405.325903) (xy 45.13862 -405.276095)
			(xy 45.18157 -405.231389) (xy 45.229859 -405.192512) (xy 45.282703 -405.160095) (xy 45.339242 -405.134666)
			(xy 45.398557 -405.116638) (xy 45.459684 -405.106305) (xy 45.490638 -405.1046) (xy 45.50029 -405.104346)
			(xy 45.517562 -405.096726) (xy 45.550328 -405.06396) (xy 45.557176 -405.056563) (xy 45.564907 -405.037964)
			(xy 45.565314 -405.027892) (xy 45.565314 -404.847552) (xy 45.564883 -404.837485) (xy 45.557158 -404.818892)
			(xy 45.550328 -404.811484) (xy 45.528484 -404.790148) (xy 45.521444 -404.783717) (xy 45.503955 -404.776156)
			(xy 45.494448 -404.775416) (xy 45.462979 -404.773907) (xy 45.400798 -404.763763) (xy 45.340451 -404.745664)
			(xy 45.282951 -404.719914) (xy 45.229264 -404.686944) (xy 45.180291 -404.647308) (xy 45.136855 -404.601672)
			(xy 45.099684 -404.550803) (xy 45.069404 -404.495554) (xy 45.046523 -404.436853) (xy 45.031424 -404.375686)
			(xy 45.024362 -404.313081) (xy 45.025455 -404.250087) (xy 45.034685 -404.187764) (xy 45.051896 -404.127158)
			(xy 45.0768 -404.069287) (xy 45.108978 -404.015121) (xy 45.147891 -403.965572) (xy 45.192884 -403.92147)
			(xy 45.243202 -403.883557) (xy 45.298001 -403.852469) (xy 45.356359 -403.828728) (xy 45.417298 -403.812734)
			(xy 45.448474 -403.808184) (xy 45.462703 -403.806499) (xy 45.491297 -403.804592) (xy 45.505624 -403.804374)
			(xy 45.505878 -403.804374) (xy 45.515737 -403.803768) (xy 45.533906 -403.796065) (xy 45.541184 -403.789388)
			(xy 46.15815 -403.172422) (xy 46.17693 -403.154309) (xy 46.219127 -403.123623) (xy 46.265608 -403.099922)
			(xy 46.315226 -403.083792) (xy 46.366759 -403.07563) (xy 46.392846 -403.07514) (xy 47.186088 -403.07514)
			(xy 47.1932 -403.06879) (xy 47.194216 -403.067774) (xy 47.194724 -403.067266) (xy 47.194724 -403.067012)
			(xy 47.245524 -402.995892) (xy 47.245778 -402.995638) (xy 47.248988 -402.990672) (xy 47.253217 -402.979632)
			(xy 47.25416 -402.973794) (xy 47.255684 -402.96211) (xy 47.25162 -402.950426) (xy 47.243349 -402.925728)
			(xy 47.231516 -402.875001) (xy 47.22517 -402.8233) (xy 47.224442 -402.797264) (xy 47.224442 -402.78812)
			(xy 47.22508 -402.756591) (xy 47.23351 -402.694095) (xy 47.249959 -402.633215) (xy 47.274149 -402.574977)
			(xy 47.305674 -402.52036) (xy 47.344003 -402.470282) (xy 47.388492 -402.425587) (xy 47.438391 -402.387027)
			(xy 47.492862 -402.35525) (xy 47.550988 -402.33079) (xy 47.61179 -402.31406) (xy 47.674247 -402.30534)
			(xy 47.705772 -402.304504) (xy 47.706026 -402.304504) (xy 47.715882 -402.30389) (xy 47.734041 -402.296179)
			(xy 47.741332 -402.289518) (xy 48.122332 -401.908518) (xy 48.129015 -401.901116) (xy 48.136619 -401.882702)
			(xy 48.136635 -401.86278) (xy 48.133254 -401.8534) (xy 48.127412 -401.838922) (xy 48.101758 -401.821904)
			(xy 48.076104 -401.821904) (xy 48.057816 -401.82927) (xy 48.055784 -401.831302) (xy 48.032895 -401.853771)
			(xy 47.982232 -401.893105) (xy 47.926832 -401.925427) (xy 47.867658 -401.950173) (xy 47.805742 -401.966914)
			(xy 47.74216 -401.975357) (xy 47.71009 -401.975828) (xy 47.678295 -401.975307) (xy 47.615248 -401.967006)
			(xy 47.553825 -401.950547) (xy 47.495075 -401.926211) (xy 47.440005 -401.894415) (xy 47.389556 -401.855703)
			(xy 47.344591 -401.810737) (xy 47.30588 -401.760287) (xy 47.274085 -401.705216) (xy 47.24975 -401.646465)
			(xy 47.233292 -401.585042) (xy 47.224992 -401.521995) (xy 47.224992 -401.458405) (xy 47.233292 -401.395358)
			(xy 47.24975 -401.333934) (xy 47.274085 -401.275184) (xy 47.30588 -401.220113) (xy 47.344591 -401.169663)
			(xy 47.389556 -401.124697) (xy 47.440005 -401.085985) (xy 47.495075 -401.054189) (xy 47.553825 -401.029853)
			(xy 47.615248 -401.013394) (xy 47.678295 -401.005093) (xy 47.71009 -401.004532) (xy 47.742129 -401.005044)
			(xy 47.80565 -401.013468) (xy 47.867513 -401.030169) (xy 47.926642 -401.05486) (xy 47.982012 -401.08711)
			(xy 48.032662 -401.126359) (xy 48.05553 -401.148804) (xy 48.056038 -401.149312) (xy 48.057816 -401.15109)
			(xy 48.076104 -401.158456) (xy 48.106076 -401.158456) (xy 48.116097 -401.15804) (xy 48.134615 -401.150373)
			(xy 48.148784 -401.136198) (xy 48.156444 -401.117677) (xy 48.156876 -401.107656) (xy 48.156876 -399.546572)
			(xy 48.156383 -399.53657) (xy 48.148717 -399.518092) (xy 48.134565 -399.503953) (xy 48.116079 -399.496307)
			(xy 48.106076 -399.495772) (xy 48.09617 -399.495772) (xy 48.08728 -399.499328) (xy 48.0827 -399.50101)
			(xy 48.073109 -399.502792) (xy 48.06823 -399.502884) (xy 47.35195 -399.502884) (xy 47.341815 -399.502404)
			(xy 47.323074 -399.494686) (xy 47.308697 -399.4804) (xy 47.300861 -399.461708) (xy 47.300388 -399.451576)
			(xy 47.300388 -399.165572) (xy 47.300198 -399.158698) (xy 47.296593 -399.145434) (xy 47.293276 -399.13941)
			(xy 47.27695 -399.111049) (xy 47.251226 -399.050878) (xy 47.233812 -398.987798) (xy 47.225023 -398.922951)
			(xy 47.225019 -398.857511) (xy 47.233799 -398.792663) (xy 47.251205 -398.729581) (xy 47.276922 -398.669406)
			(xy 47.293276 -398.641062) (xy 47.296588 -398.635036) (xy 47.300197 -398.621773) (xy 47.300388 -398.6149)
			(xy 47.300388 -397.865346) (xy 47.300194 -397.858473) (xy 47.296583 -397.845212) (xy 47.293276 -397.839184)
			(xy 47.276952 -397.810823) (xy 47.251231 -397.750652) (xy 47.23382 -397.687573) (xy 47.225035 -397.622728)
			(xy 47.225034 -397.55729) (xy 47.233817 -397.492444) (xy 47.251225 -397.429364) (xy 47.276944 -397.369192)
			(xy 47.293276 -397.340836) (xy 47.296585 -397.334809) (xy 47.300187 -397.321547) (xy 47.300388 -397.314674)
			(xy 47.300388 -397.028924) (xy 47.300814 -397.018768) (xy 47.308604 -397.000008) (xy 47.322998 -396.985677)
			(xy 47.341792 -396.97797) (xy 47.35195 -396.977616) (xy 48.06823 -396.977616) (xy 48.073109 -396.977704)
			(xy 48.082701 -396.979486) (xy 48.08728 -396.981172) (xy 48.09617 -396.984728) (xy 48.106076 -396.984728)
			(xy 48.116089 -396.984245) (xy 48.134594 -396.97659) (xy 48.148761 -396.962437) (xy 48.156434 -396.94394)
			(xy 48.156876 -396.933928) (xy 48.156876 -392.124692) (xy 48.157408 -392.09867) (xy 48.165583 -392.047272)
			(xy 48.181685 -391.997781) (xy 48.205318 -391.951412) (xy 48.235902 -391.909303) (xy 48.253904 -391.890504)
			(xy 54.985158 -385.15925) (xy 55.00394 -385.14114) (xy 55.046139 -385.110462) (xy 55.09262 -385.086768)
			(xy 55.142238 -385.070643) (xy 55.193768 -385.062484) (xy 55.219854 -385.061968) (xy 55.700422 -385.061968)
			(xy 55.71049 -385.06154) (xy 55.729085 -385.053817) (xy 55.73649 -385.046982) (xy 55.923942 -384.85953)
			(xy 55.942722 -384.841416) (xy 55.984918 -384.810728) (xy 56.031399 -384.787026) (xy 56.081018 -384.770894)
			(xy 56.13255 -384.762731) (xy 56.158638 -384.762248) (xy 57.100724 -384.762248) (xy 57.110791 -384.761819)
			(xy 57.129384 -384.754093) (xy 57.136792 -384.747262) (xy 57.282588 -384.601466) (xy 57.28589 -384.59156)
			(xy 57.294211 -384.565845) (xy 57.317097 -384.516883) (xy 57.346669 -384.471644) (xy 57.382334 -384.431034)
			(xy 57.423376 -384.395869) (xy 57.468974 -384.366852) (xy 57.518212 -384.344566) (xy 57.570104 -384.329458)
			(xy 57.62361 -384.321829) (xy 57.650634 -384.321304) (xy 57.677074 -384.321751) (xy 57.729448 -384.329049)
			(xy 57.78031 -384.343514) (xy 57.828686 -384.364868) (xy 57.873647 -384.392703) (xy 57.914331 -384.426483)
			(xy 57.949956 -384.465561) (xy 57.97984 -384.509187) (xy 58.003409 -384.556523) (xy 58.02021 -384.606663)
			(xy 58.029922 -384.658643) (xy 58.031634 -384.685032) (xy 58.032142 -384.695192) (xy 58.036206 -384.703828)
			(xy 58.038317 -384.708046) (xy 58.043819 -384.715706) (xy 58.047128 -384.719068) (xy 58.100214 -384.769868)
			(xy 58.10719 -384.775389) (xy 58.12384 -384.781626) (xy 58.132726 -384.78206) (xy 58.751724 -384.78206)
			(xy 58.761376 -384.781044) (xy 58.768618 -384.779413) (xy 58.78178 -384.772564) (xy 58.787284 -384.767582)
			(xy 60.175648 -383.379218) (xy 60.183048 -383.372377) (xy 60.201647 -383.364657) (xy 60.211716 -383.364232)
			(xy 61.655706 -383.364232) (xy 61.663834 -383.361438) (xy 61.695093 -383.350916) (xy 61.759377 -383.336141)
			(xy 61.824911 -383.328667) (xy 61.85789 -383.328164) (xy 64.382142 -383.328164) (xy 64.415019 -383.328643)
			(xy 64.480357 -383.336036) (xy 64.544457 -383.350692) (xy 64.606516 -383.372427) (xy 64.665754 -383.400967)
			(xy 64.721428 -383.435954) (xy 64.772839 -383.47695) (xy 64.796416 -383.499868) (xy 69.083682 -387.787134)
			(xy 69.091082 -387.793975) (xy 69.109681 -387.80169) (xy 69.11975 -387.80212) (xy 70.101206 -387.80212)
			(xy 70.110858 -387.801104) (xy 70.118102 -387.799477) (xy 70.131274 -387.792638) (xy 70.136766 -387.787642)
			(xy 70.533006 -387.391402) (xy 70.537996 -387.385904) (xy 70.544847 -387.372739) (xy 70.546468 -387.365494)
			(xy 70.547484 -387.355842) (xy 70.547484 -377.359418) (xy 70.547313 -377.353409) (xy 70.544482 -377.341731)
			(xy 70.541896 -377.336304) (xy 70.540058 -377.332829) (xy 70.535466 -377.326448) (xy 70.532752 -377.323604)
			(xy 70.520052 -377.310904) (xy 70.513199 -377.303508) (xy 70.505455 -377.28491) (xy 70.505066 -377.274836)
			(xy 70.505066 -369.885722) (xy 70.504895 -369.879713) (xy 70.502064 -369.868035) (xy 70.499478 -369.862608)
			(xy 70.497639 -369.859133) (xy 70.493047 -369.852753) (xy 70.490334 -369.849908) (xy 65.875408 -365.234982)
			(xy 65.867788 -365.228632) (xy 63.342266 -363.541056) (xy 63.33363 -363.53623) (xy 62.52972 -363.203236)
			(xy 62.484742 -363.183936) (xy 62.398432 -363.13777) (xy 62.317057 -363.083375) (xy 62.241398 -363.021275)
			(xy 62.206378 -362.987082) (xy 60.214764 -360.995468) (xy 60.180546 -360.960448) (xy 60.118376 -360.884801)
			(xy 60.063916 -360.803427) (xy 60.017691 -360.717109) (xy 59.998356 -360.672126) (xy 59.058048 -358.402128)
			(xy 59.056038 -358.397566) (xy 59.050537 -358.389254) (xy 59.047126 -358.385618) (xy 55.29707 -354.635562)
			(xy 55.290222 -354.628165) (xy 55.28249 -354.609566) (xy 55.282084 -354.599494) (xy 55.282084 -348.22765)
			(xy 55.280814 -348.216474) (xy 55.071264 -347.459554) (xy 53.636418 -342.274652) (xy 51.22672 -333.566516)
			(xy 51.222372 -333.550441) (xy 51.214624 -333.518049) (xy 51.211226 -333.501746) (xy 49.669954 -325.996554)
			(xy 49.668684 -325.991982) (xy 49.529746 -325.533004) (xy 49.516125 -325.486003) (xy 49.497037 -325.390019)
			(xy 49.487428 -325.292629) (xy 49.48682 -325.243698) (xy 49.48682 -325.109332) (xy 49.485804 -325.099172)
			(xy 49.044606 -322.95084) (xy 49.03724 -322.910962) (xy 49.031084 -322.871179) (xy 49.024471 -322.790942)
			(xy 49.024032 -322.750688) (xy 49.024032 -322.74891) (xy 49.024032 -320.624454) (xy 49.024286 -320.596768)
			(xy 49.02454 -320.593212) (xy 49.02454 -320.177414) (xy 49.02497 -320.136365) (xy 49.031798 -320.054552)
			(xy 49.045385 -319.973586) (xy 49.065636 -319.894024) (xy 49.078642 -319.855088) (xy 49.078642 -319.85458)
			(xy 49.079912 -319.851278) (xy 49.08042 -319.850008) (xy 49.081436 -319.84696) (xy 49.082198 -319.841372)
			(xy 49.083214 -319.836038) (xy 49.083468 -319.83045) (xy 49.083468 -319.042796) (xy 49.083068 -319.033309)
			(xy 49.076169 -319.015632) (xy 49.063344 -319.001648) (xy 49.05502 -318.997076) (xy 49.031496 -318.985063)
			(xy 48.988273 -318.954707) (xy 48.950429 -318.917861) (xy 48.918928 -318.875465) (xy 48.894573 -318.828598)
			(xy 48.877983 -318.778453) (xy 48.869582 -318.726307) (xy 48.869582 -318.673489) (xy 48.877984 -318.621344)
			(xy 48.894574 -318.571199) (xy 48.91893 -318.524332) (xy 48.950431 -318.481936) (xy 48.988275 -318.445091)
			(xy 49.031499 -318.414735) (xy 49.05502 -318.402716) (xy 49.068228 -318.396366) (xy 49.083468 -318.371728)
			(xy 49.083468 -318.092836) (xy 49.083075 -318.083345) (xy 49.076185 -318.065657) (xy 49.063361 -318.051661)
			(xy 49.05502 -318.047116) (xy 49.031494 -318.035104) (xy 48.988267 -318.004749) (xy 48.950418 -317.967904)
			(xy 48.918913 -317.925508) (xy 48.894552 -317.87864) (xy 48.877956 -317.828494) (xy 48.869549 -317.776346)
			(xy 48.869092 -317.749936) (xy 48.869092 -317.749428) (xy 48.87087 -317.715392) (xy 48.87214 -317.703962)
			(xy 48.86452 -317.682372) (xy 48.800258 -317.618364) (xy 48.791795 -317.610823) (xy 48.770434 -317.603324)
			(xy 48.75911 -317.603886) (xy 48.741747 -317.605495) (xy 48.706877 -317.605495) (xy 48.689514 -317.603886)
			(xy 48.687482 -317.603632) (xy 48.687228 -317.603632) (xy 48.676814 -317.602108) (xy 48.676306 -317.602108)
			(xy 48.662762 -317.599967) (xy 48.636057 -317.59374) (xy 48.622966 -317.589662) (xy 48.612374 -317.587597)
			(xy 48.59118 -317.591552) (xy 48.57347 -317.603849) (xy 48.562358 -317.622325) (xy 48.559797 -317.643733)
			(xy 48.562514 -317.654178) (xy 48.569245 -317.677545) (xy 48.576516 -317.725624) (xy 48.576992 -317.749936)
			(xy 48.576488 -317.775644) (xy 48.568445 -317.826426) (xy 48.552557 -317.875325) (xy 48.529214 -317.921137)
			(xy 48.498993 -317.962733) (xy 48.462637 -317.999089) (xy 48.421041 -318.02931) (xy 48.375229 -318.052653)
			(xy 48.32633 -318.068541) (xy 48.275548 -318.076584) (xy 48.224132 -318.076584) (xy 48.17335 -318.068541)
			(xy 48.124451 -318.052653) (xy 48.078639 -318.02931) (xy 48.037043 -317.999089) (xy 48.000687 -317.962733)
			(xy 47.970466 -317.921137) (xy 47.947123 -317.875325) (xy 47.931235 -317.826426) (xy 47.923192 -317.775644)
			(xy 47.922688 -317.749936) (xy 47.923189 -317.72424) (xy 47.93122 -317.67348) (xy 47.94709 -317.624601)
			(xy 47.970409 -317.578804) (xy 48.000602 -317.537218) (xy 48.036927 -317.500865) (xy 48.078491 -317.47064)
			(xy 48.124269 -317.447286) (xy 48.173137 -317.431378) (xy 48.223891 -317.423309) (xy 48.249586 -317.422784)
			(xy 48.250094 -317.422784) (xy 48.283876 -317.424816) (xy 48.284384 -317.424816) (xy 48.29556 -317.426086)
			(xy 48.31715 -317.418212) (xy 48.38954 -317.345568) (xy 48.396906 -317.323724) (xy 48.395636 -317.312294)
			(xy 48.394673 -317.303053) (xy 48.393656 -317.2845) (xy 48.393604 -317.27521) (xy 48.393604 -316.324742)
			(xy 48.394084 -316.298751) (xy 48.40221 -316.247408) (xy 48.418269 -316.197969) (xy 48.441864 -316.15165)
			(xy 48.472416 -316.109594) (xy 48.509171 -316.072836) (xy 48.551225 -316.04228) (xy 48.597541 -316.01868)
			(xy 48.646979 -316.002617) (xy 48.698321 -315.994486) (xy 48.724312 -315.994034) (xy 48.73373 -315.994069)
			(xy 48.752538 -315.995084) (xy 48.761904 -315.996066) (xy 48.762158 -315.996066) (xy 48.773551 -315.996711)
			(xy 48.79507 -315.989209) (xy 48.80356 -315.981588) (xy 48.868076 -315.91758) (xy 48.87595 -315.89599)
			(xy 48.87468 -315.88456) (xy 48.872648 -315.850016) (xy 48.872648 -315.849508) (xy 48.873174 -315.823815)
			(xy 48.881253 -315.773068) (xy 48.897167 -315.724208) (xy 48.920525 -315.678437) (xy 48.950751 -315.636881)
			(xy 48.987103 -315.600561) (xy 49.028686 -315.570372) (xy 49.074478 -315.547055) (xy 49.123352 -315.531185)
			(xy 49.174107 -315.523151) (xy 49.1998 -315.52261) (xy 49.225509 -315.523114) (xy 49.276294 -315.531157)
			(xy 49.325195 -315.547045) (xy 49.371009 -315.570386) (xy 49.412609 -315.600607) (xy 49.448968 -315.636963)
			(xy 49.479194 -315.678558) (xy 49.502541 -315.72437) (xy 49.518434 -315.773269) (xy 49.526483 -315.824053)
			(xy 49.526952 -315.849762) (xy 49.526467 -315.874073) (xy 49.519194 -315.922151) (xy 49.512474 -315.94552)
			(xy 49.509759 -315.955995) (xy 49.512434 -315.97745) (xy 49.523689 -315.99591) (xy 49.541536 -316.008114)
			(xy 49.562821 -316.011906) (xy 49.573434 -316.009782) (xy 49.586221 -316.005822) (xy 49.612288 -315.999718)
			(xy 49.625504 -315.99759) (xy 49.630838 -315.996828) (xy 49.635026 -315.995577) (xy 49.642942 -315.991875)
			(xy 49.646586 -315.989462) (xy 49.651412 -315.985652) (xy 49.652936 -315.984382) (xy 49.653444 -315.983874)
			(xy 49.674905 -315.964743) (xy 49.719767 -315.92878) (xy 49.743106 -315.911992) (xy 49.748186 -315.908436)
			(xy 49.7586 -315.896244) (xy 49.761902 -315.89218) (xy 49.766982 -315.88456) (xy 49.767744 -315.88329)
			(xy 49.768506 -315.881766) (xy 49.775909 -315.867572) (xy 49.791534 -315.839627) (xy 49.799748 -315.825886)
			(xy 49.819814 -315.793882) (xy 49.822254 -315.790003) (xy 49.825834 -315.781569) (xy 49.826926 -315.777118)
			(xy 49.833256 -315.751233) (xy 49.853116 -315.701787) (xy 49.880651 -315.656167) (xy 49.915149 -315.615556)
			(xy 49.955714 -315.581005) (xy 50.001298 -315.55341) (xy 50.050718 -315.533485) (xy 50.076608 -315.527182)
			(xy 50.081054 -315.526075) (xy 50.089491 -315.522504) (xy 50.093372 -315.52007) (xy 50.118396 -315.503885)
			(xy 50.170122 -315.474272) (xy 50.19675 -315.460888) (xy 50.204276 -315.456743) (xy 50.216235 -315.444421)
			(xy 50.220118 -315.436758) (xy 50.237523 -315.400628) (xy 50.277453 -315.331071) (xy 50.299874 -315.29782)
			(xy 50.3021 -315.294397) (xy 50.305549 -315.286996) (xy 50.306732 -315.283088) (xy 50.314448 -315.258282)
			(xy 50.336513 -315.211256) (xy 50.365642 -315.168245) (xy 50.401122 -315.130303) (xy 50.421286 -315.113924)
			(xy 50.44666 -315.095132) (xy 50.50292 -315.066484) (xy 50.533046 -315.057028) (xy 50.537013 -315.055844)
			(xy 50.544538 -315.052391) (xy 50.548032 -315.05017) (xy 50.592799 -315.020022) (xy 50.687761 -314.968722)
			(xy 50.737516 -314.947808) (xy 50.746683 -314.943619) (xy 50.761003 -314.929456) (xy 50.768802 -314.910886)
			(xy 50.769266 -314.900818) (xy 50.769266 -314.899802) (xy 50.769649 -314.876662) (xy 50.776102 -314.830833)
			(xy 50.788897 -314.786356) (xy 50.807782 -314.744104) (xy 50.832386 -314.704905) (xy 50.84699 -314.68695)
			(xy 50.83937 -314.680854) (xy 50.82463 -314.668273) (xy 50.798128 -314.639997) (xy 50.786538 -314.624466)
			(xy 50.78603 -314.623704) (xy 50.785014 -314.62218) (xy 50.783236 -314.619894) (xy 50.781712 -314.617608)
			(xy 50.781458 -314.6171) (xy 50.712878 -314.510166) (xy 50.709591 -314.504575) (xy 50.705603 -314.492239)
			(xy 50.705004 -314.485782) (xy 50.701194 -314.42025) (xy 50.701194 -314.419742) (xy 50.70003 -314.408274)
			(xy 50.69175 -314.386774) (xy 50.677483 -314.368683) (xy 50.658505 -314.355619) (xy 50.636513 -314.348751)
			(xy 50.624994 -314.348368) (xy 50.612953 -314.348788) (xy 50.590051 -314.356233) (xy 50.570571 -314.370391)
			(xy 50.55642 -314.389876) (xy 50.548984 -314.412781) (xy 50.54854 -314.424822) (xy 50.54854 -314.434474)
			(xy 50.547974 -314.460306) (xy 50.539222 -314.511225) (xy 50.522014 -314.559941) (xy 50.496843 -314.605061)
			(xy 50.464428 -314.645293) (xy 50.425697 -314.679487) (xy 50.381757 -314.706666) (xy 50.35804 -314.716922)
			(xy 50.345672 -314.721982) (xy 50.321282 -314.732907) (xy 50.309272 -314.738766) (xy 50.306986 -314.741052)
			(xy 50.27168 -314.758578) (xy 50.271172 -314.759086) (xy 50.25094 -314.769023) (xy 50.208248 -314.783487)
			(xy 50.163892 -314.791501) (xy 50.141378 -314.792614) (xy 50.131218 -314.792868) (xy 50.122582 -314.796678)
			(xy 50.118376 -314.798651) (xy 50.110705 -314.803888) (xy 50.107342 -314.807092) (xy 50.057558 -314.856876)
			(xy 50.054272 -314.860357) (xy 50.048906 -314.868282) (xy 50.04689 -314.872624) (xy 50.043334 -314.880752)
			(xy 50.042826 -314.890912) (xy 50.042826 -314.891166) (xy 50.042459 -314.900156) (xy 50.040808 -314.918075)
			(xy 50.039524 -314.92698) (xy 50.029872 -314.964572) (xy 50.02582 -314.979096) (xy 50.015257 -315.007339)
			(xy 50.00879 -315.02096) (xy 50.008536 -315.021722) (xy 50.005742 -315.027564) (xy 50.003456 -315.031882)
			(xy 50.001932 -315.03493) (xy 50.001424 -315.036454) (xy 50.000408 -315.038232) (xy 49.977802 -315.079888)
			(xy 49.977294 -315.08065) (xy 49.975516 -315.084206) (xy 49.974246 -315.086238) (xy 49.96942 -315.092588)
			(xy 49.95037 -315.11367) (xy 49.949862 -315.114178) (xy 49.923954 -315.143642) (xy 49.923446 -315.14415)
			(xy 49.914556 -315.152278) (xy 49.890426 -315.168788) (xy 49.889918 -315.169296) (xy 49.853596 -315.196982)
			(xy 49.853088 -315.19749) (xy 49.831752 -315.216032) (xy 49.815242 -315.231018) (xy 49.811686 -315.233304)
			(xy 49.797208 -315.246004) (xy 49.785524 -315.253624) (xy 49.710594 -315.288676) (xy 49.708308 -315.289692)
			(xy 49.706022 -315.290454) (xy 49.704752 -315.290962) (xy 49.698148 -315.29274) (xy 49.663858 -315.29909)
			(xy 49.66208 -315.299344) (xy 49.656492 -315.300614) (xy 49.650396 -315.302138) (xy 49.64649 -315.303777)
			(xy 49.639217 -315.308117) (xy 49.635918 -315.310774) (xy 49.619154 -315.326268) (xy 49.601965 -315.341329)
			(xy 49.563958 -315.366705) (xy 49.543462 -315.376814) (xy 49.542446 -315.377322) (xy 49.532032 -315.382402)
			(xy 49.526698 -315.384688) (xy 49.513744 -315.38926) (xy 49.490464 -315.396914) (xy 49.442229 -315.405549)
			(xy 49.393233 -315.406373) (xy 49.344735 -315.399366) (xy 49.297977 -315.384706) (xy 49.254158 -315.362771)
			(xy 49.214403 -315.334122) (xy 49.196752 -315.317124) (xy 49.092358 -315.21273) (xy 49.082198 -315.20892)
			(xy 49.056307 -315.198449) (xy 49.008189 -315.170108) (xy 48.965513 -315.134088) (xy 48.929493 -315.091413)
			(xy 48.901152 -315.043295) (xy 48.890682 -315.017404) (xy 48.886872 -315.007244) (xy 48.797718 -314.91809)
			(xy 48.788277 -314.908303) (xy 48.770977 -314.887317) (xy 48.763174 -314.87618) (xy 48.758094 -314.868306)
			(xy 48.743791 -314.845016) (xy 48.722818 -314.794552) (xy 48.71117 -314.741159) (xy 48.70958 -314.713874)
			(xy 48.709072 -314.69203) (xy 48.709072 -314.67298) (xy 48.709715 -314.646044) (xy 48.719304 -314.59303)
			(xy 48.728122 -314.56757) (xy 48.743616 -314.525406) (xy 48.74523 -314.521272) (xy 48.749704 -314.513608)
			(xy 48.752506 -314.510166) (xy 48.782478 -314.47486) (xy 48.782732 -314.474606) (xy 48.791075 -314.46403)
			(xy 48.800435 -314.438789) (xy 48.80102 -314.42533) (xy 48.80102 -314.424822) (xy 48.800557 -314.412111)
			(xy 48.792288 -314.388073) (xy 48.776643 -314.368037) (xy 48.755327 -314.354186) (xy 48.743108 -314.350654)
			(xy 48.738536 -314.349638) (xy 48.70196 -314.341002) (xy 48.697941 -314.33997) (xy 48.690282 -314.336779)
			(xy 48.68672 -314.334652) (xy 48.612806 -314.288424) (xy 48.608986 -314.285918) (xy 48.602219 -314.279782)
			(xy 48.599344 -314.276232) (xy 48.578008 -314.248292) (xy 48.577246 -314.24753) (xy 48.560482 -314.224924)
			(xy 48.559974 -314.224162) (xy 48.556672 -314.21959) (xy 48.540162 -314.208922) (xy 48.459644 -314.19419)
			(xy 48.449776 -314.192807) (xy 48.430285 -314.196846) (xy 48.421798 -314.202064) (xy 48.402698 -314.21461)
			(xy 48.361535 -314.234456) (xy 48.317873 -314.247941) (xy 48.272688 -314.254763) (xy 48.24984 -314.25515)
			(xy 48.224577 -314.25466) (xy 48.174738 -314.24635) (xy 48.126948 -314.229949) (xy 48.082509 -314.205905)
			(xy 48.042634 -314.174874) (xy 48.008411 -314.137702) (xy 47.980773 -314.095404) (xy 47.960475 -314.049134)
			(xy 47.948071 -314.000154) (xy 47.943898 -313.9498) (xy 47.948071 -313.899446) (xy 47.960475 -313.850466)
			(xy 47.980773 -313.804196) (xy 48.008411 -313.761898) (xy 48.042634 -313.724726) (xy 48.082509 -313.693695)
			(xy 48.126948 -313.669651) (xy 48.174738 -313.65325) (xy 48.224577 -313.64494) (xy 48.24984 -313.644534)
			(xy 48.250094 -313.644534) (xy 48.277404 -313.645163) (xy 48.331149 -313.654917) (xy 48.382306 -313.674062)
			(xy 48.429248 -313.70199) (xy 48.450246 -313.719464) (xy 48.45357 -313.722233) (xy 48.46098 -313.7267)
			(xy 48.464978 -313.728354) (xy 48.490886 -313.738514) (xy 48.500774 -313.738106) (xy 48.519111 -313.730717)
			(xy 48.533272 -313.716922) (xy 48.537622 -313.708034) (xy 48.537622 -313.70778) (xy 48.539105 -313.70376)
			(xy 48.543186 -313.696227) (xy 48.54575 -313.692794) (xy 48.573182 -313.657488) (xy 48.588403 -313.638857)
			(xy 48.6237 -313.606171) (xy 48.663689 -313.579427) (xy 48.707378 -313.559288) (xy 48.730408 -313.552332)
			(xy 48.738536 -313.5503) (xy 48.742346 -313.549284) (xy 48.754474 -313.545909) (xy 48.775797 -313.53256)
			(xy 48.791685 -313.513054) (xy 48.800442 -313.489471) (xy 48.801136 -313.464323) (xy 48.793693 -313.440293)
			(xy 48.778905 -313.41994) (xy 48.75835 -313.405436) (xy 48.74641 -313.401456) (xy 48.744378 -313.400948)
			(xy 48.70196 -313.391042) (xy 48.697942 -313.390009) (xy 48.690285 -313.386815) (xy 48.68672 -313.384692)
			(xy 48.612806 -313.338464) (xy 48.608985 -313.335959) (xy 48.602214 -313.329827) (xy 48.599344 -313.326272)
			(xy 48.578008 -313.298332) (xy 48.577246 -313.29757) (xy 48.560482 -313.274964) (xy 48.559974 -313.274202)
			(xy 48.556672 -313.26963) (xy 48.540162 -313.258962) (xy 48.459644 -313.24423) (xy 48.449776 -313.242846)
			(xy 48.430286 -313.246888) (xy 48.421798 -313.252104) (xy 48.402697 -313.264649) (xy 48.361534 -313.284492)
			(xy 48.317873 -313.297975) (xy 48.272688 -313.304796) (xy 48.24984 -313.30519) (xy 48.224582 -313.304701)
			(xy 48.174753 -313.296392) (xy 48.126972 -313.279994) (xy 48.082541 -313.255955) (xy 48.042674 -313.22493)
			(xy 48.008458 -313.187765) (xy 47.980826 -313.145476) (xy 47.960532 -313.099215) (xy 47.94813 -313.050244)
			(xy 47.943958 -312.9999) (xy 47.94813 -312.949556) (xy 47.960532 -312.900585) (xy 47.980826 -312.854324)
			(xy 48.008458 -312.812035) (xy 48.042674 -312.77487) (xy 48.082541 -312.743845) (xy 48.126972 -312.719806)
			(xy 48.174753 -312.703408) (xy 48.224582 -312.695099) (xy 48.24984 -312.694574) (xy 48.250094 -312.694574)
			(xy 48.277404 -312.695203) (xy 48.331148 -312.704958) (xy 48.382303 -312.724106) (xy 48.429243 -312.752036)
			(xy 48.450246 -312.769504) (xy 48.453572 -312.772271) (xy 48.460982 -312.776735) (xy 48.464978 -312.778394)
			(xy 48.490886 -312.788554) (xy 48.500771 -312.788145) (xy 48.519101 -312.780751) (xy 48.533248 -312.766949)
			(xy 48.537622 -312.758074) (xy 48.537622 -312.75782) (xy 48.539109 -312.753802) (xy 48.543197 -312.746274)
			(xy 48.54575 -312.742834) (xy 48.573182 -312.707528) (xy 48.588401 -312.688895) (xy 48.623697 -312.656205)
			(xy 48.663684 -312.629457) (xy 48.707374 -312.609316) (xy 48.730408 -312.602372) (xy 48.738536 -312.60034)
			(xy 48.742346 -312.599324) (xy 48.754464 -312.595949) (xy 48.775769 -312.582606) (xy 48.791641 -312.563112)
			(xy 48.800387 -312.539545) (xy 48.801076 -312.514416) (xy 48.793633 -312.490405) (xy 48.778852 -312.470071)
			(xy 48.75831 -312.455582) (xy 48.74641 -312.451496) (xy 48.744378 -312.450988) (xy 48.70196 -312.441082)
			(xy 48.697941 -312.44005) (xy 48.690283 -312.436858) (xy 48.68672 -312.434732) (xy 48.612806 -312.388504)
			(xy 48.608984 -312.386001) (xy 48.602209 -312.379871) (xy 48.599344 -312.376312) (xy 48.578008 -312.348372)
			(xy 48.577246 -312.34761) (xy 48.561016 -312.326997) (xy 48.535138 -312.281364) (xy 48.517446 -312.231977)
			(xy 48.508463 -312.180292) (xy 48.507904 -312.154062) (xy 48.507904 -311.94502) (xy 48.508535 -311.919967)
			(xy 48.516955 -311.870567) (xy 48.524668 -311.846722) (xy 48.526954 -311.840118) (xy 48.50664 -311.824392)
			(xy 48.470667 -311.78772) (xy 48.440787 -311.745933) (xy 48.417719 -311.700034) (xy 48.402016 -311.651122)
			(xy 48.394055 -311.600373) (xy 48.393604 -311.574688) (xy 48.393604 -310.624474) (xy 48.394161 -310.59736)
			(xy 48.40304 -310.543862) (xy 48.420538 -310.492534) (xy 48.446186 -310.444753) (xy 48.479295 -310.401804)
			(xy 48.49876 -310.38292) (xy 48.506126 -310.376062) (xy 48.523144 -310.33847) (xy 48.52162 -310.32704)
			(xy 48.520858 -310.323484) (xy 48.514844 -310.302076) (xy 48.508343 -310.258087) (xy 48.507904 -310.235854)
			(xy 48.507904 -310.044846) (xy 48.508471 -310.021666) (xy 48.515739 -309.975874) (xy 48.522382 -309.95366)
			(xy 48.52289 -309.952136) (xy 48.523144 -309.95112) (xy 48.52416 -309.947818) (xy 48.537622 -309.907686)
			(xy 48.539104 -309.903666) (xy 48.543185 -309.896132) (xy 48.54575 -309.8927) (xy 48.573182 -309.857394)
			(xy 48.588403 -309.838763) (xy 48.6237 -309.806076) (xy 48.663688 -309.779331) (xy 48.707377 -309.759192)
			(xy 48.730408 -309.752238) (xy 48.738536 -309.750206) (xy 48.742346 -309.74919) (xy 48.754475 -309.745815)
			(xy 48.7758 -309.732466) (xy 48.791689 -309.712959) (xy 48.800448 -309.689374) (xy 48.801142 -309.664224)
			(xy 48.793699 -309.640191) (xy 48.778911 -309.619837) (xy 48.758355 -309.605332) (xy 48.74641 -309.601362)
			(xy 48.744378 -309.600854) (xy 48.70196 -309.590948) (xy 48.697942 -309.589915) (xy 48.690285 -309.586721)
			(xy 48.68672 -309.584598) (xy 48.612806 -309.53837) (xy 48.608985 -309.535866) (xy 48.602213 -309.529733)
			(xy 48.599344 -309.526178) (xy 48.580548 -309.50154) (xy 48.579786 -309.500524) (xy 48.5775 -309.49773)
			(xy 48.576992 -309.497222) (xy 48.559974 -309.474108) (xy 48.558958 -309.472584) (xy 48.556672 -309.469282)
			(xy 48.540416 -309.459122) (xy 48.459644 -309.444136) (xy 48.449776 -309.442753) (xy 48.430287 -309.446795)
			(xy 48.421798 -309.45201) (xy 48.402697 -309.464554) (xy 48.361534 -309.484398) (xy 48.317872 -309.49788)
			(xy 48.272688 -309.504701) (xy 48.24984 -309.505096) (xy 48.224581 -309.504607) (xy 48.174751 -309.496297)
			(xy 48.126969 -309.479899) (xy 48.082538 -309.45586) (xy 48.04267 -309.424834) (xy 48.008453 -309.387669)
			(xy 47.980821 -309.345379) (xy 47.960526 -309.299117) (xy 47.948124 -309.250145) (xy 47.943952 -309.1998)
			(xy 47.948124 -309.149455) (xy 47.960526 -309.100483) (xy 47.980821 -309.054221) (xy 48.008453 -309.011931)
			(xy 48.04267 -308.974766) (xy 48.082538 -308.94374) (xy 48.126969 -308.919701) (xy 48.174751 -308.903303)
			(xy 48.224581 -308.894993) (xy 48.24984 -308.89448) (xy 48.263312 -308.89465) (xy 48.290148 -308.897066)
			(xy 48.303434 -308.899306) (xy 48.31588 -308.901592) (xy 48.339502 -308.893972) (xy 48.407066 -308.825646)
			(xy 48.415216 -308.816406) (xy 48.422526 -308.792917) (xy 48.421036 -308.780688) (xy 48.418646 -308.766842)
			(xy 48.4161 -308.738858) (xy 48.415956 -308.724808) (xy 48.415956 -308.724554) (xy 48.416124 -308.710568)
			(xy 48.418666 -308.682712) (xy 48.421036 -308.668928) (xy 48.422529 -308.656698) (xy 48.415216 -308.633212)
			(xy 48.407066 -308.62397) (xy 48.348392 -308.564534) (xy 48.339193 -308.556295) (xy 48.315693 -308.548839)
			(xy 48.303434 -308.55031) (xy 48.290149 -308.552554) (xy 48.263312 -308.554973) (xy 48.24984 -308.555136)
			(xy 48.224578 -308.554646) (xy 48.174742 -308.546336) (xy 48.126953 -308.529936) (xy 48.082516 -308.505893)
			(xy 48.042643 -308.474863) (xy 48.008422 -308.437694) (xy 47.980786 -308.395398) (xy 47.960489 -308.34913)
			(xy 47.948085 -308.300152) (xy 47.943912 -308.2498) (xy 47.948085 -308.199448) (xy 47.960489 -308.15047)
			(xy 47.980786 -308.104202) (xy 48.008422 -308.061906) (xy 48.042643 -308.024737) (xy 48.082516 -307.993707)
			(xy 48.126953 -307.969664) (xy 48.174742 -307.953264) (xy 48.224578 -307.944954) (xy 48.24984 -307.94452)
			(xy 48.250094 -307.94452) (xy 48.277404 -307.945149) (xy 48.331146 -307.954906) (xy 48.3823 -307.974055)
			(xy 48.429238 -308.001989) (xy 48.450246 -308.01945) (xy 48.453573 -308.022215) (xy 48.460985 -308.026675)
			(xy 48.464978 -308.02834) (xy 48.490886 -308.0385) (xy 48.500773 -308.038092) (xy 48.519108 -308.030702)
			(xy 48.533266 -308.016905) (xy 48.537622 -308.00802) (xy 48.537622 -308.007766) (xy 48.539106 -308.003747)
			(xy 48.543189 -307.996215) (xy 48.54575 -307.99278) (xy 48.573182 -307.957474) (xy 48.588403 -307.938844)
			(xy 48.623701 -307.906159) (xy 48.66369 -307.879416) (xy 48.707379 -307.859278) (xy 48.730408 -307.852318)
			(xy 48.738536 -307.850286) (xy 48.742346 -307.84927) (xy 48.754471 -307.845895) (xy 48.775791 -307.832548)
			(xy 48.791675 -307.813045) (xy 48.800429 -307.789465) (xy 48.801122 -307.764322) (xy 48.793679 -307.740295)
			(xy 48.778893 -307.719947) (xy 48.758341 -307.705447) (xy 48.74641 -307.701442) (xy 48.744378 -307.700934)
			(xy 48.70196 -307.691028) (xy 48.697941 -307.689997) (xy 48.690281 -307.686807) (xy 48.68672 -307.684678)
			(xy 48.612806 -307.63845) (xy 48.608986 -307.635945) (xy 48.602216 -307.629811) (xy 48.599344 -307.626258)
			(xy 48.580548 -307.60162) (xy 48.579786 -307.600604) (xy 48.5775 -307.59781) (xy 48.576992 -307.597302)
			(xy 48.560835 -307.576691) (xy 48.535076 -307.531098) (xy 48.517455 -307.481784) (xy 48.508488 -307.430191)
			(xy 48.507904 -307.404008) (xy 48.507904 -307.194966) (xy 48.50847 -307.171786) (xy 48.515735 -307.125993)
			(xy 48.522382 -307.10378) (xy 48.52289 -307.102256) (xy 48.523144 -307.10124) (xy 48.52416 -307.097938)
			(xy 48.537622 -307.057806) (xy 48.53911 -307.053789) (xy 48.5432 -307.046262) (xy 48.54575 -307.04282)
			(xy 48.573182 -307.007514) (xy 48.588402 -306.988882) (xy 48.623698 -306.956193) (xy 48.663686 -306.929447)
			(xy 48.707375 -306.909306) (xy 48.730408 -306.902358) (xy 48.738536 -306.900326) (xy 48.742346 -306.89931)
			(xy 48.754462 -306.895935) (xy 48.775763 -306.882594) (xy 48.791631 -306.863103) (xy 48.800375 -306.839539)
			(xy 48.801062 -306.814414) (xy 48.793619 -306.790407) (xy 48.77884 -306.770078) (xy 48.7583 -306.755592)
			(xy 48.74641 -306.751482) (xy 48.744378 -306.750974) (xy 48.70196 -306.741068) (xy 48.697941 -306.740036)
			(xy 48.690284 -306.736843) (xy 48.68672 -306.734718) (xy 48.612806 -306.68849) (xy 48.608984 -306.685986)
			(xy 48.602211 -306.679856) (xy 48.599344 -306.676298) (xy 48.580548 -306.65166) (xy 48.579786 -306.650644)
			(xy 48.5775 -306.64785) (xy 48.576992 -306.647342) (xy 48.560832 -306.626732) (xy 48.535067 -306.58114)
			(xy 48.51744 -306.531826) (xy 48.508466 -306.480232) (xy 48.507904 -306.454048) (xy 48.507904 -306.245006)
			(xy 48.508474 -306.221827) (xy 48.515748 -306.176037) (xy 48.522382 -306.15382) (xy 48.52289 -306.152296)
			(xy 48.523144 -306.15128) (xy 48.52416 -306.147978) (xy 48.537622 -306.107846) (xy 48.539107 -306.103827)
			(xy 48.543192 -306.096297) (xy 48.54575 -306.09286) (xy 48.573182 -306.057554) (xy 48.588404 -306.038925)
			(xy 48.623703 -306.006242) (xy 48.663692 -305.979501) (xy 48.707381 -305.959364) (xy 48.730408 -305.952398)
			(xy 48.738536 -305.950366) (xy 48.742346 -305.94935) (xy 48.754468 -305.945975) (xy 48.775782 -305.93263)
			(xy 48.79166 -305.913131) (xy 48.800411 -305.889556) (xy 48.801102 -305.864419) (xy 48.793659 -305.840399)
			(xy 48.778876 -305.820057) (xy 48.758327 -305.805562) (xy 48.74641 -305.801522) (xy 48.744378 -305.801014)
			(xy 48.70196 -305.791108) (xy 48.697941 -305.790076) (xy 48.690282 -305.786886) (xy 48.68672 -305.784758)
			(xy 48.612806 -305.73853) (xy 48.608986 -305.736024) (xy 48.602218 -305.729889) (xy 48.599344 -305.726338)
			(xy 48.580548 -305.7017) (xy 48.579786 -305.700684) (xy 48.5775 -305.69789) (xy 48.576992 -305.697382)
			(xy 48.560829 -305.676773) (xy 48.535058 -305.631182) (xy 48.517424 -305.581868) (xy 48.508443 -305.530273)
			(xy 48.507904 -305.504088) (xy 48.507904 -305.294792) (xy 48.508475 -305.271613) (xy 48.515751 -305.225824)
			(xy 48.522382 -305.203606) (xy 48.52289 -305.202082) (xy 48.523144 -305.201066) (xy 48.52416 -305.197764)
			(xy 48.537622 -305.157632) (xy 48.539108 -305.153614) (xy 48.543195 -305.146085) (xy 48.54575 -305.142646)
			(xy 48.573182 -305.10734) (xy 48.588401 -305.088707) (xy 48.623696 -305.056015) (xy 48.663683 -305.029267)
			(xy 48.707372 -305.009124) (xy 48.730408 -305.002184) (xy 48.738536 -305.000152) (xy 48.742346 -304.999136)
			(xy 48.754466 -304.995761) (xy 48.775775 -304.982417) (xy 48.79165 -304.962921) (xy 48.800398 -304.93935)
			(xy 48.801088 -304.914217) (xy 48.793645 -304.890202) (xy 48.778863 -304.869865) (xy 48.758318 -304.855373)
			(xy 48.74641 -304.851308) (xy 48.744378 -304.8508) (xy 48.70196 -304.840894) (xy 48.697941 -304.839862)
			(xy 48.690283 -304.836671) (xy 48.68672 -304.834544) (xy 48.612806 -304.788316) (xy 48.608987 -304.78581)
			(xy 48.60222 -304.779674) (xy 48.599344 -304.776124) (xy 48.578008 -304.748184) (xy 48.577246 -304.747422)
			(xy 48.561015 -304.726809) (xy 48.535135 -304.681176) (xy 48.517442 -304.63179) (xy 48.508456 -304.580104)
			(xy 48.507904 -304.553874) (xy 48.507904 -304.344832) (xy 48.508472 -304.321653) (xy 48.515742 -304.275861)
			(xy 48.522382 -304.253646) (xy 48.52289 -304.252122) (xy 48.523144 -304.251106) (xy 48.52416 -304.247804)
			(xy 48.537622 -304.207672) (xy 48.539105 -304.203652) (xy 48.543188 -304.19612) (xy 48.54575 -304.192686)
			(xy 48.573182 -304.15738) (xy 48.588403 -304.13875) (xy 48.623701 -304.106064) (xy 48.663689 -304.079321)
			(xy 48.707378 -304.059182) (xy 48.730408 -304.052224) (xy 48.738536 -304.050192) (xy 48.742346 -304.049176)
			(xy 48.754472 -304.045801) (xy 48.775794 -304.032453) (xy 48.791679 -304.012949) (xy 48.800435 -303.989367)
			(xy 48.801128 -303.964222) (xy 48.793685 -303.940194) (xy 48.778898 -303.919844) (xy 48.758345 -303.905342)
			(xy 48.74641 -303.901348) (xy 48.744378 -303.90084) (xy 48.70196 -303.890934) (xy 48.697941 -303.889903)
			(xy 48.690281 -303.886714) (xy 48.68672 -303.884584) (xy 48.612806 -303.838356) (xy 48.608985 -303.835851)
			(xy 48.602215 -303.829718) (xy 48.599344 -303.826164) (xy 48.578008 -303.798224) (xy 48.577246 -303.797462)
			(xy 48.561013 -303.77685) (xy 48.535127 -303.731218) (xy 48.517427 -303.681831) (xy 48.508434 -303.630145)
			(xy 48.507904 -303.603914) (xy 48.507904 -303.394872) (xy 48.508494 -303.370888) (xy 48.516283 -303.32355)
			(xy 48.523398 -303.300638) (xy 48.52416 -303.298098) (xy 48.524668 -303.296574) (xy 48.524668 -303.29632)
			(xy 48.524922 -303.295558) (xy 48.526192 -303.290478) (xy 48.527117 -303.285769) (xy 48.527379 -303.276178)
			(xy 48.5267 -303.271428) (xy 48.508618 -303.256327) (xy 48.476694 -303.221684) (xy 48.450256 -303.182693)
			(xy 48.42989 -303.140214) (xy 48.416045 -303.095185) (xy 48.409026 -303.048602) (xy 48.40859 -303.025048)
			(xy 48.40859 -303.024794) (xy 48.409136 -302.998217) (xy 48.418028 -302.945811) (xy 48.435559 -302.895631)
			(xy 48.461236 -302.84909) (xy 48.494336 -302.8075) (xy 48.513746 -302.789336) (xy 48.517632 -302.785632)
			(xy 48.523902 -302.77692) (xy 48.526192 -302.772064) (xy 48.527208 -302.769778) (xy 48.525684 -302.75784)
			(xy 48.522636 -302.747934) (xy 48.515756 -302.725116) (xy 48.508355 -302.678037) (xy 48.507904 -302.654208)
			(xy 48.507904 -301.545752) (xy 48.507408 -301.53575) (xy 48.49974 -301.517274) (xy 48.485589 -301.503136)
			(xy 48.467106 -301.495484) (xy 48.457104 -301.494952) (xy 42.978324 -301.494952) (xy 42.968261 -301.49539)
			(xy 42.949682 -301.50313) (xy 42.942256 -301.509938) (xy 42.891456 -301.5615) (xy 42.884812 -301.568858)
			(xy 42.877239 -301.587159) (xy 42.876724 -301.59706) (xy 42.876724 -301.599854) (xy 42.87622 -301.625542)
			(xy 42.868183 -301.676285) (xy 42.852307 -301.725146) (xy 42.828983 -301.770922) (xy 42.798786 -301.812486)
			(xy 42.762458 -301.848814) (xy 42.720894 -301.879011) (xy 42.675118 -301.902335) (xy 42.626257 -301.918211)
			(xy 42.575514 -301.926248) (xy 42.524138 -301.926248) (xy 42.473395 -301.918211) (xy 42.424534 -301.902335)
			(xy 42.378758 -301.879011) (xy 42.337194 -301.848814) (xy 42.300866 -301.812486) (xy 42.270669 -301.770922)
			(xy 42.247345 -301.725146) (xy 42.231469 -301.676285) (xy 42.223432 -301.625542) (xy 42.222928 -301.599854)
			(xy 42.222928 -301.59706) (xy 42.222402 -301.587164) (xy 42.214815 -301.568877) (xy 42.208196 -301.5615)
			(xy 42.157396 -301.509938) (xy 42.149999 -301.503088) (xy 42.131401 -301.495349) (xy 42.121328 -301.494952)
			(xy 42.028364 -301.494952) (xy 42.018298 -301.495383) (xy 41.999708 -301.503113) (xy 41.992296 -301.509938)
			(xy 41.941496 -301.5615) (xy 41.934848 -301.568856) (xy 41.927268 -301.587157) (xy 41.926764 -301.59706)
			(xy 41.926764 -301.599854) (xy 41.92626 -301.625542) (xy 41.918223 -301.676285) (xy 41.902347 -301.725146)
			(xy 41.879023 -301.770922) (xy 41.848826 -301.812486) (xy 41.812498 -301.848814) (xy 41.770934 -301.879011)
			(xy 41.725158 -301.902335) (xy 41.676297 -301.918211) (xy 41.625554 -301.926248) (xy 41.574178 -301.926248)
			(xy 41.523435 -301.918211) (xy 41.474574 -301.902335) (xy 41.428798 -301.879011) (xy 41.387234 -301.848814)
			(xy 41.350906 -301.812486) (xy 41.320709 -301.770922) (xy 41.297385 -301.725146) (xy 41.281509 -301.676285)
			(xy 41.273472 -301.625542) (xy 41.272968 -301.599854) (xy 41.272968 -301.59706) (xy 41.272441 -301.587165)
			(xy 41.264847 -301.568884) (xy 41.258236 -301.5615) (xy 41.207436 -301.509938) (xy 41.200036 -301.503098)
			(xy 41.181437 -301.49538) (xy 41.171368 -301.494952) (xy 40.128444 -301.494952) (xy 40.118379 -301.495387)
			(xy 40.099795 -301.503121) (xy 40.092376 -301.509938) (xy 40.041576 -301.5615) (xy 40.03493 -301.568857)
			(xy 40.027354 -301.587158) (xy 40.026844 -301.59706) (xy 40.026844 -301.599854) (xy 40.02634 -301.625542)
			(xy 40.018303 -301.676285) (xy 40.002427 -301.725146) (xy 39.979103 -301.770922) (xy 39.948906 -301.812486)
			(xy 39.912578 -301.848814) (xy 39.871014 -301.879011) (xy 39.825238 -301.902335) (xy 39.776377 -301.918211)
			(xy 39.725634 -301.926248) (xy 39.674258 -301.926248) (xy 39.623515 -301.918211) (xy 39.574654 -301.902335)
			(xy 39.528878 -301.879011) (xy 39.487314 -301.848814) (xy 39.450986 -301.812486) (xy 39.420789 -301.770922)
			(xy 39.397465 -301.725146) (xy 39.381589 -301.676285) (xy 39.373552 -301.625542) (xy 39.373048 -301.599854)
			(xy 39.373048 -301.59706) (xy 39.37252 -301.587166) (xy 39.364924 -301.568886) (xy 39.358316 -301.5615)
			(xy 39.307516 -301.509938) (xy 39.300115 -301.503101) (xy 39.281516 -301.495391) (xy 39.271448 -301.494952)
			(xy 39.178484 -301.494952) (xy 39.168416 -301.49538) (xy 39.149821 -301.503104) (xy 39.142416 -301.509938)
			(xy 39.091616 -301.5615) (xy 39.084965 -301.568855) (xy 39.077383 -301.587156) (xy 39.076884 -301.59706)
			(xy 39.076884 -301.599854) (xy 39.07638 -301.625542) (xy 39.068343 -301.676285) (xy 39.052467 -301.725146)
			(xy 39.029143 -301.770922) (xy 38.998946 -301.812486) (xy 38.962618 -301.848814) (xy 38.921054 -301.879011)
			(xy 38.875278 -301.902335) (xy 38.826417 -301.918211) (xy 38.775674 -301.926248) (xy 38.724298 -301.926248)
			(xy 38.673555 -301.918211) (xy 38.624694 -301.902335) (xy 38.578918 -301.879011) (xy 38.537354 -301.848814)
			(xy 38.501026 -301.812486) (xy 38.470829 -301.770922) (xy 38.447505 -301.725146) (xy 38.431629 -301.676285)
			(xy 38.423592 -301.625542) (xy 38.423088 -301.599854) (xy 38.423088 -301.59706) (xy 38.422561 -301.587165)
			(xy 38.414969 -301.568882) (xy 38.408356 -301.5615) (xy 38.357556 -301.509938) (xy 38.350157 -301.503095)
			(xy 38.331558 -301.49537) (xy 38.321488 -301.494952) (xy 31.553912 -301.494952) (xy 31.547903 -301.495123)
			(xy 31.536224 -301.497952) (xy 31.530798 -301.50054) (xy 31.527324 -301.50238) (xy 31.520946 -301.506975)
			(xy 31.518098 -301.509684) (xy 30.45226 -302.575522) (xy 36.523164 -302.575522) (xy 36.523164 -302.524106)
			(xy 36.531207 -302.473324) (xy 36.547095 -302.424425) (xy 36.570438 -302.378613) (xy 36.600659 -302.337017)
			(xy 36.637015 -302.300661) (xy 36.678611 -302.27044) (xy 36.724423 -302.247097) (xy 36.773322 -302.231209)
			(xy 36.824104 -302.223166) (xy 36.87552 -302.223166) (xy 36.926302 -302.231209) (xy 36.975201 -302.247097)
			(xy 37.021013 -302.27044) (xy 37.062609 -302.300661) (xy 37.098965 -302.337017) (xy 37.129186 -302.378613)
			(xy 37.152529 -302.424425) (xy 37.168417 -302.473324) (xy 37.17646 -302.524106) (xy 37.176964 -302.549814)
			(xy 37.17646 -302.575522) (xy 37.473124 -302.575522) (xy 37.473124 -302.524106) (xy 37.481167 -302.473324)
			(xy 37.497055 -302.424425) (xy 37.520398 -302.378613) (xy 37.550619 -302.337017) (xy 37.586975 -302.300661)
			(xy 37.628571 -302.27044) (xy 37.674383 -302.247097) (xy 37.723282 -302.231209) (xy 37.774064 -302.223166)
			(xy 37.82548 -302.223166) (xy 37.876262 -302.231209) (xy 37.925161 -302.247097) (xy 37.970973 -302.27044)
			(xy 38.012569 -302.300661) (xy 38.048925 -302.337017) (xy 38.079146 -302.378613) (xy 38.102489 -302.424425)
			(xy 38.118377 -302.473324) (xy 38.12642 -302.524106) (xy 38.126924 -302.549814) (xy 38.12642 -302.575522)
			(xy 43.173138 -302.575522) (xy 43.173138 -302.524106) (xy 43.181181 -302.473324) (xy 43.197069 -302.424425)
			(xy 43.220412 -302.378613) (xy 43.250633 -302.337017) (xy 43.286989 -302.300661) (xy 43.328585 -302.27044)
			(xy 43.374397 -302.247097) (xy 43.423296 -302.231209) (xy 43.474078 -302.223166) (xy 43.525494 -302.223166)
			(xy 43.576276 -302.231209) (xy 43.625175 -302.247097) (xy 43.670987 -302.27044) (xy 43.712583 -302.300661)
			(xy 43.748939 -302.337017) (xy 43.77916 -302.378613) (xy 43.802503 -302.424425) (xy 43.818391 -302.473324)
			(xy 43.826434 -302.524106) (xy 43.826938 -302.549814) (xy 43.826434 -302.575522) (xy 44.123098 -302.575522)
			(xy 44.123098 -302.524106) (xy 44.131141 -302.473324) (xy 44.147029 -302.424425) (xy 44.170372 -302.378613)
			(xy 44.200593 -302.337017) (xy 44.236949 -302.300661) (xy 44.278545 -302.27044) (xy 44.324357 -302.247097)
			(xy 44.373256 -302.231209) (xy 44.424038 -302.223166) (xy 44.475454 -302.223166) (xy 44.526236 -302.231209)
			(xy 44.575135 -302.247097) (xy 44.620947 -302.27044) (xy 44.662543 -302.300661) (xy 44.698899 -302.337017)
			(xy 44.72912 -302.378613) (xy 44.752463 -302.424425) (xy 44.768351 -302.473324) (xy 44.776394 -302.524106)
			(xy 44.776898 -302.549814) (xy 44.776394 -302.575522) (xy 44.768351 -302.626304) (xy 44.752463 -302.675203)
			(xy 44.72912 -302.721015) (xy 44.698899 -302.762611) (xy 44.662543 -302.798967) (xy 44.620947 -302.829188)
			(xy 44.575135 -302.852531) (xy 44.526236 -302.868419) (xy 44.475454 -302.876462) (xy 44.424038 -302.876462)
			(xy 44.373256 -302.868419) (xy 44.324357 -302.852531) (xy 44.278545 -302.829188) (xy 44.236949 -302.798967)
			(xy 44.200593 -302.762611) (xy 44.170372 -302.721015) (xy 44.147029 -302.675203) (xy 44.131141 -302.626304)
			(xy 44.123098 -302.575522) (xy 43.826434 -302.575522) (xy 43.818391 -302.626304) (xy 43.802503 -302.675203)
			(xy 43.77916 -302.721015) (xy 43.748939 -302.762611) (xy 43.712583 -302.798967) (xy 43.670987 -302.829188)
			(xy 43.625175 -302.852531) (xy 43.576276 -302.868419) (xy 43.525494 -302.876462) (xy 43.474078 -302.876462)
			(xy 43.423296 -302.868419) (xy 43.374397 -302.852531) (xy 43.328585 -302.829188) (xy 43.286989 -302.798967)
			(xy 43.250633 -302.762611) (xy 43.220412 -302.721015) (xy 43.197069 -302.675203) (xy 43.181181 -302.626304)
			(xy 43.173138 -302.575522) (xy 38.12642 -302.575522) (xy 38.118377 -302.626304) (xy 38.102489 -302.675203)
			(xy 38.079146 -302.721015) (xy 38.048925 -302.762611) (xy 38.012569 -302.798967) (xy 37.970973 -302.829188)
			(xy 37.925161 -302.852531) (xy 37.876262 -302.868419) (xy 37.82548 -302.876462) (xy 37.774064 -302.876462)
			(xy 37.723282 -302.868419) (xy 37.674383 -302.852531) (xy 37.628571 -302.829188) (xy 37.586975 -302.798967)
			(xy 37.550619 -302.762611) (xy 37.520398 -302.721015) (xy 37.497055 -302.675203) (xy 37.481167 -302.626304)
			(xy 37.473124 -302.575522) (xy 37.17646 -302.575522) (xy 37.168417 -302.626304) (xy 37.152529 -302.675203)
			(xy 37.129186 -302.721015) (xy 37.098965 -302.762611) (xy 37.062609 -302.798967) (xy 37.021013 -302.829188)
			(xy 36.975201 -302.852531) (xy 36.926302 -302.868419) (xy 36.87552 -302.876462) (xy 36.824104 -302.876462)
			(xy 36.773322 -302.868419) (xy 36.724423 -302.852531) (xy 36.678611 -302.829188) (xy 36.637015 -302.798967)
			(xy 36.600659 -302.762611) (xy 36.570438 -302.721015) (xy 36.547095 -302.675203) (xy 36.531207 -302.626304)
			(xy 36.523164 -302.575522) (xy 30.45226 -302.575522) (xy 29.5023 -303.525482) (xy 38.423338 -303.525482)
			(xy 38.423338 -303.474066) (xy 38.431381 -303.423284) (xy 38.447269 -303.374385) (xy 38.470612 -303.328573)
			(xy 38.500833 -303.286977) (xy 38.537189 -303.250621) (xy 38.578785 -303.2204) (xy 38.624597 -303.197057)
			(xy 38.673496 -303.181169) (xy 38.724278 -303.173126) (xy 38.775694 -303.173126) (xy 38.826476 -303.181169)
			(xy 38.875375 -303.197057) (xy 38.921187 -303.2204) (xy 38.962783 -303.250621) (xy 38.999139 -303.286977)
			(xy 39.02936 -303.328573) (xy 39.052703 -303.374385) (xy 39.068591 -303.423284) (xy 39.076634 -303.474066)
			(xy 39.077138 -303.499774) (xy 39.076634 -303.525482) (xy 39.373298 -303.525482) (xy 39.373298 -303.474066)
			(xy 39.381341 -303.423284) (xy 39.397229 -303.374385) (xy 39.420572 -303.328573) (xy 39.450793 -303.286977)
			(xy 39.487149 -303.250621) (xy 39.528745 -303.2204) (xy 39.574557 -303.197057) (xy 39.623456 -303.181169)
			(xy 39.674238 -303.173126) (xy 39.725654 -303.173126) (xy 39.776436 -303.181169) (xy 39.825335 -303.197057)
			(xy 39.871147 -303.2204) (xy 39.912743 -303.250621) (xy 39.949099 -303.286977) (xy 39.97932 -303.328573)
			(xy 40.002663 -303.374385) (xy 40.018551 -303.423284) (xy 40.026594 -303.474066) (xy 40.027098 -303.499774)
			(xy 40.026594 -303.525482) (xy 41.273218 -303.525482) (xy 41.273218 -303.474066) (xy 41.281261 -303.423284)
			(xy 41.297149 -303.374385) (xy 41.320492 -303.328573) (xy 41.350713 -303.286977) (xy 41.387069 -303.250621)
			(xy 41.428665 -303.2204) (xy 41.474477 -303.197057) (xy 41.523376 -303.181169) (xy 41.574158 -303.173126)
			(xy 41.625574 -303.173126) (xy 41.676356 -303.181169) (xy 41.725255 -303.197057) (xy 41.771067 -303.2204)
			(xy 41.812663 -303.250621) (xy 41.849019 -303.286977) (xy 41.87924 -303.328573) (xy 41.902583 -303.374385)
			(xy 41.918471 -303.423284) (xy 41.926514 -303.474066) (xy 41.927018 -303.499774) (xy 41.926514 -303.525482)
			(xy 42.223178 -303.525482) (xy 42.223178 -303.474066) (xy 42.231221 -303.423284) (xy 42.247109 -303.374385)
			(xy 42.270452 -303.328573) (xy 42.300673 -303.286977) (xy 42.337029 -303.250621) (xy 42.378625 -303.2204)
			(xy 42.424437 -303.197057) (xy 42.473336 -303.181169) (xy 42.524118 -303.173126) (xy 42.575534 -303.173126)
			(xy 42.626316 -303.181169) (xy 42.675215 -303.197057) (xy 42.721027 -303.2204) (xy 42.762623 -303.250621)
			(xy 42.798979 -303.286977) (xy 42.8292 -303.328573) (xy 42.852543 -303.374385) (xy 42.868431 -303.423284)
			(xy 42.876474 -303.474066) (xy 42.876978 -303.499774) (xy 42.876474 -303.525482) (xy 42.868431 -303.576264)
			(xy 42.852543 -303.625163) (xy 42.8292 -303.670975) (xy 42.798979 -303.712571) (xy 42.762623 -303.748927)
			(xy 42.721027 -303.779148) (xy 42.675215 -303.802491) (xy 42.626316 -303.818379) (xy 42.575534 -303.826422)
			(xy 42.524118 -303.826422) (xy 42.473336 -303.818379) (xy 42.424437 -303.802491) (xy 42.378625 -303.779148)
			(xy 42.337029 -303.748927) (xy 42.300673 -303.712571) (xy 42.270452 -303.670975) (xy 42.247109 -303.625163)
			(xy 42.231221 -303.576264) (xy 42.223178 -303.525482) (xy 41.926514 -303.525482) (xy 41.918471 -303.576264)
			(xy 41.902583 -303.625163) (xy 41.87924 -303.670975) (xy 41.849019 -303.712571) (xy 41.812663 -303.748927)
			(xy 41.771067 -303.779148) (xy 41.725255 -303.802491) (xy 41.676356 -303.818379) (xy 41.625574 -303.826422)
			(xy 41.574158 -303.826422) (xy 41.523376 -303.818379) (xy 41.474477 -303.802491) (xy 41.428665 -303.779148)
			(xy 41.387069 -303.748927) (xy 41.350713 -303.712571) (xy 41.320492 -303.670975) (xy 41.297149 -303.625163)
			(xy 41.281261 -303.576264) (xy 41.273218 -303.525482) (xy 40.026594 -303.525482) (xy 40.018551 -303.576264)
			(xy 40.002663 -303.625163) (xy 39.97932 -303.670975) (xy 39.949099 -303.712571) (xy 39.912743 -303.748927)
			(xy 39.871147 -303.779148) (xy 39.825335 -303.802491) (xy 39.776436 -303.818379) (xy 39.725654 -303.826422)
			(xy 39.674238 -303.826422) (xy 39.623456 -303.818379) (xy 39.574557 -303.802491) (xy 39.528745 -303.779148)
			(xy 39.487149 -303.748927) (xy 39.450793 -303.712571) (xy 39.420572 -303.670975) (xy 39.397229 -303.625163)
			(xy 39.381341 -303.576264) (xy 39.373298 -303.525482) (xy 39.076634 -303.525482) (xy 39.068591 -303.576264)
			(xy 39.052703 -303.625163) (xy 39.02936 -303.670975) (xy 38.999139 -303.712571) (xy 38.962783 -303.748927)
			(xy 38.921187 -303.779148) (xy 38.875375 -303.802491) (xy 38.826476 -303.818379) (xy 38.775694 -303.826422)
			(xy 38.724278 -303.826422) (xy 38.673496 -303.818379) (xy 38.624597 -303.802491) (xy 38.578785 -303.779148)
			(xy 38.537189 -303.748927) (xy 38.500833 -303.712571) (xy 38.470612 -303.670975) (xy 38.447269 -303.625163)
			(xy 38.431381 -303.576264) (xy 38.423338 -303.525482) (xy 29.5023 -303.525482) (xy 29.477462 -303.55032)
			(xy 29.470065 -303.557169) (xy 29.451466 -303.564902) (xy 29.441394 -303.565306) (xy 26.394664 -303.565306)
			(xy 26.388654 -303.565472) (xy 26.37697 -303.568293) (xy 26.37155 -303.570894) (xy 26.368077 -303.572735)
			(xy 26.361701 -303.577331) (xy 26.35885 -303.580038) (xy 25.463446 -304.475442) (xy 36.523164 -304.475442)
			(xy 36.523164 -304.424026) (xy 36.531207 -304.373244) (xy 36.547095 -304.324345) (xy 36.570438 -304.278533)
			(xy 36.600659 -304.236937) (xy 36.637015 -304.200581) (xy 36.678611 -304.17036) (xy 36.724423 -304.147017)
			(xy 36.773322 -304.131129) (xy 36.824104 -304.123086) (xy 36.87552 -304.123086) (xy 36.926302 -304.131129)
			(xy 36.975201 -304.147017) (xy 37.021013 -304.17036) (xy 37.062609 -304.200581) (xy 37.098965 -304.236937)
			(xy 37.129186 -304.278533) (xy 37.152529 -304.324345) (xy 37.168417 -304.373244) (xy 37.17646 -304.424026)
			(xy 37.176964 -304.449734) (xy 37.17646 -304.475442) (xy 37.473124 -304.475442) (xy 37.473124 -304.424026)
			(xy 37.481167 -304.373244) (xy 37.497055 -304.324345) (xy 37.520398 -304.278533) (xy 37.550619 -304.236937)
			(xy 37.586975 -304.200581) (xy 37.628571 -304.17036) (xy 37.674383 -304.147017) (xy 37.723282 -304.131129)
			(xy 37.774064 -304.123086) (xy 37.82548 -304.123086) (xy 37.876262 -304.131129) (xy 37.925161 -304.147017)
			(xy 37.970973 -304.17036) (xy 38.012569 -304.200581) (xy 38.048925 -304.236937) (xy 38.079146 -304.278533)
			(xy 38.102489 -304.324345) (xy 38.118377 -304.373244) (xy 38.12642 -304.424026) (xy 38.126924 -304.449734)
			(xy 38.12642 -304.475442) (xy 43.173138 -304.475442) (xy 43.173138 -304.424026) (xy 43.181181 -304.373244)
			(xy 43.197069 -304.324345) (xy 43.220412 -304.278533) (xy 43.250633 -304.236937) (xy 43.286989 -304.200581)
			(xy 43.328585 -304.17036) (xy 43.374397 -304.147017) (xy 43.423296 -304.131129) (xy 43.474078 -304.123086)
			(xy 43.525494 -304.123086) (xy 43.576276 -304.131129) (xy 43.625175 -304.147017) (xy 43.670987 -304.17036)
			(xy 43.712583 -304.200581) (xy 43.748939 -304.236937) (xy 43.77916 -304.278533) (xy 43.802503 -304.324345)
			(xy 43.818391 -304.373244) (xy 43.826434 -304.424026) (xy 43.826938 -304.449734) (xy 43.826434 -304.475442)
			(xy 44.123098 -304.475442) (xy 44.123098 -304.424026) (xy 44.131141 -304.373244) (xy 44.147029 -304.324345)
			(xy 44.170372 -304.278533) (xy 44.200593 -304.236937) (xy 44.236949 -304.200581) (xy 44.278545 -304.17036)
			(xy 44.324357 -304.147017) (xy 44.373256 -304.131129) (xy 44.424038 -304.123086) (xy 44.475454 -304.123086)
			(xy 44.526236 -304.131129) (xy 44.575135 -304.147017) (xy 44.620947 -304.17036) (xy 44.662543 -304.200581)
			(xy 44.698899 -304.236937) (xy 44.72912 -304.278533) (xy 44.752463 -304.324345) (xy 44.768351 -304.373244)
			(xy 44.776394 -304.424026) (xy 44.776898 -304.449734) (xy 44.776394 -304.475442) (xy 44.768351 -304.526224)
			(xy 44.752463 -304.575123) (xy 44.72912 -304.620935) (xy 44.698899 -304.662531) (xy 44.662543 -304.698887)
			(xy 44.620947 -304.729108) (xy 44.575135 -304.752451) (xy 44.526236 -304.768339) (xy 44.475454 -304.776382)
			(xy 44.424038 -304.776382) (xy 44.373256 -304.768339) (xy 44.324357 -304.752451) (xy 44.278545 -304.729108)
			(xy 44.236949 -304.698887) (xy 44.200593 -304.662531) (xy 44.170372 -304.620935) (xy 44.147029 -304.575123)
			(xy 44.131141 -304.526224) (xy 44.123098 -304.475442) (xy 43.826434 -304.475442) (xy 43.818391 -304.526224)
			(xy 43.802503 -304.575123) (xy 43.77916 -304.620935) (xy 43.748939 -304.662531) (xy 43.712583 -304.698887)
			(xy 43.670987 -304.729108) (xy 43.625175 -304.752451) (xy 43.576276 -304.768339) (xy 43.525494 -304.776382)
			(xy 43.474078 -304.776382) (xy 43.423296 -304.768339) (xy 43.374397 -304.752451) (xy 43.328585 -304.729108)
			(xy 43.286989 -304.698887) (xy 43.250633 -304.662531) (xy 43.220412 -304.620935) (xy 43.197069 -304.575123)
			(xy 43.181181 -304.526224) (xy 43.173138 -304.475442) (xy 38.12642 -304.475442) (xy 38.118377 -304.526224)
			(xy 38.102489 -304.575123) (xy 38.079146 -304.620935) (xy 38.048925 -304.662531) (xy 38.012569 -304.698887)
			(xy 37.970973 -304.729108) (xy 37.925161 -304.752451) (xy 37.876262 -304.768339) (xy 37.82548 -304.776382)
			(xy 37.774064 -304.776382) (xy 37.723282 -304.768339) (xy 37.674383 -304.752451) (xy 37.628571 -304.729108)
			(xy 37.586975 -304.698887) (xy 37.550619 -304.662531) (xy 37.520398 -304.620935) (xy 37.497055 -304.575123)
			(xy 37.481167 -304.526224) (xy 37.473124 -304.475442) (xy 37.17646 -304.475442) (xy 37.168417 -304.526224)
			(xy 37.152529 -304.575123) (xy 37.129186 -304.620935) (xy 37.098965 -304.662531) (xy 37.062609 -304.698887)
			(xy 37.021013 -304.729108) (xy 36.975201 -304.752451) (xy 36.926302 -304.768339) (xy 36.87552 -304.776382)
			(xy 36.824104 -304.776382) (xy 36.773322 -304.768339) (xy 36.724423 -304.752451) (xy 36.678611 -304.729108)
			(xy 36.637015 -304.698887) (xy 36.600659 -304.662531) (xy 36.570438 -304.620935) (xy 36.547095 -304.575123)
			(xy 36.531207 -304.526224) (xy 36.523164 -304.475442) (xy 25.463446 -304.475442) (xy 24.513232 -305.425656)
			(xy 38.423338 -305.425656) (xy 38.423338 -305.37424) (xy 38.431381 -305.323458) (xy 38.447269 -305.274559)
			(xy 38.470612 -305.228747) (xy 38.500833 -305.187151) (xy 38.537189 -305.150795) (xy 38.578785 -305.120574)
			(xy 38.624597 -305.097231) (xy 38.673496 -305.081343) (xy 38.724278 -305.0733) (xy 38.775694 -305.0733)
			(xy 38.826476 -305.081343) (xy 38.875375 -305.097231) (xy 38.921187 -305.120574) (xy 38.962783 -305.150795)
			(xy 38.999139 -305.187151) (xy 39.02936 -305.228747) (xy 39.052703 -305.274559) (xy 39.068591 -305.323458)
			(xy 39.076634 -305.37424) (xy 39.077138 -305.399948) (xy 39.076634 -305.425656) (xy 39.373298 -305.425656)
			(xy 39.373298 -305.37424) (xy 39.381341 -305.323458) (xy 39.397229 -305.274559) (xy 39.420572 -305.228747)
			(xy 39.450793 -305.187151) (xy 39.487149 -305.150795) (xy 39.528745 -305.120574) (xy 39.574557 -305.097231)
			(xy 39.623456 -305.081343) (xy 39.674238 -305.0733) (xy 39.725654 -305.0733) (xy 39.776436 -305.081343)
			(xy 39.825335 -305.097231) (xy 39.871147 -305.120574) (xy 39.912743 -305.150795) (xy 39.949099 -305.187151)
			(xy 39.97932 -305.228747) (xy 40.002663 -305.274559) (xy 40.018551 -305.323458) (xy 40.026594 -305.37424)
			(xy 40.027098 -305.399948) (xy 40.026594 -305.425656) (xy 41.273218 -305.425656) (xy 41.273218 -305.37424)
			(xy 41.281261 -305.323458) (xy 41.297149 -305.274559) (xy 41.320492 -305.228747) (xy 41.350713 -305.187151)
			(xy 41.387069 -305.150795) (xy 41.428665 -305.120574) (xy 41.474477 -305.097231) (xy 41.523376 -305.081343)
			(xy 41.574158 -305.0733) (xy 41.625574 -305.0733) (xy 41.676356 -305.081343) (xy 41.725255 -305.097231)
			(xy 41.771067 -305.120574) (xy 41.812663 -305.150795) (xy 41.849019 -305.187151) (xy 41.87924 -305.228747)
			(xy 41.902583 -305.274559) (xy 41.918471 -305.323458) (xy 41.926514 -305.37424) (xy 41.927018 -305.399948)
			(xy 41.926514 -305.425656) (xy 42.223178 -305.425656) (xy 42.223178 -305.37424) (xy 42.231221 -305.323458)
			(xy 42.247109 -305.274559) (xy 42.270452 -305.228747) (xy 42.300673 -305.187151) (xy 42.337029 -305.150795)
			(xy 42.378625 -305.120574) (xy 42.424437 -305.097231) (xy 42.473336 -305.081343) (xy 42.524118 -305.0733)
			(xy 42.575534 -305.0733) (xy 42.626316 -305.081343) (xy 42.675215 -305.097231) (xy 42.721027 -305.120574)
			(xy 42.762623 -305.150795) (xy 42.798979 -305.187151) (xy 42.8292 -305.228747) (xy 42.852543 -305.274559)
			(xy 42.868431 -305.323458) (xy 42.876474 -305.37424) (xy 42.876978 -305.399948) (xy 42.876474 -305.425656)
			(xy 42.868431 -305.476438) (xy 42.852543 -305.525337) (xy 42.8292 -305.571149) (xy 42.798979 -305.612745)
			(xy 42.762623 -305.649101) (xy 42.721027 -305.679322) (xy 42.675215 -305.702665) (xy 42.626316 -305.718553)
			(xy 42.575534 -305.726596) (xy 42.524118 -305.726596) (xy 42.473336 -305.718553) (xy 42.424437 -305.702665)
			(xy 42.378625 -305.679322) (xy 42.337029 -305.649101) (xy 42.300673 -305.612745) (xy 42.270452 -305.571149)
			(xy 42.247109 -305.525337) (xy 42.231221 -305.476438) (xy 42.223178 -305.425656) (xy 41.926514 -305.425656)
			(xy 41.918471 -305.476438) (xy 41.902583 -305.525337) (xy 41.87924 -305.571149) (xy 41.849019 -305.612745)
			(xy 41.812663 -305.649101) (xy 41.771067 -305.679322) (xy 41.725255 -305.702665) (xy 41.676356 -305.718553)
			(xy 41.625574 -305.726596) (xy 41.574158 -305.726596) (xy 41.523376 -305.718553) (xy 41.474477 -305.702665)
			(xy 41.428665 -305.679322) (xy 41.387069 -305.649101) (xy 41.350713 -305.612745) (xy 41.320492 -305.571149)
			(xy 41.297149 -305.525337) (xy 41.281261 -305.476438) (xy 41.273218 -305.425656) (xy 40.026594 -305.425656)
			(xy 40.018551 -305.476438) (xy 40.002663 -305.525337) (xy 39.97932 -305.571149) (xy 39.949099 -305.612745)
			(xy 39.912743 -305.649101) (xy 39.871147 -305.679322) (xy 39.825335 -305.702665) (xy 39.776436 -305.718553)
			(xy 39.725654 -305.726596) (xy 39.674238 -305.726596) (xy 39.623456 -305.718553) (xy 39.574557 -305.702665)
			(xy 39.528745 -305.679322) (xy 39.487149 -305.649101) (xy 39.450793 -305.612745) (xy 39.420572 -305.571149)
			(xy 39.397229 -305.525337) (xy 39.381341 -305.476438) (xy 39.373298 -305.425656) (xy 39.076634 -305.425656)
			(xy 39.068591 -305.476438) (xy 39.052703 -305.525337) (xy 39.02936 -305.571149) (xy 38.999139 -305.612745)
			(xy 38.962783 -305.649101) (xy 38.921187 -305.679322) (xy 38.875375 -305.702665) (xy 38.826476 -305.718553)
			(xy 38.775694 -305.726596) (xy 38.724278 -305.726596) (xy 38.673496 -305.718553) (xy 38.624597 -305.702665)
			(xy 38.578785 -305.679322) (xy 38.537189 -305.649101) (xy 38.500833 -305.612745) (xy 38.470612 -305.571149)
			(xy 38.447269 -305.525337) (xy 38.431381 -305.476438) (xy 38.423338 -305.425656) (xy 24.513232 -305.425656)
			(xy 23.563272 -306.375616) (xy 36.523164 -306.375616) (xy 36.523164 -306.3242) (xy 36.531207 -306.273418)
			(xy 36.547095 -306.224519) (xy 36.570438 -306.178707) (xy 36.600659 -306.137111) (xy 36.637015 -306.100755)
			(xy 36.678611 -306.070534) (xy 36.724423 -306.047191) (xy 36.773322 -306.031303) (xy 36.824104 -306.02326)
			(xy 36.87552 -306.02326) (xy 36.926302 -306.031303) (xy 36.975201 -306.047191) (xy 37.021013 -306.070534)
			(xy 37.062609 -306.100755) (xy 37.098965 -306.137111) (xy 37.129186 -306.178707) (xy 37.152529 -306.224519)
			(xy 37.168417 -306.273418) (xy 37.17646 -306.3242) (xy 37.176964 -306.349908) (xy 37.17646 -306.375616)
			(xy 37.473124 -306.375616) (xy 37.473124 -306.3242) (xy 37.481167 -306.273418) (xy 37.497055 -306.224519)
			(xy 37.520398 -306.178707) (xy 37.550619 -306.137111) (xy 37.586975 -306.100755) (xy 37.628571 -306.070534)
			(xy 37.674383 -306.047191) (xy 37.723282 -306.031303) (xy 37.774064 -306.02326) (xy 37.82548 -306.02326)
			(xy 37.876262 -306.031303) (xy 37.925161 -306.047191) (xy 37.970973 -306.070534) (xy 38.012569 -306.100755)
			(xy 38.048925 -306.137111) (xy 38.079146 -306.178707) (xy 38.102489 -306.224519) (xy 38.118377 -306.273418)
			(xy 38.12642 -306.3242) (xy 38.126924 -306.349908) (xy 38.12642 -306.375616) (xy 43.173138 -306.375616)
			(xy 43.173138 -306.3242) (xy 43.181181 -306.273418) (xy 43.197069 -306.224519) (xy 43.220412 -306.178707)
			(xy 43.250633 -306.137111) (xy 43.286989 -306.100755) (xy 43.328585 -306.070534) (xy 43.374397 -306.047191)
			(xy 43.423296 -306.031303) (xy 43.474078 -306.02326) (xy 43.525494 -306.02326) (xy 43.576276 -306.031303)
			(xy 43.625175 -306.047191) (xy 43.670987 -306.070534) (xy 43.712583 -306.100755) (xy 43.748939 -306.137111)
			(xy 43.77916 -306.178707) (xy 43.802503 -306.224519) (xy 43.818391 -306.273418) (xy 43.826434 -306.3242)
			(xy 43.826938 -306.349908) (xy 43.826434 -306.375616) (xy 44.123098 -306.375616) (xy 44.123098 -306.3242)
			(xy 44.131141 -306.273418) (xy 44.147029 -306.224519) (xy 44.170372 -306.178707) (xy 44.200593 -306.137111)
			(xy 44.236949 -306.100755) (xy 44.278545 -306.070534) (xy 44.324357 -306.047191) (xy 44.373256 -306.031303)
			(xy 44.424038 -306.02326) (xy 44.475454 -306.02326) (xy 44.526236 -306.031303) (xy 44.575135 -306.047191)
			(xy 44.620947 -306.070534) (xy 44.662543 -306.100755) (xy 44.698899 -306.137111) (xy 44.72912 -306.178707)
			(xy 44.752463 -306.224519) (xy 44.768351 -306.273418) (xy 44.776394 -306.3242) (xy 44.776898 -306.349908)
			(xy 44.776394 -306.375616) (xy 44.768351 -306.426398) (xy 44.752463 -306.475297) (xy 44.72912 -306.521109)
			(xy 44.698899 -306.562705) (xy 44.662543 -306.599061) (xy 44.620947 -306.629282) (xy 44.575135 -306.652625)
			(xy 44.526236 -306.668513) (xy 44.475454 -306.676556) (xy 44.424038 -306.676556) (xy 44.373256 -306.668513)
			(xy 44.324357 -306.652625) (xy 44.278545 -306.629282) (xy 44.236949 -306.599061) (xy 44.200593 -306.562705)
			(xy 44.170372 -306.521109) (xy 44.147029 -306.475297) (xy 44.131141 -306.426398) (xy 44.123098 -306.375616)
			(xy 43.826434 -306.375616) (xy 43.818391 -306.426398) (xy 43.802503 -306.475297) (xy 43.77916 -306.521109)
			(xy 43.748939 -306.562705) (xy 43.712583 -306.599061) (xy 43.670987 -306.629282) (xy 43.625175 -306.652625)
			(xy 43.576276 -306.668513) (xy 43.525494 -306.676556) (xy 43.474078 -306.676556) (xy 43.423296 -306.668513)
			(xy 43.374397 -306.652625) (xy 43.328585 -306.629282) (xy 43.286989 -306.599061) (xy 43.250633 -306.562705)
			(xy 43.220412 -306.521109) (xy 43.197069 -306.475297) (xy 43.181181 -306.426398) (xy 43.173138 -306.375616)
			(xy 38.12642 -306.375616) (xy 38.118377 -306.426398) (xy 38.102489 -306.475297) (xy 38.079146 -306.521109)
			(xy 38.048925 -306.562705) (xy 38.012569 -306.599061) (xy 37.970973 -306.629282) (xy 37.925161 -306.652625)
			(xy 37.876262 -306.668513) (xy 37.82548 -306.676556) (xy 37.774064 -306.676556) (xy 37.723282 -306.668513)
			(xy 37.674383 -306.652625) (xy 37.628571 -306.629282) (xy 37.586975 -306.599061) (xy 37.550619 -306.562705)
			(xy 37.520398 -306.521109) (xy 37.497055 -306.475297) (xy 37.481167 -306.426398) (xy 37.473124 -306.375616)
			(xy 37.17646 -306.375616) (xy 37.168417 -306.426398) (xy 37.152529 -306.475297) (xy 37.129186 -306.521109)
			(xy 37.098965 -306.562705) (xy 37.062609 -306.599061) (xy 37.021013 -306.629282) (xy 36.975201 -306.652625)
			(xy 36.926302 -306.668513) (xy 36.87552 -306.676556) (xy 36.824104 -306.676556) (xy 36.773322 -306.668513)
			(xy 36.724423 -306.652625) (xy 36.678611 -306.629282) (xy 36.637015 -306.599061) (xy 36.600659 -306.562705)
			(xy 36.570438 -306.521109) (xy 36.547095 -306.475297) (xy 36.531207 -306.426398) (xy 36.523164 -306.375616)
			(xy 23.563272 -306.375616) (xy 23.341838 -306.59705) (xy 23.334439 -306.603892) (xy 23.31584 -306.611612)
			(xy 23.30577 -306.612036) (xy 20.620482 -306.612036) (xy 20.614472 -306.6122) (xy 20.602787 -306.615019)
			(xy 20.597368 -306.617624) (xy 20.593895 -306.619465) (xy 20.587519 -306.624061) (xy 20.584668 -306.626768)
			(xy 20.446238 -306.765198) (xy 29.725364 -306.765198) (xy 29.729435 -306.709576) (xy 29.741561 -306.655139)
			(xy 29.761484 -306.603048) (xy 29.78878 -306.554413) (xy 29.822866 -306.51027) (xy 29.863015 -306.471561)
			(xy 29.908373 -306.43911) (xy 29.957973 -306.413609) (xy 30.010757 -306.395602) (xy 30.0656 -306.385472)
			(xy 30.121334 -306.383435) (xy 30.176771 -306.389535) (xy 30.230728 -306.403641) (xy 30.282057 -306.425453)
			(xy 30.329663 -306.454507) (xy 30.372531 -306.490182) (xy 30.409748 -306.531719) (xy 30.440521 -306.578232)
			(xy 30.464193 -306.628729) (xy 30.480261 -306.682136) (xy 30.488381 -306.737312) (xy 30.48889 -306.765198)
			(xy 30.488381 -306.793084) (xy 30.480261 -306.84826) (xy 30.464193 -306.901667) (xy 30.440521 -306.952164)
			(xy 30.409748 -306.998677) (xy 30.372531 -307.040214) (xy 30.329663 -307.075889) (xy 30.282057 -307.104943)
			(xy 30.230728 -307.126755) (xy 30.176771 -307.140861) (xy 30.121334 -307.146961) (xy 30.0656 -307.144924)
			(xy 30.010757 -307.134794) (xy 29.957973 -307.116787) (xy 29.908373 -307.091286) (xy 29.863015 -307.058835)
			(xy 29.822866 -307.020126) (xy 29.78878 -306.975983) (xy 29.761484 -306.927348) (xy 29.741561 -306.875257)
			(xy 29.729435 -306.82082) (xy 29.725364 -306.765198) (xy 20.446238 -306.765198) (xy 19.88586 -307.325576)
			(xy 38.423338 -307.325576) (xy 38.423338 -307.27416) (xy 38.431381 -307.223378) (xy 38.447269 -307.174479)
			(xy 38.470612 -307.128667) (xy 38.500833 -307.087071) (xy 38.537189 -307.050715) (xy 38.578785 -307.020494)
			(xy 38.624597 -306.997151) (xy 38.673496 -306.981263) (xy 38.724278 -306.97322) (xy 38.775694 -306.97322)
			(xy 38.826476 -306.981263) (xy 38.875375 -306.997151) (xy 38.921187 -307.020494) (xy 38.962783 -307.050715)
			(xy 38.999139 -307.087071) (xy 39.02936 -307.128667) (xy 39.052703 -307.174479) (xy 39.068591 -307.223378)
			(xy 39.076634 -307.27416) (xy 39.077138 -307.299868) (xy 39.076634 -307.325576) (xy 39.373298 -307.325576)
			(xy 39.373298 -307.27416) (xy 39.381341 -307.223378) (xy 39.397229 -307.174479) (xy 39.420572 -307.128667)
			(xy 39.450793 -307.087071) (xy 39.487149 -307.050715) (xy 39.528745 -307.020494) (xy 39.574557 -306.997151)
			(xy 39.623456 -306.981263) (xy 39.674238 -306.97322) (xy 39.725654 -306.97322) (xy 39.776436 -306.981263)
			(xy 39.825335 -306.997151) (xy 39.871147 -307.020494) (xy 39.912743 -307.050715) (xy 39.949099 -307.087071)
			(xy 39.97932 -307.128667) (xy 40.002663 -307.174479) (xy 40.018551 -307.223378) (xy 40.026594 -307.27416)
			(xy 40.027098 -307.299868) (xy 40.026594 -307.325576) (xy 41.273218 -307.325576) (xy 41.273218 -307.27416)
			(xy 41.281261 -307.223378) (xy 41.297149 -307.174479) (xy 41.320492 -307.128667) (xy 41.350713 -307.087071)
			(xy 41.387069 -307.050715) (xy 41.428665 -307.020494) (xy 41.474477 -306.997151) (xy 41.523376 -306.981263)
			(xy 41.574158 -306.97322) (xy 41.625574 -306.97322) (xy 41.676356 -306.981263) (xy 41.725255 -306.997151)
			(xy 41.771067 -307.020494) (xy 41.812663 -307.050715) (xy 41.849019 -307.087071) (xy 41.87924 -307.128667)
			(xy 41.902583 -307.174479) (xy 41.918471 -307.223378) (xy 41.926514 -307.27416) (xy 41.927018 -307.299868)
			(xy 41.926514 -307.325576) (xy 42.223178 -307.325576) (xy 42.223178 -307.27416) (xy 42.231221 -307.223378)
			(xy 42.247109 -307.174479) (xy 42.270452 -307.128667) (xy 42.300673 -307.087071) (xy 42.337029 -307.050715)
			(xy 42.378625 -307.020494) (xy 42.424437 -306.997151) (xy 42.473336 -306.981263) (xy 42.524118 -306.97322)
			(xy 42.575534 -306.97322) (xy 42.626316 -306.981263) (xy 42.675215 -306.997151) (xy 42.721027 -307.020494)
			(xy 42.762623 -307.050715) (xy 42.798979 -307.087071) (xy 42.8292 -307.128667) (xy 42.852543 -307.174479)
			(xy 42.868431 -307.223378) (xy 42.876474 -307.27416) (xy 42.876978 -307.299868) (xy 42.876474 -307.325576)
			(xy 42.868431 -307.376358) (xy 42.852543 -307.425257) (xy 42.8292 -307.471069) (xy 42.798979 -307.512665)
			(xy 42.762623 -307.549021) (xy 42.721027 -307.579242) (xy 42.675215 -307.602585) (xy 42.626316 -307.618473)
			(xy 42.575534 -307.626516) (xy 42.524118 -307.626516) (xy 42.473336 -307.618473) (xy 42.424437 -307.602585)
			(xy 42.378625 -307.579242) (xy 42.337029 -307.549021) (xy 42.300673 -307.512665) (xy 42.270452 -307.471069)
			(xy 42.247109 -307.425257) (xy 42.231221 -307.376358) (xy 42.223178 -307.325576) (xy 41.926514 -307.325576)
			(xy 41.918471 -307.376358) (xy 41.902583 -307.425257) (xy 41.87924 -307.471069) (xy 41.849019 -307.512665)
			(xy 41.812663 -307.549021) (xy 41.771067 -307.579242) (xy 41.725255 -307.602585) (xy 41.676356 -307.618473)
			(xy 41.625574 -307.626516) (xy 41.574158 -307.626516) (xy 41.523376 -307.618473) (xy 41.474477 -307.602585)
			(xy 41.428665 -307.579242) (xy 41.387069 -307.549021) (xy 41.350713 -307.512665) (xy 41.320492 -307.471069)
			(xy 41.297149 -307.425257) (xy 41.281261 -307.376358) (xy 41.273218 -307.325576) (xy 40.026594 -307.325576)
			(xy 40.018551 -307.376358) (xy 40.002663 -307.425257) (xy 39.97932 -307.471069) (xy 39.949099 -307.512665)
			(xy 39.912743 -307.549021) (xy 39.871147 -307.579242) (xy 39.825335 -307.602585) (xy 39.776436 -307.618473)
			(xy 39.725654 -307.626516) (xy 39.674238 -307.626516) (xy 39.623456 -307.618473) (xy 39.574557 -307.602585)
			(xy 39.528745 -307.579242) (xy 39.487149 -307.549021) (xy 39.450793 -307.512665) (xy 39.420572 -307.471069)
			(xy 39.397229 -307.425257) (xy 39.381341 -307.376358) (xy 39.373298 -307.325576) (xy 39.076634 -307.325576)
			(xy 39.068591 -307.376358) (xy 39.052703 -307.425257) (xy 39.02936 -307.471069) (xy 38.999139 -307.512665)
			(xy 38.962783 -307.549021) (xy 38.921187 -307.579242) (xy 38.875375 -307.602585) (xy 38.826476 -307.618473)
			(xy 38.775694 -307.626516) (xy 38.724278 -307.626516) (xy 38.673496 -307.618473) (xy 38.624597 -307.602585)
			(xy 38.578785 -307.579242) (xy 38.537189 -307.549021) (xy 38.500833 -307.512665) (xy 38.470612 -307.471069)
			(xy 38.447269 -307.425257) (xy 38.431381 -307.376358) (xy 38.423338 -307.325576) (xy 19.88586 -307.325576)
			(xy 18.760948 -308.450488) (xy 28.078174 -308.450488) (xy 28.082245 -308.394866) (xy 28.094371 -308.340429)
			(xy 28.114294 -308.288338) (xy 28.14159 -308.239703) (xy 28.175676 -308.19556) (xy 28.215825 -308.156851)
			(xy 28.261183 -308.1244) (xy 28.310783 -308.098899) (xy 28.363567 -308.080892) (xy 28.41841 -308.070762)
			(xy 28.474144 -308.068725) (xy 28.529581 -308.074825) (xy 28.583538 -308.088931) (xy 28.634867 -308.110743)
			(xy 28.682473 -308.139797) (xy 28.725341 -308.175472) (xy 28.762558 -308.217009) (xy 28.793331 -308.263522)
			(xy 28.798963 -308.275536) (xy 36.523164 -308.275536) (xy 36.523164 -308.22412) (xy 36.531207 -308.173338)
			(xy 36.547095 -308.124439) (xy 36.570438 -308.078627) (xy 36.600659 -308.037031) (xy 36.637015 -308.000675)
			(xy 36.678611 -307.970454) (xy 36.724423 -307.947111) (xy 36.773322 -307.931223) (xy 36.824104 -307.92318)
			(xy 36.87552 -307.92318) (xy 36.926302 -307.931223) (xy 36.975201 -307.947111) (xy 37.021013 -307.970454)
			(xy 37.062609 -308.000675) (xy 37.098965 -308.037031) (xy 37.129186 -308.078627) (xy 37.152529 -308.124439)
			(xy 37.168417 -308.173338) (xy 37.17646 -308.22412) (xy 37.176964 -308.249828) (xy 37.17646 -308.275536)
			(xy 37.473124 -308.275536) (xy 37.473124 -308.22412) (xy 37.481167 -308.173338) (xy 37.497055 -308.124439)
			(xy 37.520398 -308.078627) (xy 37.550619 -308.037031) (xy 37.586975 -308.000675) (xy 37.628571 -307.970454)
			(xy 37.674383 -307.947111) (xy 37.723282 -307.931223) (xy 37.774064 -307.92318) (xy 37.82548 -307.92318)
			(xy 37.876262 -307.931223) (xy 37.925161 -307.947111) (xy 37.970973 -307.970454) (xy 38.012569 -308.000675)
			(xy 38.048925 -308.037031) (xy 38.079146 -308.078627) (xy 38.102489 -308.124439) (xy 38.118377 -308.173338)
			(xy 38.12642 -308.22412) (xy 38.126924 -308.249828) (xy 38.12642 -308.275536) (xy 43.173138 -308.275536)
			(xy 43.173138 -308.22412) (xy 43.181181 -308.173338) (xy 43.197069 -308.124439) (xy 43.220412 -308.078627)
			(xy 43.250633 -308.037031) (xy 43.286989 -308.000675) (xy 43.328585 -307.970454) (xy 43.374397 -307.947111)
			(xy 43.423296 -307.931223) (xy 43.474078 -307.92318) (xy 43.525494 -307.92318) (xy 43.576276 -307.931223)
			(xy 43.625175 -307.947111) (xy 43.670987 -307.970454) (xy 43.712583 -308.000675) (xy 43.748939 -308.037031)
			(xy 43.77916 -308.078627) (xy 43.802503 -308.124439) (xy 43.818391 -308.173338) (xy 43.826434 -308.22412)
			(xy 43.826938 -308.249828) (xy 43.826434 -308.275536) (xy 44.123098 -308.275536) (xy 44.123098 -308.22412)
			(xy 44.131141 -308.173338) (xy 44.147029 -308.124439) (xy 44.170372 -308.078627) (xy 44.200593 -308.037031)
			(xy 44.236949 -308.000675) (xy 44.278545 -307.970454) (xy 44.324357 -307.947111) (xy 44.373256 -307.931223)
			(xy 44.424038 -307.92318) (xy 44.475454 -307.92318) (xy 44.526236 -307.931223) (xy 44.575135 -307.947111)
			(xy 44.620947 -307.970454) (xy 44.662543 -308.000675) (xy 44.698899 -308.037031) (xy 44.72912 -308.078627)
			(xy 44.752463 -308.124439) (xy 44.768351 -308.173338) (xy 44.776394 -308.22412) (xy 44.776898 -308.249828)
			(xy 44.776394 -308.275536) (xy 44.768351 -308.326318) (xy 44.752463 -308.375217) (xy 44.72912 -308.421029)
			(xy 44.698899 -308.462625) (xy 44.662543 -308.498981) (xy 44.620947 -308.529202) (xy 44.575135 -308.552545)
			(xy 44.526236 -308.568433) (xy 44.475454 -308.576476) (xy 44.424038 -308.576476) (xy 44.373256 -308.568433)
			(xy 44.324357 -308.552545) (xy 44.278545 -308.529202) (xy 44.236949 -308.498981) (xy 44.200593 -308.462625)
			(xy 44.170372 -308.421029) (xy 44.147029 -308.375217) (xy 44.131141 -308.326318) (xy 44.123098 -308.275536)
			(xy 43.826434 -308.275536) (xy 43.818391 -308.326318) (xy 43.802503 -308.375217) (xy 43.77916 -308.421029)
			(xy 43.748939 -308.462625) (xy 43.712583 -308.498981) (xy 43.670987 -308.529202) (xy 43.625175 -308.552545)
			(xy 43.576276 -308.568433) (xy 43.525494 -308.576476) (xy 43.474078 -308.576476) (xy 43.423296 -308.568433)
			(xy 43.374397 -308.552545) (xy 43.328585 -308.529202) (xy 43.286989 -308.498981) (xy 43.250633 -308.462625)
			(xy 43.220412 -308.421029) (xy 43.197069 -308.375217) (xy 43.181181 -308.326318) (xy 43.173138 -308.275536)
			(xy 38.12642 -308.275536) (xy 38.118377 -308.326318) (xy 38.102489 -308.375217) (xy 38.079146 -308.421029)
			(xy 38.048925 -308.462625) (xy 38.012569 -308.498981) (xy 37.970973 -308.529202) (xy 37.925161 -308.552545)
			(xy 37.876262 -308.568433) (xy 37.82548 -308.576476) (xy 37.774064 -308.576476) (xy 37.723282 -308.568433)
			(xy 37.674383 -308.552545) (xy 37.628571 -308.529202) (xy 37.586975 -308.498981) (xy 37.550619 -308.462625)
			(xy 37.520398 -308.421029) (xy 37.497055 -308.375217) (xy 37.481167 -308.326318) (xy 37.473124 -308.275536)
			(xy 37.17646 -308.275536) (xy 37.168417 -308.326318) (xy 37.152529 -308.375217) (xy 37.129186 -308.421029)
			(xy 37.098965 -308.462625) (xy 37.062609 -308.498981) (xy 37.021013 -308.529202) (xy 36.975201 -308.552545)
			(xy 36.926302 -308.568433) (xy 36.87552 -308.576476) (xy 36.824104 -308.576476) (xy 36.773322 -308.568433)
			(xy 36.724423 -308.552545) (xy 36.678611 -308.529202) (xy 36.637015 -308.498981) (xy 36.600659 -308.462625)
			(xy 36.570438 -308.421029) (xy 36.547095 -308.375217) (xy 36.531207 -308.326318) (xy 36.523164 -308.275536)
			(xy 28.798963 -308.275536) (xy 28.817003 -308.314019) (xy 28.833071 -308.367426) (xy 28.841191 -308.422602)
			(xy 28.8417 -308.450488) (xy 28.841191 -308.478374) (xy 28.833071 -308.53355) (xy 28.817003 -308.586957)
			(xy 28.793331 -308.637454) (xy 28.762558 -308.683967) (xy 28.725341 -308.725504) (xy 28.682473 -308.761179)
			(xy 28.634867 -308.790233) (xy 28.583538 -308.812045) (xy 28.529581 -308.826151) (xy 28.474144 -308.832251)
			(xy 28.41841 -308.830214) (xy 28.363567 -308.820084) (xy 28.310783 -308.802077) (xy 28.261183 -308.776576)
			(xy 28.215825 -308.744125) (xy 28.175676 -308.705416) (xy 28.14159 -308.661273) (xy 28.114294 -308.612638)
			(xy 28.094371 -308.560547) (xy 28.082245 -308.50611) (xy 28.078174 -308.450488) (xy 18.760948 -308.450488)
			(xy 17.90192 -309.309516) (xy 17.899215 -309.312368) (xy 17.894626 -309.318748) (xy 17.892776 -309.322216)
			(xy 17.890191 -309.327643) (xy 17.887363 -309.339322) (xy 17.887188 -309.34533) (xy 17.887188 -309.414926)
			(xy 26.999944 -309.414926) (xy 27.004015 -309.359304) (xy 27.016141 -309.304867) (xy 27.036064 -309.252776)
			(xy 27.06336 -309.204141) (xy 27.097446 -309.159998) (xy 27.137595 -309.121289) (xy 27.182953 -309.088838)
			(xy 27.232553 -309.063337) (xy 27.285337 -309.04533) (xy 27.34018 -309.0352) (xy 27.395914 -309.033163)
			(xy 27.451351 -309.039263) (xy 27.505308 -309.053369) (xy 27.556637 -309.075181) (xy 27.604243 -309.104235)
			(xy 27.647111 -309.13991) (xy 27.684328 -309.181447) (xy 27.713471 -309.225496) (xy 38.423338 -309.225496)
			(xy 38.423338 -309.17408) (xy 38.431381 -309.123298) (xy 38.447269 -309.074399) (xy 38.470612 -309.028587)
			(xy 38.500833 -308.986991) (xy 38.537189 -308.950635) (xy 38.578785 -308.920414) (xy 38.624597 -308.897071)
			(xy 38.673496 -308.881183) (xy 38.724278 -308.87314) (xy 38.775694 -308.87314) (xy 38.826476 -308.881183)
			(xy 38.875375 -308.897071) (xy 38.921187 -308.920414) (xy 38.962783 -308.950635) (xy 38.999139 -308.986991)
			(xy 39.02936 -309.028587) (xy 39.052703 -309.074399) (xy 39.068591 -309.123298) (xy 39.076634 -309.17408)
			(xy 39.077138 -309.199788) (xy 39.076634 -309.225496) (xy 39.373298 -309.225496) (xy 39.373298 -309.17408)
			(xy 39.381341 -309.123298) (xy 39.397229 -309.074399) (xy 39.420572 -309.028587) (xy 39.450793 -308.986991)
			(xy 39.487149 -308.950635) (xy 39.528745 -308.920414) (xy 39.574557 -308.897071) (xy 39.623456 -308.881183)
			(xy 39.674238 -308.87314) (xy 39.725654 -308.87314) (xy 39.776436 -308.881183) (xy 39.825335 -308.897071)
			(xy 39.871147 -308.920414) (xy 39.912743 -308.950635) (xy 39.949099 -308.986991) (xy 39.97932 -309.028587)
			(xy 40.002663 -309.074399) (xy 40.018551 -309.123298) (xy 40.026594 -309.17408) (xy 40.027098 -309.199788)
			(xy 40.026594 -309.225496) (xy 41.273218 -309.225496) (xy 41.273218 -309.17408) (xy 41.281261 -309.123298)
			(xy 41.297149 -309.074399) (xy 41.320492 -309.028587) (xy 41.350713 -308.986991) (xy 41.387069 -308.950635)
			(xy 41.428665 -308.920414) (xy 41.474477 -308.897071) (xy 41.523376 -308.881183) (xy 41.574158 -308.87314)
			(xy 41.625574 -308.87314) (xy 41.676356 -308.881183) (xy 41.725255 -308.897071) (xy 41.771067 -308.920414)
			(xy 41.812663 -308.950635) (xy 41.849019 -308.986991) (xy 41.87924 -309.028587) (xy 41.902583 -309.074399)
			(xy 41.918471 -309.123298) (xy 41.926514 -309.17408) (xy 41.927018 -309.199788) (xy 41.926514 -309.225496)
			(xy 42.223178 -309.225496) (xy 42.223178 -309.17408) (xy 42.231221 -309.123298) (xy 42.247109 -309.074399)
			(xy 42.270452 -309.028587) (xy 42.300673 -308.986991) (xy 42.337029 -308.950635) (xy 42.378625 -308.920414)
			(xy 42.424437 -308.897071) (xy 42.473336 -308.881183) (xy 42.524118 -308.87314) (xy 42.575534 -308.87314)
			(xy 42.626316 -308.881183) (xy 42.675215 -308.897071) (xy 42.721027 -308.920414) (xy 42.762623 -308.950635)
			(xy 42.798979 -308.986991) (xy 42.8292 -309.028587) (xy 42.852543 -309.074399) (xy 42.868431 -309.123298)
			(xy 42.876474 -309.17408) (xy 42.876978 -309.199788) (xy 46.994076 -309.199788) (xy 46.998036 -309.150734)
			(xy 47.009813 -309.10295) (xy 47.029104 -309.057674) (xy 47.055407 -309.016078) (xy 47.088042 -308.979241)
			(xy 47.126163 -308.948116) (xy 47.168784 -308.923509) (xy 47.2148 -308.906057) (xy 47.263019 -308.896213)
			(xy 47.312194 -308.894232) (xy 47.361049 -308.900164) (xy 47.40832 -308.913856) (xy 47.452782 -308.934954)
			(xy 47.493285 -308.96291) (xy 47.528778 -308.997002) (xy 47.558343 -309.036346) (xy 47.581214 -309.079923)
			(xy 47.596798 -309.126604) (xy 47.604693 -309.175181) (xy 47.605188 -309.199788) (xy 47.604693 -309.224395)
			(xy 47.596798 -309.272972) (xy 47.581214 -309.319653) (xy 47.558343 -309.36323) (xy 47.528778 -309.402574)
			(xy 47.493285 -309.436666) (xy 47.452782 -309.464622) (xy 47.40832 -309.48572) (xy 47.361049 -309.499412)
			(xy 47.312194 -309.505344) (xy 47.263019 -309.503363) (xy 47.2148 -309.493519) (xy 47.168784 -309.476067)
			(xy 47.126163 -309.45146) (xy 47.088042 -309.420335) (xy 47.055407 -309.383498) (xy 47.029104 -309.341902)
			(xy 47.009813 -309.296626) (xy 46.998036 -309.248842) (xy 46.994076 -309.199788) (xy 42.876978 -309.199788)
			(xy 42.876474 -309.225496) (xy 42.868431 -309.276278) (xy 42.852543 -309.325177) (xy 42.8292 -309.370989)
			(xy 42.798979 -309.412585) (xy 42.762623 -309.448941) (xy 42.721027 -309.479162) (xy 42.675215 -309.502505)
			(xy 42.626316 -309.518393) (xy 42.575534 -309.526436) (xy 42.524118 -309.526436) (xy 42.473336 -309.518393)
			(xy 42.424437 -309.502505) (xy 42.378625 -309.479162) (xy 42.337029 -309.448941) (xy 42.300673 -309.412585)
			(xy 42.270452 -309.370989) (xy 42.247109 -309.325177) (xy 42.231221 -309.276278) (xy 42.223178 -309.225496)
			(xy 41.926514 -309.225496) (xy 41.918471 -309.276278) (xy 41.902583 -309.325177) (xy 41.87924 -309.370989)
			(xy 41.849019 -309.412585) (xy 41.812663 -309.448941) (xy 41.771067 -309.479162) (xy 41.725255 -309.502505)
			(xy 41.676356 -309.518393) (xy 41.625574 -309.526436) (xy 41.574158 -309.526436) (xy 41.523376 -309.518393)
			(xy 41.474477 -309.502505) (xy 41.428665 -309.479162) (xy 41.387069 -309.448941) (xy 41.350713 -309.412585)
			(xy 41.320492 -309.370989) (xy 41.297149 -309.325177) (xy 41.281261 -309.276278) (xy 41.273218 -309.225496)
			(xy 40.026594 -309.225496) (xy 40.018551 -309.276278) (xy 40.002663 -309.325177) (xy 39.97932 -309.370989)
			(xy 39.949099 -309.412585) (xy 39.912743 -309.448941) (xy 39.871147 -309.479162) (xy 39.825335 -309.502505)
			(xy 39.776436 -309.518393) (xy 39.725654 -309.526436) (xy 39.674238 -309.526436) (xy 39.623456 -309.518393)
			(xy 39.574557 -309.502505) (xy 39.528745 -309.479162) (xy 39.487149 -309.448941) (xy 39.450793 -309.412585)
			(xy 39.420572 -309.370989) (xy 39.397229 -309.325177) (xy 39.381341 -309.276278) (xy 39.373298 -309.225496)
			(xy 39.076634 -309.225496) (xy 39.068591 -309.276278) (xy 39.052703 -309.325177) (xy 39.02936 -309.370989)
			(xy 38.999139 -309.412585) (xy 38.962783 -309.448941) (xy 38.921187 -309.479162) (xy 38.875375 -309.502505)
			(xy 38.826476 -309.518393) (xy 38.775694 -309.526436) (xy 38.724278 -309.526436) (xy 38.673496 -309.518393)
			(xy 38.624597 -309.502505) (xy 38.578785 -309.479162) (xy 38.537189 -309.448941) (xy 38.500833 -309.412585)
			(xy 38.470612 -309.370989) (xy 38.447269 -309.325177) (xy 38.431381 -309.276278) (xy 38.423338 -309.225496)
			(xy 27.713471 -309.225496) (xy 27.715101 -309.22796) (xy 27.738773 -309.278457) (xy 27.754841 -309.331864)
			(xy 27.762961 -309.38704) (xy 27.76347 -309.414926) (xy 27.762961 -309.442812) (xy 27.754841 -309.497988)
			(xy 27.738773 -309.551395) (xy 27.715101 -309.601892) (xy 27.684328 -309.648405) (xy 27.647111 -309.689942)
			(xy 27.604243 -309.725617) (xy 27.556637 -309.754671) (xy 27.505308 -309.776483) (xy 27.451351 -309.790589)
			(xy 27.395914 -309.796689) (xy 27.34018 -309.794652) (xy 27.285337 -309.784522) (xy 27.232553 -309.766515)
			(xy 27.182953 -309.741014) (xy 27.137595 -309.708563) (xy 27.097446 -309.669854) (xy 27.06336 -309.625711)
			(xy 27.036064 -309.577076) (xy 27.016141 -309.524985) (xy 27.004015 -309.470548) (xy 26.999944 -309.414926)
			(xy 17.887188 -309.414926) (xy 17.887188 -310.237378) (xy 34.10077 -310.237378) (xy 34.101256 -310.210127)
			(xy 34.109012 -310.156179) (xy 34.124367 -310.103884) (xy 34.147009 -310.054307) (xy 34.176475 -310.008457)
			(xy 34.212166 -309.967266) (xy 34.253357 -309.931575) (xy 34.299207 -309.902109) (xy 34.348784 -309.879467)
			(xy 34.401079 -309.864112) (xy 34.455027 -309.856356) (xy 34.509529 -309.856356) (xy 34.563477 -309.864112)
			(xy 34.615772 -309.879467) (xy 34.665349 -309.902109) (xy 34.711199 -309.931575) (xy 34.75239 -309.967266)
			(xy 34.788081 -310.008457) (xy 34.817547 -310.054307) (xy 34.840189 -310.103884) (xy 34.855544 -310.156179)
			(xy 34.858315 -310.175456) (xy 36.523164 -310.175456) (xy 36.523164 -310.12404) (xy 36.531207 -310.073258)
			(xy 36.547095 -310.024359) (xy 36.570438 -309.978547) (xy 36.600659 -309.936951) (xy 36.637015 -309.900595)
			(xy 36.678611 -309.870374) (xy 36.724423 -309.847031) (xy 36.773322 -309.831143) (xy 36.824104 -309.8231)
			(xy 36.87552 -309.8231) (xy 36.926302 -309.831143) (xy 36.975201 -309.847031) (xy 37.021013 -309.870374)
			(xy 37.062609 -309.900595) (xy 37.098965 -309.936951) (xy 37.129186 -309.978547) (xy 37.152529 -310.024359)
			(xy 37.168417 -310.073258) (xy 37.17646 -310.12404) (xy 37.176964 -310.149748) (xy 37.17646 -310.175456)
			(xy 37.473124 -310.175456) (xy 37.473124 -310.12404) (xy 37.481167 -310.073258) (xy 37.497055 -310.024359)
			(xy 37.520398 -309.978547) (xy 37.550619 -309.936951) (xy 37.586975 -309.900595) (xy 37.628571 -309.870374)
			(xy 37.674383 -309.847031) (xy 37.723282 -309.831143) (xy 37.774064 -309.8231) (xy 37.82548 -309.8231)
			(xy 37.876262 -309.831143) (xy 37.925161 -309.847031) (xy 37.970973 -309.870374) (xy 38.012569 -309.900595)
			(xy 38.048925 -309.936951) (xy 38.079146 -309.978547) (xy 38.102489 -310.024359) (xy 38.118377 -310.073258)
			(xy 38.12642 -310.12404) (xy 38.126924 -310.149748) (xy 38.12642 -310.175456) (xy 38.118377 -310.226238)
			(xy 38.102489 -310.275137) (xy 38.079146 -310.320949) (xy 38.048925 -310.362545) (xy 38.012569 -310.398901)
			(xy 37.970973 -310.429122) (xy 37.925161 -310.452465) (xy 37.876262 -310.468353) (xy 37.82548 -310.476396)
			(xy 37.774064 -310.476396) (xy 37.723282 -310.468353) (xy 37.674383 -310.452465) (xy 37.628571 -310.429122)
			(xy 37.586975 -310.398901) (xy 37.550619 -310.362545) (xy 37.520398 -310.320949) (xy 37.497055 -310.275137)
			(xy 37.481167 -310.226238) (xy 37.473124 -310.175456) (xy 37.17646 -310.175456) (xy 37.168417 -310.226238)
			(xy 37.152529 -310.275137) (xy 37.129186 -310.320949) (xy 37.098965 -310.362545) (xy 37.062609 -310.398901)
			(xy 37.021013 -310.429122) (xy 36.975201 -310.452465) (xy 36.926302 -310.468353) (xy 36.87552 -310.476396)
			(xy 36.824104 -310.476396) (xy 36.773322 -310.468353) (xy 36.724423 -310.452465) (xy 36.678611 -310.429122)
			(xy 36.637015 -310.398901) (xy 36.600659 -310.362545) (xy 36.570438 -310.320949) (xy 36.547095 -310.275137)
			(xy 36.531207 -310.226238) (xy 36.523164 -310.175456) (xy 34.858315 -310.175456) (xy 34.8633 -310.210127)
			(xy 34.863786 -310.237378) (xy 34.863273 -310.266153) (xy 34.854619 -310.323048) (xy 34.837521 -310.377998)
			(xy 34.812365 -310.429758) (xy 34.779721 -310.477154) (xy 34.760408 -310.49849) (xy 34.751082 -310.509071)
			(xy 34.73817 -310.534137) (xy 34.732608 -310.56178) (xy 34.734821 -310.589889) (xy 34.74464 -310.61632)
			(xy 34.761315 -310.639057) (xy 34.783574 -310.656364) (xy 34.796476 -310.662066) (xy 34.822543 -310.67316)
			(xy 34.871364 -310.701893) (xy 34.915401 -310.737528) (xy 34.953685 -310.779283) (xy 34.985374 -310.82624)
			(xy 35.009771 -310.877366) (xy 35.026341 -310.931537) (xy 35.034719 -310.987564) (xy 35.035236 -311.015888)
			(xy 35.03475 -311.043139) (xy 35.026994 -311.097087) (xy 35.018601 -311.12567) (xy 39.373298 -311.12567)
			(xy 39.373298 -311.074254) (xy 39.381341 -311.023472) (xy 39.397229 -310.974573) (xy 39.420572 -310.928761)
			(xy 39.450793 -310.887165) (xy 39.487149 -310.850809) (xy 39.528745 -310.820588) (xy 39.574557 -310.797245)
			(xy 39.623456 -310.781357) (xy 39.674238 -310.773314) (xy 39.725654 -310.773314) (xy 39.776436 -310.781357)
			(xy 39.825335 -310.797245) (xy 39.871147 -310.820588) (xy 39.912743 -310.850809) (xy 39.949099 -310.887165)
			(xy 39.97932 -310.928761) (xy 40.002663 -310.974573) (xy 40.018551 -311.023472) (xy 40.026594 -311.074254)
			(xy 40.027098 -311.099962) (xy 40.026594 -311.12567) (xy 41.273218 -311.12567) (xy 41.273218 -311.074254)
			(xy 41.281261 -311.023472) (xy 41.297149 -310.974573) (xy 41.320492 -310.928761) (xy 41.350713 -310.887165)
			(xy 41.387069 -310.850809) (xy 41.428665 -310.820588) (xy 41.474477 -310.797245) (xy 41.523376 -310.781357)
			(xy 41.574158 -310.773314) (xy 41.625574 -310.773314) (xy 41.676356 -310.781357) (xy 41.725255 -310.797245)
			(xy 41.771067 -310.820588) (xy 41.812663 -310.850809) (xy 41.849019 -310.887165) (xy 41.87924 -310.928761)
			(xy 41.902583 -310.974573) (xy 41.918471 -311.023472) (xy 41.926514 -311.074254) (xy 41.927018 -311.099962)
			(xy 43.193982 -311.099962) (xy 43.197942 -311.050908) (xy 43.209719 -311.003124) (xy 43.22901 -310.957848)
			(xy 43.255313 -310.916252) (xy 43.287948 -310.879415) (xy 43.326069 -310.84829) (xy 43.36869 -310.823683)
			(xy 43.414706 -310.806231) (xy 43.462925 -310.796387) (xy 43.5121 -310.794406) (xy 43.560955 -310.800338)
			(xy 43.608226 -310.81403) (xy 43.652688 -310.835128) (xy 43.693191 -310.863084) (xy 43.728684 -310.897176)
			(xy 43.758249 -310.93652) (xy 43.78112 -310.980097) (xy 43.796704 -311.026778) (xy 43.804599 -311.075355)
			(xy 43.805094 -311.099962) (xy 45.094156 -311.099962) (xy 45.098116 -311.050908) (xy 45.109893 -311.003124)
			(xy 45.129184 -310.957848) (xy 45.155487 -310.916252) (xy 45.188122 -310.879415) (xy 45.226243 -310.84829)
			(xy 45.268864 -310.823683) (xy 45.31488 -310.806231) (xy 45.363099 -310.796387) (xy 45.412274 -310.794406)
			(xy 45.461129 -310.800338) (xy 45.5084 -310.81403) (xy 45.552862 -310.835128) (xy 45.593365 -310.863084)
			(xy 45.628858 -310.897176) (xy 45.658423 -310.93652) (xy 45.681294 -310.980097) (xy 45.696878 -311.026778)
			(xy 45.704773 -311.075355) (xy 45.705268 -311.099962) (xy 46.994076 -311.099962) (xy 46.998036 -311.050908)
			(xy 47.009813 -311.003124) (xy 47.029104 -310.957848) (xy 47.055407 -310.916252) (xy 47.088042 -310.879415)
			(xy 47.126163 -310.84829) (xy 47.168784 -310.823683) (xy 47.2148 -310.806231) (xy 47.263019 -310.796387)
			(xy 47.312194 -310.794406) (xy 47.361049 -310.800338) (xy 47.40832 -310.81403) (xy 47.452782 -310.835128)
			(xy 47.493285 -310.863084) (xy 47.528778 -310.897176) (xy 47.558343 -310.93652) (xy 47.581214 -310.980097)
			(xy 47.596798 -311.026778) (xy 47.604693 -311.075355) (xy 47.605188 -311.099962) (xy 47.604693 -311.124569)
			(xy 47.596798 -311.173146) (xy 47.581214 -311.219827) (xy 47.558343 -311.263404) (xy 47.528778 -311.302748)
			(xy 47.493285 -311.33684) (xy 47.452782 -311.364796) (xy 47.40832 -311.385894) (xy 47.361049 -311.399586)
			(xy 47.312194 -311.405518) (xy 47.263019 -311.403537) (xy 47.2148 -311.393693) (xy 47.168784 -311.376241)
			(xy 47.126163 -311.351634) (xy 47.088042 -311.320509) (xy 47.055407 -311.283672) (xy 47.029104 -311.242076)
			(xy 47.009813 -311.1968) (xy 46.998036 -311.149016) (xy 46.994076 -311.099962) (xy 45.705268 -311.099962)
			(xy 45.704773 -311.124569) (xy 45.696878 -311.173146) (xy 45.681294 -311.219827) (xy 45.658423 -311.263404)
			(xy 45.628858 -311.302748) (xy 45.593365 -311.33684) (xy 45.552862 -311.364796) (xy 45.5084 -311.385894)
			(xy 45.461129 -311.399586) (xy 45.412274 -311.405518) (xy 45.363099 -311.403537) (xy 45.31488 -311.393693)
			(xy 45.268864 -311.376241) (xy 45.226243 -311.351634) (xy 45.188122 -311.320509) (xy 45.155487 -311.283672)
			(xy 45.129184 -311.242076) (xy 45.109893 -311.1968) (xy 45.098116 -311.149016) (xy 45.094156 -311.099962)
			(xy 43.805094 -311.099962) (xy 43.804599 -311.124569) (xy 43.796704 -311.173146) (xy 43.78112 -311.219827)
			(xy 43.758249 -311.263404) (xy 43.728684 -311.302748) (xy 43.693191 -311.33684) (xy 43.652688 -311.364796)
			(xy 43.608226 -311.385894) (xy 43.560955 -311.399586) (xy 43.5121 -311.405518) (xy 43.462925 -311.403537)
			(xy 43.414706 -311.393693) (xy 43.36869 -311.376241) (xy 43.326069 -311.351634) (xy 43.287948 -311.320509)
			(xy 43.255313 -311.283672) (xy 43.22901 -311.242076) (xy 43.209719 -311.1968) (xy 43.197942 -311.149016)
			(xy 43.193982 -311.099962) (xy 41.927018 -311.099962) (xy 41.926514 -311.12567) (xy 41.918471 -311.176452)
			(xy 41.902583 -311.225351) (xy 41.87924 -311.271163) (xy 41.849019 -311.312759) (xy 41.812663 -311.349115)
			(xy 41.771067 -311.379336) (xy 41.725255 -311.402679) (xy 41.676356 -311.418567) (xy 41.625574 -311.42661)
			(xy 41.574158 -311.42661) (xy 41.523376 -311.418567) (xy 41.474477 -311.402679) (xy 41.428665 -311.379336)
			(xy 41.387069 -311.349115) (xy 41.350713 -311.312759) (xy 41.320492 -311.271163) (xy 41.297149 -311.225351)
			(xy 41.281261 -311.176452) (xy 41.273218 -311.12567) (xy 40.026594 -311.12567) (xy 40.018551 -311.176452)
			(xy 40.002663 -311.225351) (xy 39.97932 -311.271163) (xy 39.949099 -311.312759) (xy 39.912743 -311.349115)
			(xy 39.871147 -311.379336) (xy 39.825335 -311.402679) (xy 39.776436 -311.418567) (xy 39.725654 -311.42661)
			(xy 39.674238 -311.42661) (xy 39.623456 -311.418567) (xy 39.574557 -311.402679) (xy 39.528745 -311.379336)
			(xy 39.487149 -311.349115) (xy 39.450793 -311.312759) (xy 39.420572 -311.271163) (xy 39.397229 -311.225351)
			(xy 39.381341 -311.176452) (xy 39.373298 -311.12567) (xy 35.018601 -311.12567) (xy 35.011639 -311.149382)
			(xy 34.988997 -311.198959) (xy 34.959531 -311.244809) (xy 34.92384 -311.286) (xy 34.882649 -311.321691)
			(xy 34.836799 -311.351157) (xy 34.787222 -311.373799) (xy 34.734927 -311.389154) (xy 34.680979 -311.39691)
			(xy 34.626477 -311.39691) (xy 34.572529 -311.389154) (xy 34.520234 -311.373799) (xy 34.470657 -311.351157)
			(xy 34.424807 -311.321691) (xy 34.383616 -311.286) (xy 34.347925 -311.244809) (xy 34.318459 -311.198959)
			(xy 34.295817 -311.149382) (xy 34.280462 -311.097087) (xy 34.272706 -311.043139) (xy 34.27222 -311.015888)
			(xy 34.272711 -310.987113) (xy 34.28137 -310.930217) (xy 34.298473 -310.875266) (xy 34.323634 -310.823506)
			(xy 34.356282 -310.776112) (xy 34.375598 -310.754776) (xy 34.384845 -310.74413) (xy 34.397761 -310.719082)
			(xy 34.40333 -310.691456) (xy 34.401129 -310.66336) (xy 34.391325 -310.636939) (xy 34.374666 -310.614208)
			(xy 34.352424 -310.596902) (xy 34.33953 -310.5912) (xy 34.31343 -310.580181) (xy 34.26461 -310.551434)
			(xy 34.220577 -310.515786) (xy 34.182297 -310.474019) (xy 34.150614 -310.427052) (xy 34.126222 -310.375917)
			(xy 34.109657 -310.321738) (xy 34.101285 -310.265705) (xy 34.10077 -310.237378) (xy 17.887188 -310.237378)
			(xy 17.887188 -310.497474) (xy 17.887741 -310.508171) (xy 17.896386 -310.527741) (xy 17.903952 -310.53532)
			(xy 17.960086 -310.585866) (xy 17.968309 -310.592643) (xy 17.988564 -310.599205) (xy 17.999202 -310.598566)
			(xy 17.999456 -310.598566) (xy 18.009207 -310.597615) (xy 18.028775 -310.596597) (xy 18.038572 -310.596534)
			(xy 18.03908 -310.596534) (xy 18.066331 -310.59702) (xy 18.120279 -310.604776) (xy 18.172573 -310.620131)
			(xy 18.22215 -310.642772) (xy 18.268 -310.672238) (xy 18.30919 -310.70793) (xy 18.344882 -310.74912)
			(xy 18.374348 -310.79497) (xy 18.396989 -310.844547) (xy 18.412344 -310.896841) (xy 18.4201 -310.950789)
			(xy 18.4201 -311.005291) (xy 18.412344 -311.059239) (xy 18.396989 -311.111533) (xy 18.374348 -311.16111)
			(xy 18.344882 -311.20696) (xy 18.30919 -311.24815) (xy 18.268 -311.283842) (xy 18.22215 -311.313308)
			(xy 18.172573 -311.335949) (xy 18.120279 -311.351304) (xy 18.066331 -311.35906) (xy 18.03908 -311.35955)
			(xy 18.038572 -311.35955) (xy 18.028775 -311.35948) (xy 18.009208 -311.358462) (xy 17.999456 -311.357518)
			(xy 17.999202 -311.357518) (xy 17.988581 -311.357004) (xy 17.968379 -311.363563) (xy 17.960086 -311.370218)
			(xy 17.903952 -311.420764) (xy 17.896284 -311.428278) (xy 17.887585 -311.447883) (xy 17.887188 -311.45861)
			(xy 17.887188 -311.604914) (xy 17.8876 -311.615642) (xy 17.896275 -311.635258) (xy 17.903952 -311.64276)
			(xy 17.967706 -311.700418) (xy 17.988026 -311.707022) (xy 17.998694 -311.706006) (xy 18.035524 -311.704228)
			(xy 18.062775 -311.704714) (xy 18.116723 -311.712471) (xy 18.169018 -311.727827) (xy 18.218595 -311.750468)
			(xy 18.264446 -311.779935) (xy 18.305636 -311.815627) (xy 18.312111 -311.8231) (xy 32.447482 -311.8231)
			(xy 32.451553 -311.767478) (xy 32.463679 -311.713041) (xy 32.483602 -311.66095) (xy 32.510898 -311.612315)
			(xy 32.544984 -311.568172) (xy 32.585133 -311.529463) (xy 32.630491 -311.497012) (xy 32.680091 -311.471511)
			(xy 32.732875 -311.453504) (xy 32.787718 -311.443374) (xy 32.843452 -311.441337) (xy 32.898889 -311.447437)
			(xy 32.952846 -311.461543) (xy 33.004175 -311.483355) (xy 33.051781 -311.512409) (xy 33.094649 -311.548084)
			(xy 33.131866 -311.589621) (xy 33.162639 -311.636134) (xy 33.186311 -311.686631) (xy 33.202379 -311.740038)
			(xy 33.210499 -311.795214) (xy 33.211008 -311.8231) (xy 33.210499 -311.850986) (xy 33.202379 -311.906162)
			(xy 33.186311 -311.959569) (xy 33.162639 -312.010066) (xy 33.131866 -312.056579) (xy 33.094649 -312.098116)
			(xy 33.051781 -312.133791) (xy 33.004175 -312.162845) (xy 32.952846 -312.184657) (xy 32.898889 -312.198763)
			(xy 32.843452 -312.204863) (xy 32.787718 -312.202826) (xy 32.732875 -312.192696) (xy 32.680091 -312.174689)
			(xy 32.630491 -312.149188) (xy 32.585133 -312.116737) (xy 32.544984 -312.078028) (xy 32.510898 -312.033885)
			(xy 32.483602 -311.98525) (xy 32.463679 -311.933159) (xy 32.451553 -311.878722) (xy 32.447482 -311.8231)
			(xy 18.312111 -311.8231) (xy 18.341327 -311.856818) (xy 18.370794 -311.902668) (xy 18.393435 -311.952246)
			(xy 18.40879 -312.004541) (xy 18.416546 -312.058489) (xy 18.416546 -312.112991) (xy 18.40879 -312.166939)
			(xy 18.393435 -312.219234) (xy 18.370794 -312.268812) (xy 18.341327 -312.314662) (xy 18.305636 -312.355853)
			(xy 18.264446 -312.391545) (xy 18.218595 -312.421012) (xy 18.169018 -312.443653) (xy 18.116723 -312.459009)
			(xy 18.062775 -312.466766) (xy 18.035524 -312.467244) (xy 17.998694 -312.465466) (xy 17.988026 -312.46445)
			(xy 17.967706 -312.471054) (xy 17.90985 -312.523378) (xy 31.731964 -312.523378) (xy 31.736035 -312.467756)
			(xy 31.748161 -312.413319) (xy 31.768084 -312.361228) (xy 31.79538 -312.312593) (xy 31.829466 -312.26845)
			(xy 31.869615 -312.229741) (xy 31.914973 -312.19729) (xy 31.964573 -312.171789) (xy 32.017357 -312.153782)
			(xy 32.0722 -312.143652) (xy 32.127934 -312.141615) (xy 32.183371 -312.147715) (xy 32.237328 -312.161821)
			(xy 32.288657 -312.183633) (xy 32.336263 -312.212687) (xy 32.379131 -312.248362) (xy 32.396823 -312.268108)
			(xy 34.021774 -312.268108) (xy 34.025845 -312.212486) (xy 34.037971 -312.158049) (xy 34.057894 -312.105958)
			(xy 34.08519 -312.057323) (xy 34.119276 -312.01318) (xy 34.159425 -311.974471) (xy 34.204783 -311.94202)
			(xy 34.254383 -311.916519) (xy 34.307167 -311.898512) (xy 34.36201 -311.888382) (xy 34.417744 -311.886345)
			(xy 34.473181 -311.892445) (xy 34.527138 -311.906551) (xy 34.578467 -311.928363) (xy 34.626073 -311.957417)
			(xy 34.668941 -311.993092) (xy 34.706158 -312.034629) (xy 34.733284 -312.07563) (xy 36.523164 -312.07563)
			(xy 36.523164 -312.024214) (xy 36.531207 -311.973432) (xy 36.547095 -311.924533) (xy 36.570438 -311.878721)
			(xy 36.600659 -311.837125) (xy 36.637015 -311.800769) (xy 36.678611 -311.770548) (xy 36.724423 -311.747205)
			(xy 36.773322 -311.731317) (xy 36.824104 -311.723274) (xy 36.87552 -311.723274) (xy 36.926302 -311.731317)
			(xy 36.975201 -311.747205) (xy 37.021013 -311.770548) (xy 37.062609 -311.800769) (xy 37.098965 -311.837125)
			(xy 37.129186 -311.878721) (xy 37.152529 -311.924533) (xy 37.168417 -311.973432) (xy 37.17646 -312.024214)
			(xy 37.176964 -312.049922) (xy 37.17646 -312.07563) (xy 37.473124 -312.07563) (xy 37.473124 -312.024214)
			(xy 37.481167 -311.973432) (xy 37.497055 -311.924533) (xy 37.520398 -311.878721) (xy 37.550619 -311.837125)
			(xy 37.586975 -311.800769) (xy 37.628571 -311.770548) (xy 37.674383 -311.747205) (xy 37.723282 -311.731317)
			(xy 37.774064 -311.723274) (xy 37.82548 -311.723274) (xy 37.876262 -311.731317) (xy 37.925161 -311.747205)
			(xy 37.970973 -311.770548) (xy 38.012569 -311.800769) (xy 38.048925 -311.837125) (xy 38.079146 -311.878721)
			(xy 38.102489 -311.924533) (xy 38.118377 -311.973432) (xy 38.12642 -312.024214) (xy 38.126924 -312.049922)
			(xy 38.12642 -312.07563) (xy 39.373298 -312.07563) (xy 39.373298 -312.024214) (xy 39.381341 -311.973432)
			(xy 39.397229 -311.924533) (xy 39.420572 -311.878721) (xy 39.450793 -311.837125) (xy 39.487149 -311.800769)
			(xy 39.528745 -311.770548) (xy 39.574557 -311.747205) (xy 39.623456 -311.731317) (xy 39.674238 -311.723274)
			(xy 39.725654 -311.723274) (xy 39.776436 -311.731317) (xy 39.825335 -311.747205) (xy 39.871147 -311.770548)
			(xy 39.912743 -311.800769) (xy 39.949099 -311.837125) (xy 39.97932 -311.878721) (xy 40.002663 -311.924533)
			(xy 40.018551 -311.973432) (xy 40.026594 -312.024214) (xy 40.027098 -312.049922) (xy 40.026594 -312.07563)
			(xy 41.273218 -312.07563) (xy 41.273218 -312.024214) (xy 41.281261 -311.973432) (xy 41.297149 -311.924533)
			(xy 41.320492 -311.878721) (xy 41.350713 -311.837125) (xy 41.387069 -311.800769) (xy 41.428665 -311.770548)
			(xy 41.474477 -311.747205) (xy 41.523376 -311.731317) (xy 41.574158 -311.723274) (xy 41.625574 -311.723274)
			(xy 41.676356 -311.731317) (xy 41.725255 -311.747205) (xy 41.771067 -311.770548) (xy 41.812663 -311.800769)
			(xy 41.849019 -311.837125) (xy 41.87924 -311.878721) (xy 41.902583 -311.924533) (xy 41.918471 -311.973432)
			(xy 41.926514 -312.024214) (xy 41.927018 -312.049922) (xy 43.193982 -312.049922) (xy 43.197942 -312.000868)
			(xy 43.209719 -311.953084) (xy 43.22901 -311.907808) (xy 43.255313 -311.866212) (xy 43.287948 -311.829375)
			(xy 43.326069 -311.79825) (xy 43.36869 -311.773643) (xy 43.414706 -311.756191) (xy 43.462925 -311.746347)
			(xy 43.5121 -311.744366) (xy 43.560955 -311.750298) (xy 43.608226 -311.76399) (xy 43.652688 -311.785088)
			(xy 43.693191 -311.813044) (xy 43.728684 -311.847136) (xy 43.758249 -311.88648) (xy 43.78112 -311.930057)
			(xy 43.796704 -311.976738) (xy 43.804599 -312.025315) (xy 43.805094 -312.049922) (xy 45.094156 -312.049922)
			(xy 45.098116 -312.000868) (xy 45.109893 -311.953084) (xy 45.129184 -311.907808) (xy 45.155487 -311.866212)
			(xy 45.188122 -311.829375) (xy 45.226243 -311.79825) (xy 45.268864 -311.773643) (xy 45.31488 -311.756191)
			(xy 45.363099 -311.746347) (xy 45.412274 -311.744366) (xy 45.461129 -311.750298) (xy 45.5084 -311.76399)
			(xy 45.552862 -311.785088) (xy 45.593365 -311.813044) (xy 45.628858 -311.847136) (xy 45.658423 -311.88648)
			(xy 45.681294 -311.930057) (xy 45.696878 -311.976738) (xy 45.704773 -312.025315) (xy 45.705268 -312.049922)
			(xy 46.994076 -312.049922) (xy 46.998036 -312.000868) (xy 47.009813 -311.953084) (xy 47.029104 -311.907808)
			(xy 47.055407 -311.866212) (xy 47.088042 -311.829375) (xy 47.126163 -311.79825) (xy 47.168784 -311.773643)
			(xy 47.2148 -311.756191) (xy 47.263019 -311.746347) (xy 47.312194 -311.744366) (xy 47.361049 -311.750298)
			(xy 47.40832 -311.76399) (xy 47.452782 -311.785088) (xy 47.493285 -311.813044) (xy 47.528778 -311.847136)
			(xy 47.558343 -311.88648) (xy 47.581214 -311.930057) (xy 47.596798 -311.976738) (xy 47.604693 -312.025315)
			(xy 47.605188 -312.049922) (xy 47.604693 -312.074529) (xy 47.596798 -312.123106) (xy 47.581214 -312.169787)
			(xy 47.558343 -312.213364) (xy 47.528778 -312.252708) (xy 47.493285 -312.2868) (xy 47.452782 -312.314756)
			(xy 47.40832 -312.335854) (xy 47.361049 -312.349546) (xy 47.312194 -312.355478) (xy 47.263019 -312.353497)
			(xy 47.2148 -312.343653) (xy 47.168784 -312.326201) (xy 47.126163 -312.301594) (xy 47.088042 -312.270469)
			(xy 47.055407 -312.233632) (xy 47.029104 -312.192036) (xy 47.009813 -312.14676) (xy 46.998036 -312.098976)
			(xy 46.994076 -312.049922) (xy 45.705268 -312.049922) (xy 45.704773 -312.074529) (xy 45.696878 -312.123106)
			(xy 45.681294 -312.169787) (xy 45.658423 -312.213364) (xy 45.628858 -312.252708) (xy 45.593365 -312.2868)
			(xy 45.552862 -312.314756) (xy 45.5084 -312.335854) (xy 45.461129 -312.349546) (xy 45.412274 -312.355478)
			(xy 45.363099 -312.353497) (xy 45.31488 -312.343653) (xy 45.268864 -312.326201) (xy 45.226243 -312.301594)
			(xy 45.188122 -312.270469) (xy 45.155487 -312.233632) (xy 45.129184 -312.192036) (xy 45.109893 -312.14676)
			(xy 45.098116 -312.098976) (xy 45.094156 -312.049922) (xy 43.805094 -312.049922) (xy 43.804599 -312.074529)
			(xy 43.796704 -312.123106) (xy 43.78112 -312.169787) (xy 43.758249 -312.213364) (xy 43.728684 -312.252708)
			(xy 43.693191 -312.2868) (xy 43.652688 -312.314756) (xy 43.608226 -312.335854) (xy 43.560955 -312.349546)
			(xy 43.5121 -312.355478) (xy 43.462925 -312.353497) (xy 43.414706 -312.343653) (xy 43.36869 -312.326201)
			(xy 43.326069 -312.301594) (xy 43.287948 -312.270469) (xy 43.255313 -312.233632) (xy 43.22901 -312.192036)
			(xy 43.209719 -312.14676) (xy 43.197942 -312.098976) (xy 43.193982 -312.049922) (xy 41.927018 -312.049922)
			(xy 41.926514 -312.07563) (xy 41.918471 -312.126412) (xy 41.902583 -312.175311) (xy 41.87924 -312.221123)
			(xy 41.849019 -312.262719) (xy 41.812663 -312.299075) (xy 41.771067 -312.329296) (xy 41.725255 -312.352639)
			(xy 41.676356 -312.368527) (xy 41.625574 -312.37657) (xy 41.574158 -312.37657) (xy 41.523376 -312.368527)
			(xy 41.474477 -312.352639) (xy 41.428665 -312.329296) (xy 41.387069 -312.299075) (xy 41.350713 -312.262719)
			(xy 41.320492 -312.221123) (xy 41.297149 -312.175311) (xy 41.281261 -312.126412) (xy 41.273218 -312.07563)
			(xy 40.026594 -312.07563) (xy 40.018551 -312.126412) (xy 40.002663 -312.175311) (xy 39.97932 -312.221123)
			(xy 39.949099 -312.262719) (xy 39.912743 -312.299075) (xy 39.871147 -312.329296) (xy 39.825335 -312.352639)
			(xy 39.776436 -312.368527) (xy 39.725654 -312.37657) (xy 39.674238 -312.37657) (xy 39.623456 -312.368527)
			(xy 39.574557 -312.352639) (xy 39.528745 -312.329296) (xy 39.487149 -312.299075) (xy 39.450793 -312.262719)
			(xy 39.420572 -312.221123) (xy 39.397229 -312.175311) (xy 39.381341 -312.126412) (xy 39.373298 -312.07563)
			(xy 38.12642 -312.07563) (xy 38.118377 -312.126412) (xy 38.102489 -312.175311) (xy 38.079146 -312.221123)
			(xy 38.048925 -312.262719) (xy 38.012569 -312.299075) (xy 37.970973 -312.329296) (xy 37.925161 -312.352639)
			(xy 37.876262 -312.368527) (xy 37.82548 -312.37657) (xy 37.774064 -312.37657) (xy 37.723282 -312.368527)
			(xy 37.674383 -312.352639) (xy 37.628571 -312.329296) (xy 37.586975 -312.299075) (xy 37.550619 -312.262719)
			(xy 37.520398 -312.221123) (xy 37.497055 -312.175311) (xy 37.481167 -312.126412) (xy 37.473124 -312.07563)
			(xy 37.17646 -312.07563) (xy 37.168417 -312.126412) (xy 37.152529 -312.175311) (xy 37.129186 -312.221123)
			(xy 37.098965 -312.262719) (xy 37.062609 -312.299075) (xy 37.021013 -312.329296) (xy 36.975201 -312.352639)
			(xy 36.926302 -312.368527) (xy 36.87552 -312.37657) (xy 36.824104 -312.37657) (xy 36.773322 -312.368527)
			(xy 36.724423 -312.352639) (xy 36.678611 -312.329296) (xy 36.637015 -312.299075) (xy 36.600659 -312.262719)
			(xy 36.570438 -312.221123) (xy 36.547095 -312.175311) (xy 36.531207 -312.126412) (xy 36.523164 -312.07563)
			(xy 34.733284 -312.07563) (xy 34.736931 -312.081142) (xy 34.760603 -312.131639) (xy 34.776671 -312.185046)
			(xy 34.784791 -312.240222) (xy 34.7853 -312.268108) (xy 34.784791 -312.295994) (xy 34.776671 -312.35117)
			(xy 34.760603 -312.404577) (xy 34.736931 -312.455074) (xy 34.706158 -312.501587) (xy 34.668941 -312.543124)
			(xy 34.626073 -312.578799) (xy 34.578467 -312.607853) (xy 34.527138 -312.629665) (xy 34.473181 -312.643771)
			(xy 34.417744 -312.649871) (xy 34.36201 -312.647834) (xy 34.307167 -312.637704) (xy 34.254383 -312.619697)
			(xy 34.204783 -312.594196) (xy 34.159425 -312.561745) (xy 34.119276 -312.523036) (xy 34.08519 -312.478893)
			(xy 34.057894 -312.430258) (xy 34.037971 -312.378167) (xy 34.025845 -312.32373) (xy 34.021774 -312.268108)
			(xy 32.396823 -312.268108) (xy 32.416348 -312.289899) (xy 32.447121 -312.336412) (xy 32.470793 -312.386909)
			(xy 32.486861 -312.440316) (xy 32.494981 -312.495492) (xy 32.49549 -312.523378) (xy 32.494981 -312.551264)
			(xy 32.486861 -312.60644) (xy 32.470793 -312.659847) (xy 32.447121 -312.710344) (xy 32.416348 -312.756857)
			(xy 32.379131 -312.798394) (xy 32.336263 -312.834069) (xy 32.288657 -312.863123) (xy 32.237328 -312.884935)
			(xy 32.183371 -312.899041) (xy 32.127934 -312.905141) (xy 32.0722 -312.903104) (xy 32.017357 -312.892974)
			(xy 31.964573 -312.874967) (xy 31.914973 -312.849466) (xy 31.869615 -312.817015) (xy 31.829466 -312.778306)
			(xy 31.79538 -312.734163) (xy 31.768084 -312.685528) (xy 31.748161 -312.633437) (xy 31.736035 -312.579)
			(xy 31.731964 -312.523378) (xy 17.90985 -312.523378) (xy 17.903952 -312.528712) (xy 17.896406 -312.536309)
			(xy 17.887746 -312.555865) (xy 17.887188 -312.566558) (xy 17.887188 -313.02559) (xy 38.423338 -313.02559)
			(xy 38.423338 -312.974174) (xy 38.431381 -312.923392) (xy 38.447269 -312.874493) (xy 38.470612 -312.828681)
			(xy 38.500833 -312.787085) (xy 38.537189 -312.750729) (xy 38.578785 -312.720508) (xy 38.624597 -312.697165)
			(xy 38.673496 -312.681277) (xy 38.724278 -312.673234) (xy 38.775694 -312.673234) (xy 38.826476 -312.681277)
			(xy 38.875375 -312.697165) (xy 38.921187 -312.720508) (xy 38.962783 -312.750729) (xy 38.999139 -312.787085)
			(xy 39.02936 -312.828681) (xy 39.052703 -312.874493) (xy 39.068591 -312.923392) (xy 39.076634 -312.974174)
			(xy 39.077138 -312.999882) (xy 39.076634 -313.02559) (xy 40.323258 -313.02559) (xy 40.323258 -312.974174)
			(xy 40.331301 -312.923392) (xy 40.347189 -312.874493) (xy 40.370532 -312.828681) (xy 40.400753 -312.787085)
			(xy 40.437109 -312.750729) (xy 40.478705 -312.720508) (xy 40.524517 -312.697165) (xy 40.573416 -312.681277)
			(xy 40.624198 -312.673234) (xy 40.675614 -312.673234) (xy 40.726396 -312.681277) (xy 40.775295 -312.697165)
			(xy 40.821107 -312.720508) (xy 40.862703 -312.750729) (xy 40.899059 -312.787085) (xy 40.92928 -312.828681)
			(xy 40.952623 -312.874493) (xy 40.968511 -312.923392) (xy 40.976554 -312.974174) (xy 40.977058 -312.999882)
			(xy 40.976554 -313.02559) (xy 42.223178 -313.02559) (xy 42.223178 -312.974174) (xy 42.231221 -312.923392)
			(xy 42.247109 -312.874493) (xy 42.270452 -312.828681) (xy 42.300673 -312.787085) (xy 42.337029 -312.750729)
			(xy 42.378625 -312.720508) (xy 42.424437 -312.697165) (xy 42.473336 -312.681277) (xy 42.524118 -312.673234)
			(xy 42.575534 -312.673234) (xy 42.626316 -312.681277) (xy 42.675215 -312.697165) (xy 42.721027 -312.720508)
			(xy 42.762623 -312.750729) (xy 42.798979 -312.787085) (xy 42.8292 -312.828681) (xy 42.852543 -312.874493)
			(xy 42.868431 -312.923392) (xy 42.876474 -312.974174) (xy 42.876978 -312.999882) (xy 44.143942 -312.999882)
			(xy 44.147902 -312.950828) (xy 44.159679 -312.903044) (xy 44.17897 -312.857768) (xy 44.205273 -312.816172)
			(xy 44.237908 -312.779335) (xy 44.276029 -312.74821) (xy 44.31865 -312.723603) (xy 44.364666 -312.706151)
			(xy 44.412885 -312.696307) (xy 44.46206 -312.694326) (xy 44.510915 -312.700258) (xy 44.558186 -312.71395)
			(xy 44.602648 -312.735048) (xy 44.643151 -312.763004) (xy 44.678644 -312.797096) (xy 44.708209 -312.83644)
			(xy 44.73108 -312.880017) (xy 44.746664 -312.926698) (xy 44.754559 -312.975275) (xy 44.755054 -312.999882)
			(xy 46.044116 -312.999882) (xy 46.048076 -312.950828) (xy 46.059853 -312.903044) (xy 46.079144 -312.857768)
			(xy 46.105447 -312.816172) (xy 46.138082 -312.779335) (xy 46.176203 -312.74821) (xy 46.218824 -312.723603)
			(xy 46.26484 -312.706151) (xy 46.313059 -312.696307) (xy 46.362234 -312.694326) (xy 46.411089 -312.700258)
			(xy 46.45836 -312.71395) (xy 46.502822 -312.735048) (xy 46.543325 -312.763004) (xy 46.578818 -312.797096)
			(xy 46.608383 -312.83644) (xy 46.631254 -312.880017) (xy 46.646838 -312.926698) (xy 46.654733 -312.975275)
			(xy 46.655228 -312.999882) (xy 46.654733 -313.024489) (xy 46.646838 -313.073066) (xy 46.631254 -313.119747)
			(xy 46.608383 -313.163324) (xy 46.578818 -313.202668) (xy 46.543325 -313.23676) (xy 46.502822 -313.264716)
			(xy 46.45836 -313.285814) (xy 46.411089 -313.299506) (xy 46.362234 -313.305438) (xy 46.313059 -313.303457)
			(xy 46.26484 -313.293613) (xy 46.218824 -313.276161) (xy 46.176203 -313.251554) (xy 46.138082 -313.220429)
			(xy 46.105447 -313.183592) (xy 46.079144 -313.141996) (xy 46.059853 -313.09672) (xy 46.048076 -313.048936)
			(xy 46.044116 -312.999882) (xy 44.755054 -312.999882) (xy 44.754559 -313.024489) (xy 44.746664 -313.073066)
			(xy 44.73108 -313.119747) (xy 44.708209 -313.163324) (xy 44.678644 -313.202668) (xy 44.643151 -313.23676)
			(xy 44.602648 -313.264716) (xy 44.558186 -313.285814) (xy 44.510915 -313.299506) (xy 44.46206 -313.305438)
			(xy 44.412885 -313.303457) (xy 44.364666 -313.293613) (xy 44.31865 -313.276161) (xy 44.276029 -313.251554)
			(xy 44.237908 -313.220429) (xy 44.205273 -313.183592) (xy 44.17897 -313.141996) (xy 44.159679 -313.09672)
			(xy 44.147902 -313.048936) (xy 44.143942 -312.999882) (xy 42.876978 -312.999882) (xy 42.876474 -313.02559)
			(xy 42.868431 -313.076372) (xy 42.852543 -313.125271) (xy 42.8292 -313.171083) (xy 42.798979 -313.212679)
			(xy 42.762623 -313.249035) (xy 42.721027 -313.279256) (xy 42.675215 -313.302599) (xy 42.626316 -313.318487)
			(xy 42.575534 -313.32653) (xy 42.524118 -313.32653) (xy 42.473336 -313.318487) (xy 42.424437 -313.302599)
			(xy 42.378625 -313.279256) (xy 42.337029 -313.249035) (xy 42.300673 -313.212679) (xy 42.270452 -313.171083)
			(xy 42.247109 -313.125271) (xy 42.231221 -313.076372) (xy 42.223178 -313.02559) (xy 40.976554 -313.02559)
			(xy 40.968511 -313.076372) (xy 40.952623 -313.125271) (xy 40.92928 -313.171083) (xy 40.899059 -313.212679)
			(xy 40.862703 -313.249035) (xy 40.821107 -313.279256) (xy 40.775295 -313.302599) (xy 40.726396 -313.318487)
			(xy 40.675614 -313.32653) (xy 40.624198 -313.32653) (xy 40.573416 -313.318487) (xy 40.524517 -313.302599)
			(xy 40.478705 -313.279256) (xy 40.437109 -313.249035) (xy 40.400753 -313.212679) (xy 40.370532 -313.171083)
			(xy 40.347189 -313.125271) (xy 40.331301 -313.076372) (xy 40.323258 -313.02559) (xy 39.076634 -313.02559)
			(xy 39.068591 -313.076372) (xy 39.052703 -313.125271) (xy 39.02936 -313.171083) (xy 38.999139 -313.212679)
			(xy 38.962783 -313.249035) (xy 38.921187 -313.279256) (xy 38.875375 -313.302599) (xy 38.826476 -313.318487)
			(xy 38.775694 -313.32653) (xy 38.724278 -313.32653) (xy 38.673496 -313.318487) (xy 38.624597 -313.302599)
			(xy 38.578785 -313.279256) (xy 38.537189 -313.249035) (xy 38.500833 -313.212679) (xy 38.470612 -313.171083)
			(xy 38.447269 -313.125271) (xy 38.431381 -313.076372) (xy 38.423338 -313.02559) (xy 17.887188 -313.02559)
			(xy 17.887188 -313.669934) (xy 34.021774 -313.669934) (xy 34.025845 -313.614312) (xy 34.037971 -313.559875)
			(xy 34.057894 -313.507784) (xy 34.08519 -313.459149) (xy 34.119276 -313.415006) (xy 34.159425 -313.376297)
			(xy 34.204783 -313.343846) (xy 34.254383 -313.318345) (xy 34.307167 -313.300338) (xy 34.36201 -313.290208)
			(xy 34.417744 -313.288171) (xy 34.473181 -313.294271) (xy 34.527138 -313.308377) (xy 34.578467 -313.330189)
			(xy 34.626073 -313.359243) (xy 34.668941 -313.394918) (xy 34.706158 -313.436455) (xy 34.736931 -313.482968)
			(xy 34.760603 -313.533465) (xy 34.776671 -313.586872) (xy 34.784791 -313.642048) (xy 34.7853 -313.669934)
			(xy 34.784791 -313.69782) (xy 34.776671 -313.752996) (xy 34.760603 -313.806403) (xy 34.736931 -313.8569)
			(xy 34.706158 -313.903413) (xy 34.668941 -313.94495) (xy 34.632171 -313.97555) (xy 38.423338 -313.97555)
			(xy 38.423338 -313.924134) (xy 38.431381 -313.873352) (xy 38.447269 -313.824453) (xy 38.470612 -313.778641)
			(xy 38.500833 -313.737045) (xy 38.537189 -313.700689) (xy 38.578785 -313.670468) (xy 38.624597 -313.647125)
			(xy 38.673496 -313.631237) (xy 38.724278 -313.623194) (xy 38.775694 -313.623194) (xy 38.826476 -313.631237)
			(xy 38.875375 -313.647125) (xy 38.921187 -313.670468) (xy 38.962783 -313.700689) (xy 38.999139 -313.737045)
			(xy 39.02936 -313.778641) (xy 39.052703 -313.824453) (xy 39.068591 -313.873352) (xy 39.076634 -313.924134)
			(xy 39.077138 -313.949842) (xy 39.076634 -313.97555) (xy 40.323258 -313.97555) (xy 40.323258 -313.924134)
			(xy 40.331301 -313.873352) (xy 40.347189 -313.824453) (xy 40.370532 -313.778641) (xy 40.400753 -313.737045)
			(xy 40.437109 -313.700689) (xy 40.478705 -313.670468) (xy 40.524517 -313.647125) (xy 40.573416 -313.631237)
			(xy 40.624198 -313.623194) (xy 40.675614 -313.623194) (xy 40.726396 -313.631237) (xy 40.775295 -313.647125)
			(xy 40.821107 -313.670468) (xy 40.862703 -313.700689) (xy 40.899059 -313.737045) (xy 40.92928 -313.778641)
			(xy 40.952623 -313.824453) (xy 40.968511 -313.873352) (xy 40.976554 -313.924134) (xy 40.977058 -313.949842)
			(xy 40.976554 -313.97555) (xy 42.223178 -313.97555) (xy 42.223178 -313.924134) (xy 42.231221 -313.873352)
			(xy 42.247109 -313.824453) (xy 42.270452 -313.778641) (xy 42.300673 -313.737045) (xy 42.337029 -313.700689)
			(xy 42.378625 -313.670468) (xy 42.424437 -313.647125) (xy 42.473336 -313.631237) (xy 42.524118 -313.623194)
			(xy 42.575534 -313.623194) (xy 42.626316 -313.631237) (xy 42.675215 -313.647125) (xy 42.721027 -313.670468)
			(xy 42.762623 -313.700689) (xy 42.798979 -313.737045) (xy 42.8292 -313.778641) (xy 42.852543 -313.824453)
			(xy 42.868431 -313.873352) (xy 42.876474 -313.924134) (xy 42.876978 -313.949842) (xy 44.143942 -313.949842)
			(xy 44.147902 -313.900788) (xy 44.159679 -313.853004) (xy 44.17897 -313.807728) (xy 44.205273 -313.766132)
			(xy 44.237908 -313.729295) (xy 44.276029 -313.69817) (xy 44.31865 -313.673563) (xy 44.364666 -313.656111)
			(xy 44.412885 -313.646267) (xy 44.46206 -313.644286) (xy 44.510915 -313.650218) (xy 44.558186 -313.66391)
			(xy 44.602648 -313.685008) (xy 44.643151 -313.712964) (xy 44.678644 -313.747056) (xy 44.708209 -313.7864)
			(xy 44.73108 -313.829977) (xy 44.746664 -313.876658) (xy 44.754559 -313.925235) (xy 44.755054 -313.949842)
			(xy 46.044116 -313.949842) (xy 46.048076 -313.900788) (xy 46.059853 -313.853004) (xy 46.079144 -313.807728)
			(xy 46.105447 -313.766132) (xy 46.138082 -313.729295) (xy 46.176203 -313.69817) (xy 46.218824 -313.673563)
			(xy 46.26484 -313.656111) (xy 46.313059 -313.646267) (xy 46.362234 -313.644286) (xy 46.411089 -313.650218)
			(xy 46.45836 -313.66391) (xy 46.502822 -313.685008) (xy 46.543325 -313.712964) (xy 46.578818 -313.747056)
			(xy 46.608383 -313.7864) (xy 46.631254 -313.829977) (xy 46.646838 -313.876658) (xy 46.654733 -313.925235)
			(xy 46.655228 -313.949842) (xy 46.654733 -313.974449) (xy 46.646838 -314.023026) (xy 46.631254 -314.069707)
			(xy 46.608383 -314.113284) (xy 46.578818 -314.152628) (xy 46.543325 -314.18672) (xy 46.502822 -314.214676)
			(xy 46.45836 -314.235774) (xy 46.411089 -314.249466) (xy 46.362234 -314.255398) (xy 46.313059 -314.253417)
			(xy 46.26484 -314.243573) (xy 46.218824 -314.226121) (xy 46.176203 -314.201514) (xy 46.138082 -314.170389)
			(xy 46.105447 -314.133552) (xy 46.079144 -314.091956) (xy 46.059853 -314.04668) (xy 46.048076 -313.998896)
			(xy 46.044116 -313.949842) (xy 44.755054 -313.949842) (xy 44.754559 -313.974449) (xy 44.746664 -314.023026)
			(xy 44.73108 -314.069707) (xy 44.708209 -314.113284) (xy 44.678644 -314.152628) (xy 44.643151 -314.18672)
			(xy 44.602648 -314.214676) (xy 44.558186 -314.235774) (xy 44.510915 -314.249466) (xy 44.46206 -314.255398)
			(xy 44.412885 -314.253417) (xy 44.364666 -314.243573) (xy 44.31865 -314.226121) (xy 44.276029 -314.201514)
			(xy 44.237908 -314.170389) (xy 44.205273 -314.133552) (xy 44.17897 -314.091956) (xy 44.159679 -314.04668)
			(xy 44.147902 -313.998896) (xy 44.143942 -313.949842) (xy 42.876978 -313.949842) (xy 42.876474 -313.97555)
			(xy 42.868431 -314.026332) (xy 42.852543 -314.075231) (xy 42.8292 -314.121043) (xy 42.798979 -314.162639)
			(xy 42.762623 -314.198995) (xy 42.721027 -314.229216) (xy 42.675215 -314.252559) (xy 42.626316 -314.268447)
			(xy 42.575534 -314.27649) (xy 42.524118 -314.27649) (xy 42.473336 -314.268447) (xy 42.424437 -314.252559)
			(xy 42.378625 -314.229216) (xy 42.337029 -314.198995) (xy 42.300673 -314.162639) (xy 42.270452 -314.121043)
			(xy 42.247109 -314.075231) (xy 42.231221 -314.026332) (xy 42.223178 -313.97555) (xy 40.976554 -313.97555)
			(xy 40.968511 -314.026332) (xy 40.952623 -314.075231) (xy 40.92928 -314.121043) (xy 40.899059 -314.162639)
			(xy 40.862703 -314.198995) (xy 40.821107 -314.229216) (xy 40.775295 -314.252559) (xy 40.726396 -314.268447)
			(xy 40.675614 -314.27649) (xy 40.624198 -314.27649) (xy 40.573416 -314.268447) (xy 40.524517 -314.252559)
			(xy 40.478705 -314.229216) (xy 40.437109 -314.198995) (xy 40.400753 -314.162639) (xy 40.370532 -314.121043)
			(xy 40.347189 -314.075231) (xy 40.331301 -314.026332) (xy 40.323258 -313.97555) (xy 39.076634 -313.97555)
			(xy 39.068591 -314.026332) (xy 39.052703 -314.075231) (xy 39.02936 -314.121043) (xy 38.999139 -314.162639)
			(xy 38.962783 -314.198995) (xy 38.921187 -314.229216) (xy 38.875375 -314.252559) (xy 38.826476 -314.268447)
			(xy 38.775694 -314.27649) (xy 38.724278 -314.27649) (xy 38.673496 -314.268447) (xy 38.624597 -314.252559)
			(xy 38.578785 -314.229216) (xy 38.537189 -314.198995) (xy 38.500833 -314.162639) (xy 38.470612 -314.121043)
			(xy 38.447269 -314.075231) (xy 38.431381 -314.026332) (xy 38.423338 -313.97555) (xy 34.632171 -313.97555)
			(xy 34.626073 -313.980625) (xy 34.578467 -314.009679) (xy 34.527138 -314.031491) (xy 34.473181 -314.045597)
			(xy 34.417744 -314.051697) (xy 34.36201 -314.04966) (xy 34.307167 -314.03953) (xy 34.254383 -314.021523)
			(xy 34.204783 -313.996022) (xy 34.159425 -313.963571) (xy 34.119276 -313.924862) (xy 34.08519 -313.880719)
			(xy 34.057894 -313.832084) (xy 34.037971 -313.779993) (xy 34.025845 -313.725556) (xy 34.021774 -313.669934)
			(xy 17.887188 -313.669934) (xy 17.887188 -314.92551) (xy 36.523164 -314.92551) (xy 36.523164 -314.874094)
			(xy 36.531207 -314.823312) (xy 36.547095 -314.774413) (xy 36.570438 -314.728601) (xy 36.600659 -314.687005)
			(xy 36.637015 -314.650649) (xy 36.678611 -314.620428) (xy 36.724423 -314.597085) (xy 36.773322 -314.581197)
			(xy 36.824104 -314.573154) (xy 36.87552 -314.573154) (xy 36.926302 -314.581197) (xy 36.975201 -314.597085)
			(xy 37.021013 -314.620428) (xy 37.062609 -314.650649) (xy 37.098965 -314.687005) (xy 37.129186 -314.728601)
			(xy 37.152529 -314.774413) (xy 37.168417 -314.823312) (xy 37.17646 -314.874094) (xy 37.176964 -314.899802)
			(xy 37.17646 -314.92551) (xy 37.473124 -314.92551) (xy 37.473124 -314.874094) (xy 37.481167 -314.823312)
			(xy 37.497055 -314.774413) (xy 37.520398 -314.728601) (xy 37.550619 -314.687005) (xy 37.586975 -314.650649)
			(xy 37.628571 -314.620428) (xy 37.674383 -314.597085) (xy 37.723282 -314.581197) (xy 37.774064 -314.573154)
			(xy 37.82548 -314.573154) (xy 37.876262 -314.581197) (xy 37.925161 -314.597085) (xy 37.970973 -314.620428)
			(xy 38.012569 -314.650649) (xy 38.048925 -314.687005) (xy 38.079146 -314.728601) (xy 38.102489 -314.774413)
			(xy 38.118377 -314.823312) (xy 38.12642 -314.874094) (xy 38.126924 -314.899802) (xy 38.12642 -314.92551)
			(xy 38.118377 -314.976292) (xy 38.102489 -315.025191) (xy 38.079146 -315.071003) (xy 38.048925 -315.112599)
			(xy 38.012569 -315.148955) (xy 37.970973 -315.179176) (xy 37.925161 -315.202519) (xy 37.876262 -315.218407)
			(xy 37.82548 -315.22645) (xy 37.774064 -315.22645) (xy 37.723282 -315.218407) (xy 37.674383 -315.202519)
			(xy 37.628571 -315.179176) (xy 37.586975 -315.148955) (xy 37.550619 -315.112599) (xy 37.520398 -315.071003)
			(xy 37.497055 -315.025191) (xy 37.481167 -314.976292) (xy 37.473124 -314.92551) (xy 37.17646 -314.92551)
			(xy 37.168417 -314.976292) (xy 37.152529 -315.025191) (xy 37.129186 -315.071003) (xy 37.098965 -315.112599)
			(xy 37.062609 -315.148955) (xy 37.021013 -315.179176) (xy 36.975201 -315.202519) (xy 36.926302 -315.218407)
			(xy 36.87552 -315.22645) (xy 36.824104 -315.22645) (xy 36.773322 -315.218407) (xy 36.724423 -315.202519)
			(xy 36.678611 -315.179176) (xy 36.637015 -315.148955) (xy 36.600659 -315.112599) (xy 36.570438 -315.071003)
			(xy 36.547095 -315.025191) (xy 36.531207 -314.976292) (xy 36.523164 -314.92551) (xy 17.887188 -314.92551)
			(xy 17.887188 -315.87547) (xy 39.373298 -315.87547) (xy 39.373298 -315.824054) (xy 39.381341 -315.773272)
			(xy 39.397229 -315.724373) (xy 39.420572 -315.678561) (xy 39.450793 -315.636965) (xy 39.487149 -315.600609)
			(xy 39.528745 -315.570388) (xy 39.574557 -315.547045) (xy 39.623456 -315.531157) (xy 39.674238 -315.523114)
			(xy 39.725654 -315.523114) (xy 39.776436 -315.531157) (xy 39.825335 -315.547045) (xy 39.871147 -315.570388)
			(xy 39.912743 -315.600609) (xy 39.949099 -315.636965) (xy 39.97932 -315.678561) (xy 40.002663 -315.724373)
			(xy 40.018551 -315.773272) (xy 40.026594 -315.824054) (xy 40.027098 -315.849762) (xy 40.026594 -315.87547)
			(xy 41.273218 -315.87547) (xy 41.273218 -315.824054) (xy 41.281261 -315.773272) (xy 41.297149 -315.724373)
			(xy 41.320492 -315.678561) (xy 41.350713 -315.636965) (xy 41.387069 -315.600609) (xy 41.428665 -315.570388)
			(xy 41.474477 -315.547045) (xy 41.523376 -315.531157) (xy 41.574158 -315.523114) (xy 41.625574 -315.523114)
			(xy 41.676356 -315.531157) (xy 41.725255 -315.547045) (xy 41.771067 -315.570388) (xy 41.812663 -315.600609)
			(xy 41.849019 -315.636965) (xy 41.87924 -315.678561) (xy 41.902583 -315.724373) (xy 41.918471 -315.773272)
			(xy 41.926514 -315.824054) (xy 41.927018 -315.849762) (xy 41.926514 -315.87547) (xy 43.173138 -315.87547)
			(xy 43.173138 -315.824054) (xy 43.181181 -315.773272) (xy 43.197069 -315.724373) (xy 43.220412 -315.678561)
			(xy 43.250633 -315.636965) (xy 43.286989 -315.600609) (xy 43.328585 -315.570388) (xy 43.374397 -315.547045)
			(xy 43.423296 -315.531157) (xy 43.474078 -315.523114) (xy 43.525494 -315.523114) (xy 43.576276 -315.531157)
			(xy 43.625175 -315.547045) (xy 43.670987 -315.570388) (xy 43.712583 -315.600609) (xy 43.748939 -315.636965)
			(xy 43.77916 -315.678561) (xy 43.802503 -315.724373) (xy 43.818391 -315.773272) (xy 43.826434 -315.824054)
			(xy 43.826938 -315.849762) (xy 43.826434 -315.87547) (xy 45.073312 -315.87547) (xy 45.073312 -315.824054)
			(xy 45.081355 -315.773272) (xy 45.097243 -315.724373) (xy 45.120586 -315.678561) (xy 45.150807 -315.636965)
			(xy 45.187163 -315.600609) (xy 45.228759 -315.570388) (xy 45.274571 -315.547045) (xy 45.32347 -315.531157)
			(xy 45.374252 -315.523114) (xy 45.425668 -315.523114) (xy 45.47645 -315.531157) (xy 45.525349 -315.547045)
			(xy 45.571161 -315.570388) (xy 45.612757 -315.600609) (xy 45.649113 -315.636965) (xy 45.679334 -315.678561)
			(xy 45.702677 -315.724373) (xy 45.718565 -315.773272) (xy 45.726608 -315.824054) (xy 45.727112 -315.849762)
			(xy 45.726608 -315.87547) (xy 46.973232 -315.87547) (xy 46.973232 -315.824054) (xy 46.981275 -315.773272)
			(xy 46.997163 -315.724373) (xy 47.020506 -315.678561) (xy 47.050727 -315.636965) (xy 47.087083 -315.600609)
			(xy 47.128679 -315.570388) (xy 47.174491 -315.547045) (xy 47.22339 -315.531157) (xy 47.274172 -315.523114)
			(xy 47.325588 -315.523114) (xy 47.37637 -315.531157) (xy 47.425269 -315.547045) (xy 47.471081 -315.570388)
			(xy 47.512677 -315.600609) (xy 47.549033 -315.636965) (xy 47.579254 -315.678561) (xy 47.602597 -315.724373)
			(xy 47.618485 -315.773272) (xy 47.626528 -315.824054) (xy 47.627032 -315.849762) (xy 47.626528 -315.87547)
			(xy 47.618485 -315.926252) (xy 47.602597 -315.975151) (xy 47.579254 -316.020963) (xy 47.549033 -316.062559)
			(xy 47.512677 -316.098915) (xy 47.471081 -316.129136) (xy 47.425269 -316.152479) (xy 47.37637 -316.168367)
			(xy 47.325588 -316.17641) (xy 47.274172 -316.17641) (xy 47.22339 -316.168367) (xy 47.174491 -316.152479)
			(xy 47.128679 -316.129136) (xy 47.087083 -316.098915) (xy 47.050727 -316.062559) (xy 47.020506 -316.020963)
			(xy 46.997163 -315.975151) (xy 46.981275 -315.926252) (xy 46.973232 -315.87547) (xy 45.726608 -315.87547)
			(xy 45.718565 -315.926252) (xy 45.702677 -315.975151) (xy 45.679334 -316.020963) (xy 45.649113 -316.062559)
			(xy 45.612757 -316.098915) (xy 45.571161 -316.129136) (xy 45.525349 -316.152479) (xy 45.47645 -316.168367)
			(xy 45.425668 -316.17641) (xy 45.374252 -316.17641) (xy 45.32347 -316.168367) (xy 45.274571 -316.152479)
			(xy 45.228759 -316.129136) (xy 45.187163 -316.098915) (xy 45.150807 -316.062559) (xy 45.120586 -316.020963)
			(xy 45.097243 -315.975151) (xy 45.081355 -315.926252) (xy 45.073312 -315.87547) (xy 43.826434 -315.87547)
			(xy 43.818391 -315.926252) (xy 43.802503 -315.975151) (xy 43.77916 -316.020963) (xy 43.748939 -316.062559)
			(xy 43.712583 -316.098915) (xy 43.670987 -316.129136) (xy 43.625175 -316.152479) (xy 43.576276 -316.168367)
			(xy 43.525494 -316.17641) (xy 43.474078 -316.17641) (xy 43.423296 -316.168367) (xy 43.374397 -316.152479)
			(xy 43.328585 -316.129136) (xy 43.286989 -316.098915) (xy 43.250633 -316.062559) (xy 43.220412 -316.020963)
			(xy 43.197069 -315.975151) (xy 43.181181 -315.926252) (xy 43.173138 -315.87547) (xy 41.926514 -315.87547)
			(xy 41.918471 -315.926252) (xy 41.902583 -315.975151) (xy 41.87924 -316.020963) (xy 41.849019 -316.062559)
			(xy 41.812663 -316.098915) (xy 41.771067 -316.129136) (xy 41.725255 -316.152479) (xy 41.676356 -316.168367)
			(xy 41.625574 -316.17641) (xy 41.574158 -316.17641) (xy 41.523376 -316.168367) (xy 41.474477 -316.152479)
			(xy 41.428665 -316.129136) (xy 41.387069 -316.098915) (xy 41.350713 -316.062559) (xy 41.320492 -316.020963)
			(xy 41.297149 -315.975151) (xy 41.281261 -315.926252) (xy 41.273218 -315.87547) (xy 40.026594 -315.87547)
			(xy 40.018551 -315.926252) (xy 40.002663 -315.975151) (xy 39.97932 -316.020963) (xy 39.949099 -316.062559)
			(xy 39.912743 -316.098915) (xy 39.871147 -316.129136) (xy 39.825335 -316.152479) (xy 39.776436 -316.168367)
			(xy 39.725654 -316.17641) (xy 39.674238 -316.17641) (xy 39.623456 -316.168367) (xy 39.574557 -316.152479)
			(xy 39.528745 -316.129136) (xy 39.487149 -316.098915) (xy 39.450793 -316.062559) (xy 39.420572 -316.020963)
			(xy 39.397229 -315.975151) (xy 39.381341 -315.926252) (xy 39.373298 -315.87547) (xy 17.887188 -315.87547)
			(xy 17.887188 -316.82543) (xy 36.523164 -316.82543) (xy 36.523164 -316.774014) (xy 36.531207 -316.723232)
			(xy 36.547095 -316.674333) (xy 36.570438 -316.628521) (xy 36.600659 -316.586925) (xy 36.637015 -316.550569)
			(xy 36.678611 -316.520348) (xy 36.724423 -316.497005) (xy 36.773322 -316.481117) (xy 36.824104 -316.473074)
			(xy 36.87552 -316.473074) (xy 36.926302 -316.481117) (xy 36.975201 -316.497005) (xy 37.021013 -316.520348)
			(xy 37.062609 -316.550569) (xy 37.098965 -316.586925) (xy 37.129186 -316.628521) (xy 37.152529 -316.674333)
			(xy 37.168417 -316.723232) (xy 37.17646 -316.774014) (xy 37.176964 -316.799722) (xy 37.17646 -316.82543)
			(xy 37.473124 -316.82543) (xy 37.473124 -316.774014) (xy 37.481167 -316.723232) (xy 37.497055 -316.674333)
			(xy 37.520398 -316.628521) (xy 37.550619 -316.586925) (xy 37.586975 -316.550569) (xy 37.628571 -316.520348)
			(xy 37.674383 -316.497005) (xy 37.723282 -316.481117) (xy 37.774064 -316.473074) (xy 37.82548 -316.473074)
			(xy 37.876262 -316.481117) (xy 37.925161 -316.497005) (xy 37.970973 -316.520348) (xy 38.012569 -316.550569)
			(xy 38.048925 -316.586925) (xy 38.079146 -316.628521) (xy 38.102489 -316.674333) (xy 38.118377 -316.723232)
			(xy 38.12642 -316.774014) (xy 38.126924 -316.799722) (xy 38.12642 -316.82543) (xy 39.373298 -316.82543)
			(xy 39.373298 -316.774014) (xy 39.381341 -316.723232) (xy 39.397229 -316.674333) (xy 39.420572 -316.628521)
			(xy 39.450793 -316.586925) (xy 39.487149 -316.550569) (xy 39.528745 -316.520348) (xy 39.574557 -316.497005)
			(xy 39.623456 -316.481117) (xy 39.674238 -316.473074) (xy 39.725654 -316.473074) (xy 39.776436 -316.481117)
			(xy 39.825335 -316.497005) (xy 39.871147 -316.520348) (xy 39.912743 -316.550569) (xy 39.949099 -316.586925)
			(xy 39.97932 -316.628521) (xy 40.002663 -316.674333) (xy 40.018551 -316.723232) (xy 40.026594 -316.774014)
			(xy 40.027098 -316.799722) (xy 40.026594 -316.82543) (xy 41.273218 -316.82543) (xy 41.273218 -316.774014)
			(xy 41.281261 -316.723232) (xy 41.297149 -316.674333) (xy 41.320492 -316.628521) (xy 41.350713 -316.586925)
			(xy 41.387069 -316.550569) (xy 41.428665 -316.520348) (xy 41.474477 -316.497005) (xy 41.523376 -316.481117)
			(xy 41.574158 -316.473074) (xy 41.625574 -316.473074) (xy 41.676356 -316.481117) (xy 41.725255 -316.497005)
			(xy 41.771067 -316.520348) (xy 41.812663 -316.550569) (xy 41.849019 -316.586925) (xy 41.87924 -316.628521)
			(xy 41.902583 -316.674333) (xy 41.918471 -316.723232) (xy 41.926514 -316.774014) (xy 41.927018 -316.799722)
			(xy 41.926514 -316.82543) (xy 43.173138 -316.82543) (xy 43.173138 -316.774014) (xy 43.181181 -316.723232)
			(xy 43.197069 -316.674333) (xy 43.220412 -316.628521) (xy 43.250633 -316.586925) (xy 43.286989 -316.550569)
			(xy 43.328585 -316.520348) (xy 43.374397 -316.497005) (xy 43.423296 -316.481117) (xy 43.474078 -316.473074)
			(xy 43.525494 -316.473074) (xy 43.576276 -316.481117) (xy 43.625175 -316.497005) (xy 43.670987 -316.520348)
			(xy 43.712583 -316.550569) (xy 43.748939 -316.586925) (xy 43.77916 -316.628521) (xy 43.802503 -316.674333)
			(xy 43.818391 -316.723232) (xy 43.826434 -316.774014) (xy 43.826938 -316.799722) (xy 43.826434 -316.82543)
			(xy 45.073312 -316.82543) (xy 45.073312 -316.774014) (xy 45.081355 -316.723232) (xy 45.097243 -316.674333)
			(xy 45.120586 -316.628521) (xy 45.150807 -316.586925) (xy 45.187163 -316.550569) (xy 45.228759 -316.520348)
			(xy 45.274571 -316.497005) (xy 45.32347 -316.481117) (xy 45.374252 -316.473074) (xy 45.425668 -316.473074)
			(xy 45.47645 -316.481117) (xy 45.525349 -316.497005) (xy 45.571161 -316.520348) (xy 45.612757 -316.550569)
			(xy 45.649113 -316.586925) (xy 45.679334 -316.628521) (xy 45.702677 -316.674333) (xy 45.718565 -316.723232)
			(xy 45.726608 -316.774014) (xy 45.727112 -316.799722) (xy 45.726608 -316.82543) (xy 46.973232 -316.82543)
			(xy 46.973232 -316.774014) (xy 46.981275 -316.723232) (xy 46.997163 -316.674333) (xy 47.020506 -316.628521)
			(xy 47.050727 -316.586925) (xy 47.087083 -316.550569) (xy 47.128679 -316.520348) (xy 47.174491 -316.497005)
			(xy 47.22339 -316.481117) (xy 47.274172 -316.473074) (xy 47.325588 -316.473074) (xy 47.37637 -316.481117)
			(xy 47.425269 -316.497005) (xy 47.471081 -316.520348) (xy 47.512677 -316.550569) (xy 47.549033 -316.586925)
			(xy 47.579254 -316.628521) (xy 47.602597 -316.674333) (xy 47.618485 -316.723232) (xy 47.626528 -316.774014)
			(xy 47.627032 -316.799722) (xy 47.626528 -316.82543) (xy 47.618485 -316.876212) (xy 47.602597 -316.925111)
			(xy 47.579254 -316.970923) (xy 47.549033 -317.012519) (xy 47.512677 -317.048875) (xy 47.471081 -317.079096)
			(xy 47.425269 -317.102439) (xy 47.37637 -317.118327) (xy 47.325588 -317.12637) (xy 47.274172 -317.12637)
			(xy 47.22339 -317.118327) (xy 47.174491 -317.102439) (xy 47.128679 -317.079096) (xy 47.087083 -317.048875)
			(xy 47.050727 -317.012519) (xy 47.020506 -316.970923) (xy 46.997163 -316.925111) (xy 46.981275 -316.876212)
			(xy 46.973232 -316.82543) (xy 45.726608 -316.82543) (xy 45.718565 -316.876212) (xy 45.702677 -316.925111)
			(xy 45.679334 -316.970923) (xy 45.649113 -317.012519) (xy 45.612757 -317.048875) (xy 45.571161 -317.079096)
			(xy 45.525349 -317.102439) (xy 45.47645 -317.118327) (xy 45.425668 -317.12637) (xy 45.374252 -317.12637)
			(xy 45.32347 -317.118327) (xy 45.274571 -317.102439) (xy 45.228759 -317.079096) (xy 45.187163 -317.048875)
			(xy 45.150807 -317.012519) (xy 45.120586 -316.970923) (xy 45.097243 -316.925111) (xy 45.081355 -316.876212)
			(xy 45.073312 -316.82543) (xy 43.826434 -316.82543) (xy 43.818391 -316.876212) (xy 43.802503 -316.925111)
			(xy 43.77916 -316.970923) (xy 43.748939 -317.012519) (xy 43.712583 -317.048875) (xy 43.670987 -317.079096)
			(xy 43.625175 -317.102439) (xy 43.576276 -317.118327) (xy 43.525494 -317.12637) (xy 43.474078 -317.12637)
			(xy 43.423296 -317.118327) (xy 43.374397 -317.102439) (xy 43.328585 -317.079096) (xy 43.286989 -317.048875)
			(xy 43.250633 -317.012519) (xy 43.220412 -316.970923) (xy 43.197069 -316.925111) (xy 43.181181 -316.876212)
			(xy 43.173138 -316.82543) (xy 41.926514 -316.82543) (xy 41.918471 -316.876212) (xy 41.902583 -316.925111)
			(xy 41.87924 -316.970923) (xy 41.849019 -317.012519) (xy 41.812663 -317.048875) (xy 41.771067 -317.079096)
			(xy 41.725255 -317.102439) (xy 41.676356 -317.118327) (xy 41.625574 -317.12637) (xy 41.574158 -317.12637)
			(xy 41.523376 -317.118327) (xy 41.474477 -317.102439) (xy 41.428665 -317.079096) (xy 41.387069 -317.048875)
			(xy 41.350713 -317.012519) (xy 41.320492 -316.970923) (xy 41.297149 -316.925111) (xy 41.281261 -316.876212)
			(xy 41.273218 -316.82543) (xy 40.026594 -316.82543) (xy 40.018551 -316.876212) (xy 40.002663 -316.925111)
			(xy 39.97932 -316.970923) (xy 39.949099 -317.012519) (xy 39.912743 -317.048875) (xy 39.871147 -317.079096)
			(xy 39.825335 -317.102439) (xy 39.776436 -317.118327) (xy 39.725654 -317.12637) (xy 39.674238 -317.12637)
			(xy 39.623456 -317.118327) (xy 39.574557 -317.102439) (xy 39.528745 -317.079096) (xy 39.487149 -317.048875)
			(xy 39.450793 -317.012519) (xy 39.420572 -316.970923) (xy 39.397229 -316.925111) (xy 39.381341 -316.876212)
			(xy 39.373298 -316.82543) (xy 38.12642 -316.82543) (xy 38.118377 -316.876212) (xy 38.102489 -316.925111)
			(xy 38.079146 -316.970923) (xy 38.048925 -317.012519) (xy 38.012569 -317.048875) (xy 37.970973 -317.079096)
			(xy 37.925161 -317.102439) (xy 37.876262 -317.118327) (xy 37.82548 -317.12637) (xy 37.774064 -317.12637)
			(xy 37.723282 -317.118327) (xy 37.674383 -317.102439) (xy 37.628571 -317.079096) (xy 37.586975 -317.048875)
			(xy 37.550619 -317.012519) (xy 37.520398 -316.970923) (xy 37.497055 -316.925111) (xy 37.481167 -316.876212)
			(xy 37.473124 -316.82543) (xy 37.17646 -316.82543) (xy 37.168417 -316.876212) (xy 37.152529 -316.925111)
			(xy 37.129186 -316.970923) (xy 37.098965 -317.012519) (xy 37.062609 -317.048875) (xy 37.021013 -317.079096)
			(xy 36.975201 -317.102439) (xy 36.926302 -317.118327) (xy 36.87552 -317.12637) (xy 36.824104 -317.12637)
			(xy 36.773322 -317.118327) (xy 36.724423 -317.102439) (xy 36.678611 -317.079096) (xy 36.637015 -317.048875)
			(xy 36.600659 -317.012519) (xy 36.570438 -316.970923) (xy 36.547095 -316.925111) (xy 36.531207 -316.876212)
			(xy 36.523164 -316.82543) (xy 17.887188 -316.82543) (xy 17.887188 -316.983364) (xy 17.887442 -316.983618)
			(xy 17.887442 -317.775644) (xy 38.423338 -317.775644) (xy 38.423338 -317.724228) (xy 38.431381 -317.673446)
			(xy 38.447269 -317.624547) (xy 38.470612 -317.578735) (xy 38.500833 -317.537139) (xy 38.537189 -317.500783)
			(xy 38.578785 -317.470562) (xy 38.624597 -317.447219) (xy 38.673496 -317.431331) (xy 38.724278 -317.423288)
			(xy 38.775694 -317.423288) (xy 38.826476 -317.431331) (xy 38.875375 -317.447219) (xy 38.921187 -317.470562)
			(xy 38.962783 -317.500783) (xy 38.999139 -317.537139) (xy 39.02936 -317.578735) (xy 39.052703 -317.624547)
			(xy 39.068591 -317.673446) (xy 39.076634 -317.724228) (xy 39.077138 -317.749936) (xy 39.076634 -317.775644)
			(xy 40.323258 -317.775644) (xy 40.323258 -317.724228) (xy 40.331301 -317.673446) (xy 40.347189 -317.624547)
			(xy 40.370532 -317.578735) (xy 40.400753 -317.537139) (xy 40.437109 -317.500783) (xy 40.478705 -317.470562)
			(xy 40.524517 -317.447219) (xy 40.573416 -317.431331) (xy 40.624198 -317.423288) (xy 40.675614 -317.423288)
			(xy 40.726396 -317.431331) (xy 40.775295 -317.447219) (xy 40.821107 -317.470562) (xy 40.862703 -317.500783)
			(xy 40.899059 -317.537139) (xy 40.92928 -317.578735) (xy 40.952623 -317.624547) (xy 40.968511 -317.673446)
			(xy 40.976554 -317.724228) (xy 40.977058 -317.749936) (xy 40.976554 -317.775644) (xy 42.223178 -317.775644)
			(xy 42.223178 -317.724228) (xy 42.231221 -317.673446) (xy 42.247109 -317.624547) (xy 42.270452 -317.578735)
			(xy 42.300673 -317.537139) (xy 42.337029 -317.500783) (xy 42.378625 -317.470562) (xy 42.424437 -317.447219)
			(xy 42.473336 -317.431331) (xy 42.524118 -317.423288) (xy 42.575534 -317.423288) (xy 42.626316 -317.431331)
			(xy 42.675215 -317.447219) (xy 42.721027 -317.470562) (xy 42.762623 -317.500783) (xy 42.798979 -317.537139)
			(xy 42.8292 -317.578735) (xy 42.852543 -317.624547) (xy 42.868431 -317.673446) (xy 42.876474 -317.724228)
			(xy 42.876978 -317.749936) (xy 42.876474 -317.775644) (xy 44.123098 -317.775644) (xy 44.123098 -317.724228)
			(xy 44.131141 -317.673446) (xy 44.147029 -317.624547) (xy 44.170372 -317.578735) (xy 44.200593 -317.537139)
			(xy 44.236949 -317.500783) (xy 44.278545 -317.470562) (xy 44.324357 -317.447219) (xy 44.373256 -317.431331)
			(xy 44.424038 -317.423288) (xy 44.475454 -317.423288) (xy 44.526236 -317.431331) (xy 44.575135 -317.447219)
			(xy 44.620947 -317.470562) (xy 44.662543 -317.500783) (xy 44.698899 -317.537139) (xy 44.72912 -317.578735)
			(xy 44.752463 -317.624547) (xy 44.768351 -317.673446) (xy 44.776394 -317.724228) (xy 44.776898 -317.749936)
			(xy 44.776394 -317.775644) (xy 46.023272 -317.775644) (xy 46.023272 -317.724228) (xy 46.031315 -317.673446)
			(xy 46.047203 -317.624547) (xy 46.070546 -317.578735) (xy 46.100767 -317.537139) (xy 46.137123 -317.500783)
			(xy 46.178719 -317.470562) (xy 46.224531 -317.447219) (xy 46.27343 -317.431331) (xy 46.324212 -317.423288)
			(xy 46.375628 -317.423288) (xy 46.42641 -317.431331) (xy 46.475309 -317.447219) (xy 46.521121 -317.470562)
			(xy 46.562717 -317.500783) (xy 46.599073 -317.537139) (xy 46.629294 -317.578735) (xy 46.652637 -317.624547)
			(xy 46.668525 -317.673446) (xy 46.676568 -317.724228) (xy 46.677072 -317.749936) (xy 46.676568 -317.775644)
			(xy 46.668525 -317.826426) (xy 46.652637 -317.875325) (xy 46.629294 -317.921137) (xy 46.599073 -317.962733)
			(xy 46.562717 -317.999089) (xy 46.521121 -318.02931) (xy 46.475309 -318.052653) (xy 46.42641 -318.068541)
			(xy 46.375628 -318.076584) (xy 46.324212 -318.076584) (xy 46.27343 -318.068541) (xy 46.224531 -318.052653)
			(xy 46.178719 -318.02931) (xy 46.137123 -317.999089) (xy 46.100767 -317.962733) (xy 46.070546 -317.921137)
			(xy 46.047203 -317.875325) (xy 46.031315 -317.826426) (xy 46.023272 -317.775644) (xy 44.776394 -317.775644)
			(xy 44.768351 -317.826426) (xy 44.752463 -317.875325) (xy 44.72912 -317.921137) (xy 44.698899 -317.962733)
			(xy 44.662543 -317.999089) (xy 44.620947 -318.02931) (xy 44.575135 -318.052653) (xy 44.526236 -318.068541)
			(xy 44.475454 -318.076584) (xy 44.424038 -318.076584) (xy 44.373256 -318.068541) (xy 44.324357 -318.052653)
			(xy 44.278545 -318.02931) (xy 44.236949 -317.999089) (xy 44.200593 -317.962733) (xy 44.170372 -317.921137)
			(xy 44.147029 -317.875325) (xy 44.131141 -317.826426) (xy 44.123098 -317.775644) (xy 42.876474 -317.775644)
			(xy 42.868431 -317.826426) (xy 42.852543 -317.875325) (xy 42.8292 -317.921137) (xy 42.798979 -317.962733)
			(xy 42.762623 -317.999089) (xy 42.721027 -318.02931) (xy 42.675215 -318.052653) (xy 42.626316 -318.068541)
			(xy 42.575534 -318.076584) (xy 42.524118 -318.076584) (xy 42.473336 -318.068541) (xy 42.424437 -318.052653)
			(xy 42.378625 -318.02931) (xy 42.337029 -317.999089) (xy 42.300673 -317.962733) (xy 42.270452 -317.921137)
			(xy 42.247109 -317.875325) (xy 42.231221 -317.826426) (xy 42.223178 -317.775644) (xy 40.976554 -317.775644)
			(xy 40.968511 -317.826426) (xy 40.952623 -317.875325) (xy 40.92928 -317.921137) (xy 40.899059 -317.962733)
			(xy 40.862703 -317.999089) (xy 40.821107 -318.02931) (xy 40.775295 -318.052653) (xy 40.726396 -318.068541)
			(xy 40.675614 -318.076584) (xy 40.624198 -318.076584) (xy 40.573416 -318.068541) (xy 40.524517 -318.052653)
			(xy 40.478705 -318.02931) (xy 40.437109 -317.999089) (xy 40.400753 -317.962733) (xy 40.370532 -317.921137)
			(xy 40.347189 -317.875325) (xy 40.331301 -317.826426) (xy 40.323258 -317.775644) (xy 39.076634 -317.775644)
			(xy 39.068591 -317.826426) (xy 39.052703 -317.875325) (xy 39.02936 -317.921137) (xy 38.999139 -317.962733)
			(xy 38.962783 -317.999089) (xy 38.921187 -318.02931) (xy 38.875375 -318.052653) (xy 38.826476 -318.068541)
			(xy 38.775694 -318.076584) (xy 38.724278 -318.076584) (xy 38.673496 -318.068541) (xy 38.624597 -318.052653)
			(xy 38.578785 -318.02931) (xy 38.537189 -317.999089) (xy 38.500833 -317.962733) (xy 38.470612 -317.921137)
			(xy 38.447269 -317.875325) (xy 38.431381 -317.826426) (xy 38.423338 -317.775644) (xy 17.887442 -317.775644)
			(xy 17.887442 -319.322958) (xy 17.887007 -319.333022) (xy 17.879271 -319.351606) (xy 17.872456 -319.359026)
			(xy 17.742916 -319.488566) (xy 17.735515 -319.495403) (xy 17.716916 -319.503112) (xy 17.706848 -319.503552)
			(xy 1.15062 -319.503552) (xy 1.152398 -319.541144) (xy 1.151912 -319.568395) (xy 1.144156 -319.622343)
			(xy 1.128801 -319.674638) (xy 1.106159 -319.724215) (xy 1.076693 -319.770065) (xy 1.041002 -319.811256)
			(xy 0.999811 -319.846947) (xy 0.953961 -319.876413) (xy 0.904384 -319.899055) (xy 0.852089 -319.91441)
			(xy 0.798141 -319.922166) (xy 0.77089 -319.922652) (xy 0.746222 -319.922266) (xy 0.697298 -319.915896)
			(xy 0.673354 -319.909952) (xy 0.664247 -319.907978) (xy 0.645735 -319.909976) (xy 0.629158 -319.918453)
			(xy 0.616702 -319.932291) (xy 0.610009 -319.949666) (xy 0.6096 -319.958974) (xy 0.6096 -320.900044)
			(xy 26.882353 -320.900044) (xy 26.886342 -320.751504) (xy 26.898299 -320.603391) (xy 26.918189 -320.456134)
			(xy 26.945954 -320.310158) (xy 26.981515 -320.165881) (xy 27.024769 -320.023722) (xy 27.075591 -319.884089)
			(xy 27.133835 -319.747386) (xy 27.199333 -319.614006) (xy 27.271896 -319.484334) (xy 27.351314 -319.358744)
			(xy 27.437359 -319.237597) (xy 27.529783 -319.121244) (xy 27.628319 -319.01002) (xy 27.732683 -318.904245)
			(xy 27.842575 -318.804225) (xy 27.957676 -318.710247) (xy 28.077656 -318.622583) (xy 28.202169 -318.541486)
			(xy 28.330855 -318.467189) (xy 28.463344 -318.399907) (xy 28.599253 -318.339833) (xy 28.738191 -318.287141)
			(xy 28.879757 -318.241982) (xy 29.023543 -318.204487) (xy 29.169134 -318.174765) (xy 29.31611 -318.1529)
			(xy 29.464049 -318.138956) (xy 29.612522 -318.132972) (xy 29.761103 -318.134967) (xy 29.909362 -318.144935)
			(xy 30.056873 -318.162846) (xy 30.203209 -318.188649) (xy 30.34795 -318.222269) (xy 30.490677 -318.263611)
			(xy 30.63098 -318.312554) (xy 30.768453 -318.368957) (xy 30.9027 -318.432658) (xy 31.033335 -318.503474)
			(xy 31.15998 -318.581199) (xy 31.28227 -318.66561) (xy 31.359915 -318.725604) (xy 38.423338 -318.725604)
			(xy 38.423338 -318.674188) (xy 38.431381 -318.623406) (xy 38.447269 -318.574507) (xy 38.470612 -318.528695)
			(xy 38.500833 -318.487099) (xy 38.537189 -318.450743) (xy 38.578785 -318.420522) (xy 38.624597 -318.397179)
			(xy 38.673496 -318.381291) (xy 38.724278 -318.373248) (xy 38.775694 -318.373248) (xy 38.826476 -318.381291)
			(xy 38.875375 -318.397179) (xy 38.921187 -318.420522) (xy 38.962783 -318.450743) (xy 38.999139 -318.487099)
			(xy 39.02936 -318.528695) (xy 39.052703 -318.574507) (xy 39.068591 -318.623406) (xy 39.076634 -318.674188)
			(xy 39.077138 -318.699896) (xy 39.076634 -318.725604) (xy 40.323258 -318.725604) (xy 40.323258 -318.674188)
			(xy 40.331301 -318.623406) (xy 40.347189 -318.574507) (xy 40.370532 -318.528695) (xy 40.400753 -318.487099)
			(xy 40.437109 -318.450743) (xy 40.478705 -318.420522) (xy 40.524517 -318.397179) (xy 40.573416 -318.381291)
			(xy 40.624198 -318.373248) (xy 40.675614 -318.373248) (xy 40.726396 -318.381291) (xy 40.775295 -318.397179)
			(xy 40.821107 -318.420522) (xy 40.862703 -318.450743) (xy 40.899059 -318.487099) (xy 40.92928 -318.528695)
			(xy 40.952623 -318.574507) (xy 40.968511 -318.623406) (xy 40.976554 -318.674188) (xy 40.977058 -318.699896)
			(xy 40.976554 -318.725604) (xy 42.223178 -318.725604) (xy 42.223178 -318.674188) (xy 42.231221 -318.623406)
			(xy 42.247109 -318.574507) (xy 42.270452 -318.528695) (xy 42.300673 -318.487099) (xy 42.337029 -318.450743)
			(xy 42.378625 -318.420522) (xy 42.424437 -318.397179) (xy 42.473336 -318.381291) (xy 42.524118 -318.373248)
			(xy 42.575534 -318.373248) (xy 42.626316 -318.381291) (xy 42.675215 -318.397179) (xy 42.721027 -318.420522)
			(xy 42.762623 -318.450743) (xy 42.798979 -318.487099) (xy 42.8292 -318.528695) (xy 42.852543 -318.574507)
			(xy 42.868431 -318.623406) (xy 42.876474 -318.674188) (xy 42.876978 -318.699896) (xy 42.876474 -318.725604)
			(xy 44.123098 -318.725604) (xy 44.123098 -318.674188) (xy 44.131141 -318.623406) (xy 44.147029 -318.574507)
			(xy 44.170372 -318.528695) (xy 44.200593 -318.487099) (xy 44.236949 -318.450743) (xy 44.278545 -318.420522)
			(xy 44.324357 -318.397179) (xy 44.373256 -318.381291) (xy 44.424038 -318.373248) (xy 44.475454 -318.373248)
			(xy 44.526236 -318.381291) (xy 44.575135 -318.397179) (xy 44.620947 -318.420522) (xy 44.662543 -318.450743)
			(xy 44.698899 -318.487099) (xy 44.72912 -318.528695) (xy 44.752463 -318.574507) (xy 44.768351 -318.623406)
			(xy 44.776394 -318.674188) (xy 44.776898 -318.699896) (xy 44.776394 -318.725604) (xy 46.023272 -318.725604)
			(xy 46.023272 -318.674188) (xy 46.031315 -318.623406) (xy 46.047203 -318.574507) (xy 46.070546 -318.528695)
			(xy 46.100767 -318.487099) (xy 46.137123 -318.450743) (xy 46.178719 -318.420522) (xy 46.224531 -318.397179)
			(xy 46.27343 -318.381291) (xy 46.324212 -318.373248) (xy 46.375628 -318.373248) (xy 46.42641 -318.381291)
			(xy 46.475309 -318.397179) (xy 46.521121 -318.420522) (xy 46.562717 -318.450743) (xy 46.599073 -318.487099)
			(xy 46.629294 -318.528695) (xy 46.652637 -318.574507) (xy 46.668525 -318.623406) (xy 46.676568 -318.674188)
			(xy 46.677072 -318.699896) (xy 46.676568 -318.725604) (xy 47.923192 -318.725604) (xy 47.923192 -318.674188)
			(xy 47.931235 -318.623406) (xy 47.947123 -318.574507) (xy 47.970466 -318.528695) (xy 48.000687 -318.487099)
			(xy 48.037043 -318.450743) (xy 48.078639 -318.420522) (xy 48.124451 -318.397179) (xy 48.17335 -318.381291)
			(xy 48.224132 -318.373248) (xy 48.275548 -318.373248) (xy 48.32633 -318.381291) (xy 48.375229 -318.397179)
			(xy 48.421041 -318.420522) (xy 48.462637 -318.450743) (xy 48.498993 -318.487099) (xy 48.529214 -318.528695)
			(xy 48.552557 -318.574507) (xy 48.568445 -318.623406) (xy 48.576488 -318.674188) (xy 48.576992 -318.699896)
			(xy 48.576488 -318.725604) (xy 48.568445 -318.776386) (xy 48.552557 -318.825285) (xy 48.529214 -318.871097)
			(xy 48.498993 -318.912693) (xy 48.462637 -318.949049) (xy 48.421041 -318.97927) (xy 48.375229 -319.002613)
			(xy 48.32633 -319.018501) (xy 48.275548 -319.026544) (xy 48.224132 -319.026544) (xy 48.17335 -319.018501)
			(xy 48.124451 -319.002613) (xy 48.078639 -318.97927) (xy 48.037043 -318.949049) (xy 48.000687 -318.912693)
			(xy 47.970466 -318.871097) (xy 47.947123 -318.825285) (xy 47.931235 -318.776386) (xy 47.923192 -318.725604)
			(xy 46.676568 -318.725604) (xy 46.668525 -318.776386) (xy 46.652637 -318.825285) (xy 46.629294 -318.871097)
			(xy 46.599073 -318.912693) (xy 46.562717 -318.949049) (xy 46.521121 -318.97927) (xy 46.475309 -319.002613)
			(xy 46.42641 -319.018501) (xy 46.375628 -319.026544) (xy 46.324212 -319.026544) (xy 46.27343 -319.018501)
			(xy 46.224531 -319.002613) (xy 46.178719 -318.97927) (xy 46.137123 -318.949049) (xy 46.100767 -318.912693)
			(xy 46.070546 -318.871097) (xy 46.047203 -318.825285) (xy 46.031315 -318.776386) (xy 46.023272 -318.725604)
			(xy 44.776394 -318.725604) (xy 44.768351 -318.776386) (xy 44.752463 -318.825285) (xy 44.72912 -318.871097)
			(xy 44.698899 -318.912693) (xy 44.662543 -318.949049) (xy 44.620947 -318.97927) (xy 44.575135 -319.002613)
			(xy 44.526236 -319.018501) (xy 44.475454 -319.026544) (xy 44.424038 -319.026544) (xy 44.373256 -319.018501)
			(xy 44.324357 -319.002613) (xy 44.278545 -318.97927) (xy 44.236949 -318.949049) (xy 44.200593 -318.912693)
			(xy 44.170372 -318.871097) (xy 44.147029 -318.825285) (xy 44.131141 -318.776386) (xy 44.123098 -318.725604)
			(xy 42.876474 -318.725604) (xy 42.868431 -318.776386) (xy 42.852543 -318.825285) (xy 42.8292 -318.871097)
			(xy 42.798979 -318.912693) (xy 42.762623 -318.949049) (xy 42.721027 -318.97927) (xy 42.675215 -319.002613)
			(xy 42.626316 -319.018501) (xy 42.575534 -319.026544) (xy 42.524118 -319.026544) (xy 42.473336 -319.018501)
			(xy 42.424437 -319.002613) (xy 42.378625 -318.97927) (xy 42.337029 -318.949049) (xy 42.300673 -318.912693)
			(xy 42.270452 -318.871097) (xy 42.247109 -318.825285) (xy 42.231221 -318.776386) (xy 42.223178 -318.725604)
			(xy 40.976554 -318.725604) (xy 40.968511 -318.776386) (xy 40.952623 -318.825285) (xy 40.92928 -318.871097)
			(xy 40.899059 -318.912693) (xy 40.862703 -318.949049) (xy 40.821107 -318.97927) (xy 40.775295 -319.002613)
			(xy 40.726396 -319.018501) (xy 40.675614 -319.026544) (xy 40.624198 -319.026544) (xy 40.573416 -319.018501)
			(xy 40.524517 -319.002613) (xy 40.478705 -318.97927) (xy 40.437109 -318.949049) (xy 40.400753 -318.912693)
			(xy 40.370532 -318.871097) (xy 40.347189 -318.825285) (xy 40.331301 -318.776386) (xy 40.323258 -318.725604)
			(xy 39.076634 -318.725604) (xy 39.068591 -318.776386) (xy 39.052703 -318.825285) (xy 39.02936 -318.871097)
			(xy 38.999139 -318.912693) (xy 38.962783 -318.949049) (xy 38.921187 -318.97927) (xy 38.875375 -319.002613)
			(xy 38.826476 -319.018501) (xy 38.775694 -319.026544) (xy 38.724278 -319.026544) (xy 38.673496 -319.018501)
			(xy 38.624597 -319.002613) (xy 38.578785 -318.97927) (xy 38.537189 -318.949049) (xy 38.500833 -318.912693)
			(xy 38.470612 -318.871097) (xy 38.447269 -318.825285) (xy 38.431381 -318.776386) (xy 38.423338 -318.725604)
			(xy 31.359915 -318.725604) (xy 31.399853 -318.756463) (xy 31.51239 -318.853497) (xy 31.619557 -318.956432)
			(xy 31.721044 -319.064971) (xy 31.816558 -319.1788) (xy 31.905825 -319.297593) (xy 31.988586 -319.421005)
			(xy 32.064604 -319.548683) (xy 32.133659 -319.680256) (xy 32.195552 -319.815347) (xy 32.250105 -319.953564)
			(xy 32.29716 -320.094511) (xy 32.336582 -320.237781) (xy 32.368256 -320.38296) (xy 32.392092 -320.529629)
			(xy 32.408021 -320.677367) (xy 32.415997 -320.825747) (xy 32.416496 -320.900044) (xy 32.415997 -320.974341)
			(xy 32.408021 -321.122721) (xy 32.392092 -321.270459) (xy 32.368256 -321.417128) (xy 32.336582 -321.562307)
			(xy 32.29716 -321.705577) (xy 32.250105 -321.846524) (xy 32.195552 -321.984741) (xy 32.133659 -322.119832)
			(xy 32.064604 -322.251405) (xy 31.988586 -322.379083) (xy 31.905825 -322.502495) (xy 31.816558 -322.621288)
			(xy 31.721044 -322.735117) (xy 31.619557 -322.843656) (xy 31.51239 -322.946591) (xy 31.399853 -323.043625)
			(xy 31.28227 -323.134478) (xy 31.15998 -323.218889) (xy 31.033335 -323.296614) (xy 30.9027 -323.36743)
			(xy 30.768453 -323.431131) (xy 30.63098 -323.487534) (xy 30.490677 -323.536477) (xy 30.34795 -323.577819)
			(xy 30.203209 -323.611439) (xy 30.056873 -323.637242) (xy 29.909362 -323.655153) (xy 29.761103 -323.665121)
			(xy 29.612522 -323.667116) (xy 29.464049 -323.661132) (xy 29.31611 -323.647188) (xy 29.169134 -323.625323)
			(xy 29.023543 -323.595601) (xy 28.879757 -323.558106) (xy 28.738191 -323.512947) (xy 28.599253 -323.460255)
			(xy 28.463344 -323.400181) (xy 28.330855 -323.332899) (xy 28.202169 -323.258602) (xy 28.077656 -323.177505)
			(xy 27.957676 -323.089841) (xy 27.842575 -322.995863) (xy 27.732683 -322.895843) (xy 27.628319 -322.790068)
			(xy 27.529783 -322.678844) (xy 27.437359 -322.562491) (xy 27.351314 -322.441344) (xy 27.271896 -322.315754)
			(xy 27.199333 -322.186082) (xy 27.133835 -322.052702) (xy 27.075591 -321.915999) (xy 27.024769 -321.776366)
			(xy 26.981515 -321.634207) (xy 26.945954 -321.48993) (xy 26.918189 -321.343954) (xy 26.898299 -321.196697)
			(xy 26.886342 -321.048584) (xy 26.882353 -320.900044) (xy 0.6096 -320.900044) (xy 0.6096 -323.153278)
			(xy 14.462504 -323.153278) (xy 14.466575 -323.097656) (xy 14.478701 -323.043219) (xy 14.498624 -322.991128)
			(xy 14.52592 -322.942493) (xy 14.560006 -322.89835) (xy 14.600155 -322.859641) (xy 14.645513 -322.82719)
			(xy 14.695113 -322.801689) (xy 14.747897 -322.783682) (xy 14.80274 -322.773552) (xy 14.858474 -322.771515)
			(xy 14.913911 -322.777615) (xy 14.967868 -322.791721) (xy 15.019197 -322.813533) (xy 15.066803 -322.842587)
			(xy 15.109671 -322.878262) (xy 15.146888 -322.919799) (xy 15.177661 -322.966312) (xy 15.201333 -323.016809)
			(xy 15.217401 -323.070216) (xy 15.225521 -323.125392) (xy 15.22603 -323.153278) (xy 15.225521 -323.181164)
			(xy 15.217401 -323.23634) (xy 15.201333 -323.289747) (xy 15.177661 -323.340244) (xy 15.146888 -323.386757)
			(xy 15.109671 -323.428294) (xy 15.066803 -323.463969) (xy 15.019197 -323.493023) (xy 14.967868 -323.514835)
			(xy 14.913911 -323.528941) (xy 14.858474 -323.535041) (xy 14.80274 -323.533004) (xy 14.747897 -323.522874)
			(xy 14.695113 -323.504867) (xy 14.645513 -323.479366) (xy 14.600155 -323.446915) (xy 14.560006 -323.408206)
			(xy 14.52592 -323.364063) (xy 14.498624 -323.315428) (xy 14.478701 -323.263337) (xy 14.466575 -323.2089)
			(xy 14.462504 -323.153278) (xy 0.6096 -323.153278) (xy 0.6096 -341.292688) (xy 11.713716 -341.292688)
			(xy 11.717787 -341.237066) (xy 11.729913 -341.182629) (xy 11.749836 -341.130538) (xy 11.777132 -341.081903)
			(xy 11.811218 -341.03776) (xy 11.851367 -340.999051) (xy 11.896725 -340.9666) (xy 11.946325 -340.941099)
			(xy 11.999109 -340.923092) (xy 12.053952 -340.912962) (xy 12.109686 -340.910925) (xy 12.165123 -340.917025)
			(xy 12.21908 -340.931131) (xy 12.270409 -340.952943) (xy 12.318015 -340.981997) (xy 12.360883 -341.017672)
			(xy 12.3981 -341.059209) (xy 12.428873 -341.105722) (xy 12.452545 -341.156219) (xy 12.468613 -341.209626)
			(xy 12.476733 -341.264802) (xy 12.477242 -341.292688) (xy 12.476733 -341.320574) (xy 12.468613 -341.37575)
			(xy 12.452545 -341.429157) (xy 12.428873 -341.479654) (xy 12.3981 -341.526167) (xy 12.360883 -341.567704)
			(xy 12.318015 -341.603379) (xy 12.270409 -341.632433) (xy 12.21908 -341.654245) (xy 12.165123 -341.668351)
			(xy 12.109686 -341.674451) (xy 12.053952 -341.672414) (xy 11.999109 -341.662284) (xy 11.946325 -341.644277)
			(xy 11.896725 -341.618776) (xy 11.851367 -341.586325) (xy 11.811218 -341.547616) (xy 11.777132 -341.503473)
			(xy 11.749836 -341.454838) (xy 11.729913 -341.402747) (xy 11.717787 -341.34831) (xy 11.713716 -341.292688)
			(xy 0.6096 -341.292688) (xy 0.6096 -342.466769) (xy 18.951172 -342.466769) (xy 18.951172 -342.412231)
			(xy 18.958934 -342.358247) (xy 18.974299 -342.305917) (xy 18.996956 -342.256307) (xy 19.026441 -342.210426)
			(xy 19.062157 -342.169208) (xy 19.103374 -342.133493) (xy 19.149255 -342.104007) (xy 19.198865 -342.08135)
			(xy 19.251195 -342.065985) (xy 19.305179 -342.058223) (xy 19.332448 -342.057736) (xy 20.196048 -342.057736)
			(xy 20.223319 -342.058203) (xy 20.277306 -342.065965) (xy 20.329638 -342.081331) (xy 20.379252 -342.103989)
			(xy 20.425135 -342.133476) (xy 20.466355 -342.169193) (xy 20.502073 -342.210413) (xy 20.53156 -342.256297)
			(xy 20.554218 -342.30591) (xy 20.569584 -342.358242) (xy 20.577347 -342.412229) (xy 20.577347 -342.466771)
			(xy 20.577347 -342.466772) (xy 22.0601 -342.466772) (xy 22.0601 -342.412228) (xy 22.067862 -342.358241)
			(xy 22.083229 -342.305907) (xy 22.105887 -342.256293) (xy 22.135375 -342.210409) (xy 22.171094 -342.169188)
			(xy 22.212315 -342.133471) (xy 22.2582 -342.103983) (xy 22.307815 -342.081326) (xy 22.360148 -342.06596)
			(xy 22.414136 -342.058199) (xy 22.441408 -342.057736) (xy 23.305008 -342.057736) (xy 23.332277 -342.058227)
			(xy 23.386259 -342.06599) (xy 23.438588 -342.081355) (xy 23.488197 -342.104012) (xy 23.534076 -342.133498)
			(xy 23.575293 -342.169213) (xy 23.611007 -342.21043) (xy 23.640492 -342.256311) (xy 23.663147 -342.30592)
			(xy 23.678512 -342.358249) (xy 23.686274 -342.412231) (xy 23.686274 -342.466768) (xy 25.169122 -342.466768)
			(xy 25.169122 -342.412232) (xy 25.176883 -342.358251) (xy 25.192247 -342.305924) (xy 25.214901 -342.256315)
			(xy 25.244384 -342.210436) (xy 25.280096 -342.169219) (xy 25.32131 -342.133503) (xy 25.367187 -342.104016)
			(xy 25.416794 -342.081358) (xy 25.46912 -342.06599) (xy 25.5231 -342.058225) (xy 25.550368 -342.057736)
			(xy 26.413968 -342.057736) (xy 26.44124 -342.058201) (xy 26.49523 -342.06596) (xy 26.547567 -342.081323)
			(xy 26.597184 -342.103979) (xy 26.643071 -342.133465) (xy 26.684295 -342.169183) (xy 26.720015 -342.210403)
			(xy 26.749506 -342.256288) (xy 26.772166 -342.305903) (xy 26.787533 -342.358238) (xy 26.795296 -342.412228)
			(xy 26.795296 -342.466772) (xy 28.278 -342.466772) (xy 28.278 -342.412228) (xy 28.285762 -342.358238)
			(xy 28.30113 -342.305903) (xy 28.32379 -342.256288) (xy 28.35328 -342.210402) (xy 28.389001 -342.169181)
			(xy 28.430225 -342.133464) (xy 28.476112 -342.103977) (xy 28.525729 -342.08132) (xy 28.578065 -342.065957)
			(xy 28.632056 -342.058198) (xy 28.659328 -342.057736) (xy 29.522928 -342.057736) (xy 29.550196 -342.058228)
			(xy 29.604176 -342.065993) (xy 29.656502 -342.081361) (xy 29.706109 -342.104019) (xy 29.751986 -342.133505)
			(xy 29.7932 -342.16922) (xy 29.828912 -342.210437) (xy 29.858395 -342.256316) (xy 29.881049 -342.305924)
			(xy 29.896413 -342.358251) (xy 29.904174 -342.412232) (xy 29.904174 -342.466768) (xy 29.904174 -342.466769)
			(xy 31.387022 -342.466769) (xy 31.387022 -342.412231) (xy 31.394784 -342.358248) (xy 31.410149 -342.305919)
			(xy 31.432804 -342.25631) (xy 31.462289 -342.210429) (xy 31.498003 -342.169212) (xy 31.53922 -342.133496)
			(xy 31.585099 -342.10401) (xy 31.634708 -342.081353) (xy 31.687036 -342.065986) (xy 31.741019 -342.058223)
			(xy 31.768288 -342.057736) (xy 32.631888 -342.057736) (xy 32.659159 -342.058203) (xy 32.713147 -342.065963)
			(xy 32.765481 -342.081329) (xy 32.815096 -342.103985) (xy 32.86098 -342.133472) (xy 32.902202 -342.16919)
			(xy 32.93792 -342.21041) (xy 32.967409 -342.256294) (xy 32.990067 -342.305908) (xy 33.005434 -342.358241)
			(xy 33.013196 -342.412229) (xy 33.013196 -342.466771) (xy 33.013196 -342.466773) (xy 34.4959 -342.466773)
			(xy 34.4959 -342.412227) (xy 34.503663 -342.358235) (xy 34.519032 -342.305899) (xy 34.541693 -342.256282)
			(xy 34.571185 -342.210396) (xy 34.606908 -342.169174) (xy 34.648134 -342.133456) (xy 34.694024 -342.10397)
			(xy 34.743644 -342.081315) (xy 34.795982 -342.065953) (xy 34.849975 -342.058196) (xy 34.877248 -342.057736)
			(xy 35.740848 -342.057736) (xy 35.768115 -342.05823) (xy 35.822093 -342.065997) (xy 35.874417 -342.081366)
			(xy 35.92402 -342.104025) (xy 35.969895 -342.133512) (xy 36.011107 -342.169227) (xy 36.046817 -342.210443)
			(xy 36.076298 -342.256322) (xy 36.098951 -342.305928) (xy 36.114313 -342.358254) (xy 36.122074 -342.412233)
			(xy 36.122074 -342.466767) (xy 36.122073 -342.466772) (xy 37.6049 -342.466772) (xy 37.6049 -342.412228)
			(xy 37.612662 -342.358241) (xy 37.628029 -342.305907) (xy 37.650687 -342.256293) (xy 37.680175 -342.210409)
			(xy 37.715894 -342.169188) (xy 37.757115 -342.133471) (xy 37.803 -342.103983) (xy 37.852615 -342.081326)
			(xy 37.904948 -342.06596) (xy 37.958936 -342.058199) (xy 37.986208 -342.057736) (xy 38.849808 -342.057736)
			(xy 38.877077 -342.058227) (xy 38.931059 -342.06599) (xy 38.983388 -342.081355) (xy 39.032997 -342.104012)
			(xy 39.078876 -342.133498) (xy 39.120093 -342.169213) (xy 39.155807 -342.21043) (xy 39.185292 -342.256311)
			(xy 39.207947 -342.30592) (xy 39.223312 -342.358249) (xy 39.231074 -342.412231) (xy 39.231074 -342.466768)
			(xy 40.713922 -342.466768) (xy 40.713922 -342.412232) (xy 40.721683 -342.358251) (xy 40.737047 -342.305924)
			(xy 40.759701 -342.256315) (xy 40.789184 -342.210436) (xy 40.824896 -342.169219) (xy 40.86611 -342.133503)
			(xy 40.911987 -342.104016) (xy 40.961594 -342.081358) (xy 41.01392 -342.06599) (xy 41.0679 -342.058225)
			(xy 41.095168 -342.057736) (xy 41.958768 -342.057736) (xy 41.98604 -342.058201) (xy 42.04003 -342.06596)
			(xy 42.092367 -342.081323) (xy 42.141984 -342.103979) (xy 42.187871 -342.133465) (xy 42.229095 -342.169183)
			(xy 42.264815 -342.210403) (xy 42.294306 -342.256288) (xy 42.316966 -342.305903) (xy 42.332333 -342.358238)
			(xy 42.340096 -342.412228) (xy 42.340096 -342.466772) (xy 43.8228 -342.466772) (xy 43.8228 -342.412228)
			(xy 43.830562 -342.358238) (xy 43.84593 -342.305903) (xy 43.86859 -342.256288) (xy 43.89808 -342.210402)
			(xy 43.933801 -342.169181) (xy 43.975025 -342.133464) (xy 44.020912 -342.103977) (xy 44.070529 -342.08132)
			(xy 44.122865 -342.065957) (xy 44.176856 -342.058198) (xy 44.204128 -342.057736) (xy 45.067728 -342.057736)
			(xy 45.094996 -342.058228) (xy 45.148976 -342.065993) (xy 45.201302 -342.081361) (xy 45.250909 -342.104019)
			(xy 45.296786 -342.133505) (xy 45.338 -342.16922) (xy 45.373712 -342.210437) (xy 45.403195 -342.256316)
			(xy 45.425849 -342.305924) (xy 45.441213 -342.358251) (xy 45.448974 -342.412232) (xy 45.448974 -342.466768)
			(xy 45.448974 -342.466769) (xy 46.931822 -342.466769) (xy 46.931822 -342.412231) (xy 46.939584 -342.358248)
			(xy 46.954949 -342.305919) (xy 46.977604 -342.25631) (xy 47.007089 -342.210429) (xy 47.042803 -342.169212)
			(xy 47.08402 -342.133496) (xy 47.129899 -342.10401) (xy 47.179508 -342.081353) (xy 47.231836 -342.065986)
			(xy 47.285819 -342.058223) (xy 47.313088 -342.057736) (xy 48.176688 -342.057736) (xy 48.203959 -342.058203)
			(xy 48.257947 -342.065963) (xy 48.310281 -342.081329) (xy 48.359896 -342.103985) (xy 48.40578 -342.133472)
			(xy 48.447002 -342.16919) (xy 48.48272 -342.21041) (xy 48.512209 -342.256294) (xy 48.534867 -342.305908)
			(xy 48.550234 -342.358241) (xy 48.557996 -342.412229) (xy 48.557996 -342.466771) (xy 48.557996 -342.466773)
			(xy 50.0407 -342.466773) (xy 50.0407 -342.412227) (xy 50.048463 -342.358235) (xy 50.063832 -342.305899)
			(xy 50.086493 -342.256282) (xy 50.115985 -342.210396) (xy 50.151708 -342.169174) (xy 50.192934 -342.133456)
			(xy 50.238824 -342.10397) (xy 50.288444 -342.081315) (xy 50.340782 -342.065953) (xy 50.394775 -342.058196)
			(xy 50.422048 -342.057736) (xy 51.285648 -342.057736) (xy 51.312915 -342.05823) (xy 51.366893 -342.065997)
			(xy 51.419217 -342.081366) (xy 51.46882 -342.104025) (xy 51.514695 -342.133512) (xy 51.555907 -342.169227)
			(xy 51.591617 -342.210443) (xy 51.621098 -342.256322) (xy 51.643751 -342.305928) (xy 51.659113 -342.358254)
			(xy 51.666874 -342.412233) (xy 51.666874 -342.466767) (xy 51.659113 -342.520746) (xy 51.643751 -342.573072)
			(xy 51.621098 -342.622678) (xy 51.591617 -342.668557) (xy 51.555907 -342.709773) (xy 51.514695 -342.745488)
			(xy 51.46882 -342.774975) (xy 51.419217 -342.797634) (xy 51.366893 -342.813003) (xy 51.312915 -342.82077)
			(xy 51.285648 -342.82126) (xy 50.422048 -342.82126) (xy 50.394775 -342.820804) (xy 50.340782 -342.813047)
			(xy 50.288444 -342.797685) (xy 50.238824 -342.77503) (xy 50.192934 -342.745544) (xy 50.151708 -342.709826)
			(xy 50.115985 -342.668604) (xy 50.086493 -342.622718) (xy 50.063832 -342.573101) (xy 50.048463 -342.520765)
			(xy 50.0407 -342.466773) (xy 48.557996 -342.466773) (xy 48.550234 -342.520759) (xy 48.534867 -342.573092)
			(xy 48.512209 -342.622706) (xy 48.48272 -342.66859) (xy 48.447002 -342.70981) (xy 48.40578 -342.745528)
			(xy 48.359896 -342.775015) (xy 48.310281 -342.797671) (xy 48.257947 -342.813037) (xy 48.203959 -342.820797)
			(xy 48.176688 -342.82126) (xy 47.313088 -342.82126) (xy 47.285819 -342.820777) (xy 47.231836 -342.813014)
			(xy 47.179508 -342.797647) (xy 47.129899 -342.77499) (xy 47.08402 -342.745504) (xy 47.042803 -342.709788)
			(xy 47.007089 -342.668571) (xy 46.977604 -342.62269) (xy 46.954949 -342.573081) (xy 46.939584 -342.520752)
			(xy 46.931822 -342.466769) (xy 45.448974 -342.466769) (xy 45.441213 -342.520749) (xy 45.425849 -342.573076)
			(xy 45.403195 -342.622684) (xy 45.373712 -342.668563) (xy 45.338 -342.70978) (xy 45.296786 -342.745495)
			(xy 45.250909 -342.774981) (xy 45.201302 -342.797639) (xy 45.148976 -342.813007) (xy 45.094996 -342.820772)
			(xy 45.067728 -342.82126) (xy 44.204128 -342.82126) (xy 44.176856 -342.820802) (xy 44.122865 -342.813043)
			(xy 44.070529 -342.79768) (xy 44.020912 -342.775023) (xy 43.975025 -342.745536) (xy 43.933801 -342.709819)
			(xy 43.89808 -342.668598) (xy 43.86859 -342.622712) (xy 43.84593 -342.573097) (xy 43.830562 -342.520762)
			(xy 43.8228 -342.466772) (xy 42.340096 -342.466772) (xy 42.332333 -342.520762) (xy 42.316966 -342.573097)
			(xy 42.294306 -342.622712) (xy 42.264815 -342.668597) (xy 42.229095 -342.709817) (xy 42.187871 -342.745535)
			(xy 42.141984 -342.775021) (xy 42.092367 -342.797677) (xy 42.04003 -342.81304) (xy 41.98604 -342.820799)
			(xy 41.958768 -342.82126) (xy 41.095168 -342.82126) (xy 41.0679 -342.820775) (xy 41.01392 -342.81301)
			(xy 40.961594 -342.797642) (xy 40.911987 -342.774984) (xy 40.86611 -342.745497) (xy 40.824896 -342.709781)
			(xy 40.789184 -342.668564) (xy 40.759701 -342.622685) (xy 40.737047 -342.573076) (xy 40.721683 -342.520749)
			(xy 40.713922 -342.466768) (xy 39.231074 -342.466768) (xy 39.231074 -342.466769) (xy 39.223312 -342.520751)
			(xy 39.207947 -342.57308) (xy 39.185292 -342.622689) (xy 39.155807 -342.66857) (xy 39.120093 -342.709787)
			(xy 39.078876 -342.745502) (xy 39.032997 -342.774988) (xy 38.983388 -342.797645) (xy 38.931059 -342.81301)
			(xy 38.877077 -342.820773) (xy 38.849808 -342.82126) (xy 37.986208 -342.82126) (xy 37.958936 -342.820801)
			(xy 37.904948 -342.81304) (xy 37.852615 -342.797674) (xy 37.803 -342.775017) (xy 37.757115 -342.745529)
			(xy 37.715894 -342.709812) (xy 37.680175 -342.668591) (xy 37.650687 -342.622707) (xy 37.628029 -342.573093)
			(xy 37.612662 -342.520759) (xy 37.6049 -342.466772) (xy 36.122073 -342.466772) (xy 36.114313 -342.520746)
			(xy 36.098951 -342.573072) (xy 36.076298 -342.622678) (xy 36.046817 -342.668557) (xy 36.011107 -342.709773)
			(xy 35.969895 -342.745488) (xy 35.92402 -342.774975) (xy 35.874417 -342.797634) (xy 35.822093 -342.813003)
			(xy 35.768115 -342.82077) (xy 35.740848 -342.82126) (xy 34.877248 -342.82126) (xy 34.849975 -342.820804)
			(xy 34.795982 -342.813047) (xy 34.743644 -342.797685) (xy 34.694024 -342.77503) (xy 34.648134 -342.745544)
			(xy 34.606908 -342.709826) (xy 34.571185 -342.668604) (xy 34.541693 -342.622718) (xy 34.519032 -342.573101)
			(xy 34.503663 -342.520765) (xy 34.4959 -342.466773) (xy 33.013196 -342.466773) (xy 33.005434 -342.520759)
			(xy 32.990067 -342.573092) (xy 32.967409 -342.622706) (xy 32.93792 -342.66859) (xy 32.902202 -342.70981)
			(xy 32.86098 -342.745528) (xy 32.815096 -342.775015) (xy 32.765481 -342.797671) (xy 32.713147 -342.813037)
			(xy 32.659159 -342.820797) (xy 32.631888 -342.82126) (xy 31.768288 -342.82126) (xy 31.741019 -342.820777)
			(xy 31.687036 -342.813014) (xy 31.634708 -342.797647) (xy 31.585099 -342.77499) (xy 31.53922 -342.745504)
			(xy 31.498003 -342.709788) (xy 31.462289 -342.668571) (xy 31.432804 -342.62269) (xy 31.410149 -342.573081)
			(xy 31.394784 -342.520752) (xy 31.387022 -342.466769) (xy 29.904174 -342.466769) (xy 29.896413 -342.520749)
			(xy 29.881049 -342.573076) (xy 29.858395 -342.622684) (xy 29.828912 -342.668563) (xy 29.7932 -342.70978)
			(xy 29.751986 -342.745495) (xy 29.706109 -342.774981) (xy 29.656502 -342.797639) (xy 29.604176 -342.813007)
			(xy 29.550196 -342.820772) (xy 29.522928 -342.82126) (xy 28.659328 -342.82126) (xy 28.632056 -342.820802)
			(xy 28.578065 -342.813043) (xy 28.525729 -342.79768) (xy 28.476112 -342.775023) (xy 28.430225 -342.745536)
			(xy 28.389001 -342.709819) (xy 28.35328 -342.668598) (xy 28.32379 -342.622712) (xy 28.30113 -342.573097)
			(xy 28.285762 -342.520762) (xy 28.278 -342.466772) (xy 26.795296 -342.466772) (xy 26.787533 -342.520762)
			(xy 26.772166 -342.573097) (xy 26.749506 -342.622712) (xy 26.720015 -342.668597) (xy 26.684295 -342.709817)
			(xy 26.643071 -342.745535) (xy 26.597184 -342.775021) (xy 26.547567 -342.797677) (xy 26.49523 -342.81304)
			(xy 26.44124 -342.820799) (xy 26.413968 -342.82126) (xy 25.550368 -342.82126) (xy 25.5231 -342.820775)
			(xy 25.46912 -342.81301) (xy 25.416794 -342.797642) (xy 25.367187 -342.774984) (xy 25.32131 -342.745497)
			(xy 25.280096 -342.709781) (xy 25.244384 -342.668564) (xy 25.214901 -342.622685) (xy 25.192247 -342.573076)
			(xy 25.176883 -342.520749) (xy 25.169122 -342.466768) (xy 23.686274 -342.466768) (xy 23.686274 -342.466769)
			(xy 23.678512 -342.520751) (xy 23.663147 -342.57308) (xy 23.640492 -342.622689) (xy 23.611007 -342.66857)
			(xy 23.575293 -342.709787) (xy 23.534076 -342.745502) (xy 23.488197 -342.774988) (xy 23.438588 -342.797645)
			(xy 23.386259 -342.81301) (xy 23.332277 -342.820773) (xy 23.305008 -342.82126) (xy 22.441408 -342.82126)
			(xy 22.414136 -342.820801) (xy 22.360148 -342.81304) (xy 22.307815 -342.797674) (xy 22.2582 -342.775017)
			(xy 22.212315 -342.745529) (xy 22.171094 -342.709812) (xy 22.135375 -342.668591) (xy 22.105887 -342.622707)
			(xy 22.083229 -342.573093) (xy 22.067862 -342.520759) (xy 22.0601 -342.466772) (xy 20.577347 -342.466772)
			(xy 20.569584 -342.520758) (xy 20.554218 -342.57309) (xy 20.53156 -342.622703) (xy 20.502073 -342.668587)
			(xy 20.466355 -342.709807) (xy 20.425135 -342.745524) (xy 20.379252 -342.775011) (xy 20.329638 -342.797669)
			(xy 20.277306 -342.813035) (xy 20.223319 -342.820797) (xy 20.196048 -342.82126) (xy 19.332448 -342.82126)
			(xy 19.305179 -342.820777) (xy 19.251195 -342.813015) (xy 19.198865 -342.79765) (xy 19.149255 -342.774993)
			(xy 19.103374 -342.745507) (xy 19.062157 -342.709792) (xy 19.026441 -342.668574) (xy 18.996956 -342.622693)
			(xy 18.974299 -342.573083) (xy 18.958934 -342.520753) (xy 18.951172 -342.466769) (xy 0.6096 -342.466769)
			(xy 0.6096 -345.49242) (xy 18.95117 -345.49242) (xy 18.95117 -345.43788) (xy 18.958932 -345.383896)
			(xy 18.974298 -345.331567) (xy 18.996954 -345.281956) (xy 19.02644 -345.236075) (xy 19.062155 -345.194857)
			(xy 19.103373 -345.159141) (xy 19.149254 -345.129655) (xy 19.198865 -345.106998) (xy 19.251194 -345.091633)
			(xy 19.305178 -345.083871) (xy 19.332448 -345.083384) (xy 20.196048 -345.083384) (xy 20.223319 -345.083855)
			(xy 20.277305 -345.091617) (xy 20.329638 -345.106983) (xy 20.379251 -345.12964) (xy 20.425134 -345.159128)
			(xy 20.466354 -345.194845) (xy 20.502071 -345.236064) (xy 20.531559 -345.281948) (xy 20.554216 -345.33156)
			(xy 20.569582 -345.383893) (xy 20.577345 -345.437879) (xy 20.577345 -345.49242) (xy 22.06013 -345.49242)
			(xy 22.06013 -345.43788) (xy 22.067892 -345.383896) (xy 22.083258 -345.331567) (xy 22.105914 -345.281956)
			(xy 22.1354 -345.236075) (xy 22.171115 -345.194857) (xy 22.212333 -345.159141) (xy 22.258214 -345.129655)
			(xy 22.307825 -345.106998) (xy 22.360154 -345.091633) (xy 22.414138 -345.083871) (xy 22.441408 -345.083384)
			(xy 23.305008 -345.083384) (xy 23.332279 -345.083855) (xy 23.386265 -345.091617) (xy 23.438598 -345.106983)
			(xy 23.488211 -345.12964) (xy 23.534094 -345.159128) (xy 23.575314 -345.194845) (xy 23.611031 -345.236064)
			(xy 23.640519 -345.281948) (xy 23.663176 -345.33156) (xy 23.678542 -345.383893) (xy 23.686305 -345.437879)
			(xy 23.686305 -345.492365) (xy 25.16917 -345.492365) (xy 25.16917 -345.437835) (xy 25.17693 -345.383861)
			(xy 25.192292 -345.33154) (xy 25.214943 -345.281938) (xy 25.244422 -345.236064) (xy 25.28013 -345.194853)
			(xy 25.321339 -345.159142) (xy 25.36721 -345.129658) (xy 25.41681 -345.107003) (xy 25.46913 -345.091637)
			(xy 25.523103 -345.083872) (xy 25.550368 -345.083384) (xy 26.413968 -345.083384) (xy 26.441244 -345.083753)
			(xy 26.495241 -345.091513) (xy 26.547583 -345.106878) (xy 26.597207 -345.129537) (xy 26.6431 -345.159027)
			(xy 26.684329 -345.194749) (xy 26.720054 -345.235975) (xy 26.749548 -345.281865) (xy 26.772211 -345.331487)
			(xy 26.78758 -345.383828) (xy 26.795344 -345.437824) (xy 26.795344 -345.492369) (xy 28.278047 -345.492369)
			(xy 28.278047 -345.437831) (xy 28.285809 -345.383848) (xy 28.301175 -345.33152) (xy 28.323832 -345.281911)
			(xy 28.353319 -345.236031) (xy 28.389035 -345.194815) (xy 28.430253 -345.159102) (xy 28.476135 -345.129619)
			(xy 28.525746 -345.106965) (xy 28.578076 -345.091603) (xy 28.632059 -345.083845) (xy 28.659328 -345.083384)
			(xy 29.522928 -345.083384) (xy 29.550199 -345.08378) (xy 29.604186 -345.091546) (xy 29.656519 -345.106916)
			(xy 29.706132 -345.129576) (xy 29.752014 -345.159067) (xy 29.793234 -345.194786) (xy 29.82895 -345.236008)
			(xy 29.858437 -345.281893) (xy 29.881094 -345.331507) (xy 29.89646 -345.383841) (xy 29.904222 -345.437829)
			(xy 29.904222 -345.492366) (xy 31.38707 -345.492366) (xy 31.38707 -345.437834) (xy 31.394831 -345.383858)
			(xy 31.410194 -345.331536) (xy 31.432846 -345.281933) (xy 31.462327 -345.236058) (xy 31.498037 -345.194846)
			(xy 31.539248 -345.159135) (xy 31.585122 -345.129652) (xy 31.634725 -345.106998) (xy 31.687047 -345.091633)
			(xy 31.741022 -345.083871) (xy 31.768288 -345.083384) (xy 32.631888 -345.083384) (xy 32.659163 -345.083755)
			(xy 32.713157 -345.091516) (xy 32.765498 -345.106884) (xy 32.815119 -345.129543) (xy 32.861009 -345.159034)
			(xy 32.902236 -345.194756) (xy 32.937959 -345.235981) (xy 32.967451 -345.281871) (xy 32.990112 -345.331491)
			(xy 33.005481 -345.383831) (xy 33.013244 -345.437825) (xy 33.013244 -345.49237) (xy 34.495948 -345.49237)
			(xy 34.495948 -345.43783) (xy 34.50371 -345.383846) (xy 34.519077 -345.331515) (xy 34.541735 -345.281905)
			(xy 34.571224 -345.236024) (xy 34.606942 -345.194808) (xy 34.648163 -345.159095) (xy 34.694047 -345.129612)
			(xy 34.74366 -345.10696) (xy 34.795992 -345.0916) (xy 34.849978 -345.083844) (xy 34.877248 -345.083384)
			(xy 35.740848 -345.083384) (xy 35.768118 -345.083782) (xy 35.822103 -345.09155) (xy 35.874433 -345.106921)
			(xy 35.924044 -345.129583) (xy 35.969924 -345.159074) (xy 36.011141 -345.194793) (xy 36.046855 -345.236015)
			(xy 36.07634 -345.281899) (xy 36.098995 -345.331512) (xy 36.11436 -345.383844) (xy 36.122122 -345.43783)
			(xy 36.122122 -345.492368) (xy 37.604947 -345.492368) (xy 37.604947 -345.437832) (xy 37.612709 -345.383851)
			(xy 37.628074 -345.331524) (xy 37.650729 -345.281916) (xy 37.680214 -345.236038) (xy 37.715928 -345.194822)
			(xy 37.757144 -345.159109) (xy 37.803023 -345.129625) (xy 37.852631 -345.106971) (xy 37.904959 -345.091607)
			(xy 37.95894 -345.083847) (xy 37.986208 -345.083384) (xy 38.849808 -345.083384) (xy 38.87708 -345.083779)
			(xy 38.93107 -345.091543) (xy 38.983404 -345.106911) (xy 39.03302 -345.12957) (xy 39.078905 -345.15906)
			(xy 39.120127 -345.194779) (xy 39.155845 -345.236001) (xy 39.185334 -345.281888) (xy 39.207992 -345.331503)
			(xy 39.223359 -345.383838) (xy 39.231121 -345.437828) (xy 39.231121 -345.492365) (xy 40.71397 -345.492365)
			(xy 40.71397 -345.437835) (xy 40.72173 -345.383861) (xy 40.737092 -345.33154) (xy 40.759743 -345.281938)
			(xy 40.789222 -345.236064) (xy 40.82493 -345.194853) (xy 40.866139 -345.159142) (xy 40.91201 -345.129658)
			(xy 40.96161 -345.107003) (xy 41.01393 -345.091637) (xy 41.067903 -345.083872) (xy 41.095168 -345.083384)
			(xy 41.958768 -345.083384) (xy 41.986044 -345.083753) (xy 42.040041 -345.091513) (xy 42.092383 -345.106878)
			(xy 42.142007 -345.129537) (xy 42.1879 -345.159027) (xy 42.229129 -345.194749) (xy 42.264854 -345.235975)
			(xy 42.294348 -345.281865) (xy 42.317011 -345.331487) (xy 42.33238 -345.383828) (xy 42.340144 -345.437824)
			(xy 42.340144 -345.492369) (xy 43.822847 -345.492369) (xy 43.822847 -345.437831) (xy 43.830609 -345.383848)
			(xy 43.845975 -345.33152) (xy 43.868632 -345.281911) (xy 43.898119 -345.236031) (xy 43.933835 -345.194815)
			(xy 43.975053 -345.159102) (xy 44.020935 -345.129619) (xy 44.070546 -345.106965) (xy 44.122876 -345.091603)
			(xy 44.176859 -345.083845) (xy 44.204128 -345.083384) (xy 45.067728 -345.083384) (xy 45.094999 -345.08378)
			(xy 45.148986 -345.091546) (xy 45.201319 -345.106916) (xy 45.250932 -345.129576) (xy 45.296814 -345.159067)
			(xy 45.338034 -345.194786) (xy 45.37375 -345.236008) (xy 45.403237 -345.281893) (xy 45.425894 -345.331507)
			(xy 45.44126 -345.383841) (xy 45.449022 -345.437829) (xy 45.449022 -345.492366) (xy 46.93187 -345.492366)
			(xy 46.93187 -345.437834) (xy 46.939631 -345.383858) (xy 46.954994 -345.331536) (xy 46.977646 -345.281933)
			(xy 47.007127 -345.236058) (xy 47.042837 -345.194846) (xy 47.084048 -345.159135) (xy 47.129922 -345.129652)
			(xy 47.179525 -345.106998) (xy 47.231847 -345.091633) (xy 47.285822 -345.083871) (xy 47.313088 -345.083384)
			(xy 48.176688 -345.083384) (xy 48.203963 -345.083755) (xy 48.257957 -345.091516) (xy 48.310298 -345.106884)
			(xy 48.359919 -345.129543) (xy 48.405809 -345.159034) (xy 48.447036 -345.194756) (xy 48.482759 -345.235981)
			(xy 48.512251 -345.281871) (xy 48.534912 -345.331491) (xy 48.550281 -345.383831) (xy 48.558044 -345.437825)
			(xy 48.558044 -345.49237) (xy 50.040748 -345.49237) (xy 50.040748 -345.43783) (xy 50.04851 -345.383846)
			(xy 50.063877 -345.331515) (xy 50.086535 -345.281905) (xy 50.116024 -345.236024) (xy 50.151742 -345.194808)
			(xy 50.192963 -345.159095) (xy 50.238847 -345.129612) (xy 50.28846 -345.10696) (xy 50.340792 -345.0916)
			(xy 50.394778 -345.083844) (xy 50.422048 -345.083384) (xy 51.285648 -345.083384) (xy 51.312918 -345.083782)
			(xy 51.366903 -345.09155) (xy 51.419233 -345.106921) (xy 51.468844 -345.129583) (xy 51.514724 -345.159074)
			(xy 51.555941 -345.194793) (xy 51.591655 -345.236015) (xy 51.62114 -345.281899) (xy 51.643795 -345.331512)
			(xy 51.65916 -345.383844) (xy 51.666922 -345.43783) (xy 51.666922 -345.49237) (xy 51.65916 -345.546356)
			(xy 51.643795 -345.598688) (xy 51.62114 -345.648301) (xy 51.591655 -345.694185) (xy 51.555941 -345.735407)
			(xy 51.514724 -345.771126) (xy 51.468843 -345.800617) (xy 51.419233 -345.823279) (xy 51.366903 -345.83865)
			(xy 51.312918 -345.846418) (xy 51.285648 -345.846908) (xy 50.422048 -345.846908) (xy 50.394778 -345.846356)
			(xy 50.340792 -345.8386) (xy 50.28846 -345.82324) (xy 50.238847 -345.800588) (xy 50.192963 -345.771105)
			(xy 50.151742 -345.735392) (xy 50.116024 -345.694176) (xy 50.086535 -345.648295) (xy 50.063877 -345.598685)
			(xy 50.04851 -345.546354) (xy 50.040748 -345.49237) (xy 48.558044 -345.49237) (xy 48.558044 -345.492375)
			(xy 48.550281 -345.546369) (xy 48.534912 -345.598709) (xy 48.512251 -345.648329) (xy 48.482759 -345.694219)
			(xy 48.447036 -345.735444) (xy 48.405809 -345.771166) (xy 48.359919 -345.800657) (xy 48.310298 -345.823316)
			(xy 48.257958 -345.838684) (xy 48.203963 -345.846445) (xy 48.176688 -345.846908) (xy 47.313088 -345.846908)
			(xy 47.285822 -345.846329) (xy 47.231847 -345.838567) (xy 47.179525 -345.823202) (xy 47.129922 -345.800548)
			(xy 47.084048 -345.771065) (xy 47.042837 -345.735354) (xy 47.007127 -345.694142) (xy 46.977646 -345.648267)
			(xy 46.954994 -345.598664) (xy 46.939631 -345.546342) (xy 46.93187 -345.492366) (xy 45.449022 -345.492366)
			(xy 45.449022 -345.492371) (xy 45.44126 -345.546359) (xy 45.425894 -345.598693) (xy 45.403237 -345.648307)
			(xy 45.37375 -345.694192) (xy 45.338034 -345.735414) (xy 45.296814 -345.771133) (xy 45.250932 -345.800624)
			(xy 45.201319 -345.823284) (xy 45.148986 -345.838654) (xy 45.094999 -345.84642) (xy 45.067728 -345.846908)
			(xy 44.204128 -345.846908) (xy 44.176859 -345.846355) (xy 44.122876 -345.838597) (xy 44.070546 -345.823235)
			(xy 44.020935 -345.800581) (xy 43.975053 -345.771098) (xy 43.933835 -345.735385) (xy 43.898119 -345.694169)
			(xy 43.868632 -345.648289) (xy 43.845975 -345.59868) (xy 43.830609 -345.546352) (xy 43.822847 -345.492369)
			(xy 42.340144 -345.492369) (xy 42.340144 -345.492376) (xy 42.33238 -345.546372) (xy 42.317011 -345.598713)
			(xy 42.294348 -345.648335) (xy 42.264854 -345.694225) (xy 42.229129 -345.735451) (xy 42.1879 -345.771173)
			(xy 42.142007 -345.800663) (xy 42.092383 -345.823322) (xy 42.040041 -345.838687) (xy 41.986044 -345.846447)
			(xy 41.958768 -345.846908) (xy 41.095168 -345.846908) (xy 41.067903 -345.846328) (xy 41.01393 -345.838563)
			(xy 40.96161 -345.823197) (xy 40.91201 -345.800542) (xy 40.866139 -345.771058) (xy 40.82493 -345.735347)
			(xy 40.789222 -345.694136) (xy 40.759743 -345.648262) (xy 40.737092 -345.59866) (xy 40.72173 -345.546339)
			(xy 40.71397 -345.492365) (xy 39.231121 -345.492365) (xy 39.231121 -345.492372) (xy 39.223359 -345.546362)
			(xy 39.207992 -345.598697) (xy 39.185334 -345.648312) (xy 39.155845 -345.694199) (xy 39.120127 -345.735421)
			(xy 39.078905 -345.77114) (xy 39.03302 -345.80063) (xy 38.983404 -345.82329) (xy 38.93107 -345.838657)
			(xy 38.87708 -345.846421) (xy 38.849808 -345.846908) (xy 37.986208 -345.846908) (xy 37.95894 -345.846353)
			(xy 37.904959 -345.838593) (xy 37.852631 -345.823229) (xy 37.803023 -345.800575) (xy 37.757144 -345.771091)
			(xy 37.715928 -345.735378) (xy 37.680214 -345.694162) (xy 37.650729 -345.648284) (xy 37.628074 -345.598676)
			(xy 37.612709 -345.546349) (xy 37.604947 -345.492368) (xy 36.122122 -345.492368) (xy 36.122122 -345.49237)
			(xy 36.11436 -345.546356) (xy 36.098995 -345.598688) (xy 36.07634 -345.648301) (xy 36.046855 -345.694185)
			(xy 36.011141 -345.735407) (xy 35.969924 -345.771126) (xy 35.924043 -345.800617) (xy 35.874433 -345.823279)
			(xy 35.822103 -345.83865) (xy 35.768118 -345.846418) (xy 35.740848 -345.846908) (xy 34.877248 -345.846908)
			(xy 34.849978 -345.846356) (xy 34.795992 -345.8386) (xy 34.74366 -345.82324) (xy 34.694047 -345.800588)
			(xy 34.648163 -345.771105) (xy 34.606942 -345.735392) (xy 34.571224 -345.694176) (xy 34.541735 -345.648295)
			(xy 34.519077 -345.598685) (xy 34.50371 -345.546354) (xy 34.495948 -345.49237) (xy 33.013244 -345.49237)
			(xy 33.013244 -345.492375) (xy 33.005481 -345.546369) (xy 32.990112 -345.598709) (xy 32.967451 -345.648329)
			(xy 32.937959 -345.694219) (xy 32.902236 -345.735444) (xy 32.861009 -345.771166) (xy 32.815119 -345.800657)
			(xy 32.765498 -345.823316) (xy 32.713158 -345.838684) (xy 32.659163 -345.846445) (xy 32.631888 -345.846908)
			(xy 31.768288 -345.846908) (xy 31.741022 -345.846329) (xy 31.687047 -345.838567) (xy 31.634725 -345.823202)
			(xy 31.585122 -345.800548) (xy 31.539248 -345.771065) (xy 31.498037 -345.735354) (xy 31.462327 -345.694142)
			(xy 31.432846 -345.648267) (xy 31.410194 -345.598664) (xy 31.394831 -345.546342) (xy 31.38707 -345.492366)
			(xy 29.904222 -345.492366) (xy 29.904222 -345.492371) (xy 29.89646 -345.546359) (xy 29.881094 -345.598693)
			(xy 29.858437 -345.648307) (xy 29.82895 -345.694192) (xy 29.793234 -345.735414) (xy 29.752014 -345.771133)
			(xy 29.706132 -345.800624) (xy 29.656519 -345.823284) (xy 29.604186 -345.838654) (xy 29.550199 -345.84642)
			(xy 29.522928 -345.846908) (xy 28.659328 -345.846908) (xy 28.632059 -345.846355) (xy 28.578076 -345.838597)
			(xy 28.525746 -345.823235) (xy 28.476135 -345.800581) (xy 28.430253 -345.771098) (xy 28.389035 -345.735385)
			(xy 28.353319 -345.694169) (xy 28.323832 -345.648289) (xy 28.301175 -345.59868) (xy 28.285809 -345.546352)
			(xy 28.278047 -345.492369) (xy 26.795344 -345.492369) (xy 26.795344 -345.492376) (xy 26.78758 -345.546372)
			(xy 26.772211 -345.598713) (xy 26.749548 -345.648335) (xy 26.720054 -345.694225) (xy 26.684329 -345.735451)
			(xy 26.6431 -345.771173) (xy 26.597207 -345.800663) (xy 26.547583 -345.823322) (xy 26.495241 -345.838687)
			(xy 26.441244 -345.846447) (xy 26.413968 -345.846908) (xy 25.550368 -345.846908) (xy 25.523103 -345.846328)
			(xy 25.46913 -345.838563) (xy 25.41681 -345.823197) (xy 25.36721 -345.800542) (xy 25.321339 -345.771058)
			(xy 25.28013 -345.735347) (xy 25.244422 -345.694136) (xy 25.214943 -345.648262) (xy 25.192292 -345.59866)
			(xy 25.17693 -345.546339) (xy 25.16917 -345.492365) (xy 23.686305 -345.492365) (xy 23.686305 -345.492421)
			(xy 23.678542 -345.546407) (xy 23.663176 -345.59874) (xy 23.640519 -345.648352) (xy 23.611031 -345.694236)
			(xy 23.575314 -345.735455) (xy 23.534094 -345.771172) (xy 23.488211 -345.80066) (xy 23.438598 -345.823317)
			(xy 23.386265 -345.838683) (xy 23.332279 -345.846445) (xy 23.305008 -345.846908) (xy 22.441408 -345.846908)
			(xy 22.414138 -345.846429) (xy 22.360154 -345.838667) (xy 22.307825 -345.823302) (xy 22.258214 -345.800645)
			(xy 22.212333 -345.771159) (xy 22.171115 -345.735443) (xy 22.1354 -345.694225) (xy 22.105914 -345.648344)
			(xy 22.083258 -345.598733) (xy 22.067892 -345.546404) (xy 22.06013 -345.49242) (xy 20.577345 -345.49242)
			(xy 20.577345 -345.492421) (xy 20.569582 -345.546407) (xy 20.554216 -345.59874) (xy 20.531559 -345.648352)
			(xy 20.502071 -345.694236) (xy 20.466354 -345.735455) (xy 20.425134 -345.771172) (xy 20.379251 -345.80066)
			(xy 20.329638 -345.823317) (xy 20.277305 -345.838683) (xy 20.223319 -345.846445) (xy 20.196048 -345.846908)
			(xy 19.332448 -345.846908) (xy 19.305178 -345.846429) (xy 19.251194 -345.838667) (xy 19.198865 -345.823302)
			(xy 19.149254 -345.800645) (xy 19.103373 -345.771159) (xy 19.062155 -345.735443) (xy 19.02644 -345.694225)
			(xy 18.996954 -345.648344) (xy 18.974298 -345.598733) (xy 18.958932 -345.546404) (xy 18.95117 -345.49242)
			(xy 0.6096 -345.49242) (xy 0.6096 -348.976496) (xy 4.708641 -348.976496) (xy 4.708641 -348.847356)
			(xy 4.716591 -348.718461) (xy 4.732461 -348.590301) (xy 4.75619 -348.46336) (xy 4.787689 -348.338121)
			(xy 4.826838 -348.215058) (xy 4.873489 -348.094639) (xy 4.927464 -347.97732) (xy 4.988559 -347.863546)
			(xy 5.056542 -347.753749) (xy 5.131156 -347.648346) (xy 5.212117 -347.547736) (xy 5.299117 -347.452301)
			(xy 5.391828 -347.362402) (xy 5.489898 -347.278381) (xy 5.592953 -347.200557) (xy 5.700604 -347.129225)
			(xy 5.812443 -347.064655) (xy 5.928044 -347.007093) (xy 6.046969 -346.956756) (xy 6.168768 -346.913836)
			(xy 6.292978 -346.878495) (xy 6.419127 -346.850868) (xy 6.546739 -346.831059) (xy 6.675328 -346.819143)
			(xy 6.804406 -346.815167) (xy 6.933484 -346.819143) (xy 7.062073 -346.831059) (xy 7.189685 -346.850868)
			(xy 7.315834 -346.878495) (xy 7.440044 -346.913836) (xy 7.561843 -346.956756) (xy 7.680768 -347.007093)
			(xy 7.796369 -347.064655) (xy 7.908208 -347.129225) (xy 8.015859 -347.200557) (xy 8.118914 -347.278381)
			(xy 8.216984 -347.362402) (xy 8.309695 -347.452301) (xy 8.396695 -347.547736) (xy 8.477656 -347.648346)
			(xy 8.55227 -347.753749) (xy 8.620253 -347.863546) (xy 8.681348 -347.97732) (xy 8.735323 -348.094639)
			(xy 8.781974 -348.215058) (xy 8.821123 -348.338121) (xy 8.852622 -348.46336) (xy 8.876351 -348.590301)
			(xy 8.879169 -348.613059) (xy 18.951174 -348.613059) (xy 18.951174 -348.558521) (xy 18.958936 -348.504537)
			(xy 18.974301 -348.452208) (xy 18.996957 -348.402598) (xy 19.026443 -348.356717) (xy 19.062158 -348.315499)
			(xy 19.103375 -348.279784) (xy 19.149256 -348.250298) (xy 19.198866 -348.227642) (xy 19.251195 -348.212276)
			(xy 19.305179 -348.204515) (xy 19.332448 -348.204028) (xy 20.196048 -348.204028) (xy 20.223319 -348.204491)
			(xy 20.277306 -348.212253) (xy 20.329639 -348.227619) (xy 20.379253 -348.250277) (xy 20.425136 -348.279764)
			(xy 20.466357 -348.315482) (xy 20.502074 -348.356702) (xy 20.531562 -348.402586) (xy 20.55422 -348.452199)
			(xy 20.569586 -348.504532) (xy 20.577349 -348.558519) (xy 20.577349 -348.613061) (xy 20.577347 -348.613072)
			(xy 22.060092 -348.613072) (xy 22.060092 -348.558528) (xy 22.067854 -348.504539) (xy 22.083221 -348.452204)
			(xy 22.10588 -348.402589) (xy 22.135369 -348.356704) (xy 22.171088 -348.315483) (xy 22.21231 -348.279764)
			(xy 22.258196 -348.250276) (xy 22.307812 -348.227618) (xy 22.360147 -348.212252) (xy 22.414136 -348.204491)
			(xy 22.441408 -348.204028) (xy 23.305008 -348.204028) (xy 23.332276 -348.204535) (xy 23.386258 -348.212297)
			(xy 23.438585 -348.227663) (xy 23.488193 -348.250319) (xy 23.534071 -348.279804) (xy 23.575287 -348.315519)
			(xy 23.611 -348.356735) (xy 23.640485 -348.402614) (xy 23.66314 -348.452223) (xy 23.678504 -348.50455)
			(xy 23.686266 -348.558532) (xy 23.686266 -348.613068) (xy 23.686266 -348.613069) (xy 25.169114 -348.613069)
			(xy 25.169114 -348.558531) (xy 25.176875 -348.504549) (xy 25.19224 -348.452221) (xy 25.214894 -348.402611)
			(xy 25.244378 -348.356731) (xy 25.28009 -348.315513) (xy 25.321305 -348.279797) (xy 25.367183 -348.250309)
			(xy 25.416791 -348.227651) (xy 25.469118 -348.212282) (xy 25.523099 -348.204517) (xy 25.550368 -348.204028)
			(xy 26.413968 -348.204028) (xy 26.44124 -348.204509) (xy 26.495229 -348.212268) (xy 26.547564 -348.227631)
			(xy 26.59718 -348.250286) (xy 26.643066 -348.279772) (xy 26.684289 -348.315488) (xy 26.720009 -348.356708)
			(xy 26.749499 -348.402592) (xy 26.772158 -348.452206) (xy 26.787526 -348.50454) (xy 26.795288 -348.558528)
			(xy 26.795288 -348.613072) (xy 26.795288 -348.613073) (xy 28.277992 -348.613073) (xy 28.277992 -348.558527)
			(xy 28.285755 -348.504536) (xy 28.301123 -348.4522) (xy 28.323783 -348.402584) (xy 28.353274 -348.356697)
			(xy 28.388995 -348.315476) (xy 28.43022 -348.279757) (xy 28.476108 -348.25027) (xy 28.525726 -348.227613)
			(xy 28.578064 -348.212249) (xy 28.632055 -348.20449) (xy 28.659328 -348.204028) (xy 29.522928 -348.204028)
			(xy 29.550195 -348.204536) (xy 29.604175 -348.212301) (xy 29.656499 -348.227668) (xy 29.706105 -348.250326)
			(xy 29.751981 -348.279811) (xy 29.793194 -348.315526) (xy 29.828905 -348.356742) (xy 29.858388 -348.40262)
			(xy 29.881041 -348.452227) (xy 29.896405 -348.504553) (xy 29.904166 -348.558533) (xy 29.904166 -348.613067)
			(xy 29.904166 -348.61307) (xy 31.387014 -348.61307) (xy 31.387014 -348.55853) (xy 31.394776 -348.504546)
			(xy 31.410141 -348.452217) (xy 31.432797 -348.402606) (xy 31.462283 -348.356724) (xy 31.497997 -348.315506)
			(xy 31.539215 -348.27979) (xy 31.585095 -348.250303) (xy 31.634705 -348.227645) (xy 31.687035 -348.212279)
			(xy 31.741018 -348.204515) (xy 31.768288 -348.204028) (xy 32.631888 -348.204028) (xy 32.659159 -348.204511)
			(xy 32.713146 -348.212271) (xy 32.765478 -348.227636) (xy 32.815092 -348.250292) (xy 32.860976 -348.279779)
			(xy 32.902196 -348.315495) (xy 32.937914 -348.356715) (xy 32.967402 -348.402598) (xy 32.99006 -348.45221)
			(xy 33.005426 -348.504543) (xy 33.013189 -348.558529) (xy 33.013189 -348.613071) (xy 33.013189 -348.613074)
			(xy 34.495892 -348.613074) (xy 34.495892 -348.558526) (xy 34.503655 -348.504534) (xy 34.519024 -348.452196)
			(xy 34.541686 -348.402578) (xy 34.571179 -348.356691) (xy 34.606902 -348.315468) (xy 34.648129 -348.27975)
			(xy 34.69402 -348.250263) (xy 34.743641 -348.227608) (xy 34.795981 -348.212245) (xy 34.849974 -348.204488)
			(xy 34.877248 -348.204028) (xy 35.740848 -348.204028) (xy 35.768114 -348.204538) (xy 35.822091 -348.212305)
			(xy 35.874414 -348.227674) (xy 35.924017 -348.250332) (xy 35.96989 -348.279819) (xy 36.011101 -348.315533)
			(xy 36.04681 -348.356748) (xy 36.076291 -348.402626) (xy 36.098943 -348.452231) (xy 36.114306 -348.504556)
			(xy 36.122066 -348.558534) (xy 36.122066 -348.613066) (xy 36.122065 -348.613072) (xy 37.604892 -348.613072)
			(xy 37.604892 -348.558528) (xy 37.612654 -348.504539) (xy 37.628021 -348.452204) (xy 37.65068 -348.402589)
			(xy 37.680169 -348.356704) (xy 37.715888 -348.315483) (xy 37.75711 -348.279764) (xy 37.802996 -348.250276)
			(xy 37.852612 -348.227618) (xy 37.904947 -348.212252) (xy 37.958936 -348.204491) (xy 37.986208 -348.204028)
			(xy 38.849808 -348.204028) (xy 38.877076 -348.204535) (xy 38.931058 -348.212297) (xy 38.983385 -348.227663)
			(xy 39.032993 -348.250319) (xy 39.078871 -348.279804) (xy 39.120087 -348.315519) (xy 39.1558 -348.356735)
			(xy 39.185285 -348.402614) (xy 39.20794 -348.452223) (xy 39.223304 -348.50455) (xy 39.231066 -348.558532)
			(xy 39.231066 -348.613068) (xy 39.231066 -348.613069) (xy 40.713914 -348.613069) (xy 40.713914 -348.558531)
			(xy 40.721675 -348.504549) (xy 40.73704 -348.452221) (xy 40.759694 -348.402611) (xy 40.789178 -348.356731)
			(xy 40.82489 -348.315513) (xy 40.866105 -348.279797) (xy 40.911983 -348.250309) (xy 40.961591 -348.227651)
			(xy 41.013918 -348.212282) (xy 41.067899 -348.204517) (xy 41.095168 -348.204028) (xy 41.958768 -348.204028)
			(xy 41.98604 -348.204509) (xy 42.040029 -348.212268) (xy 42.092364 -348.227631) (xy 42.14198 -348.250286)
			(xy 42.187866 -348.279772) (xy 42.229089 -348.315488) (xy 42.264809 -348.356708) (xy 42.294299 -348.402592)
			(xy 42.316958 -348.452206) (xy 42.332326 -348.50454) (xy 42.340088 -348.558528) (xy 42.340088 -348.613072)
			(xy 42.340088 -348.613073) (xy 43.822792 -348.613073) (xy 43.822792 -348.558527) (xy 43.830555 -348.504536)
			(xy 43.845923 -348.4522) (xy 43.868583 -348.402584) (xy 43.898074 -348.356697) (xy 43.933795 -348.315476)
			(xy 43.97502 -348.279757) (xy 44.020908 -348.25027) (xy 44.070526 -348.227613) (xy 44.122864 -348.212249)
			(xy 44.176855 -348.20449) (xy 44.204128 -348.204028) (xy 45.067728 -348.204028) (xy 45.094995 -348.204536)
			(xy 45.148975 -348.212301) (xy 45.201299 -348.227668) (xy 45.250905 -348.250326) (xy 45.296781 -348.279811)
			(xy 45.337994 -348.315526) (xy 45.373705 -348.356742) (xy 45.403188 -348.40262) (xy 45.425841 -348.452227)
			(xy 45.441205 -348.504553) (xy 45.448966 -348.558533) (xy 45.448966 -348.613067) (xy 45.448966 -348.61307)
			(xy 46.931814 -348.61307) (xy 46.931814 -348.55853) (xy 46.939576 -348.504546) (xy 46.954941 -348.452217)
			(xy 46.977597 -348.402606) (xy 47.007083 -348.356724) (xy 47.042797 -348.315506) (xy 47.084015 -348.27979)
			(xy 47.129895 -348.250303) (xy 47.179505 -348.227645) (xy 47.231835 -348.212279) (xy 47.285818 -348.204515)
			(xy 47.313088 -348.204028) (xy 48.176688 -348.204028) (xy 48.203959 -348.204511) (xy 48.257946 -348.212271)
			(xy 48.310278 -348.227636) (xy 48.359892 -348.250292) (xy 48.405776 -348.279779) (xy 48.446996 -348.315495)
			(xy 48.482714 -348.356715) (xy 48.512202 -348.402598) (xy 48.53486 -348.45221) (xy 48.550226 -348.504543)
			(xy 48.557989 -348.558529) (xy 48.557989 -348.613071) (xy 48.557989 -348.613074) (xy 50.040692 -348.613074)
			(xy 50.040692 -348.558526) (xy 50.048455 -348.504534) (xy 50.063824 -348.452196) (xy 50.086486 -348.402578)
			(xy 50.115979 -348.356691) (xy 50.151702 -348.315468) (xy 50.192929 -348.27975) (xy 50.23882 -348.250263)
			(xy 50.288441 -348.227608) (xy 50.340781 -348.212245) (xy 50.394774 -348.204488) (xy 50.422048 -348.204028)
			(xy 51.285648 -348.204028) (xy 51.312914 -348.204538) (xy 51.366891 -348.212305) (xy 51.419214 -348.227674)
			(xy 51.468817 -348.250332) (xy 51.51469 -348.279819) (xy 51.555901 -348.315533) (xy 51.59161 -348.356748)
			(xy 51.621091 -348.402626) (xy 51.643743 -348.452231) (xy 51.659106 -348.504556) (xy 51.666866 -348.558534)
			(xy 51.666866 -348.613066) (xy 51.659106 -348.667044) (xy 51.643743 -348.719369) (xy 51.621091 -348.768974)
			(xy 51.59161 -348.814852) (xy 51.555901 -348.856067) (xy 51.51469 -348.891781) (xy 51.468817 -348.921268)
			(xy 51.419214 -348.943926) (xy 51.366891 -348.959295) (xy 51.312914 -348.967062) (xy 51.285648 -348.967552)
			(xy 50.422048 -348.967552) (xy 50.394774 -348.967112) (xy 50.340781 -348.959355) (xy 50.288441 -348.943992)
			(xy 50.23882 -348.921337) (xy 50.192929 -348.89185) (xy 50.151702 -348.856132) (xy 50.115979 -348.814909)
			(xy 50.086486 -348.769022) (xy 50.063824 -348.719404) (xy 50.048455 -348.667066) (xy 50.040692 -348.613074)
			(xy 48.557989 -348.613074) (xy 48.550226 -348.667057) (xy 48.53486 -348.71939) (xy 48.512202 -348.769002)
			(xy 48.482714 -348.814885) (xy 48.446996 -348.856105) (xy 48.405776 -348.891821) (xy 48.359892 -348.921308)
			(xy 48.310278 -348.943964) (xy 48.257946 -348.959329) (xy 48.203959 -348.967089) (xy 48.176688 -348.967552)
			(xy 47.313088 -348.967552) (xy 47.285818 -348.967085) (xy 47.231835 -348.959321) (xy 47.179505 -348.943955)
			(xy 47.129895 -348.921297) (xy 47.084015 -348.89181) (xy 47.042797 -348.856094) (xy 47.007083 -348.814876)
			(xy 46.977597 -348.768994) (xy 46.954941 -348.719383) (xy 46.939576 -348.667053) (xy 46.931814 -348.61307)
			(xy 45.448966 -348.61307) (xy 45.441205 -348.667047) (xy 45.425841 -348.719373) (xy 45.403188 -348.76898)
			(xy 45.373705 -348.814858) (xy 45.337994 -348.856074) (xy 45.296781 -348.891789) (xy 45.250905 -348.921274)
			(xy 45.201299 -348.943932) (xy 45.148975 -348.959299) (xy 45.094995 -348.967064) (xy 45.067728 -348.967552)
			(xy 44.204128 -348.967552) (xy 44.176855 -348.96711) (xy 44.122864 -348.959351) (xy 44.070526 -348.943987)
			(xy 44.020908 -348.92133) (xy 43.97502 -348.891843) (xy 43.933795 -348.856124) (xy 43.898074 -348.814903)
			(xy 43.868583 -348.769016) (xy 43.845923 -348.7194) (xy 43.830555 -348.667064) (xy 43.822792 -348.613073)
			(xy 42.340088 -348.613073) (xy 42.332326 -348.66706) (xy 42.316958 -348.719394) (xy 42.294299 -348.769008)
			(xy 42.264809 -348.814892) (xy 42.229089 -348.856112) (xy 42.187866 -348.891828) (xy 42.14198 -348.921314)
			(xy 42.092364 -348.943969) (xy 42.040029 -348.959332) (xy 41.98604 -348.967091) (xy 41.958768 -348.967552)
			(xy 41.095168 -348.967552) (xy 41.067899 -348.967083) (xy 41.013918 -348.959318) (xy 40.961591 -348.943949)
			(xy 40.911983 -348.921291) (xy 40.866105 -348.891803) (xy 40.82489 -348.856087) (xy 40.789178 -348.814869)
			(xy 40.759694 -348.768989) (xy 40.73704 -348.719379) (xy 40.721675 -348.667051) (xy 40.713914 -348.613069)
			(xy 39.231066 -348.613069) (xy 39.223304 -348.66705) (xy 39.20794 -348.719377) (xy 39.185285 -348.768986)
			(xy 39.1558 -348.814865) (xy 39.120087 -348.856081) (xy 39.078871 -348.891796) (xy 39.032993 -348.921281)
			(xy 38.983385 -348.943937) (xy 38.931058 -348.959303) (xy 38.877076 -348.967065) (xy 38.849808 -348.967552)
			(xy 37.986208 -348.967552) (xy 37.958936 -348.967109) (xy 37.904947 -348.959348) (xy 37.852612 -348.943982)
			(xy 37.802996 -348.921324) (xy 37.75711 -348.891836) (xy 37.715888 -348.856117) (xy 37.680169 -348.814896)
			(xy 37.65068 -348.769011) (xy 37.628021 -348.719396) (xy 37.612654 -348.667061) (xy 37.604892 -348.613072)
			(xy 36.122065 -348.613072) (xy 36.114306 -348.667044) (xy 36.098943 -348.719369) (xy 36.076291 -348.768974)
			(xy 36.04681 -348.814852) (xy 36.011101 -348.856067) (xy 35.96989 -348.891781) (xy 35.924017 -348.921268)
			(xy 35.874414 -348.943926) (xy 35.822091 -348.959295) (xy 35.768114 -348.967062) (xy 35.740848 -348.967552)
			(xy 34.877248 -348.967552) (xy 34.849974 -348.967112) (xy 34.795981 -348.959355) (xy 34.743641 -348.943992)
			(xy 34.69402 -348.921337) (xy 34.648129 -348.89185) (xy 34.606902 -348.856132) (xy 34.571179 -348.814909)
			(xy 34.541686 -348.769022) (xy 34.519024 -348.719404) (xy 34.503655 -348.667066) (xy 34.495892 -348.613074)
			(xy 33.013189 -348.613074) (xy 33.005426 -348.667057) (xy 32.99006 -348.71939) (xy 32.967402 -348.769002)
			(xy 32.937914 -348.814885) (xy 32.902196 -348.856105) (xy 32.860976 -348.891821) (xy 32.815092 -348.921308)
			(xy 32.765478 -348.943964) (xy 32.713146 -348.959329) (xy 32.659159 -348.967089) (xy 32.631888 -348.967552)
			(xy 31.768288 -348.967552) (xy 31.741018 -348.967085) (xy 31.687035 -348.959321) (xy 31.634705 -348.943955)
			(xy 31.585095 -348.921297) (xy 31.539215 -348.89181) (xy 31.497997 -348.856094) (xy 31.462283 -348.814876)
			(xy 31.432797 -348.768994) (xy 31.410141 -348.719383) (xy 31.394776 -348.667053) (xy 31.387014 -348.61307)
			(xy 29.904166 -348.61307) (xy 29.896405 -348.667047) (xy 29.881041 -348.719373) (xy 29.858388 -348.76898)
			(xy 29.828905 -348.814858) (xy 29.793194 -348.856074) (xy 29.751981 -348.891789) (xy 29.706105 -348.921274)
			(xy 29.656499 -348.943932) (xy 29.604175 -348.959299) (xy 29.550195 -348.967064) (xy 29.522928 -348.967552)
			(xy 28.659328 -348.967552) (xy 28.632055 -348.96711) (xy 28.578064 -348.959351) (xy 28.525726 -348.943987)
			(xy 28.476108 -348.92133) (xy 28.43022 -348.891843) (xy 28.388995 -348.856124) (xy 28.353274 -348.814903)
			(xy 28.323783 -348.769016) (xy 28.301123 -348.7194) (xy 28.285755 -348.667064) (xy 28.277992 -348.613073)
			(xy 26.795288 -348.613073) (xy 26.787526 -348.66706) (xy 26.772158 -348.719394) (xy 26.749499 -348.769008)
			(xy 26.720009 -348.814892) (xy 26.684289 -348.856112) (xy 26.643066 -348.891828) (xy 26.59718 -348.921314)
			(xy 26.547564 -348.943969) (xy 26.495229 -348.959332) (xy 26.44124 -348.967091) (xy 26.413968 -348.967552)
			(xy 25.550368 -348.967552) (xy 25.523099 -348.967083) (xy 25.469118 -348.959318) (xy 25.416791 -348.943949)
			(xy 25.367183 -348.921291) (xy 25.321305 -348.891803) (xy 25.28009 -348.856087) (xy 25.244378 -348.814869)
			(xy 25.214894 -348.768989) (xy 25.19224 -348.719379) (xy 25.176875 -348.667051) (xy 25.169114 -348.613069)
			(xy 23.686266 -348.613069) (xy 23.678504 -348.66705) (xy 23.66314 -348.719377) (xy 23.640485 -348.768986)
			(xy 23.611 -348.814865) (xy 23.575287 -348.856081) (xy 23.534071 -348.891796) (xy 23.488193 -348.921281)
			(xy 23.438585 -348.943937) (xy 23.386258 -348.959303) (xy 23.332276 -348.967065) (xy 23.305008 -348.967552)
			(xy 22.441408 -348.967552) (xy 22.414136 -348.967109) (xy 22.360147 -348.959348) (xy 22.307812 -348.943982)
			(xy 22.258196 -348.921324) (xy 22.21231 -348.891836) (xy 22.171088 -348.856117) (xy 22.135369 -348.814896)
			(xy 22.10588 -348.769011) (xy 22.083221 -348.719396) (xy 22.067854 -348.667061) (xy 22.060092 -348.613072)
			(xy 20.577347 -348.613072) (xy 20.569586 -348.667048) (xy 20.55422 -348.719381) (xy 20.531562 -348.768994)
			(xy 20.502074 -348.814878) (xy 20.466357 -348.856098) (xy 20.425136 -348.891816) (xy 20.379253 -348.921303)
			(xy 20.329639 -348.943961) (xy 20.277306 -348.959327) (xy 20.223319 -348.967089) (xy 20.196048 -348.967552)
			(xy 19.332448 -348.967552) (xy 19.305179 -348.967065) (xy 19.251195 -348.959304) (xy 19.198866 -348.943938)
			(xy 19.149256 -348.921282) (xy 19.103375 -348.891796) (xy 19.062158 -348.856081) (xy 19.026443 -348.814863)
			(xy 18.996957 -348.768982) (xy 18.974301 -348.719372) (xy 18.958936 -348.667043) (xy 18.951174 -348.613059)
			(xy 8.879169 -348.613059) (xy 8.892221 -348.718461) (xy 8.900171 -348.847356) (xy 8.900668 -348.911926)
			(xy 8.900171 -348.976496) (xy 8.892221 -349.105391) (xy 8.876351 -349.233551) (xy 8.852622 -349.360492)
			(xy 8.821123 -349.485731) (xy 8.781974 -349.608794) (xy 8.735323 -349.729213) (xy 8.681348 -349.846532)
			(xy 8.620253 -349.960306) (xy 8.55227 -350.070103) (xy 8.477656 -350.175506) (xy 8.396695 -350.276116)
			(xy 8.309695 -350.371551) (xy 8.216984 -350.46145) (xy 8.118914 -350.545471) (xy 8.015859 -350.623295)
			(xy 7.908208 -350.694627) (xy 7.796369 -350.759197) (xy 7.680768 -350.816759) (xy 7.561843 -350.867096)
			(xy 7.440044 -350.910016) (xy 7.315834 -350.945357) (xy 7.189685 -350.972984) (xy 7.062073 -350.992793)
			(xy 6.933484 -351.004709) (xy 6.804406 -351.008686) (xy 6.675328 -351.004709) (xy 6.546739 -350.992793)
			(xy 6.419127 -350.972984) (xy 6.292978 -350.945357) (xy 6.168768 -350.910016) (xy 6.046969 -350.867096)
			(xy 5.928044 -350.816759) (xy 5.812443 -350.759197) (xy 5.700604 -350.694627) (xy 5.592953 -350.623295)
			(xy 5.489898 -350.545471) (xy 5.391828 -350.46145) (xy 5.299117 -350.371551) (xy 5.212117 -350.276116)
			(xy 5.131156 -350.175506) (xy 5.056542 -350.070103) (xy 4.988559 -349.960306) (xy 4.927464 -349.846532)
			(xy 4.873489 -349.729213) (xy 4.826838 -349.608794) (xy 4.787689 -349.485731) (xy 4.75619 -349.360492)
			(xy 4.732461 -349.233551) (xy 4.716591 -349.105391) (xy 4.708641 -348.976496) (xy 0.6096 -348.976496)
			(xy 0.6096 -351.638709) (xy 18.951172 -351.638709) (xy 18.951172 -351.584171) (xy 18.958934 -351.530187)
			(xy 18.974299 -351.477857) (xy 18.996956 -351.428247) (xy 19.026441 -351.382366) (xy 19.062157 -351.341148)
			(xy 19.103374 -351.305433) (xy 19.149255 -351.275947) (xy 19.198865 -351.25329) (xy 19.251195 -351.237925)
			(xy 19.305179 -351.230163) (xy 19.332448 -351.229676) (xy 20.196048 -351.229676) (xy 20.223319 -351.230143)
			(xy 20.277306 -351.237905) (xy 20.329638 -351.253271) (xy 20.379252 -351.275929) (xy 20.425135 -351.305416)
			(xy 20.466355 -351.341133) (xy 20.502073 -351.382353) (xy 20.53156 -351.428237) (xy 20.554218 -351.47785)
			(xy 20.569584 -351.530182) (xy 20.577347 -351.584169) (xy 20.577347 -351.638669) (xy 22.060139 -351.638669)
			(xy 22.060139 -351.584131) (xy 22.067901 -351.530149) (xy 22.083266 -351.477821) (xy 22.105922 -351.428212)
			(xy 22.135407 -351.382333) (xy 22.171122 -351.341117) (xy 22.212339 -351.305403) (xy 22.258219 -351.275918)
			(xy 22.307829 -351.253263) (xy 22.360157 -351.237899) (xy 22.414139 -351.230139) (xy 22.441408 -351.229676)
			(xy 23.305008 -351.229676) (xy 23.33228 -351.230087) (xy 23.386268 -351.23785) (xy 23.438602 -351.253218)
			(xy 23.488216 -351.275877) (xy 23.5341 -351.305366) (xy 23.575321 -351.341085) (xy 23.611039 -351.382306)
			(xy 23.640527 -351.428191) (xy 23.663185 -351.477806) (xy 23.678551 -351.53014) (xy 23.686314 -351.584128)
			(xy 23.686314 -351.638665) (xy 25.169162 -351.638665) (xy 25.169162 -351.584135) (xy 25.176922 -351.530159)
			(xy 25.192284 -351.477838) (xy 25.214936 -351.428234) (xy 25.244416 -351.38236) (xy 25.280124 -351.341147)
			(xy 25.321334 -351.305435) (xy 25.367206 -351.275951) (xy 25.416808 -351.253296) (xy 25.469128 -351.237929)
			(xy 25.523103 -351.230165) (xy 25.550368 -351.229676) (xy 26.413968 -351.229676) (xy 26.441243 -351.230061)
			(xy 26.495239 -351.237821) (xy 26.547581 -351.253186) (xy 26.597203 -351.275844) (xy 26.643095 -351.305333)
			(xy 26.684323 -351.341054) (xy 26.720047 -351.382279) (xy 26.749541 -351.428169) (xy 26.772203 -351.477789)
			(xy 26.787573 -351.53013) (xy 26.795336 -351.584125) (xy 26.795336 -351.63867) (xy 28.278039 -351.63867)
			(xy 28.278039 -351.58413) (xy 28.285802 -351.530146) (xy 28.301168 -351.477817) (xy 28.323825 -351.428207)
			(xy 28.353312 -351.382326) (xy 28.389029 -351.341109) (xy 28.430249 -351.305396) (xy 28.476131 -351.275912)
			(xy 28.525743 -351.253258) (xy 28.578074 -351.237896) (xy 28.632058 -351.230137) (xy 28.659328 -351.229676)
			(xy 29.522928 -351.229676) (xy 29.550199 -351.230088) (xy 29.604185 -351.237854) (xy 29.656516 -351.253223)
			(xy 29.706128 -351.275883) (xy 29.75201 -351.305373) (xy 29.793228 -351.341092) (xy 29.828944 -351.382313)
			(xy 29.85843 -351.428197) (xy 29.881086 -351.47781) (xy 29.896452 -351.530143) (xy 29.904214 -351.584129)
			(xy 29.904214 -351.638666) (xy 31.387062 -351.638666) (xy 31.387062 -351.584134) (xy 31.394823 -351.530157)
			(xy 31.410186 -351.477833) (xy 31.432839 -351.428229) (xy 31.462321 -351.382353) (xy 31.498031 -351.34114)
			(xy 31.539243 -351.305428) (xy 31.585118 -351.275945) (xy 31.634722 -351.25329) (xy 31.687045 -351.237925)
			(xy 31.741022 -351.230163) (xy 31.768288 -351.229676) (xy 32.631888 -351.229676) (xy 32.659162 -351.230063)
			(xy 32.713156 -351.237824) (xy 32.765495 -351.253191) (xy 32.815115 -351.27585) (xy 32.861004 -351.30534)
			(xy 32.90223 -351.341061) (xy 32.937952 -351.382286) (xy 32.967444 -351.428175) (xy 32.990105 -351.477794)
			(xy 33.005473 -351.530132) (xy 33.013236 -351.584126) (xy 33.013236 -351.63867) (xy 34.49594 -351.63867)
			(xy 34.49594 -351.58413) (xy 34.503702 -351.530144) (xy 34.519069 -351.477812) (xy 34.541728 -351.428201)
			(xy 34.571217 -351.38232) (xy 34.606936 -351.341102) (xy 34.648158 -351.305388) (xy 34.694043 -351.275905)
			(xy 34.743658 -351.253253) (xy 34.795991 -351.237892) (xy 34.849977 -351.230136) (xy 34.877248 -351.229676)
			(xy 35.740848 -351.229676) (xy 35.768118 -351.23009) (xy 35.822102 -351.237858) (xy 35.874431 -351.253229)
			(xy 35.92404 -351.27589) (xy 35.969919 -351.30538) (xy 36.011135 -351.341099) (xy 36.046849 -351.382319)
			(xy 36.076333 -351.428203) (xy 36.098988 -351.477814) (xy 36.114352 -351.530145) (xy 36.122114 -351.58413)
			(xy 36.122114 -351.638669) (xy 37.604939 -351.638669) (xy 37.604939 -351.584131) (xy 37.612701 -351.530149)
			(xy 37.628066 -351.477821) (xy 37.650722 -351.428212) (xy 37.680207 -351.382333) (xy 37.715922 -351.341117)
			(xy 37.757139 -351.305403) (xy 37.803019 -351.275918) (xy 37.852629 -351.253263) (xy 37.904957 -351.237899)
			(xy 37.958939 -351.230139) (xy 37.986208 -351.229676) (xy 38.849808 -351.229676) (xy 38.87708 -351.230087)
			(xy 38.931068 -351.23785) (xy 38.983402 -351.253218) (xy 39.033016 -351.275877) (xy 39.0789 -351.305366)
			(xy 39.120121 -351.341085) (xy 39.155839 -351.382306) (xy 39.185327 -351.428191) (xy 39.207985 -351.477806)
			(xy 39.223351 -351.53014) (xy 39.231114 -351.584128) (xy 39.231114 -351.638665) (xy 40.713962 -351.638665)
			(xy 40.713962 -351.584135) (xy 40.721722 -351.530159) (xy 40.737084 -351.477838) (xy 40.759736 -351.428234)
			(xy 40.789216 -351.38236) (xy 40.824924 -351.341147) (xy 40.866134 -351.305435) (xy 40.912006 -351.275951)
			(xy 40.961608 -351.253296) (xy 41.013928 -351.237929) (xy 41.067903 -351.230165) (xy 41.095168 -351.229676)
			(xy 41.958768 -351.229676) (xy 41.986043 -351.230061) (xy 42.040039 -351.237821) (xy 42.092381 -351.253186)
			(xy 42.142003 -351.275844) (xy 42.187895 -351.305333) (xy 42.229123 -351.341054) (xy 42.264847 -351.382279)
			(xy 42.294341 -351.428169) (xy 42.317003 -351.477789) (xy 42.332373 -351.53013) (xy 42.340136 -351.584125)
			(xy 42.340136 -351.63867) (xy 43.822839 -351.63867) (xy 43.822839 -351.58413) (xy 43.830602 -351.530146)
			(xy 43.845968 -351.477817) (xy 43.868625 -351.428207) (xy 43.898112 -351.382326) (xy 43.933829 -351.341109)
			(xy 43.975049 -351.305396) (xy 44.020931 -351.275912) (xy 44.070543 -351.253258) (xy 44.122874 -351.237896)
			(xy 44.176858 -351.230137) (xy 44.204128 -351.229676) (xy 45.067728 -351.229676) (xy 45.094999 -351.230088)
			(xy 45.148985 -351.237854) (xy 45.201316 -351.253223) (xy 45.250928 -351.275883) (xy 45.29681 -351.305373)
			(xy 45.338028 -351.341092) (xy 45.373744 -351.382313) (xy 45.40323 -351.428197) (xy 45.425886 -351.47781)
			(xy 45.441252 -351.530143) (xy 45.449014 -351.584129) (xy 45.449014 -351.638666) (xy 46.931862 -351.638666)
			(xy 46.931862 -351.584134) (xy 46.939623 -351.530157) (xy 46.954986 -351.477833) (xy 46.977639 -351.428229)
			(xy 47.007121 -351.382353) (xy 47.042831 -351.34114) (xy 47.084043 -351.305428) (xy 47.129918 -351.275945)
			(xy 47.179522 -351.25329) (xy 47.231845 -351.237925) (xy 47.285822 -351.230163) (xy 47.313088 -351.229676)
			(xy 48.176688 -351.229676) (xy 48.203962 -351.230063) (xy 48.257956 -351.237824) (xy 48.310295 -351.253191)
			(xy 48.359915 -351.27585) (xy 48.405804 -351.30534) (xy 48.44703 -351.341061) (xy 48.482752 -351.382286)
			(xy 48.512244 -351.428175) (xy 48.534905 -351.477794) (xy 48.550273 -351.530132) (xy 48.558036 -351.584126)
			(xy 48.558036 -351.63867) (xy 50.04074 -351.63867) (xy 50.04074 -351.58413) (xy 50.048502 -351.530144)
			(xy 50.063869 -351.477812) (xy 50.086528 -351.428201) (xy 50.116017 -351.38232) (xy 50.151736 -351.341102)
			(xy 50.192958 -351.305388) (xy 50.238843 -351.275905) (xy 50.288458 -351.253253) (xy 50.340791 -351.237892)
			(xy 50.394777 -351.230136) (xy 50.422048 -351.229676) (xy 51.285648 -351.229676) (xy 51.312918 -351.23009)
			(xy 51.366902 -351.237858) (xy 51.419231 -351.253229) (xy 51.46884 -351.27589) (xy 51.514719 -351.30538)
			(xy 51.555935 -351.341099) (xy 51.591649 -351.382319) (xy 51.621133 -351.428203) (xy 51.643788 -351.477814)
			(xy 51.659152 -351.530145) (xy 51.666914 -351.58413) (xy 51.666914 -351.63867) (xy 51.659152 -351.692655)
			(xy 51.643788 -351.744986) (xy 51.621133 -351.794597) (xy 51.591649 -351.840481) (xy 51.555935 -351.881701)
			(xy 51.514719 -351.91742) (xy 51.46884 -351.94691) (xy 51.419231 -351.969571) (xy 51.366902 -351.984942)
			(xy 51.312918 -351.99271) (xy 51.285648 -351.9932) (xy 50.422048 -351.9932) (xy 50.394777 -351.992664)
			(xy 50.340791 -351.984908) (xy 50.288458 -351.969547) (xy 50.238843 -351.946895) (xy 50.192958 -351.917411)
			(xy 50.151736 -351.881698) (xy 50.116017 -351.84048) (xy 50.086528 -351.794599) (xy 50.063869 -351.744987)
			(xy 50.048502 -351.692656) (xy 50.04074 -351.63867) (xy 48.558036 -351.63867) (xy 48.558036 -351.638674)
			(xy 48.550273 -351.692668) (xy 48.534905 -351.745006) (xy 48.512244 -351.794625) (xy 48.482752 -351.840514)
			(xy 48.44703 -351.881739) (xy 48.405804 -351.91746) (xy 48.359915 -351.94695) (xy 48.310295 -351.969609)
			(xy 48.257956 -351.984976) (xy 48.203962 -351.992737) (xy 48.176688 -351.9932) (xy 47.313088 -351.9932)
			(xy 47.285822 -351.992637) (xy 47.231845 -351.984875) (xy 47.179522 -351.96951) (xy 47.129918 -351.946855)
			(xy 47.084044 -351.917372) (xy 47.042831 -351.88166) (xy 47.007121 -351.840447) (xy 46.977639 -351.794571)
			(xy 46.954986 -351.744967) (xy 46.939623 -351.692643) (xy 46.931862 -351.638666) (xy 45.449014 -351.638666)
			(xy 45.449014 -351.638671) (xy 45.441252 -351.692657) (xy 45.425886 -351.74499) (xy 45.40323 -351.794603)
			(xy 45.373744 -351.840487) (xy 45.338028 -351.881708) (xy 45.29681 -351.917427) (xy 45.250928 -351.946917)
			(xy 45.201316 -351.969577) (xy 45.148985 -351.984946) (xy 45.094999 -351.992712) (xy 45.067728 -351.9932)
			(xy 44.204128 -351.9932) (xy 44.176858 -351.992663) (xy 44.122874 -351.984904) (xy 44.070543 -351.969542)
			(xy 44.020931 -351.946888) (xy 43.975049 -351.917404) (xy 43.933829 -351.881691) (xy 43.898112 -351.840474)
			(xy 43.868625 -351.794593) (xy 43.845968 -351.744983) (xy 43.830602 -351.692654) (xy 43.822839 -351.63867)
			(xy 42.340136 -351.63867) (xy 42.340136 -351.638675) (xy 42.332373 -351.69267) (xy 42.317003 -351.745011)
			(xy 42.294341 -351.794631) (xy 42.264847 -351.840521) (xy 42.229123 -351.881746) (xy 42.187895 -351.917467)
			(xy 42.142003 -351.946956) (xy 42.092381 -351.969614) (xy 42.040039 -351.984979) (xy 41.986043 -351.992739)
			(xy 41.958768 -351.9932) (xy 41.095168 -351.9932) (xy 41.067903 -351.992635) (xy 41.013928 -351.984871)
			(xy 40.961608 -351.969504) (xy 40.912006 -351.946849) (xy 40.866134 -351.917365) (xy 40.824924 -351.881653)
			(xy 40.789216 -351.84044) (xy 40.759736 -351.794566) (xy 40.737084 -351.744962) (xy 40.721722 -351.692641)
			(xy 40.713962 -351.638665) (xy 39.231114 -351.638665) (xy 39.231114 -351.638672) (xy 39.223351 -351.69266)
			(xy 39.207985 -351.744994) (xy 39.185327 -351.794609) (xy 39.155839 -351.840494) (xy 39.120121 -351.881715)
			(xy 39.0789 -351.917434) (xy 39.033016 -351.946923) (xy 38.983402 -351.969582) (xy 38.931068 -351.98495)
			(xy 38.87708 -351.992713) (xy 38.849808 -351.9932) (xy 37.986208 -351.9932) (xy 37.958939 -351.992661)
			(xy 37.904957 -351.984901) (xy 37.852629 -351.969537) (xy 37.803019 -351.946882) (xy 37.757139 -351.917397)
			(xy 37.715922 -351.881683) (xy 37.680207 -351.840467) (xy 37.650722 -351.794588) (xy 37.628066 -351.744979)
			(xy 37.612701 -351.692651) (xy 37.604939 -351.638669) (xy 36.122114 -351.638669) (xy 36.122114 -351.63867)
			(xy 36.114352 -351.692655) (xy 36.098988 -351.744986) (xy 36.076333 -351.794597) (xy 36.046849 -351.840481)
			(xy 36.011135 -351.881701) (xy 35.969919 -351.91742) (xy 35.92404 -351.94691) (xy 35.874431 -351.969571)
			(xy 35.822102 -351.984942) (xy 35.768118 -351.99271) (xy 35.740848 -351.9932) (xy 34.877248 -351.9932)
			(xy 34.849977 -351.992664) (xy 34.795991 -351.984908) (xy 34.743658 -351.969547) (xy 34.694043 -351.946895)
			(xy 34.648158 -351.917411) (xy 34.606936 -351.881698) (xy 34.571217 -351.84048) (xy 34.541728 -351.794599)
			(xy 34.519069 -351.744987) (xy 34.503702 -351.692656) (xy 34.49594 -351.63867) (xy 33.013236 -351.63867)
			(xy 33.013236 -351.638674) (xy 33.005473 -351.692668) (xy 32.990105 -351.745006) (xy 32.967444 -351.794625)
			(xy 32.937952 -351.840514) (xy 32.90223 -351.881739) (xy 32.861004 -351.91746) (xy 32.815115 -351.94695)
			(xy 32.765495 -351.969609) (xy 32.713156 -351.984976) (xy 32.659162 -351.992737) (xy 32.631888 -351.9932)
			(xy 31.768288 -351.9932) (xy 31.741022 -351.992637) (xy 31.687045 -351.984875) (xy 31.634722 -351.96951)
			(xy 31.585118 -351.946855) (xy 31.539244 -351.917372) (xy 31.498031 -351.88166) (xy 31.462321 -351.840447)
			(xy 31.432839 -351.794571) (xy 31.410186 -351.744967) (xy 31.394823 -351.692643) (xy 31.387062 -351.638666)
			(xy 29.904214 -351.638666) (xy 29.904214 -351.638671) (xy 29.896452 -351.692657) (xy 29.881086 -351.74499)
			(xy 29.85843 -351.794603) (xy 29.828944 -351.840487) (xy 29.793228 -351.881708) (xy 29.75201 -351.917427)
			(xy 29.706128 -351.946917) (xy 29.656516 -351.969577) (xy 29.604185 -351.984946) (xy 29.550199 -351.992712)
			(xy 29.522928 -351.9932) (xy 28.659328 -351.9932) (xy 28.632058 -351.992663) (xy 28.578074 -351.984904)
			(xy 28.525743 -351.969542) (xy 28.476131 -351.946888) (xy 28.430249 -351.917404) (xy 28.389029 -351.881691)
			(xy 28.353312 -351.840474) (xy 28.323825 -351.794593) (xy 28.301168 -351.744983) (xy 28.285802 -351.692654)
			(xy 28.278039 -351.63867) (xy 26.795336 -351.63867) (xy 26.795336 -351.638675) (xy 26.787573 -351.69267)
			(xy 26.772203 -351.745011) (xy 26.749541 -351.794631) (xy 26.720047 -351.840521) (xy 26.684323 -351.881746)
			(xy 26.643095 -351.917467) (xy 26.597203 -351.946956) (xy 26.547581 -351.969614) (xy 26.495239 -351.984979)
			(xy 26.441243 -351.992739) (xy 26.413968 -351.9932) (xy 25.550368 -351.9932) (xy 25.523103 -351.992635)
			(xy 25.469128 -351.984871) (xy 25.416808 -351.969504) (xy 25.367206 -351.946849) (xy 25.321334 -351.917365)
			(xy 25.280124 -351.881653) (xy 25.244416 -351.84044) (xy 25.214936 -351.794566) (xy 25.192284 -351.744962)
			(xy 25.176922 -351.692641) (xy 25.169162 -351.638665) (xy 23.686314 -351.638665) (xy 23.686314 -351.638672)
			(xy 23.678551 -351.69266) (xy 23.663185 -351.744994) (xy 23.640527 -351.794609) (xy 23.611039 -351.840494)
			(xy 23.575321 -351.881715) (xy 23.5341 -351.917434) (xy 23.488216 -351.946923) (xy 23.438602 -351.969582)
			(xy 23.386268 -351.98495) (xy 23.33228 -351.992713) (xy 23.305008 -351.9932) (xy 22.441408 -351.9932)
			(xy 22.414139 -351.992661) (xy 22.360157 -351.984901) (xy 22.307829 -351.969537) (xy 22.258219 -351.946882)
			(xy 22.212339 -351.917397) (xy 22.171122 -351.881683) (xy 22.135407 -351.840467) (xy 22.105922 -351.794588)
			(xy 22.083266 -351.744979) (xy 22.067901 -351.692651) (xy 22.060139 -351.638669) (xy 20.577347 -351.638669)
			(xy 20.577347 -351.638711) (xy 20.569584 -351.692698) (xy 20.554218 -351.74503) (xy 20.53156 -351.794643)
			(xy 20.502073 -351.840527) (xy 20.466355 -351.881747) (xy 20.425135 -351.917464) (xy 20.379252 -351.946951)
			(xy 20.329638 -351.969609) (xy 20.277306 -351.984975) (xy 20.223319 -351.992737) (xy 20.196048 -351.9932)
			(xy 19.332448 -351.9932) (xy 19.305179 -351.992717) (xy 19.251195 -351.984955) (xy 19.198865 -351.96959)
			(xy 19.149255 -351.946933) (xy 19.103374 -351.917447) (xy 19.062157 -351.881732) (xy 19.026441 -351.840514)
			(xy 18.996956 -351.794633) (xy 18.974299 -351.745023) (xy 18.958934 -351.692693) (xy 18.951172 -351.638709)
			(xy 0.6096 -351.638709) (xy 0.6096 -354.759373) (xy 22.060084 -354.759373) (xy 22.060084 -354.704827)
			(xy 22.067846 -354.650837) (xy 22.083214 -354.598501) (xy 22.105873 -354.548885) (xy 22.135363 -354.502999)
			(xy 22.171083 -354.461777) (xy 22.212306 -354.426058) (xy 22.258192 -354.396569) (xy 22.307809 -354.373911)
			(xy 22.360145 -354.358545) (xy 22.414135 -354.350783) (xy 22.441408 -354.35032) (xy 23.305008 -354.35032)
			(xy 23.332276 -354.350843) (xy 23.386256 -354.358605) (xy 23.438582 -354.37397) (xy 23.488189 -354.396626)
			(xy 23.534067 -354.426111) (xy 23.575281 -354.461824) (xy 23.610994 -354.50304) (xy 23.640478 -354.548918)
			(xy 23.663132 -354.598525) (xy 23.678497 -354.650852) (xy 23.686258 -354.704832) (xy 23.686258 -354.759368)
			(xy 23.686258 -354.759369) (xy 25.169106 -354.759369) (xy 25.169106 -354.704831) (xy 25.176868 -354.650847)
			(xy 25.192232 -354.598518) (xy 25.214887 -354.548908) (xy 25.244371 -354.503026) (xy 25.280085 -354.461807)
			(xy 25.3213 -354.42609) (xy 25.36718 -354.396602) (xy 25.416788 -354.373943) (xy 25.469116 -354.358574)
			(xy 25.523099 -354.350809) (xy 25.550368 -354.35032) (xy 26.413968 -354.35032) (xy 26.441239 -354.350817)
			(xy 26.495227 -354.358575) (xy 26.547561 -354.373938) (xy 26.597176 -354.396593) (xy 26.643061 -354.426078)
			(xy 26.684283 -354.461794) (xy 26.720003 -354.503013) (xy 26.749492 -354.548896) (xy 26.772151 -354.598509)
			(xy 26.787518 -354.650842) (xy 26.79528 -354.704829) (xy 26.79528 -354.759371) (xy 26.79528 -354.759374)
			(xy 28.277984 -354.759374) (xy 28.277984 -354.704826) (xy 28.285747 -354.650835) (xy 28.301115 -354.598497)
			(xy 28.323776 -354.54888) (xy 28.353268 -354.502993) (xy 28.38899 -354.46177) (xy 28.430215 -354.426051)
			(xy 28.476104 -354.396562) (xy 28.525723 -354.373905) (xy 28.578062 -354.358541) (xy 28.632054 -354.350782)
			(xy 28.659328 -354.35032) (xy 29.522928 -354.35032) (xy 29.550195 -354.350844) (xy 29.604173 -354.358609)
			(xy 29.656497 -354.373976) (xy 29.706101 -354.396633) (xy 29.751976 -354.426118) (xy 29.793188 -354.461831)
			(xy 29.828899 -354.503046) (xy 29.858381 -354.548924) (xy 29.881034 -354.59853) (xy 29.896397 -354.650855)
			(xy 29.904158 -354.704833) (xy 29.904158 -354.759367) (xy 29.904158 -354.75937) (xy 31.387006 -354.75937)
			(xy 31.387006 -354.70483) (xy 31.394768 -354.650845) (xy 31.410134 -354.598514) (xy 31.43279 -354.548902)
			(xy 31.462276 -354.50302) (xy 31.497992 -354.4618) (xy 31.53921 -354.426083) (xy 31.585091 -354.396596)
			(xy 31.634703 -354.373938) (xy 31.687033 -354.358571) (xy 31.741018 -354.350807) (xy 31.768288 -354.35032)
			(xy 32.631888 -354.35032) (xy 32.659158 -354.350819) (xy 32.713144 -354.358579) (xy 32.765476 -354.373944)
			(xy 32.815088 -354.396599) (xy 32.860971 -354.426085) (xy 32.902191 -354.461801) (xy 32.937908 -354.503019)
			(xy 32.967395 -354.548902) (xy 32.990052 -354.598513) (xy 33.005418 -354.650844) (xy 33.013181 -354.70483)
			(xy 33.013181 -354.75937) (xy 33.01318 -354.759374) (xy 34.495884 -354.759374) (xy 34.495884 -354.704826)
			(xy 34.503647 -354.650832) (xy 34.519017 -354.598493) (xy 34.541679 -354.548874) (xy 34.571172 -354.502986)
			(xy 34.606897 -354.461763) (xy 34.648125 -354.426044) (xy 34.694016 -354.396556) (xy 34.743638 -354.3739)
			(xy 34.795979 -354.358537) (xy 34.849973 -354.35078) (xy 34.877248 -354.35032) (xy 35.740848 -354.35032)
			(xy 35.768114 -354.350846) (xy 35.82209 -354.358613) (xy 35.874411 -354.373981) (xy 35.924013 -354.396639)
			(xy 35.969886 -354.426125) (xy 36.011095 -354.461839) (xy 36.046804 -354.503053) (xy 36.076284 -354.548929)
			(xy 36.098936 -354.598534) (xy 36.114298 -354.650857) (xy 36.122058 -354.704834) (xy 36.122058 -354.759366)
			(xy 36.122057 -354.759373) (xy 37.604884 -354.759373) (xy 37.604884 -354.704827) (xy 37.612646 -354.650837)
			(xy 37.628014 -354.598501) (xy 37.650673 -354.548885) (xy 37.680163 -354.502999) (xy 37.715883 -354.461777)
			(xy 37.757106 -354.426058) (xy 37.802992 -354.396569) (xy 37.852609 -354.373911) (xy 37.904945 -354.358545)
			(xy 37.958935 -354.350783) (xy 37.986208 -354.35032) (xy 38.849808 -354.35032) (xy 38.877076 -354.350843)
			(xy 38.931056 -354.358605) (xy 38.983382 -354.37397) (xy 39.032989 -354.396626) (xy 39.078867 -354.426111)
			(xy 39.120081 -354.461824) (xy 39.155794 -354.50304) (xy 39.185278 -354.548918) (xy 39.207932 -354.598525)
			(xy 39.223297 -354.650852) (xy 39.231058 -354.704832) (xy 39.231058 -354.759368) (xy 39.231058 -354.759369)
			(xy 40.713906 -354.759369) (xy 40.713906 -354.704831) (xy 40.721668 -354.650847) (xy 40.737032 -354.598518)
			(xy 40.759687 -354.548908) (xy 40.789171 -354.503026) (xy 40.824885 -354.461807) (xy 40.8661 -354.42609)
			(xy 40.91198 -354.396602) (xy 40.961588 -354.373943) (xy 41.013916 -354.358574) (xy 41.067899 -354.350809)
			(xy 41.095168 -354.35032) (xy 41.958768 -354.35032) (xy 41.986039 -354.350817) (xy 42.040027 -354.358575)
			(xy 42.092361 -354.373938) (xy 42.141976 -354.396593) (xy 42.187861 -354.426078) (xy 42.229083 -354.461794)
			(xy 42.264803 -354.503013) (xy 42.294292 -354.548896) (xy 42.316951 -354.598509) (xy 42.332318 -354.650842)
			(xy 42.34008 -354.704829) (xy 42.34008 -354.759371) (xy 42.34008 -354.759374) (xy 43.822784 -354.759374)
			(xy 43.822784 -354.704826) (xy 43.830547 -354.650835) (xy 43.845915 -354.598497) (xy 43.868576 -354.54888)
			(xy 43.898068 -354.502993) (xy 43.93379 -354.46177) (xy 43.975015 -354.426051) (xy 44.020904 -354.396562)
			(xy 44.070523 -354.373905) (xy 44.122862 -354.358541) (xy 44.176854 -354.350782) (xy 44.204128 -354.35032)
			(xy 45.067728 -354.35032) (xy 45.094995 -354.350844) (xy 45.148973 -354.358609) (xy 45.201297 -354.373976)
			(xy 45.250901 -354.396633) (xy 45.296776 -354.426118) (xy 45.337988 -354.461831) (xy 45.373699 -354.503046)
			(xy 45.403181 -354.548924) (xy 45.425834 -354.59853) (xy 45.441197 -354.650855) (xy 45.448958 -354.704833)
			(xy 45.448958 -354.759367) (xy 45.448958 -354.75937) (xy 46.931806 -354.75937) (xy 46.931806 -354.70483)
			(xy 46.939568 -354.650845) (xy 46.954934 -354.598514) (xy 46.97759 -354.548902) (xy 47.007076 -354.50302)
			(xy 47.042792 -354.4618) (xy 47.08401 -354.426083) (xy 47.129891 -354.396596) (xy 47.179503 -354.373938)
			(xy 47.231833 -354.358571) (xy 47.285818 -354.350807) (xy 47.313088 -354.35032) (xy 48.176688 -354.35032)
			(xy 48.203958 -354.350819) (xy 48.257944 -354.358579) (xy 48.310276 -354.373944) (xy 48.359888 -354.396599)
			(xy 48.405771 -354.426085) (xy 48.446991 -354.461801) (xy 48.482708 -354.503019) (xy 48.512195 -354.548902)
			(xy 48.534852 -354.598513) (xy 48.550218 -354.650844) (xy 48.557981 -354.70483) (xy 48.557981 -354.75937)
			(xy 48.55798 -354.759374) (xy 50.040684 -354.759374) (xy 50.040684 -354.704826) (xy 50.048447 -354.650832)
			(xy 50.063817 -354.598493) (xy 50.086479 -354.548874) (xy 50.115972 -354.502986) (xy 50.151697 -354.461763)
			(xy 50.192925 -354.426044) (xy 50.238816 -354.396556) (xy 50.288438 -354.3739) (xy 50.340779 -354.358537)
			(xy 50.394773 -354.35078) (xy 50.422048 -354.35032) (xy 51.285648 -354.35032) (xy 51.312914 -354.350846)
			(xy 51.36689 -354.358613) (xy 51.419211 -354.373981) (xy 51.468813 -354.396639) (xy 51.514686 -354.426125)
			(xy 51.555895 -354.461839) (xy 51.591604 -354.503053) (xy 51.621084 -354.548929) (xy 51.643736 -354.598534)
			(xy 51.659098 -354.650857) (xy 51.666858 -354.704834) (xy 51.666858 -354.759366) (xy 51.659098 -354.813343)
			(xy 51.643736 -354.865666) (xy 51.621084 -354.915271) (xy 51.591604 -354.961147) (xy 51.555895 -355.002361)
			(xy 51.514686 -355.038075) (xy 51.468813 -355.067561) (xy 51.419211 -355.090219) (xy 51.36689 -355.105587)
			(xy 51.312914 -355.113354) (xy 51.285648 -355.113844) (xy 50.422048 -355.113844) (xy 50.394773 -355.11342)
			(xy 50.340779 -355.105663) (xy 50.288438 -355.0903) (xy 50.238816 -355.067644) (xy 50.192925 -355.038156)
			(xy 50.151697 -355.002437) (xy 50.115972 -354.961214) (xy 50.086479 -354.915326) (xy 50.063817 -354.865707)
			(xy 50.048447 -354.813368) (xy 50.040684 -354.759374) (xy 48.55798 -354.759374) (xy 48.550218 -354.813356)
			(xy 48.534852 -354.865687) (xy 48.512195 -354.915298) (xy 48.482708 -354.961181) (xy 48.446991 -355.002399)
			(xy 48.405771 -355.038115) (xy 48.359888 -355.067601) (xy 48.310276 -355.090256) (xy 48.257944 -355.105621)
			(xy 48.203958 -355.113381) (xy 48.176688 -355.113844) (xy 47.313088 -355.113844) (xy 47.285818 -355.113393)
			(xy 47.231833 -355.105629) (xy 47.179503 -355.090262) (xy 47.129891 -355.067604) (xy 47.08401 -355.038117)
			(xy 47.042792 -355.0024) (xy 47.007076 -354.96118) (xy 46.97759 -354.915298) (xy 46.954934 -354.865686)
			(xy 46.939568 -354.813355) (xy 46.931806 -354.75937) (xy 45.448958 -354.75937) (xy 45.441197 -354.813345)
			(xy 45.425834 -354.86567) (xy 45.403181 -354.915276) (xy 45.373699 -354.961154) (xy 45.337988 -355.002369)
			(xy 45.296776 -355.038082) (xy 45.250901 -355.067567) (xy 45.201297 -355.090224) (xy 45.148973 -355.105591)
			(xy 45.094995 -355.113356) (xy 45.067728 -355.113844) (xy 44.204128 -355.113844) (xy 44.176854 -355.113418)
			(xy 44.122862 -355.105659) (xy 44.070523 -355.090295) (xy 44.020904 -355.067638) (xy 43.975015 -355.038149)
			(xy 43.93379 -355.00243) (xy 43.898068 -354.961207) (xy 43.868576 -354.91532) (xy 43.845915 -354.865703)
			(xy 43.830547 -354.813365) (xy 43.822784 -354.759374) (xy 42.34008 -354.759374) (xy 42.332318 -354.813358)
			(xy 42.316951 -354.865691) (xy 42.294292 -354.915304) (xy 42.264803 -354.961187) (xy 42.229083 -355.002406)
			(xy 42.187861 -355.038122) (xy 42.141976 -355.067607) (xy 42.092361 -355.090262) (xy 42.040027 -355.105625)
			(xy 41.986039 -355.113383) (xy 41.958768 -355.113844) (xy 41.095168 -355.113844) (xy 41.067899 -355.113391)
			(xy 41.013916 -355.105626) (xy 40.961588 -355.090257) (xy 40.91198 -355.067598) (xy 40.8661 -355.03811)
			(xy 40.824885 -355.002393) (xy 40.789171 -354.961174) (xy 40.759687 -354.915292) (xy 40.737032 -354.865682)
			(xy 40.721668 -354.813353) (xy 40.713906 -354.759369) (xy 39.231058 -354.759369) (xy 39.223297 -354.813348)
			(xy 39.207932 -354.865675) (xy 39.185278 -354.915282) (xy 39.155794 -354.96116) (xy 39.120081 -355.002376)
			(xy 39.078867 -355.038089) (xy 39.032989 -355.067574) (xy 38.983382 -355.09023) (xy 38.931056 -355.105595)
			(xy 38.877076 -355.113357) (xy 38.849808 -355.113844) (xy 37.986208 -355.113844) (xy 37.958935 -355.113417)
			(xy 37.904945 -355.105655) (xy 37.852609 -355.090289) (xy 37.802992 -355.067631) (xy 37.757106 -355.038142)
			(xy 37.715883 -355.002423) (xy 37.680163 -354.961201) (xy 37.650673 -354.915315) (xy 37.628014 -354.865699)
			(xy 37.612646 -354.813363) (xy 37.604884 -354.759373) (xy 36.122057 -354.759373) (xy 36.114298 -354.813343)
			(xy 36.098936 -354.865666) (xy 36.076284 -354.915271) (xy 36.046804 -354.961147) (xy 36.011095 -355.002361)
			(xy 35.969886 -355.038075) (xy 35.924013 -355.067561) (xy 35.874411 -355.090219) (xy 35.82209 -355.105587)
			(xy 35.768114 -355.113354) (xy 35.740848 -355.113844) (xy 34.877248 -355.113844) (xy 34.849973 -355.11342)
			(xy 34.795979 -355.105663) (xy 34.743638 -355.0903) (xy 34.694016 -355.067644) (xy 34.648125 -355.038156)
			(xy 34.606897 -355.002437) (xy 34.571172 -354.961214) (xy 34.541679 -354.915326) (xy 34.519017 -354.865707)
			(xy 34.503647 -354.813368) (xy 34.495884 -354.759374) (xy 33.01318 -354.759374) (xy 33.005418 -354.813356)
			(xy 32.990052 -354.865687) (xy 32.967395 -354.915298) (xy 32.937908 -354.961181) (xy 32.902191 -355.002399)
			(xy 32.860971 -355.038115) (xy 32.815088 -355.067601) (xy 32.765476 -355.090256) (xy 32.713144 -355.105621)
			(xy 32.659158 -355.113381) (xy 32.631888 -355.113844) (xy 31.768288 -355.113844) (xy 31.741018 -355.113393)
			(xy 31.687033 -355.105629) (xy 31.634703 -355.090262) (xy 31.585091 -355.067604) (xy 31.53921 -355.038117)
			(xy 31.497992 -355.0024) (xy 31.462276 -354.96118) (xy 31.43279 -354.915298) (xy 31.410134 -354.865686)
			(xy 31.394768 -354.813355) (xy 31.387006 -354.75937) (xy 29.904158 -354.75937) (xy 29.896397 -354.813345)
			(xy 29.881034 -354.86567) (xy 29.858381 -354.915276) (xy 29.828899 -354.961154) (xy 29.793188 -355.002369)
			(xy 29.751976 -355.038082) (xy 29.706101 -355.067567) (xy 29.656497 -355.090224) (xy 29.604173 -355.105591)
			(xy 29.550195 -355.113356) (xy 29.522928 -355.113844) (xy 28.659328 -355.113844) (xy 28.632054 -355.113418)
			(xy 28.578062 -355.105659) (xy 28.525723 -355.090295) (xy 28.476104 -355.067638) (xy 28.430215 -355.038149)
			(xy 28.38899 -355.00243) (xy 28.353268 -354.961207) (xy 28.323776 -354.91532) (xy 28.301115 -354.865703)
			(xy 28.285747 -354.813365) (xy 28.277984 -354.759374) (xy 26.79528 -354.759374) (xy 26.787518 -354.813358)
			(xy 26.772151 -354.865691) (xy 26.749492 -354.915304) (xy 26.720003 -354.961187) (xy 26.684283 -355.002406)
			(xy 26.643061 -355.038122) (xy 26.597176 -355.067607) (xy 26.547561 -355.090262) (xy 26.495227 -355.105625)
			(xy 26.441239 -355.113383) (xy 26.413968 -355.113844) (xy 25.550368 -355.113844) (xy 25.523099 -355.113391)
			(xy 25.469116 -355.105626) (xy 25.416788 -355.090257) (xy 25.36718 -355.067598) (xy 25.3213 -355.03811)
			(xy 25.280085 -355.002393) (xy 25.244371 -354.961174) (xy 25.214887 -354.915292) (xy 25.192232 -354.865682)
			(xy 25.176868 -354.813353) (xy 25.169106 -354.759369) (xy 23.686258 -354.759369) (xy 23.678497 -354.813348)
			(xy 23.663132 -354.865675) (xy 23.640478 -354.915282) (xy 23.610994 -354.96116) (xy 23.575281 -355.002376)
			(xy 23.534067 -355.038089) (xy 23.488189 -355.067574) (xy 23.438582 -355.09023) (xy 23.386256 -355.105595)
			(xy 23.332276 -355.113357) (xy 23.305008 -355.113844) (xy 22.441408 -355.113844) (xy 22.414135 -355.113417)
			(xy 22.360145 -355.105655) (xy 22.307809 -355.090289) (xy 22.258192 -355.067631) (xy 22.212306 -355.038142)
			(xy 22.171083 -355.002423) (xy 22.135363 -354.961201) (xy 22.105873 -354.915315) (xy 22.083214 -354.865699)
			(xy 22.067846 -354.813363) (xy 22.060084 -354.759373) (xy 0.6096 -354.759373) (xy 0.6096 -357.784969)
			(xy 22.060131 -357.784969) (xy 22.060131 -357.730431) (xy 22.067893 -357.676447) (xy 22.083259 -357.624118)
			(xy 22.105915 -357.574508) (xy 22.135401 -357.528628) (xy 22.171117 -357.487411) (xy 22.212334 -357.451696)
			(xy 22.258215 -357.422211) (xy 22.307826 -357.399556) (xy 22.360155 -357.384191) (xy 22.414139 -357.376431)
			(xy 22.441408 -357.375968) (xy 23.305008 -357.375968) (xy 23.332279 -357.376395) (xy 23.386266 -357.384158)
			(xy 23.438599 -357.399525) (xy 23.488212 -357.422184) (xy 23.534095 -357.451672) (xy 23.575315 -357.48739)
			(xy 23.611032 -357.528611) (xy 23.64052 -357.574495) (xy 23.663177 -357.624109) (xy 23.678543 -357.676442)
			(xy 23.686306 -357.730429) (xy 23.686306 -357.784966) (xy 25.169154 -357.784966) (xy 25.169154 -357.730434)
			(xy 25.176914 -357.676458) (xy 25.192277 -357.624135) (xy 25.214929 -357.574531) (xy 25.24441 -357.528655)
			(xy 25.280119 -357.487441) (xy 25.321329 -357.451729) (xy 25.367203 -357.422244) (xy 25.416805 -357.399588)
			(xy 25.469126 -357.384221) (xy 25.523102 -357.376457) (xy 25.550368 -357.375968) (xy 26.413968 -357.375968)
			(xy 26.441243 -357.376369) (xy 26.495237 -357.384128) (xy 26.547578 -357.399493) (xy 26.597199 -357.422151)
			(xy 26.64309 -357.45164) (xy 26.684317 -357.48736) (xy 26.720041 -357.528584) (xy 26.749534 -357.574473)
			(xy 26.772196 -357.624092) (xy 26.787565 -357.676431) (xy 26.795328 -357.730425) (xy 26.795328 -357.78497)
			(xy 28.278031 -357.78497) (xy 28.278032 -357.73043) (xy 28.285794 -357.676445) (xy 28.30116 -357.624114)
			(xy 28.323818 -357.574503) (xy 28.353306 -357.528621) (xy 28.389024 -357.487404) (xy 28.430244 -357.451689)
			(xy 28.476127 -357.422205) (xy 28.52574 -357.39955) (xy 28.578072 -357.384188) (xy 28.632058 -357.37643)
			(xy 28.659328 -357.375968) (xy 29.522928 -357.375968) (xy 29.550198 -357.376396) (xy 29.604183 -357.384162)
			(xy 29.656513 -357.399531) (xy 29.706124 -357.42219) (xy 29.752005 -357.451679) (xy 29.793222 -357.487397)
			(xy 29.828937 -357.528618) (xy 29.858423 -357.574501) (xy 29.881079 -357.624113) (xy 29.896444 -357.676444)
			(xy 29.904206 -357.73043) (xy 29.904206 -357.784967) (xy 31.387054 -357.784967) (xy 31.387054 -357.730433)
			(xy 31.394815 -357.676455) (xy 31.410179 -357.624131) (xy 31.432832 -357.574525) (xy 31.462315 -357.528648)
			(xy 31.498026 -357.487434) (xy 31.539239 -357.451722) (xy 31.585115 -357.422238) (xy 31.634719 -357.399583)
			(xy 31.687043 -357.384218) (xy 31.741021 -357.376455) (xy 31.768288 -357.375968) (xy 32.631888 -357.375968)
			(xy 32.659162 -357.376371) (xy 32.713154 -357.384132) (xy 32.765492 -357.399499) (xy 32.815111 -357.422157)
			(xy 32.861 -357.451647) (xy 32.902224 -357.487367) (xy 32.937946 -357.528591) (xy 32.967437 -357.574479)
			(xy 32.990097 -357.624096) (xy 33.005465 -357.676434) (xy 33.013228 -357.730426) (xy 33.013228 -357.784971)
			(xy 34.495932 -357.784971) (xy 34.495932 -357.730429) (xy 34.503694 -357.676442) (xy 34.519062 -357.62411)
			(xy 34.541721 -357.574497) (xy 34.571211 -357.528615) (xy 34.606931 -357.487397) (xy 34.648153 -357.451682)
			(xy 34.694039 -357.422198) (xy 34.743655 -357.399545) (xy 34.795989 -357.384184) (xy 34.849977 -357.376428)
			(xy 34.877248 -357.375968) (xy 35.740848 -357.375968) (xy 35.768117 -357.376398) (xy 35.8221 -357.384166)
			(xy 35.874428 -357.399536) (xy 35.924036 -357.422197) (xy 35.969914 -357.451687) (xy 36.011129 -357.487405)
			(xy 36.046842 -357.528624) (xy 36.076326 -357.574506) (xy 36.09898 -357.624117) (xy 36.114345 -357.676447)
			(xy 36.122106 -357.730431) (xy 36.122106 -357.784969) (xy 37.604931 -357.784969) (xy 37.604931 -357.730431)
			(xy 37.612693 -357.676447) (xy 37.628059 -357.624118) (xy 37.650715 -357.574508) (xy 37.680201 -357.528628)
			(xy 37.715917 -357.487411) (xy 37.757134 -357.451696) (xy 37.803015 -357.422211) (xy 37.852626 -357.399556)
			(xy 37.904955 -357.384191) (xy 37.958939 -357.376431) (xy 37.986208 -357.375968) (xy 38.849808 -357.375968)
			(xy 38.877079 -357.376395) (xy 38.931066 -357.384158) (xy 38.983399 -357.399525) (xy 39.033012 -357.422184)
			(xy 39.078895 -357.451672) (xy 39.120115 -357.48739) (xy 39.155832 -357.528611) (xy 39.18532 -357.574495)
			(xy 39.207977 -357.624109) (xy 39.223343 -357.676442) (xy 39.231106 -357.730429) (xy 39.231106 -357.784966)
			(xy 40.713954 -357.784966) (xy 40.713954 -357.730434) (xy 40.721714 -357.676458) (xy 40.737077 -357.624135)
			(xy 40.759729 -357.574531) (xy 40.78921 -357.528655) (xy 40.824919 -357.487441) (xy 40.866129 -357.451729)
			(xy 40.912003 -357.422244) (xy 40.961605 -357.399588) (xy 41.013926 -357.384221) (xy 41.067902 -357.376457)
			(xy 41.095168 -357.375968) (xy 41.958768 -357.375968) (xy 41.986043 -357.376369) (xy 42.040037 -357.384128)
			(xy 42.092378 -357.399493) (xy 42.141999 -357.422151) (xy 42.18789 -357.45164) (xy 42.229117 -357.48736)
			(xy 42.264841 -357.528584) (xy 42.294334 -357.574473) (xy 42.316996 -357.624092) (xy 42.332365 -357.676431)
			(xy 42.340128 -357.730425) (xy 42.340128 -357.78497) (xy 43.822831 -357.78497) (xy 43.822832 -357.73043)
			(xy 43.830594 -357.676445) (xy 43.84596 -357.624114) (xy 43.868618 -357.574503) (xy 43.898106 -357.528621)
			(xy 43.933824 -357.487404) (xy 43.975044 -357.451689) (xy 44.020927 -357.422205) (xy 44.07054 -357.39955)
			(xy 44.122872 -357.384188) (xy 44.176858 -357.37643) (xy 44.204128 -357.375968) (xy 45.067728 -357.375968)
			(xy 45.094998 -357.376396) (xy 45.148983 -357.384162) (xy 45.201313 -357.399531) (xy 45.250924 -357.42219)
			(xy 45.296805 -357.451679) (xy 45.338022 -357.487397) (xy 45.373737 -357.528618) (xy 45.403223 -357.574501)
			(xy 45.425879 -357.624113) (xy 45.441244 -357.676444) (xy 45.449006 -357.73043) (xy 45.449006 -357.784967)
			(xy 46.931854 -357.784967) (xy 46.931854 -357.730433) (xy 46.939615 -357.676455) (xy 46.954979 -357.624131)
			(xy 46.977632 -357.574525) (xy 47.007115 -357.528648) (xy 47.042826 -357.487434) (xy 47.084039 -357.451722)
			(xy 47.129915 -357.422238) (xy 47.179519 -357.399583) (xy 47.231843 -357.384218) (xy 47.285821 -357.376455)
			(xy 47.313088 -357.375968) (xy 48.176688 -357.375968) (xy 48.203962 -357.376371) (xy 48.257954 -357.384132)
			(xy 48.310292 -357.399499) (xy 48.359911 -357.422157) (xy 48.4058 -357.451647) (xy 48.447024 -357.487367)
			(xy 48.482746 -357.528591) (xy 48.512237 -357.574479) (xy 48.534897 -357.624096) (xy 48.550265 -357.676434)
			(xy 48.558028 -357.730426) (xy 48.558028 -357.784971) (xy 50.040732 -357.784971) (xy 50.040732 -357.730429)
			(xy 50.048494 -357.676442) (xy 50.063862 -357.62411) (xy 50.086521 -357.574497) (xy 50.116011 -357.528615)
			(xy 50.151731 -357.487397) (xy 50.192953 -357.451682) (xy 50.238839 -357.422198) (xy 50.288455 -357.399545)
			(xy 50.340789 -357.384184) (xy 50.394777 -357.376428) (xy 50.422048 -357.375968) (xy 51.285648 -357.375968)
			(xy 51.312917 -357.376398) (xy 51.3669 -357.384166) (xy 51.419228 -357.399536) (xy 51.468836 -357.422197)
			(xy 51.514714 -357.451687) (xy 51.555929 -357.487405) (xy 51.591642 -357.528624) (xy 51.621126 -357.574506)
			(xy 51.64378 -357.624117) (xy 51.659145 -357.676447) (xy 51.666906 -357.730431) (xy 51.666906 -357.784969)
			(xy 51.659145 -357.838953) (xy 51.64378 -357.891283) (xy 51.621126 -357.940894) (xy 51.591642 -357.986776)
			(xy 51.555929 -358.027995) (xy 51.514714 -358.063713) (xy 51.468836 -358.093203) (xy 51.419228 -358.115864)
			(xy 51.3669 -358.131234) (xy 51.312917 -358.139002) (xy 51.285648 -358.139492) (xy 50.422048 -358.139492)
			(xy 50.394777 -358.138972) (xy 50.340789 -358.131216) (xy 50.288455 -358.115855) (xy 50.238839 -358.093202)
			(xy 50.192953 -358.063718) (xy 50.151731 -358.028003) (xy 50.116011 -357.986785) (xy 50.086521 -357.940903)
			(xy 50.063862 -357.89129) (xy 50.048494 -357.838958) (xy 50.040732 -357.784971) (xy 48.558028 -357.784971)
			(xy 48.558028 -357.784974) (xy 48.550265 -357.838966) (xy 48.534897 -357.891304) (xy 48.512237 -357.940921)
			(xy 48.482746 -357.986809) (xy 48.447024 -358.028033) (xy 48.4058 -358.063753) (xy 48.359911 -358.093243)
			(xy 48.310292 -358.115901) (xy 48.257954 -358.131268) (xy 48.203962 -358.139029) (xy 48.176688 -358.139492)
			(xy 47.313088 -358.139492) (xy 47.285821 -358.138945) (xy 47.231843 -358.131182) (xy 47.179519 -358.115817)
			(xy 47.129915 -358.093162) (xy 47.084039 -358.063678) (xy 47.042826 -358.027966) (xy 47.007115 -357.986752)
			(xy 46.977632 -357.940875) (xy 46.954979 -357.891269) (xy 46.939615 -357.838945) (xy 46.931854 -357.784967)
			(xy 45.449006 -357.784967) (xy 45.449006 -357.78497) (xy 45.441244 -357.838956) (xy 45.425879 -357.891287)
			(xy 45.403223 -357.940899) (xy 45.373737 -357.986782) (xy 45.338022 -358.028003) (xy 45.296805 -358.063721)
			(xy 45.250924 -358.09321) (xy 45.201313 -358.115869) (xy 45.148983 -358.131238) (xy 45.094998 -358.139004)
			(xy 45.067728 -358.139492) (xy 44.204128 -358.139492) (xy 44.176858 -358.13897) (xy 44.122872 -358.131212)
			(xy 44.07054 -358.11585) (xy 44.020927 -358.093195) (xy 43.975044 -358.063711) (xy 43.933824 -358.027996)
			(xy 43.898106 -357.986779) (xy 43.868618 -357.940897) (xy 43.84596 -357.891286) (xy 43.830594 -357.838955)
			(xy 43.822831 -357.78497) (xy 42.340128 -357.78497) (xy 42.340128 -357.784975) (xy 42.332365 -357.838969)
			(xy 42.316996 -357.891308) (xy 42.294334 -357.940927) (xy 42.264841 -357.986816) (xy 42.229117 -358.02804)
			(xy 42.18789 -358.06376) (xy 42.141999 -358.093249) (xy 42.092378 -358.115907) (xy 42.040037 -358.131272)
			(xy 41.986043 -358.139031) (xy 41.958768 -358.139492) (xy 41.095168 -358.139492) (xy 41.067902 -358.138943)
			(xy 41.013926 -358.131179) (xy 40.961605 -358.115812) (xy 40.912003 -358.093156) (xy 40.866129 -358.063671)
			(xy 40.824919 -358.027959) (xy 40.78921 -357.986745) (xy 40.759729 -357.940869) (xy 40.737077 -357.891265)
			(xy 40.721714 -357.838942) (xy 40.713954 -357.784966) (xy 39.231106 -357.784966) (xy 39.231106 -357.784971)
			(xy 39.223343 -357.838958) (xy 39.207977 -357.891291) (xy 39.18532 -357.940905) (xy 39.155832 -357.986789)
			(xy 39.120115 -358.02801) (xy 39.078895 -358.063728) (xy 39.033012 -358.093216) (xy 38.983399 -358.115875)
			(xy 38.931066 -358.131242) (xy 38.877079 -358.139005) (xy 38.849808 -358.139492) (xy 37.986208 -358.139492)
			(xy 37.958939 -358.138969) (xy 37.904955 -358.131209) (xy 37.852626 -358.115844) (xy 37.803015 -358.093189)
			(xy 37.757134 -358.063704) (xy 37.715917 -358.027989) (xy 37.680201 -357.986772) (xy 37.650715 -357.940892)
			(xy 37.628059 -357.891282) (xy 37.612693 -357.838953) (xy 37.604931 -357.784969) (xy 36.122106 -357.784969)
			(xy 36.114345 -357.838953) (xy 36.09898 -357.891283) (xy 36.076326 -357.940894) (xy 36.046842 -357.986776)
			(xy 36.011129 -358.027995) (xy 35.969914 -358.063713) (xy 35.924036 -358.093203) (xy 35.874428 -358.115864)
			(xy 35.8221 -358.131234) (xy 35.768117 -358.139002) (xy 35.740848 -358.139492) (xy 34.877248 -358.139492)
			(xy 34.849977 -358.138972) (xy 34.795989 -358.131216) (xy 34.743655 -358.115855) (xy 34.694039 -358.093202)
			(xy 34.648153 -358.063718) (xy 34.606931 -358.028003) (xy 34.571211 -357.986785) (xy 34.541721 -357.940903)
			(xy 34.519062 -357.89129) (xy 34.503694 -357.838958) (xy 34.495932 -357.784971) (xy 33.013228 -357.784971)
			(xy 33.013228 -357.784974) (xy 33.005465 -357.838966) (xy 32.990097 -357.891304) (xy 32.967437 -357.940921)
			(xy 32.937946 -357.986809) (xy 32.902224 -358.028033) (xy 32.861 -358.063753) (xy 32.815111 -358.093243)
			(xy 32.765492 -358.115901) (xy 32.713154 -358.131268) (xy 32.659162 -358.139029) (xy 32.631888 -358.139492)
			(xy 31.768288 -358.139492) (xy 31.741021 -358.138945) (xy 31.687043 -358.131182) (xy 31.634719 -358.115817)
			(xy 31.585115 -358.093162) (xy 31.539239 -358.063678) (xy 31.498026 -358.027966) (xy 31.462315 -357.986752)
			(xy 31.432832 -357.940875) (xy 31.410179 -357.891269) (xy 31.394815 -357.838945) (xy 31.387054 -357.784967)
			(xy 29.904206 -357.784967) (xy 29.904206 -357.78497) (xy 29.896444 -357.838956) (xy 29.881079 -357.891287)
			(xy 29.858423 -357.940899) (xy 29.828937 -357.986782) (xy 29.793222 -358.028003) (xy 29.752005 -358.063721)
			(xy 29.706124 -358.09321) (xy 29.656513 -358.115869) (xy 29.604183 -358.131238) (xy 29.550198 -358.139004)
			(xy 29.522928 -358.139492) (xy 28.659328 -358.139492) (xy 28.632058 -358.13897) (xy 28.578072 -358.131212)
			(xy 28.52574 -358.11585) (xy 28.476127 -358.093195) (xy 28.430244 -358.063711) (xy 28.389024 -358.027996)
			(xy 28.353306 -357.986779) (xy 28.323818 -357.940897) (xy 28.30116 -357.891286) (xy 28.285794 -357.838955)
			(xy 28.278031 -357.78497) (xy 26.795328 -357.78497) (xy 26.795328 -357.784975) (xy 26.787565 -357.838969)
			(xy 26.772196 -357.891308) (xy 26.749534 -357.940927) (xy 26.720041 -357.986816) (xy 26.684317 -358.02804)
			(xy 26.64309 -358.06376) (xy 26.597199 -358.093249) (xy 26.547578 -358.115907) (xy 26.495237 -358.131272)
			(xy 26.441243 -358.139031) (xy 26.413968 -358.139492) (xy 25.550368 -358.139492) (xy 25.523102 -358.138943)
			(xy 25.469126 -358.131179) (xy 25.416805 -358.115812) (xy 25.367203 -358.093156) (xy 25.321329 -358.063671)
			(xy 25.280119 -358.027959) (xy 25.24441 -357.986745) (xy 25.214929 -357.940869) (xy 25.192277 -357.891265)
			(xy 25.176914 -357.838942) (xy 25.169154 -357.784966) (xy 23.686306 -357.784966) (xy 23.686306 -357.784971)
			(xy 23.678543 -357.838958) (xy 23.663177 -357.891291) (xy 23.64052 -357.940905) (xy 23.611032 -357.986789)
			(xy 23.575315 -358.02801) (xy 23.534095 -358.063728) (xy 23.488212 -358.093216) (xy 23.438599 -358.115875)
			(xy 23.386266 -358.131242) (xy 23.332279 -358.139005) (xy 23.305008 -358.139492) (xy 22.441408 -358.139492)
			(xy 22.414139 -358.138969) (xy 22.360155 -358.131209) (xy 22.307826 -358.115844) (xy 22.258215 -358.093189)
			(xy 22.212334 -358.063704) (xy 22.171117 -358.027989) (xy 22.135401 -357.986772) (xy 22.105915 -357.940892)
			(xy 22.083259 -357.891282) (xy 22.067893 -357.838953) (xy 22.060131 -357.784969) (xy 0.6096 -357.784969)
			(xy 0.6096 -363.334808) (xy 54.890416 -363.334808) (xy 54.890416 -362.471208) (xy 54.890906 -362.441224)
			(xy 54.898734 -362.381768) (xy 54.914255 -362.323843) (xy 54.937204 -362.268439) (xy 54.967188 -362.216505)
			(xy 55.003694 -362.168929) (xy 55.046099 -362.126524) (xy 55.093675 -362.090018) (xy 55.145609 -362.060034)
			(xy 55.201013 -362.037085) (xy 55.258938 -362.021564) (xy 55.318394 -362.013736) (xy 55.378362 -362.013736)
			(xy 55.437818 -362.021564) (xy 55.495743 -362.037085) (xy 55.551147 -362.060034) (xy 55.603081 -362.090018)
			(xy 55.650657 -362.126524) (xy 55.693062 -362.168929) (xy 55.729568 -362.216505) (xy 55.759552 -362.268439)
			(xy 55.782501 -362.323843) (xy 55.798022 -362.381768) (xy 55.80585 -362.441224) (xy 55.80634 -362.471208)
			(xy 55.80634 -363.334808) (xy 55.80585 -363.364792) (xy 55.798022 -363.424248) (xy 55.782501 -363.482173)
			(xy 55.759552 -363.537577) (xy 55.729568 -363.589511) (xy 55.693062 -363.637087) (xy 55.650657 -363.679492)
			(xy 55.603081 -363.715998) (xy 55.551147 -363.745982) (xy 55.495743 -363.768931) (xy 55.437818 -363.784452)
			(xy 55.378362 -363.79228) (xy 55.318394 -363.79228) (xy 55.258938 -363.784452) (xy 55.201013 -363.768931)
			(xy 55.145609 -363.745982) (xy 55.093675 -363.715998) (xy 55.046099 -363.679492) (xy 55.003694 -363.637087)
			(xy 54.967188 -363.589511) (xy 54.937204 -363.537577) (xy 54.914255 -363.482173) (xy 54.898734 -363.424248)
			(xy 54.890906 -363.364792) (xy 54.890416 -363.334808) (xy 0.6096 -363.334808) (xy 0.6096 -365.288322)
			(xy 2.818128 -365.288322) (xy 2.822199 -365.2327) (xy 2.834325 -365.178263) (xy 2.854248 -365.126172)
			(xy 2.881544 -365.077537) (xy 2.91563 -365.033394) (xy 2.955779 -364.994685) (xy 3.001137 -364.962234)
			(xy 3.050737 -364.936733) (xy 3.103521 -364.918726) (xy 3.158364 -364.908596) (xy 3.214098 -364.906559)
			(xy 3.269535 -364.912659) (xy 3.323492 -364.926765) (xy 3.374821 -364.948577) (xy 3.422427 -364.977631)
			(xy 3.465295 -365.013306) (xy 3.502512 -365.054843) (xy 3.533285 -365.101356) (xy 3.556957 -365.151853)
			(xy 3.573025 -365.20526) (xy 3.581145 -365.260436) (xy 3.581654 -365.288322) (xy 3.581145 -365.316208)
			(xy 3.573025 -365.371384) (xy 3.56676 -365.392208) (xy 7.202932 -365.392208) (xy 7.203418 -365.364957)
			(xy 7.211174 -365.311009) (xy 7.226529 -365.258714) (xy 7.249171 -365.209137) (xy 7.278637 -365.163287)
			(xy 7.314328 -365.122096) (xy 7.355519 -365.086405) (xy 7.401369 -365.056939) (xy 7.450946 -365.034297)
			(xy 7.503241 -365.018942) (xy 7.557189 -365.011186) (xy 7.611691 -365.011186) (xy 7.665639 -365.018942)
			(xy 7.717934 -365.034297) (xy 7.767511 -365.056939) (xy 7.813361 -365.086405) (xy 7.854552 -365.122096)
			(xy 7.890243 -365.163287) (xy 7.919709 -365.209137) (xy 7.942351 -365.258714) (xy 7.957706 -365.311009)
			(xy 7.965462 -365.364957) (xy 7.965948 -365.392208) (xy 7.965512 -365.418628) (xy 7.958226 -365.470963)
			(xy 7.94378 -365.521791) (xy 7.922453 -365.570135) (xy 7.894652 -365.61507) (xy 7.86091 -365.655735)
			(xy 7.821875 -365.691348) (xy 7.80034 -365.70666) (xy 7.788863 -365.715046) (xy 7.770739 -365.736932)
			(xy 7.759346 -365.762963) (xy 7.755566 -365.791126) (xy 7.756484 -365.797384) (xy 54.438294 -365.797384)
			(xy 54.438294 -365.737416) (xy 54.446121 -365.67796) (xy 54.461641 -365.620034) (xy 54.484589 -365.564629)
			(xy 54.514571 -365.512694) (xy 54.551076 -365.465115) (xy 54.593478 -365.422709) (xy 54.641052 -365.386199)
			(xy 54.692984 -365.356211) (xy 54.748387 -365.333257) (xy 54.806311 -365.317731) (xy 54.865766 -365.309897)
			(xy 54.89575 -365.309404) (xy 55.75935 -365.309404) (xy 55.789336 -365.309938) (xy 55.848794 -365.31776)
			(xy 55.906723 -365.333276) (xy 55.962131 -365.356222) (xy 56.01407 -365.386203) (xy 56.06165 -365.422708)
			(xy 56.104059 -365.465112) (xy 56.140569 -365.512689) (xy 56.170556 -365.564624) (xy 56.193508 -365.620029)
			(xy 56.20903 -365.677957) (xy 56.216859 -365.737414) (xy 56.216859 -365.797386) (xy 56.20903 -365.856843)
			(xy 56.193508 -365.914771) (xy 56.170556 -365.970176) (xy 56.140569 -366.022112) (xy 56.104059 -366.069688)
			(xy 56.06165 -366.112092) (xy 56.01407 -366.148597) (xy 55.962131 -366.178578) (xy 55.906723 -366.201524)
			(xy 55.848794 -366.21704) (xy 55.789336 -366.224862) (xy 55.75935 -366.225328) (xy 54.89575 -366.225328)
			(xy 54.865766 -366.224903) (xy 54.806311 -366.217069) (xy 54.748386 -366.201543) (xy 54.692984 -366.178589)
			(xy 54.641052 -366.148601) (xy 54.593478 -366.112091) (xy 54.551076 -366.069685) (xy 54.514571 -366.022106)
			(xy 54.484589 -365.970171) (xy 54.461641 -365.914766) (xy 54.446121 -365.85684) (xy 54.438294 -365.797384)
			(xy 7.756484 -365.797384) (xy 7.759691 -365.819241) (xy 7.771402 -365.845131) (xy 7.789793 -365.866792)
			(xy 7.801356 -365.875062) (xy 7.823355 -365.890327) (xy 7.863301 -365.925982) (xy 7.897866 -365.966875)
			(xy 7.926371 -366.012201) (xy 7.948254 -366.061069) (xy 7.963087 -366.112518) (xy 7.970576 -366.165536)
			(xy 7.971028 -366.192308) (xy 7.970542 -366.219559) (xy 7.962786 -366.273507) (xy 7.947431 -366.325802)
			(xy 7.924789 -366.375379) (xy 7.895323 -366.421229) (xy 7.859632 -366.46242) (xy 7.818441 -366.498111)
			(xy 7.772591 -366.527577) (xy 7.723014 -366.550219) (xy 7.670719 -366.565574) (xy 7.616771 -366.57333)
			(xy 7.562269 -366.57333) (xy 7.508321 -366.565574) (xy 7.456026 -366.550219) (xy 7.406449 -366.527577)
			(xy 7.360599 -366.498111) (xy 7.319408 -366.46242) (xy 7.283717 -366.421229) (xy 7.254251 -366.375379)
			(xy 7.231609 -366.325802) (xy 7.216254 -366.273507) (xy 7.208498 -366.219559) (xy 7.208012 -366.192308)
			(xy 7.208434 -366.165887) (xy 7.215719 -366.11355) (xy 7.230165 -366.062722) (xy 7.251495 -366.014376)
			(xy 7.279298 -365.969441) (xy 7.313043 -365.928777) (xy 7.352082 -365.893166) (xy 7.37362 -365.877856)
			(xy 7.385086 -365.869453) (xy 7.403216 -365.847574) (xy 7.414615 -365.821545) (xy 7.418399 -365.793383)
			(xy 7.414275 -365.765268) (xy 7.402562 -365.739379) (xy 7.384168 -365.717721) (xy 7.372604 -365.709454)
			(xy 7.350584 -365.694217) (xy 7.31064 -365.658556) (xy 7.276077 -365.617658) (xy 7.247575 -365.572327)
			(xy 7.225695 -365.523455) (xy 7.210867 -365.472002) (xy 7.203382 -365.418981) (xy 7.202932 -365.392208)
			(xy 3.56676 -365.392208) (xy 3.556957 -365.424791) (xy 3.533285 -365.475288) (xy 3.502512 -365.521801)
			(xy 3.465295 -365.563338) (xy 3.422427 -365.599013) (xy 3.374821 -365.628067) (xy 3.323492 -365.649879)
			(xy 3.269535 -365.663985) (xy 3.214098 -365.670085) (xy 3.158364 -365.668048) (xy 3.103521 -365.657918)
			(xy 3.050737 -365.639911) (xy 3.001137 -365.61441) (xy 2.955779 -365.581959) (xy 2.91563 -365.54325)
			(xy 2.881544 -365.499107) (xy 2.854248 -365.450472) (xy 2.834325 -365.398381) (xy 2.822199 -365.343944)
			(xy 2.818128 -365.288322) (xy 0.6096 -365.288322) (xy 0.6096 -368.23269) (xy 5.613144 -368.23269)
			(xy 5.617215 -368.177068) (xy 5.629341 -368.122631) (xy 5.649264 -368.07054) (xy 5.67656 -368.021905)
			(xy 5.710646 -367.977762) (xy 5.750795 -367.939053) (xy 5.796153 -367.906602) (xy 5.845753 -367.881101)
			(xy 5.898537 -367.863094) (xy 5.95338 -367.852964) (xy 6.009114 -367.850927) (xy 6.064551 -367.857027)
			(xy 6.118508 -367.871133) (xy 6.169837 -367.892945) (xy 6.217443 -367.921999) (xy 6.260311 -367.957674)
			(xy 6.297528 -367.999211) (xy 6.328301 -368.045724) (xy 6.351973 -368.096221) (xy 6.368041 -368.149628)
			(xy 6.376161 -368.204804) (xy 6.37667 -368.23269) (xy 6.376161 -368.260576) (xy 6.368041 -368.315752)
			(xy 6.351973 -368.369159) (xy 6.328301 -368.419656) (xy 6.297528 -368.466169) (xy 6.260311 -368.507706)
			(xy 6.217443 -368.543381) (xy 6.169837 -368.572435) (xy 6.118508 -368.594247) (xy 6.064551 -368.608353)
			(xy 6.009114 -368.614453) (xy 5.95338 -368.612416) (xy 5.898537 -368.602286) (xy 5.845753 -368.584279)
			(xy 5.796153 -368.558778) (xy 5.750795 -368.526327) (xy 5.710646 -368.487618) (xy 5.67656 -368.443475)
			(xy 5.649264 -368.39484) (xy 5.629341 -368.342749) (xy 5.617215 -368.288312) (xy 5.613144 -368.23269)
			(xy 0.6096 -368.23269) (xy 0.6096 -368.990118) (xy 29.624274 -368.990118) (xy 29.624758 -368.958499)
			(xy 29.632964 -368.895796) (xy 29.649239 -368.834688) (xy 29.673308 -368.77621) (xy 29.704764 -368.72135)
			(xy 29.743075 -368.671038) (xy 29.787592 -368.626124) (xy 29.837562 -368.587368) (xy 29.89214 -368.555426)
			(xy 29.950402 -368.530838) (xy 30.011363 -368.51402) (xy 30.073991 -368.505258) (xy 30.105604 -368.50447)
			(xy 30.105858 -368.50447) (xy 30.115718 -368.503867) (xy 30.133885 -368.496161) (xy 30.141164 -368.489484)
			(xy 31.784544 -366.846104) (xy 31.803325 -366.828083) (xy 31.845439 -366.797501) (xy 31.891813 -366.773872)
			(xy 31.941308 -366.757775) (xy 31.992709 -366.749605) (xy 32.018732 -366.749076) (xy 50.698654 -366.749076)
			(xy 50.724678 -366.749597) (xy 50.776081 -366.757765) (xy 50.825579 -366.773861) (xy 50.871955 -366.79749)
			(xy 50.914071 -366.828071) (xy 50.932842 -366.846104) (xy 52.6034 -368.516662) (xy 53.966364 -368.516662)
			(xy 53.966364 -367.653062) (xy 53.96685 -367.625793) (xy 53.974612 -367.571809) (xy 53.989977 -367.519479)
			(xy 54.012634 -367.469869) (xy 54.04212 -367.423988) (xy 54.077835 -367.382771) (xy 54.119052 -367.347056)
			(xy 54.164933 -367.31757) (xy 54.214543 -367.294913) (xy 54.266873 -367.279548) (xy 54.320857 -367.271786)
			(xy 54.375395 -367.271786) (xy 54.429379 -367.279548) (xy 54.481709 -367.294913) (xy 54.531319 -367.31757)
			(xy 54.5772 -367.347056) (xy 54.618417 -367.382771) (xy 54.654132 -367.423988) (xy 54.683618 -367.469869)
			(xy 54.706275 -367.519479) (xy 54.72164 -367.571809) (xy 54.729402 -367.625793) (xy 54.729888 -367.653062)
			(xy 54.729888 -368.516662) (xy 57.339484 -368.516662) (xy 57.339484 -367.653062) (xy 57.33997 -367.625793)
			(xy 57.347732 -367.571809) (xy 57.363097 -367.519479) (xy 57.385754 -367.469869) (xy 57.41524 -367.423988)
			(xy 57.450955 -367.382771) (xy 57.492172 -367.347056) (xy 57.538053 -367.31757) (xy 57.587663 -367.294913)
			(xy 57.639993 -367.279548) (xy 57.693977 -367.271786) (xy 57.748515 -367.271786) (xy 57.802499 -367.279548)
			(xy 57.854829 -367.294913) (xy 57.904439 -367.31757) (xy 57.95032 -367.347056) (xy 57.991537 -367.382771)
			(xy 58.027252 -367.423988) (xy 58.056738 -367.469869) (xy 58.079395 -367.519479) (xy 58.09476 -367.571809)
			(xy 58.102522 -367.625793) (xy 58.103008 -367.653062) (xy 58.103008 -368.516662) (xy 58.102522 -368.543931)
			(xy 58.09476 -368.597915) (xy 58.079395 -368.650245) (xy 58.056738 -368.699855) (xy 58.027252 -368.745736)
			(xy 57.991537 -368.786953) (xy 57.95032 -368.822668) (xy 57.904439 -368.852154) (xy 57.854829 -368.874811)
			(xy 57.802499 -368.890176) (xy 57.748515 -368.897938) (xy 57.693977 -368.897938) (xy 57.639993 -368.890176)
			(xy 57.587663 -368.874811) (xy 57.538053 -368.852154) (xy 57.492172 -368.822668) (xy 57.450955 -368.786953)
			(xy 57.41524 -368.745736) (xy 57.385754 -368.699855) (xy 57.363097 -368.650245) (xy 57.347732 -368.597915)
			(xy 57.33997 -368.543931) (xy 57.339484 -368.516662) (xy 54.729888 -368.516662) (xy 54.729402 -368.543931)
			(xy 54.72164 -368.597915) (xy 54.706275 -368.650245) (xy 54.683618 -368.699855) (xy 54.654132 -368.745736)
			(xy 54.618417 -368.786953) (xy 54.5772 -368.822668) (xy 54.531319 -368.852154) (xy 54.481709 -368.874811)
			(xy 54.429379 -368.890176) (xy 54.375395 -368.897938) (xy 54.320857 -368.897938) (xy 54.266873 -368.890176)
			(xy 54.214543 -368.874811) (xy 54.164933 -368.852154) (xy 54.119052 -368.822668) (xy 54.077835 -368.786953)
			(xy 54.04212 -368.745736) (xy 54.012634 -368.699855) (xy 53.989977 -368.650245) (xy 53.974612 -368.597915)
			(xy 53.96685 -368.543931) (xy 53.966364 -368.516662) (xy 52.6034 -368.516662) (xy 53.066696 -368.979958)
			(xy 53.084724 -368.998733) (xy 53.115305 -369.040849) (xy 53.138933 -369.087224) (xy 53.155028 -369.13672)
			(xy 53.163196 -369.188123) (xy 53.163724 -369.214146) (xy 53.163724 -371.310662) (xy 53.966364 -371.310662)
			(xy 53.966364 -370.447062) (xy 53.96685 -370.419793) (xy 53.974612 -370.365809) (xy 53.989977 -370.313479)
			(xy 54.012634 -370.263869) (xy 54.04212 -370.217988) (xy 54.077835 -370.176771) (xy 54.119052 -370.141056)
			(xy 54.164933 -370.11157) (xy 54.214543 -370.088913) (xy 54.266873 -370.073548) (xy 54.320857 -370.065786)
			(xy 54.375395 -370.065786) (xy 54.429379 -370.073548) (xy 54.481709 -370.088913) (xy 54.531319 -370.11157)
			(xy 54.5772 -370.141056) (xy 54.618417 -370.176771) (xy 54.654132 -370.217988) (xy 54.683618 -370.263869)
			(xy 54.706275 -370.313479) (xy 54.72164 -370.365809) (xy 54.729402 -370.419793) (xy 54.729888 -370.447062)
			(xy 54.729888 -371.310662) (xy 57.339484 -371.310662) (xy 57.339484 -370.447062) (xy 57.33997 -370.419793)
			(xy 57.347732 -370.365809) (xy 57.363097 -370.313479) (xy 57.385754 -370.263869) (xy 57.41524 -370.217988)
			(xy 57.450955 -370.176771) (xy 57.492172 -370.141056) (xy 57.538053 -370.11157) (xy 57.587663 -370.088913)
			(xy 57.639993 -370.073548) (xy 57.693977 -370.065786) (xy 57.748515 -370.065786) (xy 57.802499 -370.073548)
			(xy 57.854829 -370.088913) (xy 57.904439 -370.11157) (xy 57.95032 -370.141056) (xy 57.991537 -370.176771)
			(xy 58.027252 -370.217988) (xy 58.056738 -370.263869) (xy 58.079395 -370.313479) (xy 58.09476 -370.365809)
			(xy 58.102522 -370.419793) (xy 58.103008 -370.447062) (xy 58.103008 -371.310662) (xy 58.102522 -371.337931)
			(xy 58.09476 -371.391915) (xy 58.079395 -371.444245) (xy 58.056738 -371.493855) (xy 58.027252 -371.539736)
			(xy 57.991537 -371.580953) (xy 57.95032 -371.616668) (xy 57.904439 -371.646154) (xy 57.854829 -371.668811)
			(xy 57.802499 -371.684176) (xy 57.748515 -371.691938) (xy 57.693977 -371.691938) (xy 57.639993 -371.684176)
			(xy 57.587663 -371.668811) (xy 57.538053 -371.646154) (xy 57.492172 -371.616668) (xy 57.450955 -371.580953)
			(xy 57.41524 -371.539736) (xy 57.385754 -371.493855) (xy 57.363097 -371.444245) (xy 57.347732 -371.391915)
			(xy 57.33997 -371.337931) (xy 57.339484 -371.310662) (xy 54.729888 -371.310662) (xy 54.729402 -371.337931)
			(xy 54.72164 -371.391915) (xy 54.706275 -371.444245) (xy 54.683618 -371.493855) (xy 54.654132 -371.539736)
			(xy 54.618417 -371.580953) (xy 54.5772 -371.616668) (xy 54.531319 -371.646154) (xy 54.481709 -371.668811)
			(xy 54.429379 -371.684176) (xy 54.375395 -371.691938) (xy 54.320857 -371.691938) (xy 54.266873 -371.684176)
			(xy 54.214543 -371.668811) (xy 54.164933 -371.646154) (xy 54.119052 -371.616668) (xy 54.077835 -371.580953)
			(xy 54.04212 -371.539736) (xy 54.012634 -371.493855) (xy 53.989977 -371.444245) (xy 53.974612 -371.391915)
			(xy 53.96685 -371.337931) (xy 53.966364 -371.310662) (xy 53.163724 -371.310662) (xy 53.163724 -373.174768)
			(xy 53.16416 -373.184836) (xy 53.171873 -373.203434) (xy 53.17871 -373.210836) (xy 55.04561 -375.077482)
			(xy 55.053015 -375.084317) (xy 55.07161 -375.09204) (xy 55.081678 -375.092468) (xy 55.645558 -375.092468)
			(xy 55.655626 -375.092029) (xy 55.674224 -375.084319) (xy 55.681626 -375.077482) (xy 56.967628 -373.79148)
			(xy 56.971744 -373.787087) (xy 56.978029 -373.776822) (xy 56.980074 -373.77116) (xy 56.980074 -373.770652)
			(xy 56.988518 -373.745106) (xy 57.011588 -373.696501) (xy 57.041258 -373.65162) (xy 57.076939 -373.611352)
			(xy 57.117923 -373.576496) (xy 57.163398 -373.547744) (xy 57.212462 -373.525666) (xy 57.26414 -373.510699)
			(xy 57.317409 -373.503142) (xy 57.34431 -373.502682) (xy 57.371561 -373.503168) (xy 57.425508 -373.510926)
			(xy 57.477802 -373.526282) (xy 57.527379 -373.548924) (xy 57.573229 -373.57839) (xy 57.614419 -373.614081)
			(xy 57.65011 -373.655271) (xy 57.679576 -373.701121) (xy 57.702218 -373.750698) (xy 57.717574 -373.802992)
			(xy 57.725332 -373.856939) (xy 57.725818 -373.88419) (xy 57.725297 -373.911098) (xy 57.717722 -373.96438)
			(xy 57.702736 -374.016068) (xy 57.680636 -374.065138) (xy 57.65186 -374.110616) (xy 57.616979 -374.151599)
			(xy 57.576685 -374.187274) (xy 57.531778 -374.216934) (xy 57.48315 -374.239989) (xy 57.457594 -374.248426)
			(xy 57.45734 -374.248426) (xy 57.451647 -374.250405) (xy 57.441372 -374.256702) (xy 57.43702 -374.260872)
			(xy 56.03875 -375.659142) (xy 56.03621 -375.661682) (xy 56.029544 -375.668719) (xy 56.021652 -375.686405)
			(xy 56.020911 -375.705758) (xy 56.023764 -375.715022) (xy 56.0324 -375.739406) (xy 56.036383 -375.749066)
			(xy 56.050585 -375.764355) (xy 56.069718 -375.772685) (xy 56.080152 -375.773188) (xy 56.280558 -375.773188)
			(xy 56.290625 -375.772744) (xy 56.309223 -375.765037) (xy 56.316626 -375.758202) (xy 56.717438 -375.357136)
			(xy 56.721566 -375.352753) (xy 56.727843 -375.342481) (xy 56.729884 -375.336816) (xy 56.729884 -375.336308)
			(xy 56.738292 -375.31075) (xy 56.761369 -375.262146) (xy 56.791044 -375.217265) (xy 56.82673 -375.176998)
			(xy 56.867719 -375.142144) (xy 56.913198 -375.113394) (xy 56.962265 -375.091318) (xy 57.013947 -375.076353)
			(xy 57.067218 -375.068797) (xy 57.09412 -375.068338) (xy 57.121375 -375.068736) (xy 57.175331 -375.076497)
			(xy 57.192522 -375.081546) (xy 58.879484 -375.081546) (xy 58.883555 -375.025924) (xy 58.895681 -374.971487)
			(xy 58.915604 -374.919396) (xy 58.9429 -374.870761) (xy 58.976986 -374.826618) (xy 59.017135 -374.787909)
			(xy 59.062493 -374.755458) (xy 59.112093 -374.729957) (xy 59.164877 -374.71195) (xy 59.21972 -374.70182)
			(xy 59.275454 -374.699783) (xy 59.330891 -374.705883) (xy 59.384848 -374.719989) (xy 59.436177 -374.741801)
			(xy 59.483783 -374.770855) (xy 59.526651 -374.80653) (xy 59.563868 -374.848067) (xy 59.594641 -374.89458)
			(xy 59.618313 -374.945077) (xy 59.634381 -374.998484) (xy 59.642501 -375.05366) (xy 59.64301 -375.081546)
			(xy 59.642501 -375.109432) (xy 59.634381 -375.164608) (xy 59.618313 -375.218015) (xy 59.594641 -375.268512)
			(xy 59.563868 -375.315025) (xy 59.526651 -375.356562) (xy 59.483783 -375.392237) (xy 59.436177 -375.421291)
			(xy 59.384848 -375.443103) (xy 59.330891 -375.457209) (xy 59.275454 -375.463309) (xy 59.21972 -375.461272)
			(xy 59.164877 -375.451142) (xy 59.112093 -375.433135) (xy 59.062493 -375.407634) (xy 59.017135 -375.375183)
			(xy 58.976986 -375.336474) (xy 58.9429 -375.292331) (xy 58.915604 -375.243696) (xy 58.895681 -375.191605)
			(xy 58.883555 -375.137168) (xy 58.879484 -375.081546) (xy 57.192522 -375.081546) (xy 57.227633 -375.091858)
			(xy 57.277216 -375.114506) (xy 57.323072 -375.143981) (xy 57.364265 -375.179681) (xy 57.399959 -375.220881)
			(xy 57.429425 -375.266742) (xy 57.452065 -375.316329) (xy 57.467417 -375.368633) (xy 57.475168 -375.42259)
			(xy 57.475628 -375.449846) (xy 57.47515 -375.476756) (xy 57.467568 -375.530039) (xy 57.452575 -375.581728)
			(xy 57.430468 -375.630798) (xy 57.401686 -375.676275) (xy 57.366801 -375.717257) (xy 57.326503 -375.752932)
			(xy 57.281593 -375.78259) (xy 57.232961 -375.805645) (xy 57.207404 -375.814082) (xy 57.20715 -375.814082)
			(xy 57.201454 -375.816053) (xy 57.19118 -375.822355) (xy 57.18683 -375.826528) (xy 56.67375 -376.339608)
			(xy 56.6674 -376.345704) (xy 59.301886 -376.345704) (xy 59.305957 -376.290082) (xy 59.318083 -376.235645)
			(xy 59.338006 -376.183554) (xy 59.365302 -376.134919) (xy 59.399388 -376.090776) (xy 59.439537 -376.052067)
			(xy 59.484895 -376.019616) (xy 59.534495 -375.994115) (xy 59.587279 -375.976108) (xy 59.642122 -375.965978)
			(xy 59.697856 -375.963941) (xy 59.753293 -375.970041) (xy 59.80725 -375.984147) (xy 59.858579 -376.005959)
			(xy 59.906185 -376.035013) (xy 59.949053 -376.070688) (xy 59.98627 -376.112225) (xy 60.017043 -376.158738)
			(xy 60.040715 -376.209235) (xy 60.056783 -376.262642) (xy 60.064903 -376.317818) (xy 60.065412 -376.345704)
			(xy 60.064903 -376.37359) (xy 60.056783 -376.428766) (xy 60.040715 -376.482173) (xy 60.017043 -376.53267)
			(xy 59.98627 -376.579183) (xy 59.949053 -376.62072) (xy 59.906185 -376.656395) (xy 59.858579 -376.685449)
			(xy 59.80725 -376.707261) (xy 59.753293 -376.721367) (xy 59.697856 -376.727467) (xy 59.642122 -376.72543)
			(xy 59.587279 -376.7153) (xy 59.534495 -376.697293) (xy 59.484895 -376.671792) (xy 59.439537 -376.639341)
			(xy 59.399388 -376.600632) (xy 59.365302 -376.556489) (xy 59.338006 -376.507854) (xy 59.318083 -376.455763)
			(xy 59.305957 -376.401326) (xy 59.301886 -376.345704) (xy 56.6674 -376.345704) (xy 56.654973 -376.357634)
			(xy 56.612858 -376.388215) (xy 56.566483 -376.411843) (xy 56.516987 -376.427939) (xy 56.465585 -376.436108)
			(xy 56.439562 -376.436636) (xy 55.824882 -376.436636) (xy 55.812723 -376.437349) (xy 55.791101 -376.448473)
			(xy 55.78348 -376.457972) (xy 55.728108 -376.535696) (xy 55.724806 -376.559826) (xy 55.72887 -376.57151)
			(xy 55.738546 -376.601648) (xy 55.749015 -376.66407) (xy 55.749698 -376.695716) (xy 55.749698 -376.69597)
			(xy 55.749234 -376.723568) (xy 55.741296 -376.778189) (xy 55.725569 -376.831096) (xy 55.70238 -376.881183)
			(xy 55.672213 -376.927405) (xy 55.635699 -376.968796) (xy 55.5936 -377.004491) (xy 55.546795 -377.033745)
			(xy 55.496263 -377.055948) (xy 55.46979 -377.063762) (xy 55.469536 -377.064016) (xy 55.455472 -377.077711)
			(xy 55.424653 -377.102027) (xy 55.408068 -377.11253) (xy 55.398162 -377.118626) (xy 55.385462 -377.138184)
			(xy 55.37454 -377.229116) (xy 55.373777 -377.240668) (xy 55.381454 -377.262487) (xy 55.389272 -377.271026)
			(xy 55.674379 -377.556268) (xy 58.845702 -377.556268) (xy 58.849773 -377.500646) (xy 58.861899 -377.446209)
			(xy 58.881822 -377.394118) (xy 58.909118 -377.345483) (xy 58.943204 -377.30134) (xy 58.983353 -377.262631)
			(xy 59.028711 -377.23018) (xy 59.078311 -377.204679) (xy 59.131095 -377.186672) (xy 59.185938 -377.176542)
			(xy 59.241672 -377.174505) (xy 59.297109 -377.180605) (xy 59.351066 -377.194711) (xy 59.402395 -377.216523)
			(xy 59.450001 -377.245577) (xy 59.492869 -377.281252) (xy 59.530086 -377.322789) (xy 59.560859 -377.369302)
			(xy 59.584531 -377.419799) (xy 59.600599 -377.473206) (xy 59.608719 -377.528382) (xy 59.609228 -377.556268)
			(xy 59.608719 -377.584154) (xy 59.600599 -377.63933) (xy 59.584531 -377.692737) (xy 59.560859 -377.743234)
			(xy 59.530086 -377.789747) (xy 59.492869 -377.831284) (xy 59.450001 -377.866959) (xy 59.402395 -377.896013)
			(xy 59.351066 -377.917825) (xy 59.297109 -377.931931) (xy 59.241672 -377.938031) (xy 59.185938 -377.935994)
			(xy 59.131095 -377.925864) (xy 59.078311 -377.907857) (xy 59.028711 -377.882356) (xy 58.983353 -377.849905)
			(xy 58.943204 -377.811196) (xy 58.909118 -377.767053) (xy 58.881822 -377.718418) (xy 58.861899 -377.666327)
			(xy 58.849773 -377.61189) (xy 58.845702 -377.556268) (xy 55.674379 -377.556268) (xy 55.926482 -377.80849)
			(xy 55.933895 -377.815313) (xy 55.952484 -377.823043) (xy 55.96255 -377.823476) (xy 56.161178 -377.823476)
			(xy 56.167327 -377.823274) (xy 56.179268 -377.820326) (xy 56.1848 -377.817634) (xy 56.212326 -377.803796)
			(xy 56.270743 -377.784232) (xy 56.331543 -377.7743) (xy 56.362346 -377.773692) (xy 56.389595 -377.774181)
			(xy 56.443538 -377.781943) (xy 56.495827 -377.797302) (xy 56.545399 -377.819946) (xy 56.591243 -377.849413)
			(xy 56.632428 -377.885105) (xy 56.668114 -377.926294) (xy 56.697576 -377.972142) (xy 56.720214 -378.021716)
			(xy 56.735567 -378.074007) (xy 56.743322 -378.127951) (xy 56.743322 -378.182449) (xy 56.735567 -378.236393)
			(xy 56.720214 -378.288684) (xy 56.697576 -378.338258) (xy 56.668114 -378.384106) (xy 56.632428 -378.425295)
			(xy 56.591243 -378.460987) (xy 56.545399 -378.490454) (xy 56.495827 -378.513098) (xy 56.443538 -378.528457)
			(xy 56.389595 -378.536219) (xy 56.362346 -378.536708) (xy 56.331543 -378.536113) (xy 56.270741 -378.526181)
			(xy 56.212328 -378.506602) (xy 56.1848 -378.492766) (xy 56.179277 -378.49005) (xy 56.167331 -378.487094)
			(xy 56.161178 -378.486924) (xy 55.889906 -378.486924) (xy 55.878674 -378.487491) (xy 55.858327 -378.497002)
			(xy 55.843992 -378.514293) (xy 55.84063 -378.525024) (xy 55.831234 -378.558759) (xy 55.805542 -378.623906)
			(xy 55.772266 -378.685525) (xy 55.731881 -378.742737) (xy 55.684964 -378.794727) (xy 55.645297 -378.829316)
			(xy 58.842146 -378.829316) (xy 58.846217 -378.773694) (xy 58.858343 -378.719257) (xy 58.878266 -378.667166)
			(xy 58.905562 -378.618531) (xy 58.939648 -378.574388) (xy 58.979797 -378.535679) (xy 59.025155 -378.503228)
			(xy 59.074755 -378.477727) (xy 59.127539 -378.45972) (xy 59.182382 -378.44959) (xy 59.238116 -378.447553)
			(xy 59.293553 -378.453653) (xy 59.34751 -378.467759) (xy 59.398839 -378.489571) (xy 59.446445 -378.518625)
			(xy 59.489313 -378.5543) (xy 59.52653 -378.595837) (xy 59.557303 -378.64235) (xy 59.580975 -378.692847)
			(xy 59.597043 -378.746254) (xy 59.605163 -378.80143) (xy 59.605672 -378.829316) (xy 59.605163 -378.857202)
			(xy 59.597043 -378.912378) (xy 59.580975 -378.965785) (xy 59.557303 -379.016282) (xy 59.52653 -379.062795)
			(xy 59.489313 -379.104332) (xy 59.446445 -379.140007) (xy 59.398839 -379.169061) (xy 59.34751 -379.190873)
			(xy 59.293553 -379.204979) (xy 59.238116 -379.211079) (xy 59.182382 -379.209042) (xy 59.127539 -379.198912)
			(xy 59.074755 -379.180905) (xy 59.025155 -379.155404) (xy 58.979797 -379.122953) (xy 58.939648 -379.084244)
			(xy 58.905562 -379.040101) (xy 58.878266 -378.991466) (xy 58.858343 -378.939375) (xy 58.846217 -378.884938)
			(xy 58.842146 -378.829316) (xy 55.645297 -378.829316) (xy 55.632182 -378.840752) (xy 55.57429 -378.880157)
			(xy 55.512113 -378.912378) (xy 55.446538 -378.936957) (xy 55.378501 -378.953542) (xy 55.308971 -378.961898)
			(xy 55.273956 -378.962412) (xy 55.241076 -378.961932) (xy 55.17573 -378.954571) (xy 55.111619 -378.939936)
			(xy 55.049552 -378.91821) (xy 54.99031 -378.889668) (xy 54.934638 -378.854668) (xy 54.883237 -378.813652)
			(xy 54.859682 -378.790708) (xy 50.487326 -374.418352) (xy 50.464408 -374.394806) (xy 50.423445 -374.343426)
			(xy 50.388493 -374.287782) (xy 50.35999 -374.228576) (xy 50.338296 -374.16655) (xy 50.323682 -374.102485)
			(xy 50.316332 -374.037187) (xy 50.315876 -374.004332) (xy 50.315876 -370.367814) (xy 50.31545 -370.357745)
			(xy 50.30773 -370.339147) (xy 50.30089 -370.331746) (xy 49.559972 -369.591082) (xy 49.552578 -369.584235)
			(xy 49.533974 -369.57652) (xy 49.523904 -369.576096) (xy 47.71009 -369.576096) (xy 47.674678 -369.575553)
			(xy 47.60437 -369.567015) (xy 47.535603 -369.550065) (xy 47.469381 -369.52495) (xy 47.406669 -369.492036)
			(xy 47.348381 -369.451803) (xy 47.295368 -369.404838) (xy 47.248402 -369.351825) (xy 47.208168 -369.293538)
			(xy 47.175254 -369.230826) (xy 47.150138 -369.164605) (xy 47.133186 -369.095838) (xy 47.124648 -369.02553)
			(xy 47.124112 -368.990118) (xy 47.124611 -368.956798) (xy 47.132253 -368.890597) (xy 47.139352 -368.858038)
			(xy 47.142146 -368.846608) (xy 47.137066 -368.824256) (xy 47.08017 -368.752628) (xy 47.072598 -368.74391)
			(xy 47.051828 -368.733866) (xy 47.040292 -368.733324) (xy 44.057062 -368.733324) (xy 44.04699 -368.733723)
			(xy 44.028392 -368.741461) (xy 44.020994 -368.74831) (xy 43.810428 -368.958876) (xy 43.803814 -368.966176)
			(xy 43.796245 -368.984346) (xy 43.795696 -368.994182) (xy 43.795696 -368.994436) (xy 43.794856 -369.026045)
			(xy 43.786091 -369.088666) (xy 43.769272 -369.14962) (xy 43.744686 -369.207875) (xy 43.712746 -369.262447)
			(xy 43.673995 -369.312413) (xy 43.629087 -369.356926) (xy 43.578781 -369.395235) (xy 43.523929 -369.426691)
			(xy 43.465459 -369.450763) (xy 43.404359 -369.467042) (xy 43.341664 -369.475255) (xy 43.310048 -369.475766)
			(xy 43.278251 -369.475206) (xy 43.215202 -369.466911) (xy 43.153774 -369.450457) (xy 43.095019 -369.426126)
			(xy 43.039944 -369.394334) (xy 42.989489 -369.355625) (xy 42.944519 -369.310661) (xy 42.905803 -369.260211)
			(xy 42.874003 -369.20514) (xy 42.849664 -369.146389) (xy 42.833202 -369.084963) (xy 42.824899 -369.021915)
			(xy 42.8244 -368.990118) (xy 42.824858 -368.958498) (xy 42.833065 -368.895793) (xy 42.849341 -368.834683)
			(xy 42.873412 -368.776203) (xy 42.90487 -368.721342) (xy 42.943183 -368.671029) (xy 42.987703 -368.626114)
			(xy 43.037676 -368.587359) (xy 43.092256 -368.555418) (xy 43.150522 -368.530831) (xy 43.211485 -368.514016)
			(xy 43.274116 -368.505256) (xy 43.30573 -368.50447) (xy 43.305984 -368.50447) (xy 43.315845 -368.50388)
			(xy 43.334012 -368.496165) (xy 43.34129 -368.489484) (xy 43.478958 -368.351816) (xy 43.485054 -368.321844)
			(xy 43.478958 -368.30762) (xy 43.474761 -368.298481) (xy 43.460577 -368.284245) (xy 43.442016 -368.276543)
			(xy 43.431968 -368.276124) (xy 40.11422 -368.276124) (xy 40.104151 -368.276553) (xy 40.085553 -368.284271)
			(xy 40.078152 -368.29111) (xy 39.41064 -368.958876) (xy 39.403984 -368.966171) (xy 39.396268 -368.984327)
			(xy 39.395654 -368.994182) (xy 39.395654 -368.994436) (xy 39.394856 -369.026048) (xy 39.38609 -369.088672)
			(xy 39.369269 -369.149629) (xy 39.34468 -369.207887) (xy 39.312737 -369.262461) (xy 39.273982 -369.312427)
			(xy 39.229069 -369.356941) (xy 39.178759 -369.39525) (xy 39.123903 -369.426704) (xy 39.065428 -369.450773)
			(xy 39.004323 -369.46705) (xy 38.941623 -369.475257) (xy 38.910006 -369.475766) (xy 38.87821 -369.475223)
			(xy 38.815162 -369.466923) (xy 38.753736 -369.450465) (xy 38.694984 -369.426131) (xy 38.639911 -369.394336)
			(xy 38.589459 -369.355624) (xy 38.544492 -369.310659) (xy 38.505778 -369.260209) (xy 38.47398 -369.205137)
			(xy 38.449643 -369.146387) (xy 38.433182 -369.084962) (xy 38.424879 -369.021914) (xy 38.424358 -368.990118)
			(xy 38.424858 -368.9585) (xy 38.433063 -368.895798) (xy 38.449338 -368.834691) (xy 38.473406 -368.776214)
			(xy 38.504861 -368.721355) (xy 38.54317 -368.671043) (xy 38.587685 -368.626129) (xy 38.637654 -368.587373)
			(xy 38.69223 -368.555431) (xy 38.75049 -368.530842) (xy 38.811449 -368.514023) (xy 38.874075 -368.505259)
			(xy 38.905688 -368.50447) (xy 38.905942 -368.50447) (xy 38.915801 -368.503858) (xy 38.933968 -368.496159)
			(xy 38.941248 -368.489484) (xy 39.485316 -367.945416) (xy 39.491412 -367.915444) (xy 39.485316 -367.90122)
			(xy 39.481077 -367.892105) (xy 39.466911 -367.877868) (xy 39.448368 -367.870154) (xy 39.438326 -367.869724)
			(xy 36.120578 -367.869724) (xy 36.110507 -367.870132) (xy 36.091909 -367.877864) (xy 36.08451 -367.88471)
			(xy 35.010598 -368.958876) (xy 35.003936 -368.966166) (xy 34.996224 -368.984326) (xy 34.995612 -368.994182)
			(xy 34.995612 -368.994436) (xy 34.994856 -369.02605) (xy 34.986089 -369.088677) (xy 34.969266 -369.149637)
			(xy 34.944674 -369.207898) (xy 34.912729 -369.262474) (xy 34.873969 -369.312442) (xy 34.829052 -369.356956)
			(xy 34.778737 -369.395264) (xy 34.723876 -369.426718) (xy 34.665396 -369.450784) (xy 34.604287 -369.467057)
			(xy 34.541583 -369.47526) (xy 34.509964 -369.475766) (xy 34.478167 -369.475262) (xy 34.415117 -369.466957)
			(xy 34.353691 -369.450494) (xy 34.294939 -369.426155) (xy 34.239866 -369.394356) (xy 34.189414 -369.355641)
			(xy 34.144447 -369.310672) (xy 34.105734 -369.260219) (xy 34.073937 -369.205145) (xy 34.0496 -369.146392)
			(xy 34.033139 -369.084965) (xy 34.024837 -369.021915) (xy 34.024316 -368.990118) (xy 34.024759 -368.958497)
			(xy 34.032965 -368.895791) (xy 34.049242 -368.83468) (xy 34.073314 -368.776199) (xy 34.104773 -368.721337)
			(xy 34.143088 -368.671024) (xy 34.187609 -368.626109) (xy 34.237584 -368.587353) (xy 34.292167 -368.555413)
			(xy 34.350434 -368.530827) (xy 34.411399 -368.514013) (xy 34.474031 -368.505255) (xy 34.505646 -368.50447)
			(xy 34.5059 -368.50447) (xy 34.515762 -368.503888) (xy 34.533929 -368.496168) (xy 34.541206 -368.489484)
			(xy 35.542474 -367.488216) (xy 35.54857 -367.458244) (xy 35.542474 -367.44402) (xy 35.538265 -367.434888)
			(xy 35.524087 -367.420651) (xy 35.50553 -367.412946) (xy 35.495484 -367.412524) (xy 32.177736 -367.412524)
			(xy 32.167668 -367.412962) (xy 32.14907 -367.420673) (xy 32.141668 -367.42751) (xy 30.610556 -368.958876)
			(xy 30.603902 -368.966173) (xy 30.596184 -368.984327) (xy 30.59557 -368.994182) (xy 30.59557 -368.994436)
			(xy 30.594756 -369.026047) (xy 30.58599 -369.08867) (xy 30.569171 -369.149625) (xy 30.544582 -369.207882)
			(xy 30.512641 -369.262456) (xy 30.473887 -369.312422) (xy 30.428976 -369.356936) (xy 30.378668 -369.395244)
			(xy 30.323813 -369.426699) (xy 30.26534 -369.450769) (xy 30.204237 -369.467047) (xy 30.141539 -369.475256)
			(xy 30.109922 -369.475766) (xy 30.078125 -369.47523) (xy 30.015074 -369.466932) (xy 29.953646 -369.450475)
			(xy 29.894891 -369.426141) (xy 29.839816 -369.394347) (xy 29.789361 -369.355635) (xy 29.744392 -369.310669)
			(xy 29.705676 -369.260218) (xy 29.673876 -369.205144) (xy 29.649538 -369.146392) (xy 29.633076 -369.084965)
			(xy 29.624773 -369.021915) (xy 29.624274 -368.990118) (xy 0.6096 -368.990118) (xy 0.6096 -381.338836)
			(xy 1.139196 -381.338836) (xy 1.143209 -381.27504) (xy 1.155187 -381.21225) (xy 1.17494 -381.151457)
			(xy 1.202157 -381.093618) (xy 1.236408 -381.039647) (xy 1.277153 -380.990394) (xy 1.32375 -380.946637)
			(xy 1.375465 -380.909064) (xy 1.43148 -380.87827) (xy 1.490913 -380.854738) (xy 1.552827 -380.838841)
			(xy 1.616245 -380.83083) (xy 1.648206 -380.830328) (xy 2.232406 -380.830328) (xy 2.242478 -380.829925)
			(xy 2.261077 -380.822191) (xy 2.268474 -380.815342) (xy 2.796286 -380.287784) (xy 2.803124 -380.280382)
			(xy 2.810845 -380.261784) (xy 2.811272 -380.251716) (xy 2.811272 -380.000764) (xy 2.810662 -379.98872)
			(xy 2.799792 -379.967233) (xy 2.790444 -379.959616) (xy 2.72415 -379.911356) (xy 2.714064 -379.904785)
			(xy 2.690331 -379.900945) (xy 2.678684 -379.90399) (xy 2.650471 -379.912412) (xy 2.592298 -379.921476)
			(xy 2.56286 -379.922024) (xy 2.562606 -379.922024) (xy 2.535355 -379.921546) (xy 2.481407 -379.913789)
			(xy 2.429112 -379.898433) (xy 2.379535 -379.875792) (xy 2.333684 -379.846325) (xy 2.292494 -379.810633)
			(xy 2.256803 -379.769442) (xy 2.227336 -379.723592) (xy 2.204695 -379.674014) (xy 2.18934 -379.621719)
			(xy 2.181584 -379.567771) (xy 2.181584 -379.513269) (xy 2.18934 -379.459321) (xy 2.204695 -379.407026)
			(xy 2.227336 -379.357448) (xy 2.256803 -379.311598) (xy 2.292494 -379.270407) (xy 2.333684 -379.234715)
			(xy 2.379535 -379.205248) (xy 2.429112 -379.182607) (xy 2.481407 -379.167251) (xy 2.535355 -379.159494)
			(xy 2.562606 -379.159008) (xy 2.56286 -379.159008) (xy 2.592297 -379.159567) (xy 2.65047 -379.168626)
			(xy 2.678684 -379.177042) (xy 2.690329 -379.180104) (xy 2.714064 -379.176253) (xy 2.72415 -379.169676)
			(xy 2.790444 -379.121416) (xy 2.799713 -379.11373) (xy 2.810592 -379.092288) (xy 2.811272 -379.080268)
			(xy 2.811272 -378.76734) (xy 2.811818 -378.734061) (xy 2.82049 -378.66807) (xy 2.837704 -378.603777)
			(xy 2.863166 -378.542282) (xy 2.896439 -378.484637) (xy 2.936953 -378.431831) (xy 2.960116 -378.40793)
			(xy 3.617722 -377.75007) (xy 3.624571 -377.742677) (xy 3.632285 -377.724072) (xy 3.632708 -377.714002)
			(xy 3.632708 -372.921784) (xy 3.63321 -372.889823) (xy 3.641221 -372.826405) (xy 3.657118 -372.764491)
			(xy 3.68065 -372.705058) (xy 3.711444 -372.649043) (xy 3.749017 -372.597328) (xy 3.792774 -372.550731)
			(xy 3.842027 -372.509986) (xy 3.895998 -372.475735) (xy 3.953837 -372.448518) (xy 4.01463 -372.428765)
			(xy 4.07742 -372.416787) (xy 4.141216 -372.412774) (xy 4.205012 -372.416787) (xy 4.267802 -372.428765)
			(xy 4.328595 -372.448518) (xy 4.386434 -372.475735) (xy 4.440405 -372.509986) (xy 4.489658 -372.550731)
			(xy 4.533415 -372.597328) (xy 4.570988 -372.649043) (xy 4.601782 -372.705058) (xy 4.625314 -372.764491)
			(xy 4.641211 -372.826405) (xy 4.649222 -372.889823) (xy 4.649724 -372.921784) (xy 4.649724 -377.94565)
			(xy 4.649181 -377.978936) (xy 4.640439 -378.044931) (xy 4.623164 -378.109223) (xy 4.597651 -378.170712)
			(xy 4.564335 -378.228349) (xy 4.523787 -378.281147) (xy 4.500626 -378.30506) (xy 3.842766 -378.96292)
			(xy 3.83592 -378.970315) (xy 3.828205 -378.988918) (xy 3.82778 -378.998988) (xy 3.82778 -379.069346)
			(xy 3.828449 -379.080758) (xy 3.838324 -379.101335) (xy 3.84683 -379.10897) (xy 3.918204 -379.165866)
			(xy 3.940556 -379.170946) (xy 3.951732 -379.168406) (xy 3.972471 -379.164002) (xy 4.014607 -379.159294)
			(xy 4.035806 -379.159008) (xy 4.063059 -379.159479) (xy 4.11701 -379.167235) (xy 4.169307 -379.182591)
			(xy 4.218887 -379.205233) (xy 4.264741 -379.234701) (xy 4.305933 -379.270394) (xy 4.341627 -379.311586)
			(xy 4.371095 -379.357439) (xy 4.393738 -379.407019) (xy 4.409094 -379.459317) (xy 4.416851 -379.513267)
			(xy 4.416851 -379.567773) (xy 4.409094 -379.621723) (xy 4.393738 -379.674021) (xy 4.371095 -379.723601)
			(xy 4.341627 -379.769454) (xy 4.305933 -379.810646) (xy 4.264741 -379.846339) (xy 4.218887 -379.875807)
			(xy 4.169307 -379.898449) (xy 4.11701 -379.913805) (xy 4.063059 -379.921561) (xy 4.035806 -379.922024)
			(xy 4.014607 -379.921732) (xy 3.972473 -379.917018) (xy 3.951732 -379.912626) (xy 3.940556 -379.910086)
			(xy 3.918204 -379.915166) (xy 3.84683 -379.972062) (xy 3.838316 -379.979695) (xy 3.828416 -380.00027)
			(xy 3.82778 -380.011686) (xy 3.82778 -380.483364) (xy 3.827251 -380.516644) (xy 3.818577 -380.582636)
			(xy 3.801361 -380.64693) (xy 3.775896 -380.708425) (xy 3.74262 -380.766069) (xy 3.702101 -380.818874)
			(xy 3.678936 -380.842774) (xy 2.823464 -381.698246) (xy 2.799572 -381.721432) (xy 2.746779 -381.761995)
			(xy 2.689141 -381.795317) (xy 2.627646 -381.820828) (xy 2.563346 -381.838091) (xy 2.497342 -381.84681)
			(xy 2.464054 -381.847344) (xy 1.648206 -381.847344) (xy 1.616245 -381.846842) (xy 1.552827 -381.838831)
			(xy 1.490913 -381.822934) (xy 1.43148 -381.799402) (xy 1.375465 -381.768608) (xy 1.32375 -381.731035)
			(xy 1.277153 -381.687278) (xy 1.236408 -381.638025) (xy 1.202157 -381.584054) (xy 1.17494 -381.526215)
			(xy 1.155187 -381.465422) (xy 1.143209 -381.402632) (xy 1.139196 -381.338836) (xy 0.6096 -381.338836)
			(xy 0.6096 -383.246884) (xy 4.633212 -383.246884) (xy 4.637283 -383.191262) (xy 4.649409 -383.136825)
			(xy 4.669332 -383.084734) (xy 4.696628 -383.036099) (xy 4.730714 -382.991956) (xy 4.770863 -382.953247)
			(xy 4.816221 -382.920796) (xy 4.865821 -382.895295) (xy 4.918605 -382.877288) (xy 4.973448 -382.867158)
			(xy 5.029182 -382.865121) (xy 5.084619 -382.871221) (xy 5.138576 -382.885327) (xy 5.189905 -382.907139)
			(xy 5.237511 -382.936193) (xy 5.280379 -382.971868) (xy 5.317596 -383.013405) (xy 5.348369 -383.059918)
			(xy 5.372041 -383.110415) (xy 5.388109 -383.163822) (xy 5.396229 -383.218998) (xy 5.396738 -383.246884)
			(xy 5.396229 -383.27477) (xy 5.388109 -383.329946) (xy 5.372041 -383.383353) (xy 5.348369 -383.43385)
			(xy 5.317596 -383.480363) (xy 5.280379 -383.5219) (xy 5.237511 -383.557575) (xy 5.189905 -383.586629)
			(xy 5.138576 -383.608441) (xy 5.084619 -383.622547) (xy 5.029182 -383.628647) (xy 4.973448 -383.62661)
			(xy 4.918605 -383.61648) (xy 4.865821 -383.598473) (xy 4.816221 -383.572972) (xy 4.770863 -383.540521)
			(xy 4.730714 -383.501812) (xy 4.696628 -383.457669) (xy 4.669332 -383.409034) (xy 4.649409 -383.356943)
			(xy 4.637283 -383.302506) (xy 4.633212 -383.246884) (xy 0.6096 -383.246884) (xy 0.6096 -388.37489)
			(xy 1.436624 -388.37489) (xy 1.437072 -388.342628) (xy 1.444132 -388.278491) (xy 1.458135 -388.215504)
			(xy 1.478915 -388.154416) (xy 1.506223 -388.095955) (xy 1.539735 -388.040816) (xy 1.559052 -388.014972)
			(xy 1.564386 -388.008368) (xy 1.56972 -387.992366) (xy 1.56972 -387.893814) (xy 1.564386 -387.877812)
			(xy 1.559052 -387.871208) (xy 1.539732 -387.845366) (xy 1.506215 -387.790228) (xy 1.478904 -387.731768)
			(xy 1.458125 -387.670679) (xy 1.444124 -387.607691) (xy 1.437068 -387.543553) (xy 1.436624 -387.51129)
			(xy 1.43714 -387.475569) (xy 1.445751 -387.404647) (xy 1.462849 -387.335281) (xy 1.488182 -387.268481)
			(xy 1.521383 -387.205222) (xy 1.561967 -387.146426) (xy 1.609343 -387.092951) (xy 1.662818 -387.045576)
			(xy 1.721614 -387.004992) (xy 1.784873 -386.971792) (xy 1.851673 -386.946458) (xy 1.921039 -386.929361)
			(xy 1.991961 -386.92075) (xy 2.027682 -386.920232) (xy 2.060845 -386.920692) (xy 2.126753 -386.928139)
			(xy 2.191413 -386.942918) (xy 2.254011 -386.964845) (xy 2.31376 -386.993642) (xy 2.369909 -387.028948)
			(xy 2.421753 -387.070319) (xy 2.445512 -387.09346) (xy 2.565654 -387.213602) (xy 2.573076 -387.220415)
			(xy 2.591658 -387.22815) (xy 2.601722 -387.228588) (xy 3.153664 -387.228588) (xy 3.163732 -387.228147)
			(xy 3.18233 -387.220438) (xy 3.189732 -387.213602) (xy 3.55473 -386.848604) (xy 3.578505 -386.825481)
			(xy 3.63035 -386.784118) (xy 3.686499 -386.748817) (xy 3.746246 -386.720023) (xy 3.80884 -386.698095)
			(xy 3.873495 -386.683311) (xy 3.939398 -386.675856) (xy 3.97256 -386.675376) (xy 4.688586 -386.675376)
			(xy 4.698458 -386.674893) (xy 4.716762 -386.667496) (xy 4.730931 -386.653748) (xy 4.735322 -386.644896)
			(xy 4.778502 -386.54609) (xy 4.773676 -386.516372) (xy 4.763262 -386.505196) (xy 4.744441 -386.483975)
			(xy 4.712665 -386.436992) (xy 4.6882 -386.38582) (xy 4.671587 -386.331587) (xy 4.663193 -386.275492)
			(xy 4.662678 -386.247132) (xy 4.662678 -386.246878) (xy 4.663164 -386.219627) (xy 4.67092 -386.165679)
			(xy 4.686275 -386.113384) (xy 4.708917 -386.063807) (xy 4.738383 -386.017957) (xy 4.774074 -385.976766)
			(xy 4.815265 -385.941075) (xy 4.861115 -385.911609) (xy 4.910692 -385.888967) (xy 4.962987 -385.873612)
			(xy 5.016935 -385.865856) (xy 5.071437 -385.865856) (xy 5.125385 -385.873612) (xy 5.17768 -385.888967)
			(xy 5.227257 -385.911609) (xy 5.273107 -385.941075) (xy 5.314298 -385.976766) (xy 5.349989 -386.017957)
			(xy 5.379455 -386.063807) (xy 5.402097 -386.113384) (xy 5.417452 -386.165679) (xy 5.425208 -386.219627)
			(xy 5.425694 -386.246878) (xy 5.425694 -386.247132) (xy 5.425137 -386.275488) (xy 5.416727 -386.331574)
			(xy 5.400113 -386.385799) (xy 5.37566 -386.436969) (xy 5.343906 -386.483958) (xy 5.32511 -386.505196)
			(xy 5.314696 -386.516372) (xy 5.30987 -386.54609) (xy 5.35305 -386.644896) (xy 5.357435 -386.653764)
			(xy 5.371579 -386.667565) (xy 5.389903 -386.674963) (xy 5.399786 -386.675376) (xy 5.413502 -386.675376)
			(xy 5.423572 -386.674958) (xy 5.44217 -386.667233) (xy 5.44957 -386.66039) (xy 5.594096 -386.515864)
			(xy 5.601208 -386.50164) (xy 5.602478 -386.493766) (xy 5.608729 -386.456834) (xy 5.629338 -386.384821)
			(xy 5.658886 -386.31599) (xy 5.696898 -386.251447) (xy 5.742765 -386.192227) (xy 5.768848 -386.165344)
			(xy 6.079998 -385.854194) (xy 6.106888 -385.82812) (xy 6.166115 -385.782267) (xy 6.230659 -385.74426)
			(xy 6.299484 -385.714706) (xy 6.37149 -385.694079) (xy 6.40842 -385.687824) (xy 6.416294 -385.686554)
			(xy 6.430518 -385.679442) (xy 6.459474 -385.65074) (xy 6.466285 -385.643317) (xy 6.474022 -385.624735)
			(xy 6.47446 -385.614672) (xy 6.47446 -385.564634) (xy 6.474191 -385.556521) (xy 6.46914 -385.541105)
			(xy 6.464554 -385.534408) (xy 6.442901 -385.503892) (xy 6.406608 -385.438458) (xy 6.378855 -385.368971)
			(xy 6.360085 -385.296538) (xy 6.350599 -385.222316) (xy 6.35 -385.184904) (xy 6.35 -384.744976) (xy 6.350446 -384.711533)
			(xy 6.358019 -384.645075) (xy 6.373054 -384.5799) (xy 6.395359 -384.516841) (xy 6.424646 -384.456707)
			(xy 6.442202 -384.428238) (xy 6.447025 -384.419929) (xy 6.450605 -384.401066) (xy 6.447 -384.382207)
			(xy 6.442202 -384.373882) (xy 6.424673 -384.345399) (xy 6.395403 -384.285262) (xy 6.373107 -384.222205)
			(xy 6.358069 -384.157035) (xy 6.350482 -384.090585) (xy 6.35 -384.057144) (xy 6.35 -383.617216) (xy 6.350573 -383.5798)
			(xy 6.360019 -383.505566) (xy 6.378775 -383.433122) (xy 6.40654 -383.363631) (xy 6.442867 -383.298207)
			(xy 6.464554 -383.267712) (xy 6.469115 -383.261003) (xy 6.474162 -383.245593) (xy 6.47446 -383.237486)
			(xy 6.47446 -383.11709) (xy 6.474211 -383.108976) (xy 6.469146 -383.09356) (xy 6.464554 -383.086864)
			(xy 6.442882 -383.056362) (xy 6.406591 -382.990924) (xy 6.378842 -382.921433) (xy 6.360078 -382.848997)
			(xy 6.350597 -382.774773) (xy 6.35 -382.73736) (xy 6.35 -382.297686) (xy 6.350551 -382.260246) (xy 6.360017 -382.185967)
			(xy 6.378783 -382.113477) (xy 6.406549 -382.043936) (xy 6.44287 -381.978455) (xy 6.464554 -381.947928)
			(xy 6.469049 -381.941257) (xy 6.474095 -381.925992) (xy 6.47446 -381.917956) (xy 6.47446 -380.82347)
			(xy 6.474913 -380.790315) (xy 6.482329 -380.72442) (xy 6.497074 -380.659769) (xy 6.518964 -380.597176)
			(xy 6.547724 -380.537426) (xy 6.582992 -380.481272) (xy 6.624324 -380.429419) (xy 6.647434 -380.40564)
			(xy 6.783324 -380.269496) (xy 6.790436 -380.255272) (xy 6.791706 -380.247398) (xy 6.797965 -380.210468)
			(xy 6.818572 -380.138454) (xy 6.848117 -380.069623) (xy 6.886128 -380.005079) (xy 6.931993 -379.945859)
			(xy 6.958076 -379.918976) (xy 7.268972 -379.60808) (xy 7.292951 -379.584747) (xy 7.345327 -379.543109)
			(xy 7.402073 -379.507656) (xy 7.462462 -379.478844) (xy 7.52572 -379.457041) (xy 7.558278 -379.44933)
			(xy 7.567599 -379.446818) (xy 7.583566 -379.436004) (xy 7.594397 -379.420047) (xy 7.596886 -379.410722)
			(xy 7.604579 -379.378161) (xy 7.626402 -379.314911) (xy 7.655227 -379.254529) (xy 7.690684 -379.197788)
			(xy 7.732322 -379.145413) (xy 7.755636 -379.121416) (xy 8.066532 -378.81052) (xy 8.09053 -378.787206)
			(xy 8.1429 -378.745564) (xy 8.199642 -378.710108) (xy 8.260027 -378.681291) (xy 8.323282 -378.659484)
			(xy 8.355838 -378.65177) (xy 8.36516 -378.649266) (xy 8.381123 -378.638443) (xy 8.391954 -378.622487)
			(xy 8.394446 -378.613162) (xy 8.402166 -378.580608) (xy 8.423983 -378.517358) (xy 8.452801 -378.456975)
			(xy 8.488253 -378.400232) (xy 8.529885 -378.347855) (xy 8.553196 -378.323856) (xy 8.864092 -378.01296)
			(xy 8.888092 -377.989649) (xy 8.940463 -377.948008) (xy 8.997204 -377.912552) (xy 9.057588 -377.883734)
			(xy 9.120842 -377.861925) (xy 9.153398 -377.85421) (xy 9.162727 -377.851723) (xy 9.178694 -377.840898)
			(xy 9.189521 -377.824931) (xy 9.192006 -377.815602) (xy 9.199753 -377.783055) (xy 9.221564 -377.719804)
			(xy 9.250376 -377.659421) (xy 9.285822 -377.602676) (xy 9.327447 -377.550296) (xy 9.350756 -377.526296)
			(xy 9.661652 -377.2154) (xy 9.68564 -377.192077) (xy 9.738014 -377.150436) (xy 9.794757 -377.114982)
			(xy 9.855145 -377.086168) (xy 9.918401 -377.064362) (xy 9.950958 -377.05665) (xy 9.960288 -377.05417)
			(xy 9.976251 -377.043337) (xy 9.987078 -377.027371) (xy 9.989566 -377.018042) (xy 9.997273 -376.985485)
			(xy 10.019092 -376.922234) (xy 10.047914 -376.861852) (xy 10.083369 -376.80511) (xy 10.125003 -376.752734)
			(xy 10.148316 -376.728736) (xy 10.459212 -376.41784) (xy 10.483219 -376.394536) (xy 10.535587 -376.352892)
			(xy 10.592326 -376.317434) (xy 10.652709 -376.288615) (xy 10.715963 -376.266805) (xy 10.748518 -376.25909)
			(xy 10.757855 -376.256627) (xy 10.773822 -376.245791) (xy 10.784645 -376.229815) (xy 10.787126 -376.220482)
			(xy 10.794859 -376.187931) (xy 10.816673 -376.124681) (xy 10.845489 -376.064298) (xy 10.880938 -376.007554)
			(xy 10.922566 -375.955175) (xy 10.945876 -375.931176) (xy 11.256772 -375.62028) (xy 11.280751 -375.596947)
			(xy 11.333127 -375.555309) (xy 11.389873 -375.519856) (xy 11.450262 -375.491044) (xy 11.51352 -375.469241)
			(xy 11.546078 -375.46153) (xy 11.555399 -375.459018) (xy 11.571366 -375.448204) (xy 11.582197 -375.432247)
			(xy 11.584686 -375.422922) (xy 11.592379 -375.390361) (xy 11.614202 -375.327111) (xy 11.643027 -375.266729)
			(xy 11.678484 -375.209988) (xy 11.720122 -375.157613) (xy 11.743436 -375.133616) (xy 12.054332 -374.82272)
			(xy 12.081214 -374.796638) (xy 12.140443 -374.750786) (xy 12.204988 -374.71278) (xy 12.273816 -374.683228)
			(xy 12.345824 -374.662604) (xy 12.382754 -374.65635) (xy 12.390628 -374.65508) (xy 12.404852 -374.647968)
			(xy 13.014198 -374.038622) (xy 13.021021 -374.031208) (xy 13.028751 -374.012619) (xy 13.029184 -374.002554)
			(xy 13.029184 -373.789956) (xy 13.028892 -373.781907) (xy 13.023836 -373.766624) (xy 13.019278 -373.759984)
			(xy 12.997577 -373.729467) (xy 12.96123 -373.663997) (xy 12.933458 -373.594454) (xy 12.914708 -373.521956)
			(xy 12.905281 -373.447668) (xy 12.904724 -373.410226) (xy 12.904724 -372.970806) (xy 12.9053 -372.933367)
			(xy 12.914762 -372.85909) (xy 12.933523 -372.7866) (xy 12.961283 -372.717058) (xy 12.997598 -372.651576)
			(xy 13.019278 -372.621048) (xy 13.023758 -372.614367) (xy 13.028815 -372.59911) (xy 13.029184 -372.591076)
			(xy 13.029184 -372.150132) (xy 13.028746 -372.140064) (xy 13.021035 -372.121466) (xy 13.014198 -372.114064)
			(xy 12.581636 -371.681502) (xy 12.574217 -371.674686) (xy 12.555632 -371.666952) (xy 12.545568 -371.666516)
			(xy 12.380214 -371.666516) (xy 12.365482 -371.671342) (xy 12.358878 -371.675914) (xy 12.35837 -371.676422)
			(xy 12.327876 -371.698107) (xy 12.262438 -371.734401) (xy 12.192945 -371.762151) (xy 12.120507 -371.780912)
			(xy 12.04628 -371.790385) (xy 12.008866 -371.790976) (xy 11.569446 -371.790976) (xy 11.532008 -371.790379)
			(xy 11.457731 -371.780922) (xy 11.385242 -371.762166) (xy 11.3157 -371.734411) (xy 11.250217 -371.6981)
			(xy 11.219688 -371.676422) (xy 11.213021 -371.671919) (xy 11.197753 -371.666876) (xy 11.189716 -371.666516)
			(xy 10.586212 -371.666516) (xy 10.577595 -371.666815) (xy 10.561324 -371.672488) (xy 10.547872 -371.683256)
			(xy 10.543032 -371.690392) (xy 10.4902 -371.774466) (xy 10.48893 -371.800628) (xy 10.494772 -371.812312)
			(xy 10.508979 -371.842574) (xy 10.531221 -371.90562) (xy 10.546208 -371.970774) (xy 10.553748 -372.037202)
			(xy 10.554208 -372.07063) (xy 10.553647 -372.106349) (xy 10.545033 -372.177264) (xy 10.527935 -372.246625)
			(xy 10.502602 -372.313419) (xy 10.469403 -372.376674) (xy 10.428822 -372.435465) (xy 10.381451 -372.488937)
			(xy 10.327981 -372.53631) (xy 10.269191 -372.576893) (xy 10.205938 -372.610094) (xy 10.139144 -372.635429)
			(xy 10.069784 -372.65253) (xy 9.998868 -372.661146) (xy 9.96315 -372.661688) (xy 9.930888 -372.661225)
			(xy 9.866751 -372.65417) (xy 9.803764 -372.640171) (xy 9.742676 -372.619395) (xy 9.684215 -372.592089)
			(xy 9.629075 -372.558577) (xy 9.603232 -372.53926) (xy 9.596628 -372.533926) (xy 9.580626 -372.528592)
			(xy 9.482074 -372.528592) (xy 9.466072 -372.533926) (xy 9.459468 -372.53926) (xy 9.433625 -372.558578)
			(xy 9.378487 -372.592095) (xy 9.320027 -372.619406) (xy 9.258939 -372.640186) (xy 9.195951 -372.654187)
			(xy 9.131812 -372.661243) (xy 9.09955 -372.661688) (xy 9.06383 -372.661149) (xy 8.992911 -372.652538)
			(xy 8.923548 -372.635441) (xy 8.856751 -372.610108) (xy 8.793494 -372.576908) (xy 8.7347 -372.536326)
			(xy 8.681227 -372.488953) (xy 8.633854 -372.43548) (xy 8.593272 -372.376686) (xy 8.560072 -372.313429)
			(xy 8.534739 -372.246632) (xy 8.517642 -372.177269) (xy 8.509031 -372.10635) (xy 8.508492 -372.07063)
			(xy 8.508943 -372.037466) (xy 8.516389 -371.971558) (xy 8.531169 -371.906897) (xy 8.553096 -371.844299)
			(xy 8.581895 -371.784549) (xy 8.617203 -371.7284) (xy 8.658577 -371.676558) (xy 8.68172 -371.6528)
			(xy 8.7884 -371.54612) (xy 8.795125 -371.538663) (xy 8.802695 -371.520085) (xy 8.803132 -371.510052)
			(xy 8.803132 -371.409214) (xy 8.80359 -371.376051) (xy 8.811037 -371.310143) (xy 8.825817 -371.245483)
			(xy 8.847743 -371.182885) (xy 8.876541 -371.123136) (xy 8.911847 -371.066986) (xy 8.953219 -371.015143)
			(xy 8.97636 -370.991384) (xy 9.584436 -370.383308) (xy 9.60823 -370.360205) (xy 9.660072 -370.318841)
			(xy 9.716217 -370.283538) (xy 9.775961 -370.254741) (xy 9.838552 -370.23281) (xy 9.903204 -370.218022)
			(xy 9.969105 -370.210563) (xy 10.002266 -370.21008) (xy 12.925298 -370.21008) (xy 12.958462 -370.210516)
			(xy 13.024371 -370.217965) (xy 13.089032 -370.232747) (xy 13.15163 -370.254677) (xy 13.21138 -370.283478)
			(xy 13.267528 -370.318789) (xy 13.31937 -370.360165) (xy 13.343128 -370.383308) (xy 14.312392 -371.352572)
			(xy 14.335512 -371.376349) (xy 14.376875 -371.428194) (xy 14.412176 -371.484343) (xy 14.440971 -371.544089)
			(xy 14.462899 -371.606683) (xy 14.477683 -371.671338) (xy 14.485139 -371.737241) (xy 14.48562 -371.770402)
			(xy 14.48562 -371.790214) (xy 27.42438 -371.790214) (xy 27.424932 -371.757484) (xy 27.433792 -371.692625)
			(xy 27.451287 -371.629545) (xy 27.477098 -371.569388) (xy 27.493468 -371.54104) (xy 27.496766 -371.535007)
			(xy 27.500382 -371.52175) (xy 27.50058 -371.514878) (xy 27.50058 -370.765324) (xy 27.500381 -370.758451)
			(xy 27.496778 -370.745188) (xy 27.493468 -370.739162) (xy 27.477094 -370.710817) (xy 27.451293 -370.650657)
			(xy 27.433805 -370.587576) (xy 27.424948 -370.522717) (xy 27.42438 -370.489988) (xy 27.424966 -370.457259)
			(xy 27.433816 -370.392402) (xy 27.451301 -370.329322) (xy 27.477102 -370.269163) (xy 27.493468 -370.240814)
			(xy 27.496775 -370.234786) (xy 27.500386 -370.221525) (xy 27.50058 -370.214652) (xy 27.50058 -369.928902)
			(xy 27.501029 -369.918771) (xy 27.508764 -369.900042) (xy 27.523062 -369.885684) (xy 27.541759 -369.877872)
			(xy 27.551888 -369.87734) (xy 28.268168 -369.87734) (xy 28.278325 -369.877748) (xy 28.297085 -369.885541)
			(xy 28.311411 -369.899943) (xy 28.319104 -369.918743) (xy 28.319476 -369.928902) (xy 28.319476 -370.214652)
			(xy 28.319689 -370.221524) (xy 28.323283 -370.234786) (xy 28.326588 -370.240814) (xy 28.342958 -370.269161)
			(xy 28.368759 -370.329321) (xy 28.386247 -370.392401) (xy 28.395106 -370.457259) (xy 28.395676 -370.489988)
			(xy 28.39513 -370.522709) (xy 31.825015 -370.522709) (xy 31.825017 -370.457271) (xy 31.833802 -370.392425)
			(xy 31.851212 -370.329346) (xy 31.876932 -370.269175) (xy 31.893256 -370.240814) (xy 31.896562 -370.234785)
			(xy 31.900174 -370.221525) (xy 31.900368 -370.214652) (xy 31.900368 -369.928902) (xy 31.900766 -369.918727)
			(xy 31.908556 -369.899926) (xy 31.92295 -369.88554) (xy 31.941755 -369.877761) (xy 31.95193 -369.87734)
			(xy 32.66821 -369.87734) (xy 32.678369 -369.877825) (xy 32.697138 -369.885603) (xy 32.711503 -369.899972)
			(xy 32.719277 -369.918743) (xy 32.719772 -369.928902) (xy 32.719772 -370.214652) (xy 32.719986 -370.221524)
			(xy 32.723579 -370.234786) (xy 32.726884 -370.240814) (xy 32.743195 -370.269181) (xy 32.768913 -370.329351)
			(xy 32.786321 -370.392429) (xy 32.795105 -370.457272) (xy 32.795107 -370.522708) (xy 32.786325 -370.587551)
			(xy 32.76892 -370.650629) (xy 32.743205 -370.710801) (xy 32.726884 -370.739162) (xy 32.723582 -370.745193)
			(xy 32.719968 -370.758452) (xy 32.719772 -370.765324) (xy 32.719772 -371.514878) (xy 32.719976 -371.52175)
			(xy 32.723576 -371.535013) (xy 32.726884 -371.54104) (xy 32.743217 -371.569395) (xy 32.768933 -371.629568)
			(xy 32.786339 -371.692648) (xy 32.79512 -371.757493) (xy 32.795119 -371.822931) (xy 32.786334 -371.887776)
			(xy 32.768925 -371.950855) (xy 32.743206 -372.011026) (xy 32.726884 -372.039388) (xy 32.723572 -372.045414)
			(xy 32.719965 -372.058677) (xy 32.719772 -372.06555) (xy 32.719772 -372.351554) (xy 32.719299 -372.361721)
			(xy 32.711531 -372.380513) (xy 32.69716 -372.394899) (xy 32.678377 -372.402688) (xy 32.66821 -372.403116)
			(xy 31.95193 -372.403116) (xy 31.941755 -372.40271) (xy 31.922952 -372.394927) (xy 31.908564 -372.380535)
			(xy 31.900787 -372.361729) (xy 31.900368 -372.351554) (xy 31.900368 -372.06555) (xy 31.900161 -372.058678)
			(xy 31.896563 -372.045415) (xy 31.893256 -372.039388) (xy 31.876945 -372.01102) (xy 31.851225 -371.950851)
			(xy 31.833815 -371.887774) (xy 31.82503 -371.82293) (xy 31.825028 -371.757494) (xy 31.833811 -371.69265)
			(xy 31.851218 -371.629572) (xy 31.876934 -371.569401) (xy 31.893256 -371.54104) (xy 31.896553 -371.535007)
			(xy 31.90017 -371.52175) (xy 31.900368 -371.514878) (xy 31.900368 -370.765324) (xy 31.900171 -370.758451)
			(xy 31.896567 -370.745188) (xy 31.893256 -370.739162) (xy 31.876923 -370.710807) (xy 31.851206 -370.650634)
			(xy 31.833798 -370.587554) (xy 31.825015 -370.522709) (xy 28.39513 -370.522709) (xy 28.39513 -370.522718)
			(xy 28.386269 -370.587577) (xy 28.368773 -370.650658) (xy 28.342959 -370.710815) (xy 28.326588 -370.739162)
			(xy 28.323286 -370.745193) (xy 28.319673 -370.758452) (xy 28.319476 -370.765324) (xy 28.319476 -371.514878)
			(xy 28.319679 -371.52175) (xy 28.32328 -371.535013) (xy 28.326588 -371.54104) (xy 28.342968 -371.569381)
			(xy 28.365869 -371.622787) (xy 29.624859 -371.622787) (xy 29.624864 -371.557348) (xy 29.633651 -371.492502)
			(xy 29.651063 -371.429422) (xy 29.676784 -371.36925) (xy 29.693108 -371.340888) (xy 29.696428 -371.334866)
			(xy 29.70003 -371.3216) (xy 29.70022 -371.314726) (xy 29.70022 -371.028722) (xy 29.700682 -371.018554)
			(xy 29.708456 -370.999763) (xy 29.72283 -370.985378) (xy 29.741614 -370.97759) (xy 29.751782 -370.97716)
			(xy 30.468062 -370.97716) (xy 30.478234 -370.977596) (xy 30.497032 -370.985372) (xy 30.511419 -370.999755)
			(xy 30.519201 -371.01855) (xy 30.519624 -371.028722) (xy 30.519624 -371.314726) (xy 30.519803 -371.3216)
			(xy 30.52342 -371.334863) (xy 30.526736 -371.340888) (xy 30.543027 -371.369267) (xy 30.568749 -371.429434)
			(xy 30.586161 -371.492509) (xy 30.594949 -371.55735) (xy 30.594954 -371.622785) (xy 30.586174 -371.687627)
			(xy 30.56877 -371.750705) (xy 30.543056 -371.810875) (xy 30.526736 -371.839236) (xy 30.523411 -371.845256)
			(xy 30.519812 -371.858523) (xy 30.519624 -371.865398) (xy 30.519624 -372.614698) (xy 30.519814 -372.621571)
			(xy 30.523423 -372.634834) (xy 30.526736 -372.64086) (xy 30.543088 -372.669205) (xy 30.568804 -372.72938)
			(xy 30.58621 -372.792462) (xy 30.59499 -372.857309) (xy 30.594988 -372.890034) (xy 34.024316 -372.890034)
			(xy 34.024873 -372.857304) (xy 34.033731 -372.792445) (xy 34.051224 -372.729365) (xy 34.077034 -372.669208)
			(xy 34.093404 -372.64086) (xy 34.096733 -372.634842) (xy 34.10033 -372.621573) (xy 34.100516 -372.614698)
			(xy 34.100516 -371.865398) (xy 34.100323 -371.858525) (xy 34.096715 -371.845262) (xy 34.093404 -371.839236)
			(xy 34.077053 -371.810879) (xy 34.051248 -371.750722) (xy 34.033754 -371.687645) (xy 34.024889 -371.62279)
			(xy 34.024316 -371.590062) (xy 34.024885 -371.557333) (xy 34.033739 -371.492474) (xy 34.051229 -371.429394)
			(xy 34.077036 -371.369236) (xy 34.093404 -371.340888) (xy 34.096723 -371.334866) (xy 34.100326 -371.3216)
			(xy 34.100516 -371.314726) (xy 34.100516 -371.028722) (xy 34.101044 -371.0186) (xy 34.10876 -370.999883)
			(xy 34.123033 -370.985527) (xy 34.141705 -370.977703) (xy 34.151824 -370.97716) (xy 34.868104 -370.97716)
			(xy 34.878253 -370.977618) (xy 34.896998 -370.985407) (xy 34.91132 -370.999792) (xy 34.919027 -371.018571)
			(xy 34.919412 -371.028722) (xy 34.919412 -371.314726) (xy 34.919592 -371.3216) (xy 34.923208 -371.334863)
			(xy 34.926524 -371.340888) (xy 34.942887 -371.369239) (xy 34.968689 -371.429398) (xy 34.986179 -371.492477)
			(xy 34.995041 -371.557333) (xy 34.995612 -371.590062) (xy 34.99505 -371.622792) (xy 34.986193 -371.68765)
			(xy 34.968701 -371.75073) (xy 34.951762 -371.790214) (xy 36.224464 -371.790214) (xy 36.225018 -371.757484)
			(xy 36.233878 -371.692626) (xy 36.251372 -371.629546) (xy 36.277182 -371.569388) (xy 36.293552 -371.54104)
			(xy 36.296849 -371.535006) (xy 36.300466 -371.52175) (xy 36.300664 -371.514878) (xy 36.300664 -370.765324)
			(xy 36.300467 -370.758451) (xy 36.296863 -370.745188) (xy 36.293552 -370.739162) (xy 36.277176 -370.710818)
			(xy 36.251376 -370.650657) (xy 36.233889 -370.587576) (xy 36.225032 -370.522718) (xy 36.224464 -370.489988)
			(xy 36.225052 -370.457259) (xy 36.233902 -370.392402) (xy 36.251386 -370.329322) (xy 36.277187 -370.269163)
			(xy 36.293552 -370.240814) (xy 36.296858 -370.234785) (xy 36.30047 -370.221525) (xy 36.300664 -370.214652)
			(xy 36.300664 -369.928902) (xy 36.301129 -369.918772) (xy 36.308861 -369.900047) (xy 36.323154 -369.88569)
			(xy 36.341845 -369.877875) (xy 36.351972 -369.87734) (xy 37.068252 -369.87734) (xy 37.078408 -369.877762)
			(xy 37.097167 -369.885549) (xy 37.111494 -369.899947) (xy 37.119188 -369.918744) (xy 37.11956 -369.928902)
			(xy 37.11956 -370.214652) (xy 37.119775 -370.221523) (xy 37.123368 -370.234786) (xy 37.126672 -370.240814)
			(xy 37.14304 -370.269162) (xy 37.168842 -370.329322) (xy 37.186331 -370.392402) (xy 37.19519 -370.457259)
			(xy 37.19576 -370.489988) (xy 37.195203 -370.522718) (xy 37.186343 -370.587576) (xy 37.16885 -370.650656)
			(xy 37.143041 -370.710814) (xy 37.126672 -370.739162) (xy 37.123369 -370.745192) (xy 37.119756 -370.758452)
			(xy 37.11956 -370.765324) (xy 37.11956 -371.514878) (xy 37.119765 -371.52175) (xy 37.123365 -371.535013)
			(xy 37.126672 -371.54104) (xy 37.143051 -371.569382) (xy 37.165952 -371.622787) (xy 38.424945 -371.622787)
			(xy 38.42495 -371.557348) (xy 38.433737 -371.492502) (xy 38.451148 -371.429422) (xy 38.476869 -371.36925)
			(xy 38.493192 -371.340888) (xy 38.49651 -371.334865) (xy 38.500114 -371.3216) (xy 38.500304 -371.314726)
			(xy 38.500304 -371.028722) (xy 38.50085 -371.01857) (xy 38.508611 -370.999808) (xy 38.522961 -370.985443)
			(xy 38.541714 -370.977661) (xy 38.551866 -370.97716) (xy 39.268146 -370.97716) (xy 39.278309 -370.977596)
			(xy 39.297084 -370.98539) (xy 39.311448 -370.999773) (xy 39.319217 -371.018558) (xy 39.319708 -371.028722)
			(xy 39.319708 -371.314726) (xy 39.319889 -371.3216) (xy 39.323504 -371.334863) (xy 39.32682 -371.340888)
			(xy 39.343111 -371.369267) (xy 39.368834 -371.429433) (xy 39.386247 -371.492508) (xy 39.395036 -371.55735)
			(xy 39.39504 -371.622785) (xy 39.38626 -371.687628) (xy 39.368856 -371.750705) (xy 39.351971 -371.790214)
			(xy 40.624252 -371.790214) (xy 40.624808 -371.757484) (xy 40.633668 -371.692626) (xy 40.651161 -371.629546)
			(xy 40.67697 -371.569388) (xy 40.69334 -371.54104) (xy 40.696636 -371.535006) (xy 40.700254 -371.52175)
			(xy 40.700452 -371.514878) (xy 40.700452 -370.765324) (xy 40.700257 -370.758451) (xy 40.696651 -370.745188)
			(xy 40.69334 -370.739162) (xy 40.676963 -370.710819) (xy 40.651163 -370.650657) (xy 40.633676 -370.587576)
			(xy 40.62482 -370.522718) (xy 40.624252 -370.489988) (xy 40.624841 -370.457259) (xy 40.633691 -370.392402)
			(xy 40.651174 -370.329322) (xy 40.676975 -370.269163) (xy 40.69334 -370.240814) (xy 40.696645 -370.234785)
			(xy 40.700258 -370.221525) (xy 40.700452 -370.214652) (xy 40.700452 -369.928902) (xy 40.700929 -369.918774)
			(xy 40.708658 -369.900051) (xy 40.722947 -369.885694) (xy 40.741634 -369.877877) (xy 40.75176 -369.87734)
			(xy 41.46804 -369.87734) (xy 41.478202 -369.87769) (xy 41.496963 -369.885506) (xy 41.511286 -369.899925)
			(xy 41.518977 -369.918738) (xy 41.519348 -369.928902) (xy 41.519348 -370.214652) (xy 41.519552 -370.221524)
			(xy 41.523151 -370.234787) (xy 41.52646 -370.240814) (xy 41.542827 -370.269162) (xy 41.56863 -370.329322)
			(xy 41.586119 -370.392402) (xy 41.594978 -370.457259) (xy 41.595548 -370.489988) (xy 41.594993 -370.522708)
			(xy 45.024891 -370.522708) (xy 45.024893 -370.457271) (xy 45.033677 -370.392426) (xy 45.051087 -370.329347)
			(xy 45.076805 -370.269175) (xy 45.093128 -370.240814) (xy 45.09644 -370.234788) (xy 45.100047 -370.221525)
			(xy 45.10024 -370.214652) (xy 45.10024 -369.928902) (xy 45.100665 -369.91873) (xy 45.10845 -369.899935)
			(xy 45.122835 -369.88555) (xy 45.14163 -369.877765) (xy 45.151802 -369.87734) (xy 45.868082 -369.87734)
			(xy 45.878253 -369.877778) (xy 45.897047 -369.885558) (xy 45.911433 -369.899939) (xy 45.919218 -369.918731)
			(xy 45.919644 -369.928902) (xy 45.919644 -370.214652) (xy 45.919849 -370.221524) (xy 45.923448 -370.234787)
			(xy 45.926756 -370.240814) (xy 45.943068 -370.269181) (xy 45.968787 -370.329351) (xy 45.986196 -370.392428)
			(xy 45.994981 -370.457272) (xy 45.994983 -370.522708) (xy 45.986201 -370.587552) (xy 45.968794 -370.65063)
			(xy 45.943078 -370.710801) (xy 45.926756 -370.739162) (xy 45.923459 -370.745196) (xy 45.919842 -370.758452)
			(xy 45.919644 -370.765324) (xy 45.919644 -371.514878) (xy 45.919839 -371.521751) (xy 45.923445 -371.535014)
			(xy 45.926756 -371.54104) (xy 45.94309 -371.569395) (xy 45.965909 -371.622787) (xy 47.225018 -371.622787)
			(xy 47.225022 -371.557348) (xy 47.233811 -371.492501) (xy 47.251225 -371.42942) (xy 47.27695 -371.369249)
			(xy 47.293276 -371.340888) (xy 47.296593 -371.334865) (xy 47.300198 -371.3216) (xy 47.300388 -371.314726)
			(xy 47.300388 -371.028722) (xy 47.300783 -371.018546) (xy 47.30857 -370.999742) (xy 47.322966 -370.985355)
			(xy 47.341773 -370.977578) (xy 47.35195 -370.97716) (xy 48.06823 -370.97716) (xy 48.078392 -370.977609)
			(xy 48.097167 -370.985398) (xy 48.111532 -370.999777) (xy 48.119301 -371.018559) (xy 48.119792 -371.028722)
			(xy 48.119792 -371.314726) (xy 48.119975 -371.3216) (xy 48.123589 -371.334863) (xy 48.126904 -371.340888)
			(xy 48.143193 -371.369267) (xy 48.168911 -371.429435) (xy 48.186321 -371.49251) (xy 48.195108 -371.557351)
			(xy 48.195112 -371.622784) (xy 48.186334 -371.687626) (xy 48.168933 -371.750703) (xy 48.143222 -371.810874)
			(xy 48.126904 -371.839236) (xy 48.123577 -371.845255) (xy 48.119979 -371.858523) (xy 48.119792 -371.865398)
			(xy 48.119792 -372.614698) (xy 48.119986 -372.621571) (xy 48.123593 -372.634834) (xy 48.126904 -372.64086)
			(xy 48.143254 -372.669206) (xy 48.168966 -372.729381) (xy 48.18637 -372.792463) (xy 48.195149 -372.85731)
			(xy 48.195145 -372.922748) (xy 48.186358 -372.987594) (xy 48.168947 -373.050674) (xy 48.143227 -373.110846)
			(xy 48.126904 -373.139208) (xy 48.123587 -373.145231) (xy 48.119983 -373.158496) (xy 48.119792 -373.16537)
			(xy 48.119792 -373.451374) (xy 48.119246 -373.461526) (xy 48.111486 -373.480289) (xy 48.097136 -373.494655)
			(xy 48.078382 -373.502435) (xy 48.06823 -373.502936) (xy 47.35195 -373.502936) (xy 47.341778 -373.502495)
			(xy 47.32298 -373.494721) (xy 47.308592 -373.48034) (xy 47.30081 -373.461545) (xy 47.300388 -373.451374)
			(xy 47.300388 -373.16537) (xy 47.300209 -373.158496) (xy 47.296592 -373.145233) (xy 47.293276 -373.139208)
			(xy 47.276981 -373.110831) (xy 47.251259 -373.050664) (xy 47.233847 -372.987589) (xy 47.225059 -372.922747)
			(xy 47.225055 -372.857312) (xy 47.233835 -372.792469) (xy 47.25124 -372.729391) (xy 47.276955 -372.669221)
			(xy 47.293276 -372.64086) (xy 47.296603 -372.634841) (xy 47.300201 -372.621573) (xy 47.300388 -372.614698)
			(xy 47.300388 -371.865398) (xy 47.300199 -371.858525) (xy 47.296589 -371.845262) (xy 47.293276 -371.839236)
			(xy 47.27692 -371.810893) (xy 47.251204 -371.750718) (xy 47.233798 -371.687635) (xy 47.225018 -371.622787)
			(xy 45.965909 -371.622787) (xy 45.968807 -371.629567) (xy 45.986214 -371.692647) (xy 45.994996 -371.757493)
			(xy 45.994995 -371.822931) (xy 45.986209 -371.887776) (xy 45.968799 -371.950855) (xy 45.943079 -372.011027)
			(xy 45.926756 -372.039388) (xy 45.92345 -372.045417) (xy 45.919838 -372.058677) (xy 45.919644 -372.06555)
			(xy 45.919644 -372.351554) (xy 45.919198 -372.361725) (xy 45.911425 -372.380522) (xy 45.897046 -372.394909)
			(xy 45.878253 -372.402693) (xy 45.868082 -372.403116) (xy 45.151802 -372.403116) (xy 45.141625 -372.402733)
			(xy 45.122821 -372.394941) (xy 45.108435 -372.380542) (xy 45.100658 -372.361732) (xy 45.10024 -372.351554)
			(xy 45.10024 -372.06555) (xy 45.100024 -372.058679) (xy 45.096432 -372.045416) (xy 45.093128 -372.039388)
			(xy 45.076818 -372.01102) (xy 45.0511 -371.95085) (xy 45.033691 -371.887773) (xy 45.024906 -371.82293)
			(xy 45.024904 -371.757494) (xy 45.033686 -371.692651) (xy 45.051092 -371.629572) (xy 45.076807 -371.569401)
			(xy 45.093128 -371.54104) (xy 45.09643 -371.535009) (xy 45.100043 -371.52175) (xy 45.10024 -371.514878)
			(xy 45.10024 -370.765324) (xy 45.100034 -370.758452) (xy 45.096435 -370.745189) (xy 45.093128 -370.739162)
			(xy 45.076796 -370.710806) (xy 45.05108 -370.650634) (xy 45.033673 -370.587554) (xy 45.024891 -370.522708)
			(xy 41.594993 -370.522708) (xy 41.594993 -370.522718) (xy 41.586133 -370.587576) (xy 41.568639 -370.650656)
			(xy 41.54283 -370.710814) (xy 41.52646 -370.739162) (xy 41.523163 -370.745196) (xy 41.519546 -370.758452)
			(xy 41.519348 -370.765324) (xy 41.519348 -371.514878) (xy 41.519542 -371.521751) (xy 41.523148 -371.535014)
			(xy 41.52646 -371.54104) (xy 41.542838 -371.569383) (xy 41.568637 -371.629544) (xy 41.586124 -371.692626)
			(xy 41.59498 -371.757484) (xy 41.595548 -371.790214) (xy 41.59496 -371.822943) (xy 41.58611 -371.8878)
			(xy 41.568626 -371.95088) (xy 41.542825 -372.011039) (xy 41.52646 -372.039388) (xy 41.523154 -372.045417)
			(xy 41.519542 -372.058677) (xy 41.519348 -372.06555) (xy 41.519348 -372.351554) (xy 41.518835 -372.361679)
			(xy 41.51112 -372.380402) (xy 41.496842 -372.39476) (xy 41.478162 -372.402579) (xy 41.46804 -372.403116)
			(xy 40.75176 -372.403116) (xy 40.741605 -372.402711) (xy 40.722855 -372.394906) (xy 40.708534 -372.380504)
			(xy 40.700833 -372.361711) (xy 40.700452 -372.351554) (xy 40.700452 -372.06555) (xy 40.700247 -372.058678)
			(xy 40.696648 -372.045415) (xy 40.69334 -372.039388) (xy 40.676973 -372.011039) (xy 40.651171 -371.95088)
			(xy 40.633681 -371.8878) (xy 40.624822 -371.822943) (xy 40.624252 -371.790214) (xy 39.351971 -371.790214)
			(xy 39.343141 -371.810875) (xy 39.32682 -371.839236) (xy 39.323494 -371.845255) (xy 39.319895 -371.858523)
			(xy 39.319708 -371.865398) (xy 39.319708 -372.614698) (xy 39.319899 -372.621571) (xy 39.323508 -372.634834)
			(xy 39.32682 -372.64086) (xy 39.343172 -372.669205) (xy 39.368889 -372.729379) (xy 39.386296 -372.792462)
			(xy 39.395077 -372.857309) (xy 39.395075 -372.890034) (xy 42.8244 -372.890034) (xy 42.824959 -372.857304)
			(xy 42.833817 -372.792446) (xy 42.851309 -372.729366) (xy 42.877119 -372.669208) (xy 42.893488 -372.64086)
			(xy 42.896816 -372.634842) (xy 42.900414 -372.621573) (xy 42.9006 -372.614698) (xy 42.9006 -371.865398)
			(xy 42.900409 -371.858525) (xy 42.8968 -371.845262) (xy 42.893488 -371.839236) (xy 42.877136 -371.81088)
			(xy 42.851331 -371.750723) (xy 42.833838 -371.687645) (xy 42.824973 -371.62279) (xy 42.8244 -371.590062)
			(xy 42.824971 -371.557333) (xy 42.833825 -371.492475) (xy 42.851314 -371.429394) (xy 42.87712 -371.369236)
			(xy 42.893488 -371.340888) (xy 42.896806 -371.334865) (xy 42.90041 -371.3216) (xy 42.9006 -371.314726)
			(xy 42.9006 -371.028722) (xy 42.901143 -371.018602) (xy 42.908856 -370.999888) (xy 42.923125 -370.985533)
			(xy 42.941791 -370.977706) (xy 42.951908 -370.97716) (xy 43.668188 -370.97716) (xy 43.678336 -370.977631)
			(xy 43.697081 -370.985415) (xy 43.711403 -370.999796) (xy 43.71911 -371.018572) (xy 43.719496 -371.028722)
			(xy 43.719496 -371.314726) (xy 43.719678 -371.3216) (xy 43.723293 -371.334863) (xy 43.726608 -371.340888)
			(xy 43.74297 -371.369239) (xy 43.768772 -371.429398) (xy 43.786263 -371.492477) (xy 43.795125 -371.557333)
			(xy 43.795696 -371.590062) (xy 43.795136 -371.622792) (xy 43.786279 -371.68765) (xy 43.768787 -371.75073)
			(xy 43.742977 -371.810888) (xy 43.726608 -371.839236) (xy 43.723281 -371.845255) (xy 43.719683 -371.858523)
			(xy 43.719496 -371.865398) (xy 43.719496 -372.614698) (xy 43.719689 -372.621571) (xy 43.723296 -372.634834)
			(xy 43.726608 -372.64086) (xy 43.742958 -372.669218) (xy 43.768764 -372.729374) (xy 43.786258 -372.792451)
			(xy 43.795123 -372.857306) (xy 43.795696 -372.890034) (xy 43.795124 -372.922763) (xy 43.78627 -372.987621)
			(xy 43.768781 -373.050701) (xy 43.742976 -373.11086) (xy 43.726608 -373.139208) (xy 43.723291 -373.145232)
			(xy 43.719687 -373.158496) (xy 43.719496 -373.16537) (xy 43.719496 -373.451374) (xy 43.718953 -373.461495)
			(xy 43.711241 -373.480208) (xy 43.696972 -373.494564) (xy 43.678306 -373.502391) (xy 43.668188 -373.502936)
			(xy 42.951908 -373.502936) (xy 42.941759 -373.502473) (xy 42.923014 -373.494686) (xy 42.908691 -373.480303)
			(xy 42.900985 -373.461525) (xy 42.9006 -373.451374) (xy 42.9006 -373.16537) (xy 42.90042 -373.158496)
			(xy 42.896804 -373.145233) (xy 42.893488 -373.139208) (xy 42.877124 -373.110858) (xy 42.851322 -373.050698)
			(xy 42.833832 -372.987619) (xy 42.824971 -372.922763) (xy 42.8244 -372.890034) (xy 39.395075 -372.890034)
			(xy 39.395073 -372.922749) (xy 39.386284 -372.987596) (xy 39.36887 -373.050676) (xy 39.343146 -373.110847)
			(xy 39.32682 -373.139208) (xy 39.323504 -373.145232) (xy 39.319899 -373.158496) (xy 39.319708 -373.16537)
			(xy 39.319708 -373.451374) (xy 39.319147 -373.461525) (xy 39.311389 -373.480284) (xy 39.297045 -373.494649)
			(xy 39.278296 -373.502432) (xy 39.268146 -373.502936) (xy 38.551866 -373.502936) (xy 38.541703 -373.502494)
			(xy 38.522928 -373.494703) (xy 38.508563 -373.480322) (xy 38.500794 -373.461538) (xy 38.500304 -373.451374)
			(xy 38.500304 -373.16537) (xy 38.500123 -373.158496) (xy 38.496507 -373.145233) (xy 38.493192 -373.139208)
			(xy 38.4769 -373.11083) (xy 38.451182 -373.050662) (xy 38.433773 -372.987587) (xy 38.424986 -372.922746)
			(xy 38.424982 -372.857312) (xy 38.433761 -372.79247) (xy 38.451163 -372.729393) (xy 38.476873 -372.669222)
			(xy 38.493192 -372.64086) (xy 38.49652 -372.634842) (xy 38.500118 -372.621573) (xy 38.500304 -372.614698)
			(xy 38.500304 -371.865398) (xy 38.500112 -371.858525) (xy 38.496504 -371.845262) (xy 38.493192 -371.839236)
			(xy 38.476839 -371.810892) (xy 38.451127 -371.750716) (xy 38.433724 -371.687634) (xy 38.424945 -371.622787)
			(xy 37.165952 -371.622787) (xy 37.16885 -371.629544) (xy 37.186336 -371.692626) (xy 37.195192 -371.757484)
			(xy 37.19576 -371.790214) (xy 37.19517 -371.822943) (xy 37.18632 -371.8878) (xy 37.168837 -371.95088)
			(xy 37.143037 -372.011039) (xy 37.126672 -372.039388) (xy 37.12336 -372.045414) (xy 37.119753 -372.058677)
			(xy 37.11956 -372.06555) (xy 37.11956 -372.351554) (xy 37.119036 -372.361678) (xy 37.111323 -372.380398)
			(xy 37.097048 -372.394756) (xy 37.078373 -372.402576) (xy 37.068252 -372.403116) (xy 36.351972 -372.403116)
			(xy 36.341818 -372.402702) (xy 36.323068 -372.3949) (xy 36.308746 -372.380501) (xy 36.301045 -372.36171)
			(xy 36.300664 -372.351554) (xy 36.300664 -372.06555) (xy 36.300457 -372.058678) (xy 36.29686 -372.045415)
			(xy 36.293552 -372.039388) (xy 36.277187 -372.011039) (xy 36.251384 -371.950879) (xy 36.233894 -371.8878)
			(xy 36.225034 -371.822943) (xy 36.224464 -371.790214) (xy 34.951762 -371.790214) (xy 34.942893 -371.810888)
			(xy 34.926524 -371.839236) (xy 34.923198 -371.845255) (xy 34.919599 -371.858523) (xy 34.919412 -371.865398)
			(xy 34.919412 -372.614698) (xy 34.919603 -372.621571) (xy 34.923212 -372.634834) (xy 34.926524 -372.64086)
			(xy 34.942876 -372.669217) (xy 34.968681 -372.729374) (xy 34.986174 -372.792451) (xy 34.995039 -372.857306)
			(xy 34.995612 -372.890034) (xy 34.995037 -372.922763) (xy 34.986184 -372.987621) (xy 34.968696 -373.050701)
			(xy 34.942891 -373.11086) (xy 34.926524 -373.139208) (xy 34.923208 -373.145232) (xy 34.919603 -373.158496)
			(xy 34.919412 -373.16537) (xy 34.919412 -373.451374) (xy 34.918854 -373.461493) (xy 34.911144 -373.480203)
			(xy 34.89688 -373.494559) (xy 34.878219 -373.502388) (xy 34.868104 -373.502936) (xy 34.151824 -373.502936)
			(xy 34.141676 -373.50246) (xy 34.122931 -373.494679) (xy 34.108608 -373.480299) (xy 34.100901 -373.461524)
			(xy 34.100516 -373.451374) (xy 34.100516 -373.16537) (xy 34.100333 -373.158496) (xy 34.096719 -373.145233)
			(xy 34.093404 -373.139208) (xy 34.077042 -373.110857) (xy 34.051239 -373.050698) (xy 34.033749 -372.987619)
			(xy 34.024887 -372.922763) (xy 34.024316 -372.890034) (xy 30.594988 -372.890034) (xy 30.594986 -372.922749)
			(xy 30.586198 -372.987595) (xy 30.568785 -373.050675) (xy 30.543061 -373.110847) (xy 30.526736 -373.139208)
			(xy 30.523421 -373.145233) (xy 30.519815 -373.158496) (xy 30.519624 -373.16537) (xy 30.519624 -373.451374)
			(xy 30.519214 -373.461549) (xy 30.51143 -373.48035) (xy 30.49704 -373.494737) (xy 30.478237 -373.502516)
			(xy 30.468062 -373.502936) (xy 29.751782 -373.502936) (xy 29.741606 -373.50255) (xy 29.722806 -373.494754)
			(xy 29.708421 -373.480357) (xy 29.700641 -373.46155) (xy 29.70022 -373.451374) (xy 29.70022 -373.16537)
			(xy 29.700037 -373.158496) (xy 29.696422 -373.145233) (xy 29.693108 -373.139208) (xy 29.676816 -373.110831)
			(xy 29.651097 -373.050663) (xy 29.633687 -372.987588) (xy 29.6249 -372.922746) (xy 29.624896 -372.857312)
			(xy 29.633675 -372.79247) (xy 29.651078 -372.729392) (xy 29.676789 -372.669222) (xy 29.693108 -372.64086)
			(xy 29.696438 -372.634843) (xy 29.700034 -372.621573) (xy 29.70022 -372.614698) (xy 29.70022 -371.865398)
			(xy 29.700026 -371.858525) (xy 29.696419 -371.845262) (xy 29.693108 -371.839236) (xy 29.676755 -371.810892)
			(xy 29.651042 -371.750717) (xy 29.633638 -371.687634) (xy 29.624859 -371.622787) (xy 28.365869 -371.622787)
			(xy 28.368767 -371.629544) (xy 28.386252 -371.692626) (xy 28.395108 -371.757484) (xy 28.395676 -371.790214)
			(xy 28.395097 -371.822943) (xy 28.386246 -371.887801) (xy 28.368759 -371.950881) (xy 28.342955 -372.01104)
			(xy 28.326588 -372.039388) (xy 28.323277 -372.045414) (xy 28.319669 -372.058677) (xy 28.319476 -372.06555)
			(xy 28.319476 -372.351554) (xy 28.318936 -372.361676) (xy 28.311226 -372.380393) (xy 28.296956 -372.39475)
			(xy 28.278287 -372.402574) (xy 28.268168 -372.403116) (xy 27.551888 -372.403116) (xy 27.541735 -372.402689)
			(xy 27.522985 -372.394892) (xy 27.508663 -372.380498) (xy 27.500961 -372.361709) (xy 27.50058 -372.351554)
			(xy 27.50058 -372.06555) (xy 27.500371 -372.058678) (xy 27.496775 -372.045415) (xy 27.493468 -372.039388)
			(xy 27.477104 -372.011038) (xy 27.4513 -371.950879) (xy 27.43381 -371.8878) (xy 27.42495 -371.822943)
			(xy 27.42438 -371.790214) (xy 14.48562 -371.790214) (xy 14.48562 -374.382284) (xy 14.485175 -374.415448)
			(xy 14.477727 -374.481357) (xy 14.462946 -374.546017) (xy 14.441018 -374.608615) (xy 14.412218 -374.668365)
			(xy 14.376909 -374.724514) (xy 14.335535 -374.776356) (xy 14.312392 -374.800114) (xy 13.422376 -375.69013)
			(xy 27.42438 -375.69013) (xy 27.424939 -375.6574) (xy 27.433797 -375.592542) (xy 27.45129 -375.529462)
			(xy 27.477099 -375.469304) (xy 27.493468 -375.440956) (xy 27.496796 -375.434938) (xy 27.500393 -375.421669)
			(xy 27.50058 -375.414794) (xy 27.50058 -374.665494) (xy 27.500393 -374.65862) (xy 27.496781 -374.645358)
			(xy 27.493468 -374.639332) (xy 27.477122 -374.610972) (xy 27.451314 -374.550817) (xy 27.433818 -374.487741)
			(xy 27.424953 -374.422886) (xy 27.42438 -374.390158) (xy 27.424952 -374.357429) (xy 27.433807 -374.292571)
			(xy 27.451295 -374.229491) (xy 27.477101 -374.169332) (xy 27.493468 -374.140984) (xy 27.496786 -374.134961)
			(xy 27.50039 -374.121696) (xy 27.50058 -374.114822) (xy 27.50058 -373.828818) (xy 27.501042 -373.818688)
			(xy 27.508772 -373.799959) (xy 27.523066 -373.785601) (xy 27.54176 -373.777788) (xy 27.551888 -373.777256)
			(xy 28.268168 -373.777256) (xy 28.278315 -373.777747) (xy 28.297058 -373.785523) (xy 28.311381 -373.799899)
			(xy 28.31909 -373.81867) (xy 28.319476 -373.828818) (xy 28.319476 -374.114822) (xy 28.319663 -374.121696)
			(xy 28.323275 -374.134958) (xy 28.326588 -374.140984) (xy 28.342946 -374.169337) (xy 28.36875 -374.229495)
			(xy 28.386242 -374.292574) (xy 28.395104 -374.357429) (xy 28.395676 -374.390158) (xy 28.395117 -374.422884)
			(xy 31.824998 -374.422884) (xy 31.825003 -374.357444) (xy 31.833792 -374.292597) (xy 31.851206 -374.229517)
			(xy 31.87693 -374.169345) (xy 31.893256 -374.140984) (xy 31.896573 -374.13496) (xy 31.900178 -374.121696)
			(xy 31.900368 -374.114822) (xy 31.900368 -373.828818) (xy 31.900779 -373.818644) (xy 31.908564 -373.799844)
			(xy 31.922954 -373.785457) (xy 31.941756 -373.777677) (xy 31.95193 -373.777256) (xy 32.66821 -373.777256)
			(xy 32.678384 -373.777656) (xy 32.697183 -373.785448) (xy 32.711568 -373.799841) (xy 32.719349 -373.818643)
			(xy 32.719772 -373.828818) (xy 32.719772 -374.114822) (xy 32.719959 -374.121696) (xy 32.723571 -374.134958)
			(xy 32.726884 -374.140984) (xy 32.74317 -374.169365) (xy 32.76889 -374.229532) (xy 32.786301 -374.292606)
			(xy 32.795088 -374.357447) (xy 32.795093 -374.422881) (xy 32.786315 -374.487723) (xy 32.768914 -374.5508)
			(xy 32.743203 -374.610971) (xy 32.726884 -374.639332) (xy 32.723557 -374.64535) (xy 32.719959 -374.658619)
			(xy 32.719772 -374.665494) (xy 32.719772 -375.414794) (xy 32.71997 -375.421667) (xy 32.723574 -375.434929)
			(xy 32.726884 -375.440956) (xy 32.743231 -375.469303) (xy 32.768945 -375.529478) (xy 32.786349 -375.59256)
			(xy 32.795129 -375.657406) (xy 32.795126 -375.722845) (xy 32.786339 -375.787691) (xy 32.768928 -375.850771)
			(xy 32.743208 -375.910942) (xy 32.726884 -375.939304) (xy 32.723567 -375.945327) (xy 32.719963 -375.958592)
			(xy 32.719772 -375.965466) (xy 32.719772 -376.25147) (xy 32.719312 -376.261638) (xy 32.711538 -376.28043)
			(xy 32.697164 -376.294816) (xy 32.678378 -376.302604) (xy 32.66821 -376.303032) (xy 31.95193 -376.303032)
			(xy 31.941757 -376.302611) (xy 31.922957 -376.29483) (xy 31.90857 -376.280443) (xy 31.900789 -376.261643)
			(xy 31.900368 -376.25147) (xy 31.900368 -375.965466) (xy 31.900193 -375.958591) (xy 31.896573 -375.945329)
			(xy 31.893256 -375.939304) (xy 31.876959 -375.910929) (xy 31.851238 -375.850761) (xy 31.833826 -375.787685)
			(xy 31.825039 -375.722843) (xy 31.825036 -375.657408) (xy 31.833816 -375.592565) (xy 31.851221 -375.529488)
			(xy 31.876935 -375.469317) (xy 31.893256 -375.440956) (xy 31.896583 -375.434937) (xy 31.900181 -375.421669)
			(xy 31.900368 -375.414794) (xy 31.900368 -374.665494) (xy 31.900182 -374.65862) (xy 31.89657 -374.645357)
			(xy 31.893256 -374.639332) (xy 31.876898 -374.610991) (xy 31.851182 -374.550815) (xy 31.833778 -374.487732)
			(xy 31.824998 -374.422884) (xy 28.395117 -374.422884) (xy 28.395117 -374.422888) (xy 28.38626 -374.487746)
			(xy 28.368768 -374.550827) (xy 28.342958 -374.610984) (xy 28.326588 -374.639332) (xy 28.323261 -374.645351)
			(xy 28.319663 -374.658619) (xy 28.319476 -374.665494) (xy 28.319476 -375.414794) (xy 28.319673 -375.421667)
			(xy 28.323278 -375.434929) (xy 28.326588 -375.440956) (xy 28.342935 -375.469316) (xy 28.368742 -375.529471)
			(xy 28.386236 -375.592548) (xy 28.395103 -375.657402) (xy 28.395676 -375.69013) (xy 28.395105 -375.722859)
			(xy 28.386251 -375.787718) (xy 28.368762 -375.850798) (xy 28.342956 -375.910956) (xy 28.326588 -375.939304)
			(xy 28.323271 -375.945327) (xy 28.319667 -375.958592) (xy 28.319476 -375.965466) (xy 28.319476 -376.25147)
			(xy 28.31895 -376.261593) (xy 28.311235 -376.28031) (xy 28.29696 -376.294667) (xy 28.278288 -376.30249)
			(xy 28.268168 -376.303032) (xy 27.551888 -376.303032) (xy 27.541737 -376.302589) (xy 27.52299 -376.294796)
			(xy 27.508669 -376.280406) (xy 27.500964 -376.261623) (xy 27.50058 -376.25147) (xy 27.50058 -375.965466)
			(xy 27.500404 -375.958592) (xy 27.496785 -375.945329) (xy 27.493468 -375.939304) (xy 27.477111 -375.91095)
			(xy 27.451305 -375.850793) (xy 27.433813 -375.787715) (xy 27.424951 -375.722859) (xy 27.42438 -375.69013)
			(xy 13.422376 -375.69013) (xy 12.289585 -376.822921) (xy 29.624883 -376.822921) (xy 29.624883 -376.757485)
			(xy 29.633665 -376.692641) (xy 29.651072 -376.629563) (xy 29.676787 -376.569392) (xy 29.693108 -376.54103)
			(xy 29.696413 -376.535) (xy 29.700025 -376.52174) (xy 29.70022 -376.514868) (xy 29.70022 -375.765568)
			(xy 29.700038 -375.758694) (xy 29.696423 -375.745431) (xy 29.693108 -375.739406) (xy 29.676814 -375.711029)
			(xy 29.651095 -375.650862) (xy 29.633685 -375.587786) (xy 29.624899 -375.522944) (xy 29.624895 -375.45751)
			(xy 29.633674 -375.392668) (xy 29.651077 -375.32959) (xy 29.676789 -375.26942) (xy 29.693108 -375.241058)
			(xy 29.696438 -375.235041) (xy 29.700034 -375.221771) (xy 29.70022 -375.214896) (xy 29.70022 -374.928638)
			(xy 29.700695 -374.918471) (xy 29.708464 -374.899681) (xy 29.722834 -374.885295) (xy 29.741616 -374.877506)
			(xy 29.751782 -374.877076) (xy 30.468062 -374.877076) (xy 30.478236 -374.877496) (xy 30.497037 -374.885276)
			(xy 30.511424 -374.899663) (xy 30.519204 -374.918464) (xy 30.519624 -374.928638) (xy 30.519624 -375.214896)
			(xy 30.519815 -375.221769) (xy 30.523424 -375.235032) (xy 30.526736 -375.241058) (xy 30.543086 -375.269404)
			(xy 30.568803 -375.329578) (xy 30.586209 -375.39266) (xy 30.594989 -375.457508) (xy 30.594985 -375.522947)
			(xy 30.586198 -375.587794) (xy 30.568784 -375.650873) (xy 30.543061 -375.711045) (xy 30.526736 -375.739406)
			(xy 30.523422 -375.745431) (xy 30.519816 -375.758694) (xy 30.519624 -375.765568) (xy 30.519624 -376.514868)
			(xy 30.519825 -376.521741) (xy 30.523427 -376.535003) (xy 30.526736 -376.54103) (xy 30.543062 -376.569389)
			(xy 30.568781 -376.629561) (xy 30.58619 -376.69264) (xy 30.594973 -376.757485) (xy 30.594973 -376.790204)
			(xy 34.024316 -376.790204) (xy 34.024859 -376.757474) (xy 34.033721 -376.692615) (xy 34.051218 -376.629534)
			(xy 34.077032 -376.569377) (xy 34.093404 -376.54103) (xy 34.096708 -376.535) (xy 34.10032 -376.52174)
			(xy 34.100516 -376.514868) (xy 34.100516 -375.765568) (xy 34.100334 -375.758694) (xy 34.096719 -375.745431)
			(xy 34.093404 -375.739406) (xy 34.077041 -375.711055) (xy 34.051239 -375.650896) (xy 34.033748 -375.587817)
			(xy 34.024887 -375.522961) (xy 34.024316 -375.490232) (xy 34.024872 -375.457502) (xy 34.03373 -375.392643)
			(xy 34.051223 -375.329563) (xy 34.077034 -375.269406) (xy 34.093404 -375.241058) (xy 34.096734 -375.235041)
			(xy 34.10033 -375.221771) (xy 34.100516 -375.214896) (xy 34.100516 -374.928638) (xy 34.101057 -374.918517)
			(xy 34.108768 -374.899801) (xy 34.123038 -374.885444) (xy 34.141706 -374.87762) (xy 34.151824 -374.877076)
			(xy 34.868104 -374.877076) (xy 34.878255 -374.877518) (xy 34.897003 -374.88531) (xy 34.911325 -374.8997)
			(xy 34.919029 -374.918485) (xy 34.919412 -374.928638) (xy 34.919412 -375.214896) (xy 34.919604 -375.221769)
			(xy 34.923212 -375.235032) (xy 34.926524 -375.241058) (xy 34.942875 -375.269415) (xy 34.96868 -375.329572)
			(xy 34.986174 -375.392649) (xy 34.995039 -375.457504) (xy 34.995612 -375.490232) (xy 34.995036 -375.522961)
			(xy 34.986183 -375.587819) (xy 34.968696 -375.650899) (xy 34.951868 -375.69013) (xy 36.224464 -375.69013)
			(xy 36.225026 -375.6574) (xy 36.233883 -375.592542) (xy 36.251375 -375.529462) (xy 36.277183 -375.469304)
			(xy 36.293552 -375.440956) (xy 36.296879 -375.434937) (xy 36.300477 -375.421669) (xy 36.300664 -375.414794)
			(xy 36.300664 -374.665494) (xy 36.300479 -374.65862) (xy 36.296866 -374.645357) (xy 36.293552 -374.639332)
			(xy 36.277204 -374.610973) (xy 36.251397 -374.550817) (xy 36.233902 -374.487741) (xy 36.225037 -374.422886)
			(xy 36.224464 -374.390158) (xy 36.225038 -374.357429) (xy 36.233892 -374.292571) (xy 36.25138 -374.229491)
			(xy 36.277185 -374.169332) (xy 36.293552 -374.140984) (xy 36.296869 -374.13496) (xy 36.300474 -374.121696)
			(xy 36.300664 -374.114822) (xy 36.300664 -373.828818) (xy 36.301142 -373.818689) (xy 36.308868 -373.799964)
			(xy 36.323158 -373.785606) (xy 36.341846 -373.777791) (xy 36.351972 -373.777256) (xy 37.068252 -373.777256)
			(xy 37.078398 -373.77776) (xy 37.09714 -373.785532) (xy 37.111464 -373.799903) (xy 37.119173 -373.818671)
			(xy 37.11956 -373.828818) (xy 37.11956 -374.114822) (xy 37.119749 -374.121695) (xy 37.12336 -374.134958)
			(xy 37.126672 -374.140984) (xy 37.143029 -374.169338) (xy 37.168833 -374.229496) (xy 37.186325 -374.292574)
			(xy 37.195188 -374.357429) (xy 37.19576 -374.390158) (xy 37.19519 -374.422887) (xy 37.186334 -374.487745)
			(xy 37.168845 -374.550825) (xy 37.14304 -374.610984) (xy 37.126672 -374.639332) (xy 37.123344 -374.64535)
			(xy 37.119747 -374.658619) (xy 37.11956 -374.665494) (xy 37.11956 -375.414794) (xy 37.119759 -375.421667)
			(xy 37.123363 -375.434929) (xy 37.126672 -375.440956) (xy 37.143017 -375.469316) (xy 37.168825 -375.529472)
			(xy 37.18632 -375.592548) (xy 37.195187 -375.657402) (xy 37.19576 -375.69013) (xy 37.195177 -375.722859)
			(xy 37.186325 -375.787716) (xy 37.16884 -375.850796) (xy 37.143038 -375.910955) (xy 37.126672 -375.939304)
			(xy 37.123354 -375.945327) (xy 37.119751 -375.958592) (xy 37.11956 -375.965466) (xy 37.11956 -376.25147)
			(xy 37.119049 -376.261595) (xy 37.111331 -376.280315) (xy 37.097052 -376.294673) (xy 37.078374 -376.302493)
			(xy 37.068252 -376.303032) (xy 36.351972 -376.303032) (xy 36.34182 -376.302602) (xy 36.323073 -376.294803)
			(xy 36.308752 -376.28041) (xy 36.301047 -376.261624) (xy 36.300664 -376.25147) (xy 36.300664 -375.965466)
			(xy 36.300489 -375.958591) (xy 36.29687 -375.945329) (xy 36.293552 -375.939304) (xy 36.277193 -375.910951)
			(xy 36.251388 -375.850793) (xy 36.233897 -375.787715) (xy 36.225035 -375.722859) (xy 36.224464 -375.69013)
			(xy 34.951868 -375.69013) (xy 34.942891 -375.711058) (xy 34.926524 -375.739406) (xy 34.923209 -375.74543)
			(xy 34.919603 -375.758694) (xy 34.919412 -375.765568) (xy 34.919412 -376.514868) (xy 34.919615 -376.52174)
			(xy 34.923216 -376.535003) (xy 34.926524 -376.54103) (xy 34.942904 -376.569371) (xy 34.968702 -376.629534)
			(xy 34.986187 -376.692616) (xy 34.995044 -376.757474) (xy 34.995612 -376.790204) (xy 34.995069 -376.822921)
			(xy 38.424969 -376.822921) (xy 38.424969 -376.757486) (xy 38.433751 -376.692642) (xy 38.451157 -376.629563)
			(xy 38.476871 -376.569392) (xy 38.493192 -376.54103) (xy 38.496496 -376.535) (xy 38.500108 -376.52174)
			(xy 38.500304 -376.514868) (xy 38.500304 -375.765568) (xy 38.500124 -375.758694) (xy 38.496508 -375.745431)
			(xy 38.493192 -375.739406) (xy 38.476898 -375.711029) (xy 38.451181 -375.650861) (xy 38.433771 -375.587786)
			(xy 38.424985 -375.522944) (xy 38.424982 -375.45751) (xy 38.43376 -375.392668) (xy 38.451163 -375.329591)
			(xy 38.476873 -375.26942) (xy 38.493192 -375.241058) (xy 38.496521 -375.23504) (xy 38.500118 -375.221771)
			(xy 38.500304 -375.214896) (xy 38.500304 -374.928638) (xy 38.500794 -374.918473) (xy 38.50856 -374.899686)
			(xy 38.522925 -374.885301) (xy 38.541702 -374.877508) (xy 38.551866 -374.877076) (xy 39.268146 -374.877076)
			(xy 39.278311 -374.877497) (xy 39.297089 -374.885293) (xy 39.311454 -374.899682) (xy 39.31922 -374.918472)
			(xy 39.319708 -374.928638) (xy 39.319708 -375.214896) (xy 39.3199 -375.221769) (xy 39.323508 -375.235032)
			(xy 39.32682 -375.241058) (xy 39.343171 -375.269404) (xy 39.368888 -375.329578) (xy 39.386294 -375.39266)
			(xy 39.395075 -375.457508) (xy 39.395072 -375.522947) (xy 39.386283 -375.587794) (xy 39.36887 -375.650874)
			(xy 39.352087 -375.69013) (xy 40.624252 -375.69013) (xy 40.624815 -375.6574) (xy 40.633673 -375.592542)
			(xy 40.651164 -375.529462) (xy 40.676971 -375.469304) (xy 40.69334 -375.440956) (xy 40.696666 -375.434937)
			(xy 40.700265 -375.421669) (xy 40.700452 -375.414794) (xy 40.700452 -374.665494) (xy 40.700268 -374.65862)
			(xy 40.696655 -374.645357) (xy 40.69334 -374.639332) (xy 40.676991 -374.610974) (xy 40.651184 -374.550818)
			(xy 40.63369 -374.487741) (xy 40.624825 -374.422886) (xy 40.624252 -374.390158) (xy 40.624828 -374.357429)
			(xy 40.633681 -374.292571) (xy 40.651169 -374.229491) (xy 40.676973 -374.169332) (xy 40.69334 -374.140984)
			(xy 40.696656 -374.13496) (xy 40.700262 -374.121696) (xy 40.700452 -374.114822) (xy 40.700452 -373.828818)
			(xy 40.700942 -373.818691) (xy 40.708666 -373.799968) (xy 40.722951 -373.785611) (xy 40.741636 -373.777793)
			(xy 40.75176 -373.777256) (xy 41.46804 -373.777256) (xy 41.478191 -373.777688) (xy 41.496936 -373.785489)
			(xy 41.511256 -373.799881) (xy 41.518963 -373.818665) (xy 41.519348 -373.828818) (xy 41.519348 -374.114822)
			(xy 41.519526 -374.121696) (xy 41.523143 -374.134959) (xy 41.52646 -374.140984) (xy 41.542815 -374.169339)
			(xy 41.568621 -374.229496) (xy 41.586113 -374.292574) (xy 41.594976 -374.357429) (xy 41.595548 -374.390158)
			(xy 41.594979 -374.422884) (xy 45.024874 -374.422884) (xy 45.024879 -374.357444) (xy 45.033668 -374.292598)
			(xy 45.051081 -374.229517) (xy 45.076803 -374.169345) (xy 45.093128 -374.140984) (xy 45.09645 -374.134963)
			(xy 45.100051 -374.121696) (xy 45.10024 -374.114822) (xy 45.10024 -373.828818) (xy 45.100678 -373.818647)
			(xy 45.108458 -373.799853) (xy 45.122839 -373.785467) (xy 45.141631 -373.777682) (xy 45.151802 -373.777256)
			(xy 45.868082 -373.777256) (xy 45.878255 -373.777679) (xy 45.897053 -373.785461) (xy 45.911439 -373.799847)
			(xy 45.919221 -373.818645) (xy 45.919644 -373.828818) (xy 45.919644 -374.114822) (xy 45.919822 -374.121696)
			(xy 45.923439 -374.134959) (xy 45.926756 -374.140984) (xy 45.943043 -374.169365) (xy 45.968764 -374.229531)
			(xy 45.986176 -374.292606) (xy 45.994964 -374.357447) (xy 45.994969 -374.422881) (xy 45.986191 -374.487723)
			(xy 45.968788 -374.5508) (xy 45.943076 -374.610971) (xy 45.926756 -374.639332) (xy 45.923434 -374.645353)
			(xy 45.919832 -374.65862) (xy 45.919644 -374.665494) (xy 45.919644 -375.414794) (xy 45.919833 -375.421668)
			(xy 45.923443 -375.434931) (xy 45.926756 -375.440956) (xy 45.943104 -375.469303) (xy 45.968819 -375.529478)
			(xy 45.986225 -375.592559) (xy 45.995005 -375.657406) (xy 45.995002 -375.722845) (xy 45.986214 -375.787691)
			(xy 45.968802 -375.850771) (xy 45.94308 -375.910943) (xy 45.926756 -375.939304) (xy 45.923444 -375.94533)
			(xy 45.919836 -375.958593) (xy 45.919644 -375.965466) (xy 45.919644 -376.25147) (xy 45.919211 -376.261642)
			(xy 45.911433 -376.280439) (xy 45.897049 -376.294826) (xy 45.878254 -376.302609) (xy 45.868082 -376.303032)
			(xy 45.151802 -376.303032) (xy 45.141627 -376.302634) (xy 45.122826 -376.294844) (xy 45.10844 -376.28045)
			(xy 45.100661 -376.261645) (xy 45.10024 -376.25147) (xy 45.10024 -375.965466) (xy 45.100056 -375.958592)
			(xy 45.096442 -375.94533) (xy 45.093128 -375.939304) (xy 45.076832 -375.910929) (xy 45.051112 -375.850761)
			(xy 45.033702 -375.787685) (xy 45.024915 -375.722843) (xy 45.024912 -375.657408) (xy 45.033691 -375.592566)
			(xy 45.051095 -375.529488) (xy 45.076808 -375.469317) (xy 45.093128 -375.440956) (xy 45.09646 -375.43494)
			(xy 45.100054 -375.42167) (xy 45.10024 -375.414794) (xy 45.10024 -374.665494) (xy 45.100045 -374.658621)
			(xy 45.096438 -374.645358) (xy 45.093128 -374.639332) (xy 45.076771 -374.61099) (xy 45.051057 -374.550814)
			(xy 45.033653 -374.487732) (xy 45.024874 -374.422884) (xy 41.594979 -374.422884) (xy 41.594979 -374.422887)
			(xy 41.586124 -374.487745) (xy 41.568634 -374.550825) (xy 41.542828 -374.610984) (xy 41.52646 -374.639332)
			(xy 41.523139 -374.645353) (xy 41.519536 -374.65862) (xy 41.519348 -374.665494) (xy 41.519348 -375.414794)
			(xy 41.519536 -375.421668) (xy 41.523146 -375.434931) (xy 41.52646 -375.440956) (xy 41.542804 -375.469317)
			(xy 41.568612 -375.529472) (xy 41.586108 -375.592548) (xy 41.594975 -375.657402) (xy 41.595548 -375.69013)
			(xy 41.594967 -375.722859) (xy 41.586115 -375.787716) (xy 41.568629 -375.850797) (xy 41.542826 -375.910955)
			(xy 41.52646 -375.939304) (xy 41.523149 -375.94533) (xy 41.51954 -375.958593) (xy 41.519348 -375.965466)
			(xy 41.519348 -376.25147) (xy 41.518849 -376.261596) (xy 41.511129 -376.280319) (xy 41.496846 -376.294677)
			(xy 41.478164 -376.302495) (xy 41.46804 -376.303032) (xy 40.75176 -376.303032) (xy 40.741607 -376.302612)
			(xy 40.72286 -376.294809) (xy 40.708539 -376.280413) (xy 40.700835 -376.261625) (xy 40.700452 -376.25147)
			(xy 40.700452 -375.965466) (xy 40.700279 -375.958591) (xy 40.696658 -375.945328) (xy 40.69334 -375.939304)
			(xy 40.67698 -375.910952) (xy 40.651176 -375.850794) (xy 40.633684 -375.787715) (xy 40.624823 -375.722859)
			(xy 40.624252 -375.69013) (xy 39.352087 -375.69013) (xy 39.343146 -375.711045) (xy 39.32682 -375.739406)
			(xy 39.323505 -375.74543) (xy 39.319899 -375.758694) (xy 39.319708 -375.765568) (xy 39.319708 -376.514868)
			(xy 39.319911 -376.52174) (xy 39.323512 -376.535003) (xy 39.32682 -376.54103) (xy 39.343147 -376.569389)
			(xy 39.368866 -376.62956) (xy 39.386276 -376.692639) (xy 39.395059 -376.757485) (xy 39.395059 -376.790204)
			(xy 42.8244 -376.790204) (xy 42.824945 -376.757474) (xy 42.833807 -376.692615) (xy 42.851303 -376.629535)
			(xy 42.877116 -376.569377) (xy 42.893488 -376.54103) (xy 42.896791 -376.535) (xy 42.900404 -376.52174)
			(xy 42.9006 -376.514868) (xy 42.9006 -375.765568) (xy 42.90042 -375.758694) (xy 42.896804 -375.745431)
			(xy 42.893488 -375.739406) (xy 42.877124 -375.711056) (xy 42.851322 -375.650897) (xy 42.833832 -375.587817)
			(xy 42.824971 -375.522961) (xy 42.8244 -375.490232) (xy 42.824958 -375.457502) (xy 42.833816 -375.392644)
			(xy 42.851309 -375.329564) (xy 42.877118 -375.269406) (xy 42.893488 -375.241058) (xy 42.896817 -375.23504)
			(xy 42.900414 -375.221771) (xy 42.9006 -375.214896) (xy 42.9006 -374.928638) (xy 42.901157 -374.918519)
			(xy 42.908865 -374.899806) (xy 42.923129 -374.88545) (xy 42.941792 -374.877622) (xy 42.951908 -374.877076)
			(xy 43.668188 -374.877076) (xy 43.678338 -374.877531) (xy 43.697086 -374.885318) (xy 43.711409 -374.899704)
			(xy 43.719113 -374.918486) (xy 43.719496 -374.928638) (xy 43.719496 -375.214896) (xy 43.71969 -375.221769)
			(xy 43.723297 -375.235032) (xy 43.726608 -375.241058) (xy 43.742958 -375.269416) (xy 43.768763 -375.329572)
			(xy 43.786257 -375.392649) (xy 43.795123 -375.457504) (xy 43.795696 -375.490232) (xy 43.795123 -375.522961)
			(xy 43.786269 -375.587819) (xy 43.768781 -375.650899) (xy 43.742976 -375.711058) (xy 43.726608 -375.739406)
			(xy 43.723292 -375.74543) (xy 43.719687 -375.758694) (xy 43.719496 -375.765568) (xy 43.719496 -376.514868)
			(xy 43.719701 -376.52174) (xy 43.723301 -376.535003) (xy 43.726608 -376.54103) (xy 43.742986 -376.569372)
			(xy 43.768785 -376.629534) (xy 43.786271 -376.692616) (xy 43.795128 -376.757474) (xy 43.795128 -376.757485)
			(xy 47.225041 -376.757485) (xy 47.233825 -376.69264) (xy 47.251234 -376.629562) (xy 47.276953 -376.569391)
			(xy 47.293276 -376.54103) (xy 47.296578 -376.534999) (xy 47.300192 -376.52174) (xy 47.300388 -376.514868)
			(xy 47.300388 -375.765568) (xy 47.30021 -375.758694) (xy 47.296592 -375.745431) (xy 47.293276 -375.739406)
			(xy 47.27698 -375.71103) (xy 47.251258 -375.650863) (xy 47.233845 -375.587787) (xy 47.225058 -375.522945)
			(xy 47.225054 -375.45751) (xy 47.233834 -375.392667) (xy 47.251239 -375.329589) (xy 47.276955 -375.269419)
			(xy 47.293276 -375.241058) (xy 47.296604 -375.23504) (xy 47.300202 -375.221771) (xy 47.300388 -375.214896)
			(xy 47.300388 -374.928892) (xy 47.300815 -374.918739) (xy 47.308611 -374.899989) (xy 47.323006 -374.885666)
			(xy 47.341795 -374.877965) (xy 47.35195 -374.877584) (xy 48.06823 -374.877584) (xy 48.078364 -374.878003)
			(xy 48.097094 -374.885749) (xy 48.111451 -374.900056) (xy 48.119261 -374.91876) (xy 48.119792 -374.928892)
			(xy 48.119792 -375.214896) (xy 48.119986 -375.221769) (xy 48.123593 -375.235032) (xy 48.126904 -375.241058)
			(xy 48.143252 -375.269405) (xy 48.168965 -375.32958) (xy 48.186368 -375.392661) (xy 48.195148 -375.457508)
			(xy 48.195144 -375.522947) (xy 48.186357 -375.587792) (xy 48.168947 -375.650872) (xy 48.143227 -375.711044)
			(xy 48.126904 -375.739406) (xy 48.123587 -375.74543) (xy 48.119983 -375.758694) (xy 48.119792 -375.765568)
			(xy 48.119792 -376.514868) (xy 48.119997 -376.52174) (xy 48.123596 -376.535003) (xy 48.126904 -376.54103)
			(xy 48.143228 -376.56939) (xy 48.168943 -376.629562) (xy 48.186349 -376.692641) (xy 48.195132 -376.757485)
			(xy 48.195131 -376.822922) (xy 48.186348 -376.887766) (xy 48.168941 -376.950845) (xy 48.143225 -377.011016)
			(xy 48.126904 -377.039378) (xy 48.123597 -377.045407) (xy 48.119987 -377.058667) (xy 48.119792 -377.06554)
			(xy 48.119792 -377.351544) (xy 48.119414 -377.361702) (xy 48.111603 -377.380457) (xy 48.097193 -377.394779)
			(xy 48.07839 -377.402476) (xy 48.06823 -377.402852) (xy 47.35195 -377.402852) (xy 47.341825 -377.402332)
			(xy 47.323104 -377.394619) (xy 47.308746 -377.380343) (xy 47.300926 -377.361666) (xy 47.300388 -377.351544)
			(xy 47.300388 -377.06554) (xy 47.300182 -377.058668) (xy 47.296583 -377.045405) (xy 47.293276 -377.039378)
			(xy 47.276956 -377.011015) (xy 47.251236 -376.950845) (xy 47.233826 -376.887766) (xy 47.225042 -376.822922)
			(xy 47.225041 -376.757485) (xy 43.795128 -376.757485) (xy 43.795696 -376.790204) (xy 43.795155 -376.822934)
			(xy 43.786292 -376.887794) (xy 43.768795 -376.950874) (xy 43.74298 -377.011031) (xy 43.726608 -377.039378)
			(xy 43.723302 -377.045407) (xy 43.719691 -377.058667) (xy 43.719496 -377.06554) (xy 43.719496 -377.35129)
			(xy 43.718966 -377.361412) (xy 43.711248 -377.380126) (xy 43.696976 -377.394481) (xy 43.678307 -377.402307)
			(xy 43.668188 -377.402852) (xy 42.951908 -377.402852) (xy 42.941761 -377.402373) (xy 42.923019 -377.39459)
			(xy 42.908697 -377.380211) (xy 42.900988 -377.361439) (xy 42.9006 -377.35129) (xy 42.9006 -377.06554)
			(xy 42.900393 -377.058668) (xy 42.896795 -377.045405) (xy 42.893488 -377.039378) (xy 42.877113 -377.011034)
			(xy 42.851313 -376.950873) (xy 42.833827 -376.887791) (xy 42.824969 -376.822933) (xy 42.8244 -376.790204)
			(xy 39.395059 -376.790204) (xy 39.395059 -376.822922) (xy 39.386274 -376.887767) (xy 39.368864 -376.950846)
			(xy 39.343144 -377.011017) (xy 39.32682 -377.039378) (xy 39.323514 -377.045407) (xy 39.319903 -377.058667)
			(xy 39.319708 -377.06554) (xy 39.319708 -377.35129) (xy 39.31916 -377.361441) (xy 39.311397 -377.380202)
			(xy 39.297049 -377.394566) (xy 39.278297 -377.402349) (xy 39.268146 -377.402852) (xy 38.551866 -377.402852)
			(xy 38.541705 -377.402394) (xy 38.522933 -377.394607) (xy 38.508569 -377.38023) (xy 38.500797 -377.361452)
			(xy 38.500304 -377.35129) (xy 38.500304 -377.06554) (xy 38.500096 -377.058668) (xy 38.496499 -377.045405)
			(xy 38.493192 -377.039378) (xy 38.476875 -377.011014) (xy 38.451159 -376.950843) (xy 38.433752 -376.887765)
			(xy 38.424969 -376.822921) (xy 34.995069 -376.822921) (xy 34.995069 -376.822934) (xy 34.986206 -376.887793)
			(xy 34.968709 -376.950874) (xy 34.942896 -377.011031) (xy 34.926524 -377.039378) (xy 34.923219 -377.045407)
			(xy 34.919607 -377.058667) (xy 34.919412 -377.06554) (xy 34.919412 -377.35129) (xy 34.918867 -377.36141)
			(xy 34.911152 -377.380121) (xy 34.896884 -377.394476) (xy 34.878221 -377.402304) (xy 34.868104 -377.402852)
			(xy 34.151824 -377.402852) (xy 34.141678 -377.40236) (xy 34.122936 -377.394582) (xy 34.108614 -377.380208)
			(xy 34.100904 -377.361438) (xy 34.100516 -377.35129) (xy 34.100516 -377.06554) (xy 34.100307 -377.058668)
			(xy 34.09671 -377.045405) (xy 34.093404 -377.039378) (xy 34.07703 -377.011033) (xy 34.05123 -376.950872)
			(xy 34.033743 -376.887791) (xy 34.024885 -376.822933) (xy 34.024316 -376.790204) (xy 30.594973 -376.790204)
			(xy 30.594973 -376.822922) (xy 30.586188 -376.887767) (xy 30.568779 -376.950846) (xy 30.543059 -377.011017)
			(xy 30.526736 -377.039378) (xy 30.523432 -377.045408) (xy 30.519819 -377.058668) (xy 30.519624 -377.06554)
			(xy 30.519624 -377.35129) (xy 30.519227 -377.361466) (xy 30.511438 -377.380267) (xy 30.497044 -377.394654)
			(xy 30.478238 -377.402433) (xy 30.468062 -377.402852) (xy 29.751782 -377.402852) (xy 29.741622 -377.402381)
			(xy 29.72285 -377.394599) (xy 29.708485 -377.380226) (xy 29.700713 -377.36145) (xy 29.70022 -377.35129)
			(xy 29.70022 -377.06554) (xy 29.70001 -377.058668) (xy 29.696414 -377.045405) (xy 29.693108 -377.039378)
			(xy 29.67679 -377.011015) (xy 29.651074 -376.950844) (xy 29.633666 -376.887765) (xy 29.624883 -376.822921)
			(xy 12.289585 -376.822921) (xy 9.52246 -379.590046) (xy 27.42438 -379.590046) (xy 27.424946 -379.557317)
			(xy 27.433802 -379.492458) (xy 27.451292 -379.429378) (xy 27.477099 -379.36922) (xy 27.493468 -379.340872)
			(xy 27.49679 -379.334851) (xy 27.500391 -379.321584) (xy 27.50058 -379.31471) (xy 27.50058 -378.56541)
			(xy 27.500387 -378.558537) (xy 27.496779 -378.545274) (xy 27.493468 -378.539248) (xy 27.477088 -378.510906)
			(xy 27.451288 -378.450745) (xy 27.433802 -378.387663) (xy 27.424947 -378.322804) (xy 27.42438 -378.290074)
			(xy 27.424959 -378.257345) (xy 27.433812 -378.192487) (xy 27.451298 -378.129407) (xy 27.477102 -378.069249)
			(xy 27.493468 -378.0409) (xy 27.49678 -378.034874) (xy 27.500388 -378.021611) (xy 27.50058 -378.014738)
			(xy 27.50058 -377.728734) (xy 27.501056 -377.718605) (xy 27.50878 -377.699877) (xy 27.52307 -377.685518)
			(xy 27.541761 -377.677705) (xy 27.551888 -377.677172) (xy 28.268168 -377.677172) (xy 28.278317 -377.677647)
			(xy 28.297063 -377.685427) (xy 28.311387 -377.699807) (xy 28.319092 -377.718584) (xy 28.319476 -377.728734)
			(xy 28.319476 -378.014738) (xy 28.319695 -378.021609) (xy 28.323285 -378.034872) (xy 28.326588 -378.0409)
			(xy 28.342952 -378.06925) (xy 28.368755 -378.129409) (xy 28.386245 -378.192488) (xy 28.395106 -378.257345)
			(xy 28.395676 -378.290074) (xy 28.395124 -378.322797) (xy 31.825007 -378.322797) (xy 31.82501 -378.257358)
			(xy 31.833797 -378.192512) (xy 31.85121 -378.129433) (xy 31.876931 -378.069261) (xy 31.893256 -378.0409)
			(xy 31.896567 -378.034874) (xy 31.900176 -378.021611) (xy 31.900368 -378.014738) (xy 31.900368 -377.728734)
			(xy 31.900793 -377.718561) (xy 31.908572 -377.699761) (xy 31.922958 -377.685374) (xy 31.941757 -377.677593)
			(xy 31.95193 -377.677172) (xy 32.66821 -377.677172) (xy 32.678386 -377.677557) (xy 32.697188 -377.685351)
			(xy 32.711574 -377.699749) (xy 32.719352 -377.718557) (xy 32.719772 -377.728734) (xy 32.719772 -378.014738)
			(xy 32.719991 -378.021609) (xy 32.723581 -378.034872) (xy 32.726884 -378.0409) (xy 32.743183 -378.069274)
			(xy 32.768902 -378.129442) (xy 32.786312 -378.192518) (xy 32.795097 -378.25736) (xy 32.7951 -378.322795)
			(xy 32.786321 -378.387638) (xy 32.768917 -378.450716) (xy 32.743204 -378.510887) (xy 32.726884 -378.539248)
			(xy 32.723551 -378.545264) (xy 32.719957 -378.558534) (xy 32.719772 -378.56541) (xy 32.719772 -379.31471)
			(xy 32.719964 -379.321583) (xy 32.723572 -379.334846) (xy 32.726884 -379.340872) (xy 32.743244 -379.369212)
			(xy 32.768957 -379.429388) (xy 32.78636 -379.492471) (xy 32.795138 -379.55732) (xy 32.795133 -379.622759)
			(xy 32.786344 -379.687606) (xy 32.768931 -379.750686) (xy 32.743209 -379.810858) (xy 32.726884 -379.83922)
			(xy 32.723561 -379.845241) (xy 32.719961 -379.858507) (xy 32.719772 -379.865382) (xy 32.719772 -380.151386)
			(xy 32.719325 -380.161556) (xy 32.711547 -380.180348) (xy 32.697168 -380.194733) (xy 32.678379 -380.20252)
			(xy 32.66821 -380.202948) (xy 31.95193 -380.202948) (xy 31.941759 -380.202511) (xy 31.922962 -380.194733)
			(xy 31.908576 -380.180351) (xy 31.900792 -380.161557) (xy 31.900368 -380.151386) (xy 31.900368 -379.865382)
			(xy 31.900187 -379.858508) (xy 31.896572 -379.845245) (xy 31.893256 -379.83922) (xy 31.876972 -379.810837)
			(xy 31.85125 -379.750671) (xy 31.833837 -379.687597) (xy 31.825048 -379.622756) (xy 31.825043 -379.557323)
			(xy 31.833821 -379.49248) (xy 31.851224 -379.429403) (xy 31.876936 -379.369233) (xy 31.893256 -379.340872)
			(xy 31.896577 -379.33485) (xy 31.900179 -379.321584) (xy 31.900368 -379.31471) (xy 31.900368 -378.56541)
			(xy 31.900176 -378.558537) (xy 31.896568 -378.545274) (xy 31.893256 -378.539248) (xy 31.876911 -378.510899)
			(xy 31.851195 -378.450725) (xy 31.833788 -378.387644) (xy 31.825007 -378.322797) (xy 28.395124 -378.322797)
			(xy 28.395124 -378.322804) (xy 28.386265 -378.387663) (xy 28.36877 -378.450743) (xy 28.342959 -378.510901)
			(xy 28.326588 -378.539248) (xy 28.323255 -378.545264) (xy 28.319661 -378.558534) (xy 28.319476 -378.56541)
			(xy 28.319476 -379.31471) (xy 28.319667 -379.321583) (xy 28.323276 -379.334846) (xy 28.326588 -379.340872)
			(xy 28.342941 -379.369228) (xy 28.368746 -379.429385) (xy 28.386239 -379.492462) (xy 28.395104 -379.557318)
			(xy 28.395676 -379.590046) (xy 28.395112 -379.622776) (xy 28.386256 -379.687634) (xy 28.368765 -379.750714)
			(xy 28.342957 -379.810872) (xy 28.326588 -379.83922) (xy 28.323265 -379.845241) (xy 28.319665 -379.858508)
			(xy 28.319476 -379.865382) (xy 28.319476 -380.151386) (xy 28.318962 -380.16151) (xy 28.311242 -380.180228)
			(xy 28.296964 -380.194584) (xy 28.278289 -380.202406) (xy 28.268168 -380.202948) (xy 27.551888 -380.202948)
			(xy 27.541739 -380.202489) (xy 27.522996 -380.194699) (xy 27.508674 -380.180314) (xy 27.500966 -380.161537)
			(xy 27.50058 -380.151386) (xy 27.50058 -379.865382) (xy 27.500398 -379.858508) (xy 27.496783 -379.845245)
			(xy 27.493468 -379.83922) (xy 27.477117 -379.810863) (xy 27.45131 -379.750707) (xy 27.433816 -379.687629)
			(xy 27.424952 -379.622774) (xy 27.42438 -379.590046) (xy 9.52246 -379.590046) (xy 8.455106 -380.6574)
			(xy 29.62489 -380.6574) (xy 29.63367 -380.592557) (xy 29.651075 -380.529479) (xy 29.676788 -380.469308)
			(xy 29.693108 -380.440946) (xy 29.696407 -380.434914) (xy 29.700022 -380.421656) (xy 29.70022 -380.414784)
			(xy 29.70022 -379.665484) (xy 29.700032 -379.658611) (xy 29.696421 -379.645348) (xy 29.693108 -379.639322)
			(xy 29.676827 -379.610938) (xy 29.651108 -379.550772) (xy 29.633696 -379.487698) (xy 29.624908 -379.422858)
			(xy 29.624903 -379.357425) (xy 29.63368 -379.292583) (xy 29.65108 -379.229506) (xy 29.67679 -379.169336)
			(xy 29.693108 -379.140974) (xy 29.696433 -379.134954) (xy 29.700032 -379.121687) (xy 29.70022 -379.114812)
			(xy 29.70022 -378.828554) (xy 29.700695 -378.818396) (xy 29.708482 -378.799629) (xy 29.722852 -378.785266)
			(xy 29.741623 -378.77749) (xy 29.751782 -378.776992) (xy 30.468062 -378.776992) (xy 30.478212 -378.777564)
			(xy 30.496971 -378.785317) (xy 30.511336 -378.799658) (xy 30.51912 -378.818405) (xy 30.519624 -378.828554)
			(xy 30.519624 -379.114812) (xy 30.519809 -379.121686) (xy 30.523422 -379.134949) (xy 30.526736 -379.140974)
			(xy 30.5431 -379.169313) (xy 30.568815 -379.229489) (xy 30.586219 -379.292572) (xy 30.594998 -379.357421)
			(xy 30.594993 -379.422861) (xy 30.586203 -379.487709) (xy 30.568788 -379.550789) (xy 30.543062 -379.610961)
			(xy 30.526736 -379.639322) (xy 30.523416 -379.645344) (xy 30.519814 -379.65861) (xy 30.519624 -379.665484)
			(xy 30.519624 -380.414784) (xy 30.519819 -380.421657) (xy 30.523425 -380.43492) (xy 30.526736 -380.440946)
			(xy 30.543076 -380.469298) (xy 30.568793 -380.529471) (xy 30.5862 -380.592551) (xy 30.594982 -380.657398)
			(xy 30.594981 -380.69012) (xy 34.024316 -380.69012) (xy 34.024866 -380.65739) (xy 34.033726 -380.592531)
			(xy 34.051221 -380.529451) (xy 34.077033 -380.469293) (xy 34.093404 -380.440946) (xy 34.096703 -380.434914)
			(xy 34.100318 -380.421656) (xy 34.100516 -380.414784) (xy 34.100516 -379.665484) (xy 34.100328 -379.65861)
			(xy 34.096717 -379.645348) (xy 34.093404 -379.639322) (xy 34.077048 -379.610968) (xy 34.051243 -379.55081)
			(xy 34.033751 -379.487732) (xy 34.024888 -379.422877) (xy 34.024316 -379.390148) (xy 34.024879 -379.357418)
			(xy 34.033735 -379.29256) (xy 34.051226 -379.22948) (xy 34.077035 -379.169322) (xy 34.093404 -379.140974)
			(xy 34.096728 -379.134954) (xy 34.100328 -379.121687) (xy 34.100516 -379.114812) (xy 34.100516 -378.828554)
			(xy 34.100988 -378.818427) (xy 34.108727 -378.79971) (xy 34.123017 -378.785356) (xy 34.1417 -378.777534)
			(xy 34.151824 -378.776992) (xy 34.868104 -378.776992) (xy 34.878257 -378.777418) (xy 34.897008 -378.785214)
			(xy 34.911331 -378.799609) (xy 34.919032 -378.818399) (xy 34.919412 -378.828554) (xy 34.919412 -379.114812)
			(xy 34.919598 -379.121686) (xy 34.92321 -379.134949) (xy 34.926524 -379.140974) (xy 34.942882 -379.169328)
			(xy 34.968685 -379.229486) (xy 34.986177 -379.292564) (xy 34.99504 -379.357419) (xy 34.995612 -379.390148)
			(xy 34.995044 -379.422877) (xy 34.986188 -379.487735) (xy 34.968699 -379.550816) (xy 34.95187 -379.590046)
			(xy 36.224464 -379.590046) (xy 36.225033 -379.557317) (xy 36.233888 -379.492459) (xy 36.251378 -379.429379)
			(xy 36.277184 -379.36922) (xy 36.293552 -379.340872) (xy 36.296873 -379.33485) (xy 36.300475 -379.321584)
			(xy 36.300664 -379.31471) (xy 36.300664 -378.56541) (xy 36.300473 -378.558537) (xy 36.296864 -378.545274)
			(xy 36.293552 -378.539248) (xy 36.277171 -378.510907) (xy 36.251371 -378.450745) (xy 36.233886 -378.387663)
			(xy 36.225031 -378.322804) (xy 36.224464 -378.290074) (xy 36.225045 -378.257345) (xy 36.233897 -378.192488)
			(xy 36.251383 -378.129407) (xy 36.277186 -378.069249) (xy 36.293552 -378.0409) (xy 36.296863 -378.034873)
			(xy 36.300472 -378.021611) (xy 36.300664 -378.014738) (xy 36.300664 -377.728734) (xy 36.301155 -377.718607)
			(xy 36.308876 -377.699882) (xy 36.323162 -377.685523) (xy 36.341847 -377.677707) (xy 36.351972 -377.677172)
			(xy 37.068252 -377.677172) (xy 37.0784 -377.67766) (xy 37.097145 -377.685435) (xy 37.11147 -377.699811)
			(xy 37.119176 -377.718585) (xy 37.11956 -377.728734) (xy 37.11956 -378.014738) (xy 37.119781 -378.021609)
			(xy 37.12337 -378.034872) (xy 37.126672 -378.0409) (xy 37.143035 -378.069251) (xy 37.168838 -378.12941)
			(xy 37.186329 -378.192489) (xy 37.195189 -378.257345) (xy 37.19576 -378.290074) (xy 37.195197 -378.322804)
			(xy 37.186339 -378.387662) (xy 37.168848 -378.450742) (xy 37.14304 -378.5109) (xy 37.126672 -378.539248)
			(xy 37.123338 -378.545263) (xy 37.119745 -378.558534) (xy 37.11956 -378.56541) (xy 37.11956 -379.31471)
			(xy 37.119753 -379.321583) (xy 37.123361 -379.334846) (xy 37.126672 -379.340872) (xy 37.143024 -379.369229)
			(xy 37.16883 -379.429385) (xy 37.186323 -379.492463) (xy 37.195188 -379.557318) (xy 37.19576 -379.590046)
			(xy 37.195184 -379.622775) (xy 37.18633 -379.687633) (xy 37.168843 -379.750713) (xy 37.143039 -379.810871)
			(xy 37.126672 -379.83922) (xy 37.123348 -379.84524) (xy 37.119749 -379.858507) (xy 37.11956 -379.865382)
			(xy 37.11956 -380.151386) (xy 37.119062 -380.161512) (xy 37.111339 -380.180233) (xy 37.097056 -380.194589)
			(xy 37.078375 -380.202409) (xy 37.068252 -380.202948) (xy 36.351972 -380.202948) (xy 36.341822 -380.202502)
			(xy 36.323078 -380.194707) (xy 36.308758 -380.180318) (xy 36.30105 -380.161538) (xy 36.300664 -380.151386)
			(xy 36.300664 -379.865382) (xy 36.300483 -379.858508) (xy 36.296868 -379.845245) (xy 36.293552 -379.83922)
			(xy 36.277199 -379.810864) (xy 36.251393 -379.750707) (xy 36.2339 -379.68763) (xy 36.225036 -379.622774)
			(xy 36.224464 -379.590046) (xy 34.95187 -379.590046) (xy 34.942892 -379.610974) (xy 34.926524 -379.639322)
			(xy 34.923203 -379.645344) (xy 34.919601 -379.65861) (xy 34.919412 -379.665484) (xy 34.919412 -380.414784)
			(xy 34.919609 -380.421657) (xy 34.923214 -380.43492) (xy 34.926524 -380.440946) (xy 34.94291 -380.469284)
			(xy 34.968707 -380.529448) (xy 34.98619 -380.592531) (xy 34.995045 -380.65739) (xy 34.995045 -380.6574)
			(xy 38.424976 -380.6574) (xy 38.433756 -380.592557) (xy 38.45116 -380.529479) (xy 38.476873 -380.469308)
			(xy 38.493192 -380.440946) (xy 38.49649 -380.434913) (xy 38.500106 -380.421656) (xy 38.500304 -380.414784)
			(xy 38.500304 -379.665484) (xy 38.500118 -379.65861) (xy 38.496506 -379.645348) (xy 38.493192 -379.639322)
			(xy 38.476912 -379.610938) (xy 38.451193 -379.550771) (xy 38.433782 -379.487698) (xy 38.424994 -379.422858)
			(xy 38.424989 -379.357425) (xy 38.433766 -379.292583) (xy 38.451166 -379.229506) (xy 38.476874 -379.169336)
			(xy 38.493192 -379.140974) (xy 38.496515 -379.134954) (xy 38.500116 -379.121687) (xy 38.500304 -379.114812)
			(xy 38.500304 -378.828554) (xy 38.500795 -378.818397) (xy 38.508578 -378.799634) (xy 38.522944 -378.785271)
			(xy 38.541709 -378.777493) (xy 38.551866 -378.776992) (xy 39.268146 -378.776992) (xy 39.278301 -378.777495)
			(xy 39.297062 -378.785276) (xy 39.311424 -378.799638) (xy 39.319205 -378.818399) (xy 39.319708 -378.828554)
			(xy 39.319708 -379.114812) (xy 39.319894 -379.121686) (xy 39.323506 -379.134949) (xy 39.32682 -379.140974)
			(xy 39.343184 -379.169312) (xy 39.3689 -379.229488) (xy 39.386305 -379.292572) (xy 39.395085 -379.357421)
			(xy 39.395079 -379.422861) (xy 39.386289 -379.487709) (xy 39.368873 -379.550789) (xy 39.352089 -379.590046)
			(xy 40.624252 -379.590046) (xy 40.624822 -379.557317) (xy 40.633678 -379.492459) (xy 40.651167 -379.429379)
			(xy 40.676972 -379.36922) (xy 40.69334 -379.340872) (xy 40.69666 -379.33485) (xy 40.700263 -379.321584)
			(xy 40.700452 -379.31471) (xy 40.700452 -378.56541) (xy 40.700262 -378.558537) (xy 40.696653 -378.545274)
			(xy 40.69334 -378.539248) (xy 40.676958 -378.510908) (xy 40.651159 -378.450745) (xy 40.633674 -378.387663)
			(xy 40.624819 -378.322804) (xy 40.624252 -378.290074) (xy 40.624835 -378.257345) (xy 40.633686 -378.192488)
			(xy 40.651172 -378.129408) (xy 40.676974 -378.069249) (xy 40.69334 -378.0409) (xy 40.69665 -378.034873)
			(xy 40.700259 -378.021611) (xy 40.700452 -378.014738) (xy 40.700452 -377.728734) (xy 40.700955 -377.718608)
			(xy 40.708674 -377.699885) (xy 40.722955 -377.685528) (xy 40.741637 -377.677709) (xy 40.75176 -377.677172)
			(xy 41.46804 -377.677172) (xy 41.478193 -377.677588) (xy 41.496941 -377.685392) (xy 41.511262 -377.699789)
			(xy 41.518965 -377.718579) (xy 41.519348 -377.728734) (xy 41.519348 -378.014738) (xy 41.519558 -378.02161)
			(xy 41.523153 -378.034873) (xy 41.52646 -378.0409) (xy 41.542822 -378.069251) (xy 41.568625 -378.12941)
			(xy 41.586116 -378.192489) (xy 41.594977 -378.257345) (xy 41.595548 -378.290074) (xy 41.594987 -378.322804)
			(xy 41.586129 -378.387662) (xy 41.568637 -378.450742) (xy 41.542829 -378.5109) (xy 41.52646 -378.539248)
			(xy 41.523133 -378.545267) (xy 41.519534 -378.558535) (xy 41.519348 -378.56541) (xy 41.519348 -379.31471)
			(xy 41.51953 -379.321584) (xy 41.523144 -379.334847) (xy 41.52646 -379.340872) (xy 41.542811 -379.36923)
			(xy 41.568617 -379.429386) (xy 41.586111 -379.492463) (xy 41.594976 -379.557318) (xy 41.595548 -379.590046)
			(xy 41.594974 -379.622775) (xy 41.58612 -379.687633) (xy 41.568632 -379.750713) (xy 41.542827 -379.810872)
			(xy 41.52646 -379.83922) (xy 41.523143 -379.845244) (xy 41.519538 -379.858508) (xy 41.519348 -379.865382)
			(xy 41.519348 -380.151386) (xy 41.518862 -380.161513) (xy 41.511136 -380.180236) (xy 41.49685 -380.194594)
			(xy 41.478165 -380.202411) (xy 41.46804 -380.202948) (xy 40.75176 -380.202948) (xy 40.741609 -380.202512)
			(xy 40.722865 -380.194712) (xy 40.708545 -380.180321) (xy 40.700838 -380.161539) (xy 40.700452 -380.151386)
			(xy 40.700452 -379.865382) (xy 40.700273 -379.858508) (xy 40.696656 -379.845245) (xy 40.69334 -379.83922)
			(xy 40.676986 -379.810864) (xy 40.651181 -379.750707) (xy 40.633687 -379.68763) (xy 40.624824 -379.622774)
			(xy 40.624252 -379.590046) (xy 39.352089 -379.590046) (xy 39.343147 -379.610961) (xy 39.32682 -379.639322)
			(xy 39.323499 -379.645344) (xy 39.319897 -379.65861) (xy 39.319708 -379.665484) (xy 39.319708 -380.414784)
			(xy 39.319905 -380.421657) (xy 39.32351 -380.43492) (xy 39.32682 -380.440946) (xy 39.34316 -380.469297)
			(xy 39.368879 -380.52947) (xy 39.386286 -380.592551) (xy 39.395069 -380.657398) (xy 39.395067 -380.69012)
			(xy 42.8244 -380.69012) (xy 42.824953 -380.65739) (xy 42.833812 -380.592531) (xy 42.851306 -380.529451)
			(xy 42.877118 -380.469294) (xy 42.893488 -380.440946) (xy 42.896786 -380.434913) (xy 42.900402 -380.421656)
			(xy 42.9006 -380.414784) (xy 42.9006 -379.665484) (xy 42.900414 -379.65861) (xy 42.896802 -379.645347)
			(xy 42.893488 -379.639322) (xy 42.87713 -379.610969) (xy 42.851327 -379.55081) (xy 42.833835 -379.487732)
			(xy 42.824972 -379.422877) (xy 42.8244 -379.390148) (xy 42.824965 -379.357418) (xy 42.833821 -379.29256)
			(xy 42.851312 -379.22948) (xy 42.877119 -379.169322) (xy 42.893488 -379.140974) (xy 42.896811 -379.134953)
			(xy 42.900412 -379.121687) (xy 42.9006 -379.114812) (xy 42.9006 -378.828554) (xy 42.901088 -378.818429)
			(xy 42.908823 -378.799715) (xy 42.923108 -378.785361) (xy 42.941786 -378.777537) (xy 42.951908 -378.776992)
			(xy 43.668188 -378.776992) (xy 43.67834 -378.777431) (xy 43.697091 -378.785221) (xy 43.711414 -378.799613)
			(xy 43.719116 -378.8184) (xy 43.719496 -378.828554) (xy 43.719496 -379.114812) (xy 43.719684 -379.121686)
			(xy 43.723295 -379.134948) (xy 43.726608 -379.140974) (xy 43.742964 -379.169329) (xy 43.768768 -379.229486)
			(xy 43.78626 -379.292564) (xy 43.795124 -379.357419) (xy 43.795696 -379.390148) (xy 43.79513 -379.422878)
			(xy 43.786274 -379.487736) (xy 43.768784 -379.550816) (xy 43.751954 -379.590046) (xy 44.923964 -379.590046)
			(xy 44.924391 -379.556959) (xy 44.931855 -379.491207) (xy 44.946682 -379.426715) (xy 44.968682 -379.364304)
			(xy 44.997575 -379.304771) (xy 45.032994 -379.248873) (xy 45.074486 -379.197323) (xy 45.121524 -379.150777)
			(xy 45.173508 -379.10983) (xy 45.229776 -379.075001) (xy 45.259498 -379.060456) (xy 45.259752 -379.060202)
			(xy 45.270391 -379.054387) (xy 45.285106 -379.035159) (xy 45.287946 -379.023372) (xy 45.30217 -378.94133)
			(xy 45.30359 -378.929223) (xy 45.296285 -378.906004) (xy 45.2882 -378.89688) (xy 45.095668 -378.704348)
			(xy 45.072765 -378.680756) (xy 45.031768 -378.629348) (xy 44.996779 -378.573677) (xy 44.968237 -378.514442)
			(xy 44.9465 -378.452385) (xy 44.931841 -378.388286) (xy 44.924445 -378.32295) (xy 44.923964 -378.290074)
			(xy 44.924411 -378.254658) (xy 44.932952 -378.184342) (xy 44.949907 -378.115569) (xy 44.975028 -378.04934)
			(xy 45.007948 -377.986623) (xy 45.048189 -377.928331) (xy 45.095163 -377.875315) (xy 45.148185 -377.828347)
			(xy 45.206481 -377.788113) (xy 45.269202 -377.7552) (xy 45.335434 -377.730086) (xy 45.404209 -377.71314)
			(xy 45.474526 -377.704607) (xy 45.509942 -377.704096) (xy 45.542822 -377.704575) (xy 45.608168 -377.711936)
			(xy 45.672279 -377.726571) (xy 45.734346 -377.748297) (xy 45.793589 -377.776839) (xy 45.849261 -377.811839)
			(xy 45.900661 -377.852856) (xy 45.924216 -377.8758) (xy 47.092362 -379.0442) (xy 47.100422 -379.051549)
			(xy 47.120828 -379.05919) (xy 47.131732 -379.058932) (xy 47.219108 -379.05309) (xy 47.238412 -379.04293)
			(xy 47.245016 -379.03404) (xy 47.265796 -379.007643) (xy 47.312484 -378.959331) (xy 47.364391 -378.916678)
			(xy 47.420837 -378.880242) (xy 47.48108 -378.850502) (xy 47.544329 -378.827848) (xy 47.609755 -378.812577)
			(xy 47.676498 -378.804891) (xy 47.71009 -378.804424) (xy 47.710344 -378.804424) (xy 47.743198 -378.804866)
			(xy 47.808492 -378.812234) (xy 47.872552 -378.826861) (xy 47.934572 -378.848563) (xy 47.993776 -378.877068)
			(xy 48.049418 -378.912019) (xy 48.1008 -378.952975) (xy 48.124364 -378.975874) (xy 48.39081 -379.242574)
			(xy 48.398216 -379.249407) (xy 48.41681 -379.257132) (xy 48.426878 -379.25756) (xy 54.930294 -379.25756)
			(xy 54.940199 -379.257077) (xy 54.958499 -379.249482) (xy 54.965854 -379.242828) (xy 54.989394 -379.220284)
			(xy 55.04059 -379.179941) (xy 55.09595 -379.145535) (xy 55.15479 -379.117493) (xy 55.216382 -379.096161)
			(xy 55.279962 -379.081804) (xy 55.344743 -379.0746) (xy 55.377334 -379.074172) (xy 55.412736 -379.074724)
			(xy 55.483023 -379.083259) (xy 55.55177 -379.100202) (xy 55.617975 -379.125304) (xy 55.680672 -379.158201)
			(xy 55.738949 -379.198412) (xy 55.791956 -379.245353) (xy 55.838921 -379.298338) (xy 55.87916 -379.356597)
			(xy 55.912085 -379.419279) (xy 55.937218 -379.485472) (xy 55.954192 -379.554211) (xy 55.96276 -379.624494)
			(xy 55.963312 -379.659896) (xy 55.962678 -379.697314) (xy 55.953072 -379.771533) (xy 55.934104 -379.843927)
			(xy 55.92064 -379.878844) (xy 55.92064 -379.879098) (xy 55.916614 -379.890836) (xy 55.919283 -379.915478)
			(xy 55.92572 -379.926088) (xy 55.972964 -379.996192) (xy 55.980476 -380.006134) (xy 56.002434 -380.017852)
			(xy 56.014874 -380.018544) (xy 56.602122 -380.018544) (xy 56.636205 -380.019104) (xy 56.70391 -380.02702)
			(xy 56.770238 -380.042743) (xy 56.834292 -380.066059) (xy 56.895207 -380.096653) (xy 56.952158 -380.134112)
			(xy 57.004375 -380.17793) (xy 57.051153 -380.227513) (xy 57.091858 -380.282191) (xy 57.12594 -380.341225)
			(xy 57.152939 -380.403816) (xy 57.172488 -380.469119) (xy 57.184325 -380.536249) (xy 57.188289 -380.6043)
			(xy 57.184325 -380.672351) (xy 57.172488 -380.739481) (xy 57.152939 -380.804784) (xy 57.12594 -380.867375)
			(xy 57.091858 -380.926409) (xy 57.051153 -380.981087) (xy 57.004375 -381.03067) (xy 56.952158 -381.074488)
			(xy 56.895207 -381.111947) (xy 56.834292 -381.142541) (xy 56.770238 -381.165857) (xy 56.70391 -381.18158)
			(xy 56.636205 -381.189496) (xy 56.602122 -381.189992) (xy 48.029368 -381.189992) (xy 48.022708 -381.190243)
			(xy 48.009846 -381.19371) (xy 48.003968 -381.19685) (xy 47.970353 -381.215619) (xy 47.899261 -381.245169)
			(xy 47.824911 -381.265157) (xy 47.748585 -381.275236) (xy 47.71009 -381.275844) (xy 47.709836 -381.275844)
			(xy 47.678355 -381.27542) (xy 47.61576 -381.26864) (xy 47.55425 -381.255196) (xy 47.494533 -381.235244)
			(xy 47.465742 -381.222504) (xy 47.453804 -381.21717) (xy 47.428404 -381.218948) (xy 47.345092 -381.272288)
			(xy 47.338122 -381.277137) (xy 47.327598 -381.290446) (xy 47.322037 -381.306476) (xy 47.321724 -381.31496)
			(xy 47.321724 -382.626616) (xy 47.322107 -382.636641) (xy 47.329787 -382.655163) (xy 47.343971 -382.669336)
			(xy 47.362498 -382.677001) (xy 47.372524 -382.677416) (xy 48.06823 -382.677416) (xy 48.078356 -382.677901)
			(xy 48.097073 -382.685634) (xy 48.111427 -382.699921) (xy 48.11925 -382.718601) (xy 48.119792 -382.728724)
			(xy 48.119792 -383.014728) (xy 48.119974 -383.021602) (xy 48.123589 -383.034865) (xy 48.126904 -383.04089)
			(xy 48.143194 -383.069269) (xy 48.168913 -383.129436) (xy 48.186322 -383.192511) (xy 48.195109 -383.257352)
			(xy 48.195113 -383.322786) (xy 48.186335 -383.387628) (xy 48.168933 -383.450705) (xy 48.143222 -383.510876)
			(xy 48.126904 -383.539238) (xy 48.123576 -383.545256) (xy 48.119979 -383.558525) (xy 48.119792 -383.5654)
			(xy 48.119792 -384.3147) (xy 48.119985 -384.321573) (xy 48.123592 -384.334836) (xy 48.126904 -384.340862)
			(xy 48.143255 -384.369207) (xy 48.168968 -384.429382) (xy 48.186371 -384.492464) (xy 48.19515 -384.557312)
			(xy 48.195146 -384.62275) (xy 48.186359 -384.687596) (xy 48.168947 -384.750676) (xy 48.143227 -384.810848)
			(xy 48.126904 -384.83921) (xy 48.123586 -384.845233) (xy 48.119982 -384.858498) (xy 48.119792 -384.865372)
			(xy 48.119792 -385.151376) (xy 48.119359 -385.16153) (xy 48.11157 -385.180283) (xy 48.097176 -385.194608)
			(xy 48.078386 -385.202307) (xy 48.06823 -385.202684) (xy 47.372524 -385.202684) (xy 47.362506 -385.203139)
			(xy 47.343993 -385.210798) (xy 47.329821 -385.224959) (xy 47.322147 -385.243467) (xy 47.321724 -385.253484)
			(xy 47.321724 -385.730242) (xy 47.322121 -385.740315) (xy 47.329861 -385.758913) (xy 47.33671 -385.76631)
			(xy 47.66945 -386.09905) (xy 47.676879 -386.105854) (xy 47.695456 -386.113596) (xy 47.705518 -386.114036)
			(xy 48.842422 -386.114036) (xy 48.852495 -386.113639) (xy 48.871093 -386.1059) (xy 48.87849 -386.09905)
			(xy 52.601368 -382.375918) (xy 52.624903 -382.352989) (xy 52.676286 -382.312027) (xy 52.731931 -382.277077)
			(xy 52.79114 -382.248575) (xy 52.853167 -382.226883) (xy 52.917233 -382.212271) (xy 52.982532 -382.204923)
			(xy 53.015388 -382.204468) (xy 55.588154 -382.204468) (xy 55.598222 -382.204027) (xy 55.61682 -382.196318)
			(xy 55.624222 -382.189482) (xy 56.025796 -381.787654) (xy 56.049371 -381.764766) (xy 56.100745 -381.7238)
			(xy 56.156383 -381.688844) (xy 56.215585 -381.660337) (xy 56.277606 -381.638638) (xy 56.341667 -381.624018)
			(xy 56.406962 -381.616663) (xy 56.439816 -381.616204) (xy 56.592978 -381.616204) (xy 56.603049 -381.615793)
			(xy 56.621649 -381.608065) (xy 56.629046 -381.601218) (xy 57.024016 -381.205994) (xy 57.047571 -381.183086)
			(xy 57.09895 -381.142123) (xy 57.154592 -381.107171) (xy 57.213797 -381.078667) (xy 57.275821 -381.056971)
			(xy 57.339885 -381.042354) (xy 57.405181 -381.035002) (xy 57.438036 -381.034544) (xy 57.43829 -381.034544)
			(xy 57.473694 -381.035065) (xy 57.543985 -381.043597) (xy 57.612736 -381.060537) (xy 57.678945 -381.085639)
			(xy 57.741646 -381.118536) (xy 57.799926 -381.15875) (xy 57.852935 -381.205694) (xy 57.899901 -381.258683)
			(xy 57.940138 -381.316947) (xy 57.973062 -381.379634) (xy 57.998191 -381.445833) (xy 58.015159 -381.514577)
			(xy 58.02372 -381.584865) (xy 58.024268 -381.620268) (xy 58.024268 -381.622554) (xy 58.024617 -381.632602)
			(xy 58.032219 -381.651198) (xy 58.039 -381.658622) (xy 58.076084 -381.696214) (xy 58.092848 -381.69596)
			(xy 58.612532 -381.69596) (xy 58.646616 -381.696489) (xy 58.714321 -381.704406) (xy 58.78065 -381.72013)
			(xy 58.844706 -381.743447) (xy 58.905621 -381.774043) (xy 58.962572 -381.811503) (xy 59.01479 -381.855322)
			(xy 59.061568 -381.904906) (xy 59.102273 -381.959585) (xy 59.136356 -382.01862) (xy 59.163354 -382.081213)
			(xy 59.182904 -382.146517) (xy 59.194741 -382.213648) (xy 59.198705 -382.2817) (xy 59.194741 -382.349752)
			(xy 59.182904 -382.416883) (xy 59.163354 -382.482187) (xy 59.136356 -382.54478) (xy 59.102273 -382.603815)
			(xy 59.061568 -382.658494) (xy 59.01479 -382.708078) (xy 58.962572 -382.751897) (xy 58.905621 -382.789357)
			(xy 58.844706 -382.819953) (xy 58.78065 -382.84327) (xy 58.714321 -382.858994) (xy 58.646616 -382.866911)
			(xy 58.612532 -382.867408) (xy 58.357516 -382.867408) (xy 58.347447 -382.86784) (xy 58.328849 -382.875556)
			(xy 58.321448 -382.882394) (xy 57.481978 -383.722118) (xy 57.458421 -383.745026) (xy 57.407045 -383.785993)
			(xy 57.351404 -383.82095) (xy 57.292199 -383.849457) (xy 57.230175 -383.871156) (xy 57.166111 -383.885774)
			(xy 57.100813 -383.893127) (xy 57.067958 -383.893568) (xy 53.429408 -383.893568) (xy 53.419337 -383.89398)
			(xy 53.400738 -383.901708) (xy 53.39334 -383.908554) (xy 49.690274 -387.611874) (xy 49.666718 -387.634781)
			(xy 49.61534 -387.675745) (xy 49.559698 -387.710698) (xy 49.500493 -387.739202) (xy 49.438469 -387.760899)
			(xy 49.374406 -387.775515) (xy 49.309109 -387.782866) (xy 49.276254 -387.783324) (xy 47.116746 -387.783324)
			(xy 47.083892 -387.782874) (xy 47.018599 -387.775506) (xy 46.95454 -387.760879) (xy 46.89252 -387.739178)
			(xy 46.833317 -387.710674) (xy 46.777674 -387.675726) (xy 46.72629 -387.634772) (xy 46.702726 -387.611874)
			(xy 45.799248 -386.708396) (xy 45.776316 -386.684832) (xy 45.735322 -386.633418) (xy 45.700337 -386.577742)
			(xy 45.671799 -386.518502) (xy 45.650067 -386.456441) (xy 45.635413 -386.392339) (xy 45.628022 -386.327)
			(xy 45.627544 -386.294122) (xy 45.627544 -384.153664) (xy 45.627043 -384.143659) (xy 45.619379 -384.125175)
			(xy 45.605231 -384.111025) (xy 45.586748 -384.103359) (xy 45.576744 -384.102864) (xy 45.151802 -384.102864)
			(xy 45.141676 -384.102372) (xy 45.122956 -384.094645) (xy 45.108599 -384.080361) (xy 45.100779 -384.06168)
			(xy 45.10024 -384.051556) (xy 45.10024 -383.765552) (xy 45.100023 -383.758681) (xy 45.096431 -383.745418)
			(xy 45.093128 -383.73939) (xy 45.07682 -383.711021) (xy 45.051101 -383.650852) (xy 45.033692 -383.587775)
			(xy 45.024907 -383.522931) (xy 45.024905 -383.457496) (xy 45.033687 -383.392652) (xy 45.051092 -383.329574)
			(xy 45.076807 -383.269403) (xy 45.093128 -383.241042) (xy 45.09643 -383.235011) (xy 45.100043 -383.221752)
			(xy 45.10024 -383.21488) (xy 45.10024 -382.465326) (xy 45.100033 -382.458454) (xy 45.096435 -382.445191)
			(xy 45.093128 -382.439164) (xy 45.076798 -382.410807) (xy 45.051081 -382.350635) (xy 45.033675 -382.287555)
			(xy 45.024892 -382.22271) (xy 45.024893 -382.157273) (xy 45.033678 -382.092428) (xy 45.051087 -382.029349)
			(xy 45.076805 -381.969177) (xy 45.093128 -381.940816) (xy 45.096439 -381.93479) (xy 45.100047 -381.921527)
			(xy 45.10024 -381.914654) (xy 45.10024 -381.628904) (xy 45.100626 -381.618745) (xy 45.108427 -381.599985)
			(xy 45.122836 -381.58566) (xy 45.141641 -381.577968) (xy 45.151802 -381.577596) (xy 45.576744 -381.577596)
			(xy 45.586755 -381.577148) (xy 45.605248 -381.569473) (xy 45.6194 -381.555308) (xy 45.627057 -381.536807)
			(xy 45.627544 -381.526796) (xy 45.627544 -380.557278) (xy 45.627145 -380.547205) (xy 45.619407 -380.528607)
			(xy 45.612558 -380.52121) (xy 45.095668 -380.00432) (xy 45.072751 -379.980741) (xy 45.031756 -379.929331)
			(xy 44.996768 -379.873657) (xy 44.968228 -379.81442) (xy 44.946493 -379.752361) (xy 44.931837 -379.688261)
			(xy 44.924443 -379.622923) (xy 44.923964 -379.590046) (xy 43.751954 -379.590046) (xy 43.742976 -379.610974)
			(xy 43.726608 -379.639322) (xy 43.723286 -379.645343) (xy 43.719685 -379.65861) (xy 43.719496 -379.665484)
			(xy 43.719496 -380.414784) (xy 43.719694 -380.421657) (xy 43.723298 -380.43492) (xy 43.726608 -380.440946)
			(xy 43.742993 -380.469285) (xy 43.76879 -380.529448) (xy 43.786274 -380.592531) (xy 43.795129 -380.65739)
			(xy 43.795696 -380.69012) (xy 43.795117 -380.722849) (xy 43.786265 -380.787707) (xy 43.768779 -380.850787)
			(xy 43.742975 -380.910946) (xy 43.726608 -380.939294) (xy 43.723296 -380.94532) (xy 43.719688 -380.958583)
			(xy 43.719496 -380.965456) (xy 43.719496 -381.251206) (xy 43.718979 -381.261329) (xy 43.711256 -381.280043)
			(xy 43.69698 -381.294398) (xy 43.678308 -381.302223) (xy 43.668188 -381.302768) (xy 42.951908 -381.302768)
			(xy 42.94175 -381.302371) (xy 42.922992 -381.294572) (xy 42.908667 -381.280167) (xy 42.900973 -381.261366)
			(xy 42.9006 -381.251206) (xy 42.9006 -380.965456) (xy 42.900386 -380.958584) (xy 42.896793 -380.945322)
			(xy 42.893488 -380.939294) (xy 42.877119 -380.910947) (xy 42.851318 -380.850786) (xy 42.83383 -380.787706)
			(xy 42.82497 -380.722849) (xy 42.8244 -380.69012) (xy 39.395067 -380.69012) (xy 39.395066 -380.722836)
			(xy 39.386279 -380.787682) (xy 39.368867 -380.850762) (xy 39.343145 -380.910933) (xy 39.32682 -380.939294)
			(xy 39.323509 -380.94532) (xy 39.319901 -380.958583) (xy 39.319708 -380.965456) (xy 39.319708 -381.251206)
			(xy 39.319173 -381.261358) (xy 39.311405 -381.280119) (xy 39.297052 -381.294482) (xy 39.278298 -381.302265)
			(xy 39.268146 -381.302768) (xy 38.551866 -381.302768) (xy 38.541707 -381.302295) (xy 38.522938 -381.29451)
			(xy 38.508574 -381.280138) (xy 38.5008 -381.261365) (xy 38.500304 -381.251206) (xy 38.500304 -380.965456)
			(xy 38.50009 -380.958584) (xy 38.496497 -380.945322) (xy 38.493192 -380.939294) (xy 38.476888 -380.910923)
			(xy 38.451171 -380.850754) (xy 38.433763 -380.787677) (xy 38.424978 -380.722835) (xy 38.424976 -380.6574)
			(xy 34.995045 -380.6574) (xy 34.995612 -380.69012) (xy 34.995031 -380.722849) (xy 34.98618 -380.787707)
			(xy 34.968694 -380.850787) (xy 34.94289 -380.910945) (xy 34.926524 -380.939294) (xy 34.923213 -380.945321)
			(xy 34.919605 -380.958583) (xy 34.919412 -380.965456) (xy 34.919412 -381.251206) (xy 34.91888 -381.261327)
			(xy 34.91116 -381.280038) (xy 34.896888 -381.294392) (xy 34.878222 -381.30222) (xy 34.868104 -381.302768)
			(xy 34.151824 -381.302768) (xy 34.141667 -381.302358) (xy 34.122909 -381.294565) (xy 34.108584 -381.280164)
			(xy 34.100889 -381.261365) (xy 34.100516 -381.251206) (xy 34.100516 -380.965456) (xy 34.1003 -380.958585)
			(xy 34.096708 -380.945322) (xy 34.093404 -380.939294) (xy 34.077036 -380.910946) (xy 34.051235 -380.850786)
			(xy 34.033746 -380.787706) (xy 34.024886 -380.722849) (xy 34.024316 -380.69012) (xy 30.594981 -380.69012)
			(xy 30.59498 -380.722836) (xy 30.586194 -380.787682) (xy 30.568782 -380.850762) (xy 30.54306 -380.910933)
			(xy 30.526736 -380.939294) (xy 30.523426 -380.945321) (xy 30.519817 -380.958583) (xy 30.519624 -380.965456)
			(xy 30.519624 -381.251206) (xy 30.51924 -381.261383) (xy 30.511446 -381.280185) (xy 30.497048 -381.294571)
			(xy 30.478239 -381.302349) (xy 30.468062 -381.302768) (xy 29.751782 -381.302768) (xy 29.741624 -381.302282)
			(xy 29.722855 -381.294502) (xy 29.708491 -381.280135) (xy 29.700716 -381.261364) (xy 29.70022 -381.251206)
			(xy 29.70022 -380.965456) (xy 29.700004 -380.958585) (xy 29.696412 -380.945322) (xy 29.693108 -380.939294)
			(xy 29.676804 -380.910923) (xy 29.651086 -380.850754) (xy 29.633677 -380.787677) (xy 29.624892 -380.722835)
			(xy 29.62489 -380.6574) (xy 8.455106 -380.6574) (xy 8.316976 -380.79553) (xy 8.309965 -380.80321)
			(xy 8.302317 -380.822529) (xy 8.302898 -380.8433) (xy 8.306816 -380.852934) (xy 8.35406 -380.954026)
			(xy 8.381492 -380.969774) (xy 8.397494 -380.968504) (xy 8.430006 -380.967234) (xy 8.457256 -380.967684)
			(xy 8.511201 -380.975441) (xy 8.563494 -380.990796) (xy 8.613069 -381.013436) (xy 8.658917 -381.042901)
			(xy 8.700106 -381.078591) (xy 8.735796 -381.119779) (xy 8.765262 -381.165628) (xy 8.787903 -381.215202)
			(xy 8.803258 -381.267495) (xy 8.811016 -381.32144) (xy 8.811016 -381.345694) (xy 9.548112 -381.345694)
			(xy 9.552183 -381.290072) (xy 9.564309 -381.235635) (xy 9.584232 -381.183544) (xy 9.611528 -381.134909)
			(xy 9.645614 -381.090766) (xy 9.685763 -381.052057) (xy 9.731121 -381.019606) (xy 9.780721 -380.994105)
			(xy 9.833505 -380.976098) (xy 9.888348 -380.965968) (xy 9.944082 -380.963931) (xy 9.999519 -380.970031)
			(xy 10.053476 -380.984137) (xy 10.104805 -381.005949) (xy 10.152411 -381.035003) (xy 10.195279 -381.070678)
			(xy 10.232496 -381.112215) (xy 10.263269 -381.158728) (xy 10.286941 -381.209225) (xy 10.303009 -381.262632)
			(xy 10.311129 -381.317808) (xy 10.311638 -381.345694) (xy 10.311517 -381.352298) (xy 11.832588 -381.352298)
			(xy 11.836659 -381.296676) (xy 11.848785 -381.242239) (xy 11.868708 -381.190148) (xy 11.896004 -381.141513)
			(xy 11.93009 -381.09737) (xy 11.970239 -381.058661) (xy 12.015597 -381.02621) (xy 12.065197 -381.000709)
			(xy 12.117981 -380.982702) (xy 12.172824 -380.972572) (xy 12.228558 -380.970535) (xy 12.283995 -380.976635)
			(xy 12.337952 -380.990741) (xy 12.389281 -381.012553) (xy 12.436887 -381.041607) (xy 12.479755 -381.077282)
			(xy 12.516972 -381.118819) (xy 12.547745 -381.165332) (xy 12.571417 -381.215829) (xy 12.587485 -381.269236)
			(xy 12.595605 -381.324412) (xy 12.596114 -381.352298) (xy 12.595605 -381.380184) (xy 12.590812 -381.41275)
			(xy 13.548104 -381.41275) (xy 13.552175 -381.357128) (xy 13.564301 -381.302691) (xy 13.584224 -381.2506)
			(xy 13.61152 -381.201965) (xy 13.645606 -381.157822) (xy 13.685755 -381.119113) (xy 13.731113 -381.086662)
			(xy 13.780713 -381.061161) (xy 13.833497 -381.043154) (xy 13.88834 -381.033024) (xy 13.944074 -381.030987)
			(xy 13.999511 -381.037087) (xy 14.053468 -381.051193) (xy 14.104797 -381.073005) (xy 14.152403 -381.102059)
			(xy 14.195271 -381.137734) (xy 14.232488 -381.179271) (xy 14.263261 -381.225784) (xy 14.286933 -381.276281)
			(xy 14.303001 -381.329688) (xy 14.311121 -381.384864) (xy 14.31163 -381.41275) (xy 14.311121 -381.440636)
			(xy 14.303001 -381.495812) (xy 14.286933 -381.549219) (xy 14.263261 -381.599716) (xy 14.232488 -381.646229)
			(xy 14.195271 -381.687766) (xy 14.152403 -381.723441) (xy 14.104797 -381.752495) (xy 14.053468 -381.774307)
			(xy 13.999511 -381.788413) (xy 13.944074 -381.794513) (xy 13.88834 -381.792476) (xy 13.833497 -381.782346)
			(xy 13.780713 -381.764339) (xy 13.731113 -381.738838) (xy 13.685755 -381.706387) (xy 13.645606 -381.667678)
			(xy 13.61152 -381.623535) (xy 13.584224 -381.5749) (xy 13.564301 -381.522809) (xy 13.552175 -381.468372)
			(xy 13.548104 -381.41275) (xy 12.590812 -381.41275) (xy 12.587485 -381.43536) (xy 12.571417 -381.488767)
			(xy 12.547745 -381.539264) (xy 12.516972 -381.585777) (xy 12.479755 -381.627314) (xy 12.436887 -381.662989)
			(xy 12.389281 -381.692043) (xy 12.337952 -381.713855) (xy 12.283995 -381.727961) (xy 12.228558 -381.734061)
			(xy 12.172824 -381.732024) (xy 12.117981 -381.721894) (xy 12.065197 -381.703887) (xy 12.015597 -381.678386)
			(xy 11.970239 -381.645935) (xy 11.93009 -381.607226) (xy 11.896004 -381.563083) (xy 11.868708 -381.514448)
			(xy 11.848785 -381.462357) (xy 11.836659 -381.40792) (xy 11.832588 -381.352298) (xy 10.311517 -381.352298)
			(xy 10.311129 -381.37358) (xy 10.303009 -381.428756) (xy 10.286941 -381.482163) (xy 10.263269 -381.53266)
			(xy 10.232496 -381.579173) (xy 10.195279 -381.62071) (xy 10.152411 -381.656385) (xy 10.104805 -381.685439)
			(xy 10.053476 -381.707251) (xy 9.999519 -381.721357) (xy 9.944082 -381.727457) (xy 9.888348 -381.72542)
			(xy 9.833505 -381.71529) (xy 9.780721 -381.697283) (xy 9.731121 -381.671782) (xy 9.685763 -381.639331)
			(xy 9.645614 -381.600622) (xy 9.611528 -381.556479) (xy 9.584232 -381.507844) (xy 9.564309 -381.455753)
			(xy 9.552183 -381.401316) (xy 9.548112 -381.345694) (xy 8.811016 -381.345694) (xy 8.811017 -381.37594)
			(xy 8.803262 -381.429886) (xy 8.78791 -381.482179) (xy 8.765271 -381.531755) (xy 8.735808 -381.577605)
			(xy 8.70012 -381.618795) (xy 8.658933 -381.654487) (xy 8.613086 -381.683954) (xy 8.563513 -381.706597)
			(xy 8.511221 -381.721955) (xy 8.457276 -381.729714) (xy 8.402776 -381.729718) (xy 8.34883 -381.721966)
			(xy 8.296536 -381.706615) (xy 8.246959 -381.683979) (xy 8.201108 -381.654518) (xy 8.159917 -381.618831)
			(xy 8.124223 -381.577646) (xy 8.094754 -381.531801) (xy 8.072108 -381.482228) (xy 8.056749 -381.429937)
			(xy 8.048987 -381.375992) (xy 8.048498 -381.348742) (xy 8.04894 -381.32254) (xy 8.056112 -381.270631)
			(xy 8.070328 -381.220192) (xy 8.091318 -381.172177) (xy 8.104632 -381.149606) (xy 8.113776 -381.13462)
			(xy 8.109712 -381.099822) (xy 8.097012 -381.087122) (xy 8.0896 -381.080438) (xy 8.071167 -381.072841)
			(xy 8.051229 -381.072841) (xy 8.032796 -381.080438) (xy 8.025384 -381.087122) (xy 7.945374 -381.167132)
			(xy 7.938524 -381.174524) (xy 7.930811 -381.193129) (xy 7.930388 -381.2032) (xy 7.930388 -383.490216)
			(xy 27.42438 -383.490216) (xy 27.424933 -383.457486) (xy 27.433793 -383.392627) (xy 27.451287 -383.329547)
			(xy 27.477098 -383.26939) (xy 27.493468 -383.241042) (xy 27.496765 -383.235009) (xy 27.500382 -383.221752)
			(xy 27.50058 -383.21488) (xy 27.50058 -382.465326) (xy 27.50038 -382.458453) (xy 27.496778 -382.44519)
			(xy 27.493468 -382.439164) (xy 27.477095 -382.410819) (xy 27.451293 -382.350658) (xy 27.433805 -382.287578)
			(xy 27.424948 -382.222719) (xy 27.42438 -382.18999) (xy 27.424967 -382.157261) (xy 27.433817 -382.092404)
			(xy 27.451301 -382.029324) (xy 27.477102 -381.969165) (xy 27.493468 -381.940816) (xy 27.496774 -381.934787)
			(xy 27.500386 -381.921527) (xy 27.50058 -381.914654) (xy 27.50058 -381.628904) (xy 27.501088 -381.618798)
			(xy 27.508821 -381.600124) (xy 27.52311 -381.58583) (xy 27.541782 -381.578091) (xy 27.551888 -381.577596)
			(xy 28.268168 -381.577596) (xy 28.278288 -381.578042) (xy 28.29699 -381.585779) (xy 28.311306 -381.600086)
			(xy 28.319053 -381.618784) (xy 28.319476 -381.628904) (xy 28.319476 -381.914654) (xy 28.319688 -381.921526)
			(xy 28.323283 -381.934788) (xy 28.326588 -381.940816) (xy 28.342959 -381.969162) (xy 28.36876 -382.029323)
			(xy 28.386248 -382.092403) (xy 28.395107 -382.157261) (xy 28.395676 -382.18999) (xy 28.395131 -382.22271)
			(xy 31.825016 -382.22271) (xy 31.825018 -382.157273) (xy 31.833803 -382.092427) (xy 31.851213 -382.029348)
			(xy 31.876933 -381.969177) (xy 31.893256 -381.940816) (xy 31.896561 -381.934787) (xy 31.900173 -381.921527)
			(xy 31.900368 -381.914654) (xy 31.900368 -381.628904) (xy 31.900824 -381.618754) (xy 31.908613 -381.600008)
			(xy 31.922998 -381.585686) (xy 31.941778 -381.57798) (xy 31.95193 -381.577596) (xy 32.66821 -381.577596)
			(xy 32.678332 -381.578117) (xy 32.697045 -381.58584) (xy 32.711399 -381.600115) (xy 32.719226 -381.618785)
			(xy 32.719772 -381.628904) (xy 32.719772 -381.914654) (xy 32.719985 -381.921526) (xy 32.723579 -381.934788)
			(xy 32.726884 -381.940816) (xy 32.743197 -381.969182) (xy 32.768914 -382.029352) (xy 32.786322 -382.09243)
			(xy 32.795107 -382.157274) (xy 32.795108 -382.222709) (xy 32.786326 -382.287553) (xy 32.76892 -382.350631)
			(xy 32.743205 -382.410803) (xy 32.726884 -382.439164) (xy 32.723581 -382.445194) (xy 32.719968 -382.458454)
			(xy 32.719772 -382.465326) (xy 32.719772 -383.21488) (xy 32.719975 -383.221752) (xy 32.723576 -383.235015)
			(xy 32.726884 -383.241042) (xy 32.743219 -383.269396) (xy 32.768934 -383.329569) (xy 32.78634 -383.392649)
			(xy 32.795121 -383.457495) (xy 32.79512 -383.522932) (xy 32.786334 -383.587778) (xy 32.768925 -383.650857)
			(xy 32.743207 -383.711028) (xy 32.726884 -383.73939) (xy 32.723572 -383.745416) (xy 32.719965 -383.758679)
			(xy 32.719772 -383.765552) (xy 32.719772 -384.051556) (xy 32.719342 -384.061711) (xy 32.711555 -384.080468)
			(xy 32.697161 -384.094793) (xy 32.678367 -384.10249) (xy 32.66821 -384.102864) (xy 31.95193 -384.102864)
			(xy 31.941806 -384.102349) (xy 31.923086 -384.094632) (xy 31.908729 -384.080354) (xy 31.900908 -384.061678)
			(xy 31.900368 -384.051556) (xy 31.900368 -383.765552) (xy 31.90016 -383.75868) (xy 31.896563 -383.745417)
			(xy 31.893256 -383.73939) (xy 31.876947 -383.711021) (xy 31.851227 -383.650852) (xy 31.833817 -383.587775)
			(xy 31.825031 -383.522932) (xy 31.825029 -383.457496) (xy 31.833811 -383.392652) (xy 31.851218 -383.329574)
			(xy 31.876934 -383.269403) (xy 31.893256 -383.241042) (xy 31.896552 -383.235008) (xy 31.90017 -383.221752)
			(xy 31.900368 -383.21488) (xy 31.900368 -382.465326) (xy 31.90017 -382.458453) (xy 31.896566 -382.44519)
			(xy 31.893256 -382.439164) (xy 31.876925 -382.410808) (xy 31.851207 -382.350635) (xy 31.833799 -382.287556)
			(xy 31.825016 -382.22271) (xy 28.395131 -382.22271) (xy 28.395131 -382.22272) (xy 28.38627 -382.287579)
			(xy 28.368773 -382.35066) (xy 28.34296 -382.410817) (xy 28.326588 -382.439164) (xy 28.323285 -382.445194)
			(xy 28.319672 -382.458454) (xy 28.319476 -382.465326) (xy 28.319476 -383.21488) (xy 28.319679 -383.221752)
			(xy 28.32328 -383.235015) (xy 28.326588 -383.241042) (xy 28.342969 -383.269383) (xy 28.365871 -383.322789)
			(xy 29.62486 -383.322789) (xy 29.624864 -383.25735) (xy 29.633652 -383.192504) (xy 29.651064 -383.129424)
			(xy 29.676784 -383.069252) (xy 29.693108 -383.04089) (xy 29.696427 -383.034867) (xy 29.70003 -383.021602)
			(xy 29.70022 -383.014728) (xy 29.70022 -382.728724) (xy 29.700641 -382.718569) (xy 29.708433 -382.699813)
			(xy 29.72283 -382.685488) (xy 29.741625 -382.677791) (xy 29.751782 -382.677416) (xy 30.468062 -382.677416)
			(xy 30.478183 -382.677957) (xy 30.496899 -382.685668) (xy 30.511256 -382.699938) (xy 30.51908 -382.718606)
			(xy 30.519624 -382.728724) (xy 30.519624 -383.014728) (xy 30.519802 -383.021602) (xy 30.523419 -383.034865)
			(xy 30.526736 -383.04089) (xy 30.543029 -383.069268) (xy 30.56875 -383.129435) (xy 30.586163 -383.19251)
			(xy 30.59495 -383.257352) (xy 30.594955 -383.322786) (xy 30.586175 -383.387629) (xy 30.568771 -383.450707)
			(xy 30.543057 -383.510877) (xy 30.526736 -383.539238) (xy 30.523411 -383.545258) (xy 30.519811 -383.558525)
			(xy 30.519624 -383.5654) (xy 30.519624 -384.3147) (xy 30.519813 -384.321573) (xy 30.523423 -384.334836)
			(xy 30.526736 -384.340862) (xy 30.54309 -384.369206) (xy 30.568806 -384.429381) (xy 30.586211 -384.492463)
			(xy 30.594991 -384.557311) (xy 30.594989 -384.590036) (xy 34.024316 -384.590036) (xy 34.024873 -384.557306)
			(xy 34.033731 -384.492448) (xy 34.051224 -384.429367) (xy 34.077034 -384.36921) (xy 34.093404 -384.340862)
			(xy 34.096733 -384.334844) (xy 34.100329 -384.321575) (xy 34.100516 -384.3147) (xy 34.100516 -383.5654)
			(xy 34.100322 -383.558527) (xy 34.096715 -383.545264) (xy 34.093404 -383.539238) (xy 34.077054 -383.51088)
			(xy 34.051248 -383.450724) (xy 34.033754 -383.387647) (xy 34.024889 -383.322792) (xy 34.024316 -383.290064)
			(xy 34.024886 -383.257335) (xy 34.03374 -383.192476) (xy 34.051229 -383.129396) (xy 34.077036 -383.069238)
			(xy 34.093404 -383.04089) (xy 34.096723 -383.034867) (xy 34.100326 -383.021602) (xy 34.100516 -383.014728)
			(xy 34.100516 -382.728724) (xy 34.100936 -382.718601) (xy 34.108679 -382.699895) (xy 34.122995 -382.685579)
			(xy 34.141701 -382.677836) (xy 34.151824 -382.677416) (xy 34.868104 -382.677416) (xy 34.878229 -382.677813)
			(xy 34.896935 -382.685566) (xy 34.91125 -382.699888) (xy 34.918992 -382.718599) (xy 34.919412 -382.728724)
			(xy 34.919412 -383.014728) (xy 34.919592 -383.021602) (xy 34.923208 -383.034865) (xy 34.926524 -383.04089)
			(xy 34.942888 -383.06924) (xy 34.96869 -383.1294) (xy 34.98618 -383.192479) (xy 34.995041 -383.257335)
			(xy 34.995612 -383.290064) (xy 34.995051 -383.322794) (xy 34.986193 -383.387652) (xy 34.968702 -383.450732)
			(xy 34.951763 -383.490216) (xy 36.224464 -383.490216) (xy 36.225019 -383.457486) (xy 36.233879 -383.392628)
			(xy 36.251372 -383.329548) (xy 36.277182 -383.26939) (xy 36.293552 -383.241042) (xy 36.296848 -383.235008)
			(xy 36.300466 -383.221752) (xy 36.300664 -383.21488) (xy 36.300664 -382.465326) (xy 36.300467 -382.458453)
			(xy 36.296863 -382.44519) (xy 36.293552 -382.439164) (xy 36.277177 -382.41082) (xy 36.251376 -382.350659)
			(xy 36.233889 -382.287578) (xy 36.225032 -382.22272) (xy 36.224464 -382.18999) (xy 36.225053 -382.157261)
			(xy 36.233903 -382.092404) (xy 36.251386 -382.029324) (xy 36.277187 -381.969165) (xy 36.293552 -381.940816)
			(xy 36.296857 -381.934787) (xy 36.300469 -381.921527) (xy 36.300664 -381.914654) (xy 36.300664 -381.628904)
			(xy 36.301188 -381.6188) (xy 36.308917 -381.600129) (xy 36.323202 -381.585835) (xy 36.341868 -381.578094)
			(xy 36.351972 -381.577596) (xy 37.068252 -381.577596) (xy 37.078371 -381.578055) (xy 37.097073 -381.585787)
			(xy 37.111388 -381.60009) (xy 37.119136 -381.618786) (xy 37.11956 -381.628904) (xy 37.11956 -381.914654)
			(xy 37.119774 -381.921526) (xy 37.123368 -381.934788) (xy 37.126672 -381.940816) (xy 37.143041 -381.969163)
			(xy 37.168843 -382.029323) (xy 37.186332 -382.092403) (xy 37.195191 -382.157261) (xy 37.19576 -382.18999)
			(xy 37.195204 -382.22272) (xy 37.186344 -382.287578) (xy 37.168851 -382.350658) (xy 37.143041 -382.410816)
			(xy 37.126672 -382.439164) (xy 37.123368 -382.445194) (xy 37.119756 -382.458454) (xy 37.11956 -382.465326)
			(xy 37.11956 -383.21488) (xy 37.119765 -383.221752) (xy 37.123365 -383.235015) (xy 37.126672 -383.241042)
			(xy 37.143052 -383.269384) (xy 37.165953 -383.322788) (xy 38.424947 -383.322788) (xy 38.424951 -383.25735)
			(xy 38.433738 -383.192504) (xy 38.451149 -383.129424) (xy 38.476869 -383.069252) (xy 38.493192 -383.04089)
			(xy 38.49651 -383.034867) (xy 38.500114 -383.021602) (xy 38.500304 -383.014728) (xy 38.500304 -382.728724)
			(xy 38.500741 -382.718571) (xy 38.50853 -382.699818) (xy 38.522922 -382.685494) (xy 38.541711 -382.677794)
			(xy 38.551866 -382.677416) (xy 39.268146 -382.677416) (xy 39.278273 -382.677888) (xy 39.29699 -382.685627)
			(xy 39.311344 -382.699917) (xy 39.319166 -382.7186) (xy 39.319708 -382.728724) (xy 39.319708 -383.014728)
			(xy 39.319888 -383.021602) (xy 39.323504 -383.034865) (xy 39.32682 -383.04089) (xy 39.343113 -383.069268)
			(xy 39.368836 -383.129435) (xy 39.386249 -383.19251) (xy 39.395037 -383.257352) (xy 39.395041 -383.322787)
			(xy 39.386261 -383.38763) (xy 39.368856 -383.450707) (xy 39.351971 -383.490216) (xy 40.624252 -383.490216)
			(xy 40.624809 -383.457486) (xy 40.633668 -383.392628) (xy 40.651161 -383.329548) (xy 40.676971 -383.26939)
			(xy 40.69334 -383.241042) (xy 40.696635 -383.235008) (xy 40.700254 -383.221752) (xy 40.700452 -383.21488)
			(xy 40.700452 -382.465326) (xy 40.700256 -382.458453) (xy 40.696651 -382.44519) (xy 40.69334 -382.439164)
			(xy 40.676964 -382.41082) (xy 40.651164 -382.350659) (xy 40.633677 -382.287578) (xy 40.62482 -382.22272)
			(xy 40.624252 -382.18999) (xy 40.624842 -382.157261) (xy 40.633691 -382.092404) (xy 40.651175 -382.029324)
			(xy 40.676975 -381.969165) (xy 40.69334 -381.940816) (xy 40.696644 -381.934786) (xy 40.700257 -381.921527)
			(xy 40.700452 -381.914654) (xy 40.700452 -381.628904) (xy 40.700987 -381.618801) (xy 40.708715 -381.600133)
			(xy 40.722996 -381.585839) (xy 40.741658 -381.578096) (xy 40.75176 -381.577596) (xy 41.46804 -381.577596)
			(xy 41.478151 -381.578052) (xy 41.496829 -381.585802) (xy 41.511122 -381.600108) (xy 41.518856 -381.618793)
			(xy 41.519348 -381.628904) (xy 41.519348 -381.914654) (xy 41.519551 -381.921526) (xy 41.523151 -381.93479)
			(xy 41.52646 -381.940816) (xy 41.542828 -381.969164) (xy 41.56863 -382.029324) (xy 41.586119 -382.092404)
			(xy 41.594979 -382.157261) (xy 41.595548 -382.18999) (xy 41.594994 -382.22272) (xy 41.586134 -382.287578)
			(xy 41.56864 -382.350658) (xy 41.54283 -382.410816) (xy 41.52646 -382.439164) (xy 41.523163 -382.445197)
			(xy 41.519545 -382.458454) (xy 41.519348 -382.465326) (xy 41.519348 -383.21488) (xy 41.519542 -383.221753)
			(xy 41.523148 -383.235016) (xy 41.52646 -383.241042) (xy 41.542838 -383.269384) (xy 41.568638 -383.329546)
			(xy 41.586124 -383.392628) (xy 41.59498 -383.457486) (xy 41.595548 -383.490216) (xy 41.594961 -383.522945)
			(xy 41.58611 -383.587802) (xy 41.568626 -383.650882) (xy 41.542825 -383.711041) (xy 41.52646 -383.73939)
			(xy 41.523154 -383.745419) (xy 41.519542 -383.758679) (xy 41.519348 -383.765552) (xy 41.519348 -384.051556)
			(xy 41.518849 -384.06167) (xy 41.511124 -384.080363) (xy 41.496834 -384.094677) (xy 41.478153 -384.102432)
			(xy 41.46804 -384.102864) (xy 40.75176 -384.102864) (xy 40.74163 -384.102516) (xy 40.722919 -384.094748)
			(xy 40.708605 -384.08041) (xy 40.700868 -384.061686) (xy 40.700452 -384.051556) (xy 40.700452 -383.765552)
			(xy 40.700246 -383.75868) (xy 40.696648 -383.745417) (xy 40.69334 -383.73939) (xy 40.676974 -383.711041)
			(xy 40.651172 -383.650882) (xy 40.633682 -383.587802) (xy 40.624822 -383.522945) (xy 40.624252 -383.490216)
			(xy 39.351971 -383.490216) (xy 39.343141 -383.510877) (xy 39.32682 -383.539238) (xy 39.323493 -383.545257)
			(xy 39.319895 -383.558525) (xy 39.319708 -383.5654) (xy 39.319708 -384.3147) (xy 39.319899 -384.321573)
			(xy 39.323508 -384.334836) (xy 39.32682 -384.340862) (xy 39.343174 -384.369206) (xy 39.368891 -384.429381)
			(xy 39.386297 -384.492463) (xy 39.395078 -384.557311) (xy 39.395076 -384.590036) (xy 42.8244 -384.590036)
			(xy 42.82496 -384.557306) (xy 42.833817 -384.492448) (xy 42.851309 -384.429368) (xy 42.877119 -384.36921)
			(xy 42.893488 -384.340862) (xy 42.896815 -384.334844) (xy 42.900413 -384.321575) (xy 42.9006 -384.3147)
			(xy 42.9006 -383.5654) (xy 42.900408 -383.558527) (xy 42.8968 -383.545264) (xy 42.893488 -383.539238)
			(xy 42.877136 -383.510881) (xy 42.851331 -383.450724) (xy 42.833838 -383.387647) (xy 42.824973 -383.322792)
			(xy 42.8244 -383.290064) (xy 42.824972 -383.257335) (xy 42.833826 -383.192477) (xy 42.851315 -383.129397)
			(xy 42.87712 -383.069238) (xy 42.893488 -383.04089) (xy 42.896805 -383.034867) (xy 42.90041 -383.021602)
			(xy 42.9006 -383.014728) (xy 42.9006 -382.728724) (xy 42.901035 -382.718603) (xy 42.908776 -382.6999)
			(xy 42.923086 -382.685585) (xy 42.941787 -382.677839) (xy 42.951908 -382.677416) (xy 43.668188 -382.677416)
			(xy 43.678312 -382.677826) (xy 43.697018 -382.685573) (xy 43.711333 -382.699892) (xy 43.719076 -382.7186)
			(xy 43.719496 -382.728724) (xy 43.719496 -383.014728) (xy 43.719678 -383.021602) (xy 43.723293 -383.034865)
			(xy 43.726608 -383.04089) (xy 43.74297 -383.069241) (xy 43.768773 -383.1294) (xy 43.786263 -383.192479)
			(xy 43.795125 -383.257335) (xy 43.795696 -383.290064) (xy 43.795137 -383.322794) (xy 43.786279 -383.387652)
			(xy 43.768787 -383.450732) (xy 43.742977 -383.51089) (xy 43.726608 -383.539238) (xy 43.72328 -383.545256)
			(xy 43.719683 -383.558525) (xy 43.719496 -383.5654) (xy 43.719496 -384.3147) (xy 43.719688 -384.321573)
			(xy 43.723296 -384.334836) (xy 43.726608 -384.340862) (xy 43.742959 -384.369219) (xy 43.768764 -384.429376)
			(xy 43.786258 -384.492453) (xy 43.795123 -384.557308) (xy 43.795696 -384.590036) (xy 43.795124 -384.622765)
			(xy 43.78627 -384.687623) (xy 43.768782 -384.750704) (xy 43.742976 -384.810862) (xy 43.726608 -384.83921)
			(xy 43.72329 -384.845233) (xy 43.719686 -384.858498) (xy 43.719496 -384.865372) (xy 43.719496 -385.151376)
			(xy 43.719064 -385.161497) (xy 43.711323 -385.180201) (xy 43.697011 -385.194517) (xy 43.678309 -385.202262)
			(xy 43.668188 -385.202684) (xy 42.951908 -385.202684) (xy 42.941784 -385.202277) (xy 42.923078 -385.194529)
			(xy 42.908762 -385.180209) (xy 42.90102 -385.1615) (xy 42.9006 -385.151376) (xy 42.9006 -384.865372)
			(xy 42.900419 -384.858498) (xy 42.896803 -384.845235) (xy 42.893488 -384.83921) (xy 42.877125 -384.810859)
			(xy 42.851323 -384.7507) (xy 42.833833 -384.687621) (xy 42.824971 -384.622765) (xy 42.8244 -384.590036)
			(xy 39.395076 -384.590036) (xy 39.395074 -384.622751) (xy 39.386285 -384.687598) (xy 39.36887 -384.750678)
			(xy 39.343146 -384.810849) (xy 39.32682 -384.83921) (xy 39.323503 -384.845234) (xy 39.319898 -384.858498)
			(xy 39.319708 -384.865372) (xy 39.319708 -385.151376) (xy 39.319259 -385.161528) (xy 39.311473 -385.180278)
			(xy 39.297085 -385.194602) (xy 39.278299 -385.202304) (xy 39.268146 -385.202684) (xy 38.551866 -385.202684)
			(xy 38.54174 -385.202202) (xy 38.523023 -385.194468) (xy 38.508668 -385.18018) (xy 38.500846 -385.1615)
			(xy 38.500304 -385.151376) (xy 38.500304 -384.865372) (xy 38.500122 -384.858498) (xy 38.496507 -384.845235)
			(xy 38.493192 -384.83921) (xy 38.476902 -384.810831) (xy 38.451184 -384.750664) (xy 38.433774 -384.687589)
			(xy 38.424988 -384.622748) (xy 38.424983 -384.557314) (xy 38.433762 -384.492472) (xy 38.451163 -384.429395)
			(xy 38.476874 -384.369224) (xy 38.493192 -384.340862) (xy 38.49652 -384.334844) (xy 38.500117 -384.321575)
			(xy 38.500304 -384.3147) (xy 38.500304 -383.5654) (xy 38.500112 -383.558527) (xy 38.496504 -383.545264)
			(xy 38.493192 -383.539238) (xy 38.476841 -383.510893) (xy 38.451128 -383.450718) (xy 38.433725 -383.387636)
			(xy 38.424947 -383.322788) (xy 37.165953 -383.322788) (xy 37.168851 -383.329546) (xy 37.186337 -383.392628)
			(xy 37.195192 -383.457486) (xy 37.19576 -383.490216) (xy 37.195171 -383.522945) (xy 37.186321 -383.587802)
			(xy 37.168837 -383.650882) (xy 37.143037 -383.711041) (xy 37.126672 -383.73939) (xy 37.123359 -383.745415)
			(xy 37.119753 -383.758679) (xy 37.11956 -383.765552) (xy 37.11956 -384.051556) (xy 37.119147 -384.061681)
			(xy 37.111406 -384.080391) (xy 37.097087 -384.094708) (xy 37.078377 -384.102448) (xy 37.068252 -384.102864)
			(xy 36.351972 -384.102864) (xy 36.341843 -384.102506) (xy 36.323132 -384.094742) (xy 36.308817 -384.080407)
			(xy 36.30108 -384.061685) (xy 36.300664 -384.051556) (xy 36.300664 -383.765552) (xy 36.300457 -383.75868)
			(xy 36.296859 -383.745417) (xy 36.293552 -383.73939) (xy 36.277187 -383.71104) (xy 36.251384 -383.650881)
			(xy 36.233894 -383.587802) (xy 36.225034 -383.522945) (xy 36.224464 -383.490216) (xy 34.951763 -383.490216)
			(xy 34.942893 -383.51089) (xy 34.926524 -383.539238) (xy 34.923197 -383.545257) (xy 34.919599 -383.558525)
			(xy 34.919412 -383.5654) (xy 34.919412 -384.3147) (xy 34.919603 -384.321573) (xy 34.923212 -384.334836)
			(xy 34.926524 -384.340862) (xy 34.942877 -384.369218) (xy 34.968681 -384.429375) (xy 34.986174 -384.492453)
			(xy 34.995039 -384.557308) (xy 34.995612 -384.590036) (xy 34.995038 -384.622765) (xy 34.986185 -384.687623)
			(xy 34.968696 -384.750703) (xy 34.942891 -384.810862) (xy 34.926524 -384.83921) (xy 34.923207 -384.845234)
			(xy 34.919602 -384.858498) (xy 34.919412 -384.865372) (xy 34.919412 -385.151376) (xy 34.918965 -385.161495)
			(xy 34.911227 -385.180196) (xy 34.89692 -385.194511) (xy 34.878223 -385.202259) (xy 34.868104 -385.202684)
			(xy 34.151824 -385.202684) (xy 34.141701 -385.202264) (xy 34.122995 -385.194521) (xy 34.108679 -385.180205)
			(xy 34.100936 -385.161499) (xy 34.100516 -385.151376) (xy 34.100516 -384.865372) (xy 34.100333 -384.858498)
			(xy 34.096718 -384.845235) (xy 34.093404 -384.83921) (xy 34.077043 -384.810858) (xy 34.05124 -384.7507)
			(xy 34.033749 -384.687621) (xy 34.024887 -384.622765) (xy 34.024316 -384.590036) (xy 30.594989 -384.590036)
			(xy 30.594987 -384.622751) (xy 30.586199 -384.687597) (xy 30.568785 -384.750677) (xy 30.543061 -384.810849)
			(xy 30.526736 -384.83921) (xy 30.523421 -384.845234) (xy 30.519815 -384.858498) (xy 30.519624 -384.865372)
			(xy 30.519624 -385.151376) (xy 30.519159 -385.161526) (xy 30.511376 -385.180273) (xy 30.496993 -385.194596)
			(xy 30.478213 -385.202301) (xy 30.468062 -385.202684) (xy 29.751782 -385.202684) (xy 29.741657 -385.202189)
			(xy 29.72294 -385.19446) (xy 29.708585 -385.180177) (xy 29.700762 -385.161498) (xy 29.70022 -385.151376)
			(xy 29.70022 -384.865372) (xy 29.700036 -384.858498) (xy 29.696422 -384.845236) (xy 29.693108 -384.83921)
			(xy 29.676817 -384.810832) (xy 29.651098 -384.750664) (xy 29.633688 -384.687589) (xy 29.624901 -384.622748)
			(xy 29.624897 -384.557314) (xy 29.633676 -384.492472) (xy 29.651078 -384.429394) (xy 29.676789 -384.369224)
			(xy 29.693108 -384.340862) (xy 29.696437 -384.334844) (xy 29.700033 -384.321575) (xy 29.70022 -384.3147)
			(xy 29.70022 -383.5654) (xy 29.700026 -383.558527) (xy 29.696419 -383.545264) (xy 29.693108 -383.539238)
			(xy 29.676756 -383.510893) (xy 29.651043 -383.450718) (xy 29.633639 -383.387636) (xy 29.62486 -383.322789)
			(xy 28.365871 -383.322789) (xy 28.368768 -383.329545) (xy 28.386253 -383.392627) (xy 28.395108 -383.457486)
			(xy 28.395676 -383.490216) (xy 28.395098 -383.522945) (xy 28.386247 -383.587803) (xy 28.36876 -383.650883)
			(xy 28.342955 -383.711042) (xy 28.326588 -383.73939) (xy 28.323276 -383.745416) (xy 28.319669 -383.758679)
			(xy 28.319476 -383.765552) (xy 28.319476 -384.051556) (xy 28.319047 -384.061679) (xy 28.311309 -384.080386)
			(xy 28.296996 -384.094702) (xy 28.27829 -384.102445) (xy 28.268168 -384.102864) (xy 27.551888 -384.102864)
			(xy 27.54176 -384.102493) (xy 27.523049 -384.094734) (xy 27.508734 -384.080404) (xy 27.500996 -384.061684)
			(xy 27.50058 -384.051556) (xy 27.50058 -383.765552) (xy 27.500371 -383.75868) (xy 27.496774 -383.745417)
			(xy 27.493468 -383.73939) (xy 27.477105 -383.711039) (xy 27.451301 -383.650881) (xy 27.43381 -383.587802)
			(xy 27.42495 -383.522945) (xy 27.42438 -383.490216) (xy 7.930388 -383.490216) (xy 7.930388 -384.746754)
			(xy 14.91564 -384.746754) (xy 14.919711 -384.691132) (xy 14.931837 -384.636695) (xy 14.95176 -384.584604)
			(xy 14.979056 -384.535969) (xy 15.013142 -384.491826) (xy 15.053291 -384.453117) (xy 15.098649 -384.420666)
			(xy 15.148249 -384.395165) (xy 15.201033 -384.377158) (xy 15.255876 -384.367028) (xy 15.31161 -384.364991)
			(xy 15.367047 -384.371091) (xy 15.421004 -384.385197) (xy 15.472333 -384.407009) (xy 15.519939 -384.436063)
			(xy 15.562807 -384.471738) (xy 15.600024 -384.513275) (xy 15.630797 -384.559788) (xy 15.654469 -384.610285)
			(xy 15.670537 -384.663692) (xy 15.678657 -384.718868) (xy 15.679166 -384.746754) (xy 15.678657 -384.77464)
			(xy 15.670537 -384.829816) (xy 15.654469 -384.883223) (xy 15.630797 -384.93372) (xy 15.600024 -384.980233)
			(xy 15.562807 -385.02177) (xy 15.519939 -385.057445) (xy 15.472333 -385.086499) (xy 15.421004 -385.108311)
			(xy 15.367047 -385.122417) (xy 15.31161 -385.128517) (xy 15.255876 -385.12648) (xy 15.201033 -385.11635)
			(xy 15.148249 -385.098343) (xy 15.098649 -385.072842) (xy 15.053291 -385.040391) (xy 15.013142 -385.001682)
			(xy 14.979056 -384.957539) (xy 14.95176 -384.908904) (xy 14.931837 -384.856813) (xy 14.919711 -384.802376)
			(xy 14.91564 -384.746754) (xy 7.930388 -384.746754) (xy 7.930388 -385.994402) (xy 7.929932 -386.027558)
			(xy 7.922519 -386.093453) (xy 7.907775 -386.158104) (xy 7.885886 -386.220698) (xy 7.857126 -386.280447)
			(xy 7.821858 -386.336601) (xy 7.780525 -386.388454) (xy 7.757414 -386.412232) (xy 6.211062 -387.958584)
			(xy 6.187268 -387.981686) (xy 6.135426 -388.023051) (xy 6.079281 -388.058354) (xy 6.019537 -388.087152)
			(xy 5.956946 -388.109082) (xy 5.892294 -388.12387) (xy 5.826393 -388.131329) (xy 5.793232 -388.131812)
			(xy 4.35229 -388.131812) (xy 4.34222 -388.132229) (xy 4.323622 -388.139955) (xy 4.316222 -388.146798)
			(xy 4.250644 -388.21233) (xy 14.92834 -388.21233) (xy 14.932411 -388.156708) (xy 14.944537 -388.102271)
			(xy 14.96446 -388.05018) (xy 14.991756 -388.001545) (xy 15.025842 -387.957402) (xy 15.065991 -387.918693)
			(xy 15.111349 -387.886242) (xy 15.160949 -387.860741) (xy 15.213733 -387.842734) (xy 15.268576 -387.832604)
			(xy 15.32431 -387.830567) (xy 15.379747 -387.836667) (xy 15.433704 -387.850773) (xy 15.485033 -387.872585)
			(xy 15.532639 -387.901639) (xy 15.575507 -387.937314) (xy 15.612724 -387.978851) (xy 15.643497 -388.025364)
			(xy 15.667169 -388.075861) (xy 15.683237 -388.129268) (xy 15.691357 -388.184444) (xy 15.691866 -388.21233)
			(xy 15.691357 -388.240216) (xy 15.683237 -388.295392) (xy 15.667169 -388.348799) (xy 15.643497 -388.399296)
			(xy 15.612724 -388.445809) (xy 15.575507 -388.487346) (xy 15.532639 -388.523021) (xy 15.485033 -388.552075)
			(xy 15.433704 -388.573887) (xy 15.379747 -388.587993) (xy 15.32431 -388.594093) (xy 15.268576 -388.592056)
			(xy 15.213733 -388.581926) (xy 15.160949 -388.563919) (xy 15.111349 -388.538418) (xy 15.065991 -388.505967)
			(xy 15.025842 -388.467258) (xy 14.991756 -388.423115) (xy 14.96446 -388.37448) (xy 14.944537 -388.322389)
			(xy 14.932411 -388.267952) (xy 14.92834 -388.21233) (xy 4.250644 -388.21233) (xy 3.951224 -388.511542)
			(xy 3.92746 -388.534666) (xy 3.875599 -388.575988) (xy 3.819439 -388.611247) (xy 3.759687 -388.640001)
			(xy 3.697093 -388.661888) (xy 3.632443 -388.676634) (xy 3.566549 -388.684053) (xy 3.533394 -388.684516)
			(xy 2.574798 -388.684516) (xy 2.564728 -388.684936) (xy 2.54613 -388.69266) (xy 2.53873 -388.699502)
			(xy 2.491486 -388.746746) (xy 4.630672 -388.746746) (xy 4.634743 -388.691124) (xy 4.646869 -388.636687)
			(xy 4.666792 -388.584596) (xy 4.694088 -388.535961) (xy 4.728174 -388.491818) (xy 4.768323 -388.453109)
			(xy 4.813681 -388.420658) (xy 4.863281 -388.395157) (xy 4.916065 -388.37715) (xy 4.970908 -388.36702)
			(xy 5.026642 -388.364983) (xy 5.082079 -388.371083) (xy 5.136036 -388.385189) (xy 5.187365 -388.407001)
			(xy 5.234971 -388.436055) (xy 5.277839 -388.47173) (xy 5.315056 -388.513267) (xy 5.345829 -388.55978)
			(xy 5.369501 -388.610277) (xy 5.385569 -388.663684) (xy 5.393689 -388.71886) (xy 5.394198 -388.746746)
			(xy 5.393689 -388.774632) (xy 5.385569 -388.829808) (xy 5.369501 -388.883215) (xy 5.345829 -388.933712)
			(xy 5.315056 -388.980225) (xy 5.277839 -389.021762) (xy 5.234971 -389.057437) (xy 5.187365 -389.086491)
			(xy 5.136036 -389.108303) (xy 5.082079 -389.122409) (xy 5.026642 -389.128509) (xy 4.970908 -389.126472)
			(xy 4.916065 -389.116342) (xy 4.863281 -389.098335) (xy 4.813681 -389.072834) (xy 4.768323 -389.040383)
			(xy 4.728174 -389.001674) (xy 4.694088 -388.957531) (xy 4.666792 -388.908896) (xy 4.646869 -388.856805)
			(xy 4.634743 -388.802368) (xy 4.630672 -388.746746) (xy 2.491486 -388.746746) (xy 2.445512 -388.79272)
			(xy 2.421747 -388.815853) (xy 2.369899 -388.857214) (xy 2.313748 -388.892513) (xy 2.254 -388.921306)
			(xy 2.191404 -388.943232) (xy 2.126748 -388.958014) (xy 2.060844 -388.965468) (xy 2.027682 -388.965948)
			(xy 1.991961 -388.965428) (xy 1.92104 -388.956817) (xy 1.851674 -388.93972) (xy 1.784874 -388.914387)
			(xy 1.721615 -388.881186) (xy 1.662819 -388.840602) (xy 1.609344 -388.793227) (xy 1.561969 -388.739752)
			(xy 1.521385 -388.680957) (xy 1.488184 -388.617698) (xy 1.462851 -388.550898) (xy 1.445753 -388.481532)
			(xy 1.437142 -388.410611) (xy 1.436624 -388.37489) (xy 0.6096 -388.37489) (xy 0.6096 -389.720836)
			(xy 4.413248 -389.720836) (xy 4.417319 -389.665214) (xy 4.429445 -389.610777) (xy 4.449368 -389.558686)
			(xy 4.476664 -389.510051) (xy 4.51075 -389.465908) (xy 4.550899 -389.427199) (xy 4.596257 -389.394748)
			(xy 4.645857 -389.369247) (xy 4.698641 -389.35124) (xy 4.753484 -389.34111) (xy 4.809218 -389.339073)
			(xy 4.864655 -389.345173) (xy 4.918612 -389.359279) (xy 4.969941 -389.381091) (xy 5.017547 -389.410145)
			(xy 5.060415 -389.44582) (xy 5.097632 -389.487357) (xy 5.128405 -389.53387) (xy 5.152077 -389.584367)
			(xy 5.168145 -389.637774) (xy 5.176265 -389.69295) (xy 5.176774 -389.720836) (xy 5.176301 -389.746744)
			(xy 14.934944 -389.746744) (xy 14.939015 -389.691122) (xy 14.951141 -389.636685) (xy 14.971064 -389.584594)
			(xy 14.99836 -389.535959) (xy 15.032446 -389.491816) (xy 15.072595 -389.453107) (xy 15.117953 -389.420656)
			(xy 15.167553 -389.395155) (xy 15.220337 -389.377148) (xy 15.27518 -389.367018) (xy 15.330914 -389.364981)
			(xy 15.386351 -389.371081) (xy 15.440308 -389.385187) (xy 15.491637 -389.406999) (xy 15.539243 -389.436053)
			(xy 15.582111 -389.471728) (xy 15.619328 -389.513265) (xy 15.650101 -389.559778) (xy 15.673773 -389.610275)
			(xy 15.689841 -389.663682) (xy 15.697961 -389.718858) (xy 15.69847 -389.746744) (xy 15.697961 -389.77463)
			(xy 15.689841 -389.829806) (xy 15.673773 -389.883213) (xy 15.650101 -389.93371) (xy 15.619328 -389.980223)
			(xy 15.582111 -390.02176) (xy 15.539243 -390.057435) (xy 15.491637 -390.086489) (xy 15.440308 -390.108301)
			(xy 15.386351 -390.122407) (xy 15.330914 -390.128507) (xy 15.27518 -390.12647) (xy 15.220337 -390.11634)
			(xy 15.167553 -390.098333) (xy 15.117953 -390.072832) (xy 15.072595 -390.040381) (xy 15.032446 -390.001672)
			(xy 14.99836 -389.957529) (xy 14.971064 -389.908894) (xy 14.951141 -389.856803) (xy 14.939015 -389.802366)
			(xy 14.934944 -389.746744) (xy 5.176301 -389.746744) (xy 5.176265 -389.748722) (xy 5.168145 -389.803898)
			(xy 5.152077 -389.857305) (xy 5.128405 -389.907802) (xy 5.097632 -389.954315) (xy 5.060415 -389.995852)
			(xy 5.017547 -390.031527) (xy 4.969941 -390.060581) (xy 4.918612 -390.082393) (xy 4.864655 -390.096499)
			(xy 4.809218 -390.102599) (xy 4.753484 -390.100562) (xy 4.698641 -390.090432) (xy 4.645857 -390.072425)
			(xy 4.596257 -390.046924) (xy 4.550899 -390.014473) (xy 4.51075 -389.975764) (xy 4.476664 -389.931621)
			(xy 4.449368 -389.882986) (xy 4.429445 -389.830895) (xy 4.417319 -389.776458) (xy 4.413248 -389.720836)
			(xy 0.6096 -389.720836) (xy 0.6096 -390.790938) (xy 1.383536 -390.790938) (xy 1.387607 -390.735316)
			(xy 1.399733 -390.680879) (xy 1.419656 -390.628788) (xy 1.446952 -390.580153) (xy 1.481038 -390.53601)
			(xy 1.521187 -390.497301) (xy 1.566545 -390.46485) (xy 1.616145 -390.439349) (xy 1.668929 -390.421342)
			(xy 1.723772 -390.411212) (xy 1.779506 -390.409175) (xy 1.834943 -390.415275) (xy 1.8889 -390.429381)
			(xy 1.940229 -390.451193) (xy 1.987835 -390.480247) (xy 2.030703 -390.515922) (xy 2.06792 -390.557459)
			(xy 2.098693 -390.603972) (xy 2.122365 -390.654469) (xy 2.138433 -390.707876) (xy 2.146553 -390.763052)
			(xy 2.147062 -390.790938) (xy 2.146553 -390.818824) (xy 2.138433 -390.874) (xy 2.122365 -390.927407)
			(xy 2.098693 -390.977904) (xy 2.06792 -391.024417) (xy 2.030703 -391.065954) (xy 1.987835 -391.101629)
			(xy 1.940229 -391.130683) (xy 1.8889 -391.152495) (xy 1.834943 -391.166601) (xy 1.779506 -391.172701)
			(xy 1.723772 -391.170664) (xy 1.668929 -391.160534) (xy 1.616145 -391.142527) (xy 1.566545 -391.117026)
			(xy 1.521187 -391.084575) (xy 1.481038 -391.045866) (xy 1.446952 -391.001723) (xy 1.419656 -390.953088)
			(xy 1.399733 -390.900997) (xy 1.387607 -390.84656) (xy 1.383536 -390.790938) (xy 0.6096 -390.790938)
			(xy 0.6096 -391.614914) (xy 13.80693 -391.614914) (xy 13.811001 -391.559292) (xy 13.823127 -391.504855)
			(xy 13.84305 -391.452764) (xy 13.870346 -391.404129) (xy 13.904432 -391.359986) (xy 13.944581 -391.321277)
			(xy 13.989939 -391.288826) (xy 14.039539 -391.263325) (xy 14.092323 -391.245318) (xy 14.147166 -391.235188)
			(xy 14.2029 -391.233151) (xy 14.258337 -391.239251) (xy 14.312294 -391.253357) (xy 14.363623 -391.275169)
			(xy 14.411229 -391.304223) (xy 14.454097 -391.339898) (xy 14.491314 -391.381435) (xy 14.522087 -391.427948)
			(xy 14.545759 -391.478445) (xy 14.561827 -391.531852) (xy 14.569947 -391.587028) (xy 14.570456 -391.614914)
			(xy 14.569947 -391.6428) (xy 14.566986 -391.66292) (xy 16.249394 -391.66292) (xy 16.253465 -391.607298)
			(xy 16.265591 -391.552861) (xy 16.285514 -391.50077) (xy 16.31281 -391.452135) (xy 16.346896 -391.407992)
			(xy 16.387045 -391.369283) (xy 16.432403 -391.336832) (xy 16.482003 -391.311331) (xy 16.534787 -391.293324)
			(xy 16.58963 -391.283194) (xy 16.645364 -391.281157) (xy 16.700801 -391.287257) (xy 16.754758 -391.301363)
			(xy 16.806087 -391.323175) (xy 16.853693 -391.352229) (xy 16.896561 -391.387904) (xy 16.933778 -391.429441)
			(xy 16.964551 -391.475954) (xy 16.988223 -391.526451) (xy 17.004291 -391.579858) (xy 17.012411 -391.635034)
			(xy 17.01292 -391.66292) (xy 17.012411 -391.690806) (xy 17.004291 -391.745982) (xy 16.988223 -391.799389)
			(xy 16.964551 -391.849886) (xy 16.933778 -391.896399) (xy 16.896561 -391.937936) (xy 16.853693 -391.973611)
			(xy 16.806087 -392.002665) (xy 16.754758 -392.024477) (xy 16.700801 -392.038583) (xy 16.645364 -392.044683)
			(xy 16.58963 -392.042646) (xy 16.534787 -392.032516) (xy 16.482003 -392.014509) (xy 16.432403 -391.989008)
			(xy 16.387045 -391.956557) (xy 16.346896 -391.917848) (xy 16.31281 -391.873705) (xy 16.285514 -391.82507)
			(xy 16.265591 -391.772979) (xy 16.253465 -391.718542) (xy 16.249394 -391.66292) (xy 14.566986 -391.66292)
			(xy 14.561827 -391.697976) (xy 14.545759 -391.751383) (xy 14.522087 -391.80188) (xy 14.491314 -391.848393)
			(xy 14.454097 -391.88993) (xy 14.411229 -391.925605) (xy 14.363623 -391.954659) (xy 14.312294 -391.976471)
			(xy 14.258337 -391.990577) (xy 14.2029 -391.996677) (xy 14.147166 -391.99464) (xy 14.092323 -391.98451)
			(xy 14.039539 -391.966503) (xy 13.989939 -391.941002) (xy 13.944581 -391.908551) (xy 13.904432 -391.869842)
			(xy 13.870346 -391.825699) (xy 13.84305 -391.777064) (xy 13.823127 -391.724973) (xy 13.811001 -391.670536)
			(xy 13.80693 -391.614914) (xy 0.6096 -391.614914) (xy 0.6096 -393.133072) (xy 23.365966 -393.133072)
			(xy 23.370037 -393.07745) (xy 23.382163 -393.023013) (xy 23.402086 -392.970922) (xy 23.429382 -392.922287)
			(xy 23.463468 -392.878144) (xy 23.503617 -392.839435) (xy 23.548975 -392.806984) (xy 23.598575 -392.781483)
			(xy 23.651359 -392.763476) (xy 23.706202 -392.753346) (xy 23.761936 -392.751309) (xy 23.817373 -392.757409)
			(xy 23.87133 -392.771515) (xy 23.922659 -392.793327) (xy 23.970265 -392.822381) (xy 24.013133 -392.858056)
			(xy 24.05035 -392.899593) (xy 24.081123 -392.946106) (xy 24.104795 -392.996603) (xy 24.120863 -393.05001)
			(xy 24.128983 -393.105186) (xy 24.129492 -393.133072) (xy 24.128983 -393.160958) (xy 24.120863 -393.216134)
			(xy 24.104795 -393.269541) (xy 24.081123 -393.320038) (xy 24.05035 -393.366551) (xy 24.013133 -393.408088)
			(xy 23.970265 -393.443763) (xy 23.922659 -393.472817) (xy 23.87133 -393.494629) (xy 23.817373 -393.508735)
			(xy 23.761936 -393.514835) (xy 23.706202 -393.512798) (xy 23.651359 -393.502668) (xy 23.598575 -393.484661)
			(xy 23.548975 -393.45916) (xy 23.503617 -393.426709) (xy 23.463468 -393.388) (xy 23.429382 -393.343857)
			(xy 23.402086 -393.295222) (xy 23.382163 -393.243131) (xy 23.370037 -393.188694) (xy 23.365966 -393.133072)
			(xy 0.6096 -393.133072) (xy 0.6096 -394.48232) (xy 2.2512 -394.48232) (xy 2.255271 -394.426698) (xy 2.267397 -394.372261)
			(xy 2.28732 -394.32017) (xy 2.314616 -394.271535) (xy 2.348702 -394.227392) (xy 2.388851 -394.188683)
			(xy 2.434209 -394.156232) (xy 2.483809 -394.130731) (xy 2.536593 -394.112724) (xy 2.591436 -394.102594)
			(xy 2.64717 -394.100557) (xy 2.702607 -394.106657) (xy 2.756564 -394.120763) (xy 2.807893 -394.142575)
			(xy 2.855499 -394.171629) (xy 2.898367 -394.207304) (xy 2.935584 -394.248841) (xy 2.966357 -394.295354)
			(xy 2.990029 -394.345851) (xy 3.006097 -394.399258) (xy 3.014217 -394.454434) (xy 3.014726 -394.48232)
			(xy 3.014217 -394.510206) (xy 3.006097 -394.565382) (xy 2.990029 -394.618789) (xy 2.966357 -394.669286)
			(xy 2.935584 -394.715799) (xy 2.900811 -394.754608) (xy 5.302756 -394.754608) (xy 5.306827 -394.698986)
			(xy 5.318953 -394.644549) (xy 5.338876 -394.592458) (xy 5.366172 -394.543823) (xy 5.400258 -394.49968)
			(xy 5.440407 -394.460971) (xy 5.485765 -394.42852) (xy 5.535365 -394.403019) (xy 5.588149 -394.385012)
			(xy 5.642992 -394.374882) (xy 5.698726 -394.372845) (xy 5.754163 -394.378945) (xy 5.80812 -394.393051)
			(xy 5.859449 -394.414863) (xy 5.907055 -394.443917) (xy 5.949923 -394.479592) (xy 5.98714 -394.521129)
			(xy 6.017913 -394.567642) (xy 6.041585 -394.618139) (xy 6.057653 -394.671546) (xy 6.065773 -394.726722)
			(xy 6.066282 -394.754608) (xy 6.066212 -394.758418) (xy 6.280656 -394.758418) (xy 6.284727 -394.702796)
			(xy 6.296853 -394.648359) (xy 6.316776 -394.596268) (xy 6.344072 -394.547633) (xy 6.378158 -394.50349)
			(xy 6.418307 -394.464781) (xy 6.463665 -394.43233) (xy 6.513265 -394.406829) (xy 6.566049 -394.388822)
			(xy 6.620892 -394.378692) (xy 6.676626 -394.376655) (xy 6.732063 -394.382755) (xy 6.78602 -394.396861)
			(xy 6.837349 -394.418673) (xy 6.884955 -394.447727) (xy 6.927823 -394.483402) (xy 6.96504 -394.524939)
			(xy 6.995813 -394.571452) (xy 7.019485 -394.621949) (xy 7.035553 -394.675356) (xy 7.043673 -394.730532)
			(xy 7.044182 -394.758418) (xy 7.043673 -394.786304) (xy 7.035553 -394.84148) (xy 7.019485 -394.894887)
			(xy 6.995813 -394.945384) (xy 6.96504 -394.991897) (xy 6.927823 -395.033434) (xy 6.884955 -395.069109)
			(xy 6.837349 -395.098163) (xy 6.78602 -395.119975) (xy 6.732063 -395.134081) (xy 6.676626 -395.140181)
			(xy 6.620892 -395.138144) (xy 6.566049 -395.128014) (xy 6.513265 -395.110007) (xy 6.463665 -395.084506)
			(xy 6.418307 -395.052055) (xy 6.378158 -395.013346) (xy 6.344072 -394.969203) (xy 6.316776 -394.920568)
			(xy 6.296853 -394.868477) (xy 6.284727 -394.81404) (xy 6.280656 -394.758418) (xy 6.066212 -394.758418)
			(xy 6.065773 -394.782494) (xy 6.057653 -394.83767) (xy 6.041585 -394.891077) (xy 6.017913 -394.941574)
			(xy 5.98714 -394.988087) (xy 5.949923 -395.029624) (xy 5.907055 -395.065299) (xy 5.859449 -395.094353)
			(xy 5.80812 -395.116165) (xy 5.754163 -395.130271) (xy 5.698726 -395.136371) (xy 5.642992 -395.134334)
			(xy 5.588149 -395.124204) (xy 5.535365 -395.106197) (xy 5.485765 -395.080696) (xy 5.440407 -395.048245)
			(xy 5.400258 -395.009536) (xy 5.366172 -394.965393) (xy 5.338876 -394.916758) (xy 5.318953 -394.864667)
			(xy 5.306827 -394.81023) (xy 5.302756 -394.754608) (xy 2.900811 -394.754608) (xy 2.898367 -394.757336)
			(xy 2.855499 -394.793011) (xy 2.807893 -394.822065) (xy 2.756564 -394.843877) (xy 2.702607 -394.857983)
			(xy 2.64717 -394.864083) (xy 2.591436 -394.862046) (xy 2.536593 -394.851916) (xy 2.483809 -394.833909)
			(xy 2.434209 -394.808408) (xy 2.388851 -394.775957) (xy 2.348702 -394.737248) (xy 2.314616 -394.693105)
			(xy 2.28732 -394.64447) (xy 2.267397 -394.592379) (xy 2.255271 -394.537942) (xy 2.2512 -394.48232)
			(xy 0.6096 -394.48232) (xy 0.6096 -395.206728) (xy 10.019536 -395.206728) (xy 10.023607 -395.151106)
			(xy 10.035733 -395.096669) (xy 10.055656 -395.044578) (xy 10.082952 -394.995943) (xy 10.117038 -394.9518)
			(xy 10.157187 -394.913091) (xy 10.202545 -394.88064) (xy 10.252145 -394.855139) (xy 10.304929 -394.837132)
			(xy 10.359772 -394.827002) (xy 10.415506 -394.824965) (xy 10.470943 -394.831065) (xy 10.5249 -394.845171)
			(xy 10.576229 -394.866983) (xy 10.623835 -394.896037) (xy 10.666703 -394.931712) (xy 10.70392 -394.973249)
			(xy 10.734693 -395.019762) (xy 10.758365 -395.070259) (xy 10.774433 -395.123666) (xy 10.782553 -395.178842)
			(xy 10.78302 -395.204442) (xy 11.574778 -395.204442) (xy 11.578849 -395.14882) (xy 11.590975 -395.094383)
			(xy 11.610898 -395.042292) (xy 11.638194 -394.993657) (xy 11.67228 -394.949514) (xy 11.712429 -394.910805)
			(xy 11.757787 -394.878354) (xy 11.807387 -394.852853) (xy 11.860171 -394.834846) (xy 11.915014 -394.824716)
			(xy 11.970748 -394.822679) (xy 12.026185 -394.828779) (xy 12.080142 -394.842885) (xy 12.131471 -394.864697)
			(xy 12.179077 -394.893751) (xy 12.221945 -394.929426) (xy 12.259162 -394.970963) (xy 12.289935 -395.017476)
			(xy 12.313607 -395.067973) (xy 12.329675 -395.12138) (xy 12.337795 -395.176556) (xy 12.338151 -395.19606)
			(xy 15.04772 -395.19606) (xy 15.051791 -395.140438) (xy 15.063917 -395.086001) (xy 15.08384 -395.03391)
			(xy 15.111136 -394.985275) (xy 15.145222 -394.941132) (xy 15.185371 -394.902423) (xy 15.230729 -394.869972)
			(xy 15.280329 -394.844471) (xy 15.333113 -394.826464) (xy 15.387956 -394.816334) (xy 15.44369 -394.814297)
			(xy 15.499127 -394.820397) (xy 15.553084 -394.834503) (xy 15.604413 -394.856315) (xy 15.652019 -394.885369)
			(xy 15.694887 -394.921044) (xy 15.732104 -394.962581) (xy 15.762877 -395.009094) (xy 15.786549 -395.059591)
			(xy 15.802617 -395.112998) (xy 15.810737 -395.168174) (xy 15.811246 -395.19606) (xy 16.06372 -395.19606)
			(xy 16.067791 -395.140438) (xy 16.079917 -395.086001) (xy 16.09984 -395.03391) (xy 16.127136 -394.985275)
			(xy 16.161222 -394.941132) (xy 16.201371 -394.902423) (xy 16.246729 -394.869972) (xy 16.296329 -394.844471)
			(xy 16.349113 -394.826464) (xy 16.403956 -394.816334) (xy 16.45969 -394.814297) (xy 16.515127 -394.820397)
			(xy 16.569084 -394.834503) (xy 16.620413 -394.856315) (xy 16.668019 -394.885369) (xy 16.710887 -394.921044)
			(xy 16.748104 -394.962581) (xy 16.778877 -395.009094) (xy 16.802549 -395.059591) (xy 16.818617 -395.112998)
			(xy 16.826737 -395.168174) (xy 16.827246 -395.19606) (xy 16.826737 -395.223946) (xy 16.818617 -395.279122)
			(xy 16.802549 -395.332529) (xy 16.778877 -395.383026) (xy 16.748104 -395.429539) (xy 16.710887 -395.471076)
			(xy 16.668019 -395.506751) (xy 16.620413 -395.535805) (xy 16.569084 -395.557617) (xy 16.515127 -395.571723)
			(xy 16.45969 -395.577823) (xy 16.403956 -395.575786) (xy 16.349113 -395.565656) (xy 16.296329 -395.547649)
			(xy 16.246729 -395.522148) (xy 16.201371 -395.489697) (xy 16.161222 -395.450988) (xy 16.127136 -395.406845)
			(xy 16.09984 -395.35821) (xy 16.079917 -395.306119) (xy 16.067791 -395.251682) (xy 16.06372 -395.19606)
			(xy 15.811246 -395.19606) (xy 15.810737 -395.223946) (xy 15.802617 -395.279122) (xy 15.786549 -395.332529)
			(xy 15.762877 -395.383026) (xy 15.732104 -395.429539) (xy 15.694887 -395.471076) (xy 15.652019 -395.506751)
			(xy 15.604413 -395.535805) (xy 15.553084 -395.557617) (xy 15.499127 -395.571723) (xy 15.44369 -395.577823)
			(xy 15.387956 -395.575786) (xy 15.333113 -395.565656) (xy 15.280329 -395.547649) (xy 15.230729 -395.522148)
			(xy 15.185371 -395.489697) (xy 15.145222 -395.450988) (xy 15.111136 -395.406845) (xy 15.08384 -395.35821)
			(xy 15.063917 -395.306119) (xy 15.051791 -395.251682) (xy 15.04772 -395.19606) (xy 12.338151 -395.19606)
			(xy 12.338304 -395.204442) (xy 12.337795 -395.232328) (xy 12.329675 -395.287504) (xy 12.313607 -395.340911)
			(xy 12.289935 -395.391408) (xy 12.259162 -395.437921) (xy 12.221945 -395.479458) (xy 12.179077 -395.515133)
			(xy 12.131471 -395.544187) (xy 12.080142 -395.565999) (xy 12.026185 -395.580105) (xy 11.970748 -395.586205)
			(xy 11.915014 -395.584168) (xy 11.860171 -395.574038) (xy 11.807387 -395.556031) (xy 11.757787 -395.53053)
			(xy 11.712429 -395.498079) (xy 11.67228 -395.45937) (xy 11.638194 -395.415227) (xy 11.610898 -395.366592)
			(xy 11.590975 -395.314501) (xy 11.578849 -395.260064) (xy 11.574778 -395.204442) (xy 10.78302 -395.204442)
			(xy 10.783062 -395.206728) (xy 10.782553 -395.234614) (xy 10.774433 -395.28979) (xy 10.758365 -395.343197)
			(xy 10.734693 -395.393694) (xy 10.70392 -395.440207) (xy 10.666703 -395.481744) (xy 10.623835 -395.517419)
			(xy 10.576229 -395.546473) (xy 10.5249 -395.568285) (xy 10.470943 -395.582391) (xy 10.415506 -395.588491)
			(xy 10.359772 -395.586454) (xy 10.304929 -395.576324) (xy 10.252145 -395.558317) (xy 10.202545 -395.532816)
			(xy 10.157187 -395.500365) (xy 10.117038 -395.461656) (xy 10.082952 -395.417513) (xy 10.055656 -395.368878)
			(xy 10.035733 -395.316787) (xy 10.023607 -395.26235) (xy 10.019536 -395.206728) (xy 0.6096 -395.206728)
			(xy 0.6096 -398.164722) (xy 3.141726 -398.164722) (xy 3.141726 -398.035362) (xy 3.149849 -397.906256)
			(xy 3.166062 -397.777916) (xy 3.190302 -397.650846) (xy 3.222472 -397.52555) (xy 3.262447 -397.40252)
			(xy 3.310068 -397.282244) (xy 3.365147 -397.165195) (xy 3.427467 -397.051835) (xy 3.496782 -396.942612)
			(xy 3.572818 -396.837957) (xy 3.655276 -396.738283) (xy 3.743829 -396.643983) (xy 3.838129 -396.55543)
			(xy 3.937803 -396.472972) (xy 4.042458 -396.396936) (xy 4.151681 -396.327621) (xy 4.265041 -396.265301)
			(xy 4.38209 -396.210222) (xy 4.502366 -396.162601) (xy 4.625396 -396.122626) (xy 4.750692 -396.090456)
			(xy 4.877762 -396.066216) (xy 5.006102 -396.050003) (xy 5.135208 -396.04188) (xy 5.199888 -396.041372)
			(xy 6.800088 -396.041372) (xy 6.864769 -396.041866) (xy 6.993875 -396.049988) (xy 7.122217 -396.066201)
			(xy 7.249287 -396.090441) (xy 7.374584 -396.122612) (xy 7.497614 -396.162587) (xy 7.617892 -396.210208)
			(xy 7.734942 -396.265287) (xy 7.848302 -396.327608) (xy 7.957526 -396.396923) (xy 8.062181 -396.47296)
			(xy 8.161856 -396.555418) (xy 8.256157 -396.643972) (xy 8.344711 -396.738272) (xy 8.427169 -396.837947)
			(xy 8.503206 -396.942603) (xy 8.572521 -397.051826) (xy 8.634842 -397.165187) (xy 8.689921 -397.282236)
			(xy 8.737543 -397.402514) (xy 8.777518 -397.525544) (xy 8.809688 -397.650841) (xy 8.833928 -397.777911)
			(xy 8.835476 -397.790162) (xy 27.42438 -397.790162) (xy 27.424954 -397.757433) (xy 27.433808 -397.692575)
			(xy 27.451296 -397.629495) (xy 27.477101 -397.569336) (xy 27.493468 -397.540988) (xy 27.496784 -397.534964)
			(xy 27.500389 -397.5217) (xy 27.50058 -397.514826) (xy 27.50058 -396.765526) (xy 27.50038 -396.758653)
			(xy 27.496778 -396.74539) (xy 27.493468 -396.739364) (xy 27.477095 -396.711019) (xy 27.451293 -396.650858)
			(xy 27.433805 -396.587778) (xy 27.424948 -396.522919) (xy 27.42438 -396.49019) (xy 27.424967 -396.457461)
			(xy 27.433817 -396.392604) (xy 27.451301 -396.329524) (xy 27.477102 -396.269365) (xy 27.493468 -396.241016)
			(xy 27.496774 -396.234987) (xy 27.500386 -396.221727) (xy 27.50058 -396.214854) (xy 27.50058 -395.92885)
			(xy 27.501069 -395.918722) (xy 27.508787 -395.899994) (xy 27.523074 -395.885635) (xy 27.541762 -395.877821)
			(xy 27.551888 -395.877288) (xy 28.268168 -395.877288) (xy 28.278319 -395.877747) (xy 28.297068 -395.88553)
			(xy 28.311392 -395.899915) (xy 28.319095 -395.918698) (xy 28.319476 -395.92885) (xy 28.319476 -396.214854)
			(xy 28.319688 -396.221726) (xy 28.323283 -396.234988) (xy 28.326588 -396.241016) (xy 28.342959 -396.269362)
			(xy 28.36876 -396.329523) (xy 28.386248 -396.392603) (xy 28.395107 -396.457461) (xy 28.395676 -396.49019)
			(xy 28.395131 -396.52292) (xy 28.38627 -396.587779) (xy 28.368773 -396.65086) (xy 28.34296 -396.711017)
			(xy 28.326588 -396.739364) (xy 28.323285 -396.745394) (xy 28.319672 -396.758654) (xy 28.319476 -396.765526)
			(xy 28.319476 -397.514826) (xy 28.319661 -397.5217) (xy 28.323274 -397.534962) (xy 28.326588 -397.540988)
			(xy 28.335995 -397.557291) (xy 29.624885 -397.557291) (xy 29.633667 -397.492447) (xy 29.651073 -397.429369)
			(xy 29.676787 -397.369198) (xy 29.693108 -397.340836) (xy 29.696411 -397.334805) (xy 29.700024 -397.321546)
			(xy 29.70022 -397.314674) (xy 29.70022 -397.028924) (xy 29.700641 -397.018769) (xy 29.708433 -397.000013)
			(xy 29.72283 -396.985688) (xy 29.741625 -396.977991) (xy 29.751782 -396.977616) (xy 30.468062 -396.977616)
			(xy 30.478183 -396.978157) (xy 30.496899 -396.985868) (xy 30.511256 -397.000138) (xy 30.51908 -397.018806)
			(xy 30.519624 -397.028924) (xy 30.519624 -397.314674) (xy 30.519823 -397.321547) (xy 30.523426 -397.33481)
			(xy 30.526736 -397.340836) (xy 30.543067 -397.369192) (xy 30.568786 -397.429364) (xy 30.586194 -397.492444)
			(xy 30.594977 -397.55729) (xy 30.594976 -397.622727) (xy 30.58619 -397.687573) (xy 30.56878 -397.750652)
			(xy 30.54306 -397.810823) (xy 30.536116 -397.822887) (xy 31.825 -397.822887) (xy 31.825005 -397.757448)
			(xy 31.833793 -397.692601) (xy 31.851207 -397.629521) (xy 31.876931 -397.569349) (xy 31.893256 -397.540988)
			(xy 31.896571 -397.534964) (xy 31.900177 -397.5217) (xy 31.900368 -397.514826) (xy 31.900368 -396.765526)
			(xy 31.90017 -396.758653) (xy 31.896566 -396.74539) (xy 31.893256 -396.739364) (xy 31.876925 -396.711008)
			(xy 31.851207 -396.650835) (xy 31.833799 -396.587756) (xy 31.825016 -396.52291) (xy 31.825018 -396.457473)
			(xy 31.833803 -396.392627) (xy 31.851213 -396.329548) (xy 31.876933 -396.269377) (xy 31.893256 -396.241016)
			(xy 31.896561 -396.234987) (xy 31.900173 -396.221727) (xy 31.900368 -396.214854) (xy 31.900368 -395.92885)
			(xy 31.900805 -395.918678) (xy 31.90858 -395.899879) (xy 31.922962 -395.885491) (xy 31.941758 -395.877709)
			(xy 31.95193 -395.877288) (xy 32.66821 -395.877288) (xy 32.678388 -395.877657) (xy 32.697193 -395.885455)
			(xy 32.711579 -395.899858) (xy 32.719355 -395.918671) (xy 32.719772 -395.92885) (xy 32.719772 -396.214854)
			(xy 32.719985 -396.221726) (xy 32.723579 -396.234988) (xy 32.726884 -396.241016) (xy 32.743197 -396.269382)
			(xy 32.768914 -396.329552) (xy 32.786322 -396.39263) (xy 32.795107 -396.457474) (xy 32.795108 -396.522909)
			(xy 32.786326 -396.587753) (xy 32.76892 -396.650831) (xy 32.743205 -396.711003) (xy 32.726884 -396.739364)
			(xy 32.723581 -396.745394) (xy 32.719968 -396.758654) (xy 32.719772 -396.765526) (xy 32.719772 -397.514826)
			(xy 32.719958 -397.5217) (xy 32.723571 -397.534962) (xy 32.726884 -397.540988) (xy 32.743173 -397.569367)
			(xy 32.768893 -397.629534) (xy 32.786304 -397.692609) (xy 32.795091 -397.757451) (xy 32.795095 -397.822884)
			(xy 32.786317 -397.887727) (xy 32.768914 -397.950804) (xy 32.743203 -398.010975) (xy 32.726884 -398.039336)
			(xy 32.723555 -398.045354) (xy 32.719959 -398.058623) (xy 32.719772 -398.065498) (xy 32.719772 -398.351502)
			(xy 32.719268 -398.361659) (xy 32.711495 -398.380426) (xy 32.697133 -398.394791) (xy 32.678367 -398.402567)
			(xy 32.66821 -398.403064) (xy 31.95193 -398.403064) (xy 31.941761 -398.402611) (xy 31.922967 -398.394837)
			(xy 31.908581 -398.38046) (xy 31.900795 -398.361671) (xy 31.900368 -398.351502) (xy 31.900368 -398.065498)
			(xy 31.900181 -398.058624) (xy 31.89657 -398.045361) (xy 31.893256 -398.039336) (xy 31.876901 -398.010993)
			(xy 31.851186 -397.950818) (xy 31.83378 -397.887735) (xy 31.825 -397.822887) (xy 30.536116 -397.822887)
			(xy 30.526736 -397.839184) (xy 30.52343 -397.845213) (xy 30.519818 -397.858473) (xy 30.519624 -397.865346)
			(xy 30.519624 -398.6149) (xy 30.519813 -398.621773) (xy 30.523423 -398.635036) (xy 30.526736 -398.641062)
			(xy 30.54309 -398.669406) (xy 30.568806 -398.729581) (xy 30.586211 -398.792663) (xy 30.594991 -398.857511)
			(xy 30.594989 -398.890236) (xy 34.024316 -398.890236) (xy 34.024873 -398.857506) (xy 34.033731 -398.792648)
			(xy 34.051224 -398.729567) (xy 34.077034 -398.66941) (xy 34.093404 -398.641062) (xy 34.096733 -398.635044)
			(xy 34.100329 -398.621775) (xy 34.100516 -398.6149) (xy 34.100516 -397.865346) (xy 34.100305 -397.858474)
			(xy 34.09671 -397.845211) (xy 34.093404 -397.839184) (xy 34.077032 -397.810838) (xy 34.051232 -397.750677)
			(xy 34.033744 -397.687597) (xy 34.024885 -397.622739) (xy 34.024316 -397.59001) (xy 34.024862 -397.55728)
			(xy 34.033723 -397.492421) (xy 34.051219 -397.429341) (xy 34.077033 -397.369183) (xy 34.093404 -397.340836)
			(xy 34.096706 -397.334805) (xy 34.10032 -397.321546) (xy 34.100516 -397.314674) (xy 34.100516 -397.028924)
			(xy 34.100936 -397.018801) (xy 34.108679 -397.000095) (xy 34.122995 -396.985779) (xy 34.141701 -396.978036)
			(xy 34.151824 -396.977616) (xy 34.868104 -396.977616) (xy 34.878229 -396.978013) (xy 34.896935 -396.985766)
			(xy 34.91125 -397.000088) (xy 34.918992 -397.018799) (xy 34.919412 -397.028924) (xy 34.919412 -397.314674)
			(xy 34.919613 -397.321547) (xy 34.923215 -397.334809) (xy 34.926524 -397.340836) (xy 34.942906 -397.369176)
			(xy 34.968704 -397.429339) (xy 34.986188 -397.492421) (xy 34.995044 -397.55728) (xy 34.995612 -397.59001)
			(xy 34.995027 -397.622739) (xy 34.986176 -397.687596) (xy 34.968692 -397.750676) (xy 34.951757 -397.790162)
			(xy 36.224464 -397.790162) (xy 36.22504 -397.757433) (xy 36.233893 -397.692575) (xy 36.251381 -397.629495)
			(xy 36.277185 -397.569336) (xy 36.293552 -397.540988) (xy 36.296867 -397.534964) (xy 36.300473 -397.5217)
			(xy 36.300664 -397.514826) (xy 36.300664 -396.765526) (xy 36.300467 -396.758653) (xy 36.296863 -396.74539)
			(xy 36.293552 -396.739364) (xy 36.277177 -396.71102) (xy 36.251376 -396.650859) (xy 36.233889 -396.587778)
			(xy 36.225032 -396.52292) (xy 36.224464 -396.49019) (xy 36.225053 -396.457461) (xy 36.233903 -396.392604)
			(xy 36.251386 -396.329524) (xy 36.277187 -396.269365) (xy 36.293552 -396.241016) (xy 36.296857 -396.234987)
			(xy 36.300469 -396.221727) (xy 36.300664 -396.214854) (xy 36.300664 -395.92885) (xy 36.301168 -395.918724)
			(xy 36.308884 -395.899999) (xy 36.323166 -395.88564) (xy 36.341848 -395.877823) (xy 36.351972 -395.877288)
			(xy 37.068252 -395.877288) (xy 37.078402 -395.877761) (xy 37.097151 -395.885538) (xy 37.111475 -395.899919)
			(xy 37.119179 -395.918699) (xy 37.11956 -395.92885) (xy 37.11956 -396.214854) (xy 37.119774 -396.221726)
			(xy 37.123368 -396.234988) (xy 37.126672 -396.241016) (xy 37.143041 -396.269363) (xy 37.168843 -396.329523)
			(xy 37.186332 -396.392603) (xy 37.195191 -396.457461) (xy 37.19576 -396.49019) (xy 37.195204 -396.52292)
			(xy 37.186344 -396.587778) (xy 37.168851 -396.650858) (xy 37.143041 -396.711016) (xy 37.126672 -396.739364)
			(xy 37.123368 -396.745394) (xy 37.119756 -396.758654) (xy 37.11956 -396.765526) (xy 37.11956 -397.514826)
			(xy 37.119747 -397.5217) (xy 37.123359 -397.534962) (xy 37.126672 -397.540988) (xy 37.136078 -397.557291)
			(xy 38.424972 -397.557291) (xy 38.433753 -397.492447) (xy 38.451158 -397.429369) (xy 38.476872 -397.369198)
			(xy 38.493192 -397.340836) (xy 38.496493 -397.334805) (xy 38.500108 -397.321546) (xy 38.500304 -397.314674)
			(xy 38.500304 -397.028924) (xy 38.500741 -397.018771) (xy 38.50853 -397.000018) (xy 38.522922 -396.985694)
			(xy 38.541711 -396.977994) (xy 38.551866 -396.977616) (xy 39.268146 -396.977616) (xy 39.278273 -396.978088)
			(xy 39.29699 -396.985827) (xy 39.311344 -397.000117) (xy 39.319166 -397.0188) (xy 39.319708 -397.028924)
			(xy 39.319708 -397.314674) (xy 39.319909 -397.321547) (xy 39.323511 -397.334809) (xy 39.32682 -397.340836)
			(xy 39.343152 -397.369192) (xy 39.368871 -397.429364) (xy 39.38628 -397.492444) (xy 39.395063 -397.55729)
			(xy 39.395062 -397.622728) (xy 39.386276 -397.687573) (xy 39.368865 -397.750652) (xy 39.351976 -397.790162)
			(xy 40.624252 -397.790162) (xy 40.624829 -397.757433) (xy 40.633683 -397.692575) (xy 40.65117 -397.629495)
			(xy 40.676973 -397.569337) (xy 40.69334 -397.540988) (xy 40.696654 -397.534963) (xy 40.700261 -397.5217)
			(xy 40.700452 -397.514826) (xy 40.700452 -396.765526) (xy 40.700256 -396.758653) (xy 40.696651 -396.74539)
			(xy 40.69334 -396.739364) (xy 40.676964 -396.71102) (xy 40.651164 -396.650859) (xy 40.633677 -396.587778)
			(xy 40.62482 -396.52292) (xy 40.624252 -396.49019) (xy 40.624842 -396.457461) (xy 40.633691 -396.392604)
			(xy 40.651175 -396.329524) (xy 40.676975 -396.269365) (xy 40.69334 -396.241016) (xy 40.696644 -396.234986)
			(xy 40.700257 -396.221727) (xy 40.700452 -396.214854) (xy 40.700452 -395.92885) (xy 40.700968 -395.918725)
			(xy 40.708682 -395.900003) (xy 40.722959 -395.885644) (xy 40.741638 -395.877825) (xy 40.75176 -395.877288)
			(xy 41.46804 -395.877288) (xy 41.478195 -395.877689) (xy 41.496946 -395.885495) (xy 41.511268 -395.899898)
			(xy 41.518968 -395.918693) (xy 41.519348 -395.92885) (xy 41.519348 -396.214854) (xy 41.519551 -396.221726)
			(xy 41.523151 -396.23499) (xy 41.52646 -396.241016) (xy 41.542828 -396.269364) (xy 41.56863 -396.329524)
			(xy 41.586119 -396.392604) (xy 41.594979 -396.457461) (xy 41.595548 -396.49019) (xy 41.594994 -396.52292)
			(xy 41.586134 -396.587778) (xy 41.56864 -396.650858) (xy 41.54283 -396.711016) (xy 41.52646 -396.739364)
			(xy 41.523163 -396.745397) (xy 41.519545 -396.758654) (xy 41.519348 -396.765526) (xy 41.519348 -397.514826)
			(xy 41.519524 -397.5217) (xy 41.523143 -397.534963) (xy 41.52646 -397.540988) (xy 41.542817 -397.569342)
			(xy 41.568622 -397.6295) (xy 41.586114 -397.692578) (xy 41.594977 -397.757433) (xy 41.595548 -397.790162)
			(xy 41.594981 -397.822891) (xy 41.586125 -397.887749) (xy 41.568635 -397.95083) (xy 41.542828 -398.010988)
			(xy 41.52646 -398.039336) (xy 41.523137 -398.045357) (xy 41.519536 -398.058623) (xy 41.519348 -398.065498)
			(xy 41.519348 -398.351502) (xy 41.518875 -398.36163) (xy 41.511144 -398.380354) (xy 41.496853 -398.39471)
			(xy 41.478166 -398.402527) (xy 41.46804 -398.403064) (xy 40.75176 -398.403064) (xy 40.741599 -398.40271)
			(xy 40.722839 -398.394895) (xy 40.708515 -398.380477) (xy 40.700824 -398.361666) (xy 40.700452 -398.351502)
			(xy 40.700452 -398.065498) (xy 40.700267 -398.058624) (xy 40.696655 -398.045361) (xy 40.69334 -398.039336)
			(xy 40.676993 -398.010977) (xy 40.651185 -397.950821) (xy 40.633691 -397.887745) (xy 40.624825 -397.82289)
			(xy 40.624252 -397.790162) (xy 39.351976 -397.790162) (xy 39.343144 -397.810823) (xy 39.32682 -397.839184)
			(xy 39.323512 -397.845212) (xy 39.319902 -397.858473) (xy 39.319708 -397.865346) (xy 39.319708 -398.6149)
			(xy 39.319899 -398.621773) (xy 39.323508 -398.635036) (xy 39.32682 -398.641062) (xy 39.343174 -398.669406)
			(xy 39.368891 -398.729581) (xy 39.386297 -398.792663) (xy 39.395078 -398.857511) (xy 39.395076 -398.890236)
			(xy 42.8244 -398.890236) (xy 42.82496 -398.857506) (xy 42.833817 -398.792648) (xy 42.851309 -398.729568)
			(xy 42.877119 -398.66941) (xy 42.893488 -398.641062) (xy 42.896815 -398.635044) (xy 42.900413 -398.621775)
			(xy 42.9006 -398.6149) (xy 42.9006 -397.865346) (xy 42.90039 -397.858474) (xy 42.896794 -397.845211)
			(xy 42.893488 -397.839184) (xy 42.877115 -397.810839) (xy 42.851315 -397.750678) (xy 42.833828 -397.687597)
			(xy 42.824969 -397.622739) (xy 42.8244 -397.59001) (xy 42.824948 -397.55728) (xy 42.833809 -397.492421)
			(xy 42.851304 -397.429341) (xy 42.877117 -397.369183) (xy 42.893488 -397.340836) (xy 42.896789 -397.334805)
			(xy 42.900404 -397.321546) (xy 42.9006 -397.314674) (xy 42.9006 -397.028924) (xy 42.901035 -397.018803)
			(xy 42.908776 -397.0001) (xy 42.923086 -396.985785) (xy 42.941787 -396.978039) (xy 42.951908 -396.977616)
			(xy 43.668188 -396.977616) (xy 43.678312 -396.978026) (xy 43.697018 -396.985773) (xy 43.711333 -397.000092)
			(xy 43.719076 -397.0188) (xy 43.719496 -397.028924) (xy 43.719496 -397.314674) (xy 43.719698 -397.321546)
			(xy 43.723299 -397.334809) (xy 43.726608 -397.340836) (xy 43.742989 -397.369177) (xy 43.768787 -397.42934)
			(xy 43.786272 -397.492422) (xy 43.795128 -397.55728) (xy 43.795696 -397.59001) (xy 43.795113 -397.622739)
			(xy 43.786262 -397.687597) (xy 43.768777 -397.750677) (xy 43.742974 -397.810835) (xy 43.736016 -397.822887)
			(xy 45.024876 -397.822887) (xy 45.024881 -397.757448) (xy 45.033669 -397.692601) (xy 45.051081 -397.629521)
			(xy 45.076804 -397.569349) (xy 45.093128 -397.540988) (xy 45.096449 -397.534966) (xy 45.10005 -397.5217)
			(xy 45.10024 -397.514826) (xy 45.10024 -396.765526) (xy 45.100033 -396.758654) (xy 45.096435 -396.745391)
			(xy 45.093128 -396.739364) (xy 45.076798 -396.711007) (xy 45.051081 -396.650835) (xy 45.033675 -396.587755)
			(xy 45.024892 -396.52291) (xy 45.024893 -396.457473) (xy 45.033678 -396.392628) (xy 45.051087 -396.329549)
			(xy 45.076805 -396.269377) (xy 45.093128 -396.241016) (xy 45.096439 -396.23499) (xy 45.100047 -396.221727)
			(xy 45.10024 -396.214854) (xy 45.10024 -395.92885) (xy 45.100705 -395.918681) (xy 45.108474 -395.899887)
			(xy 45.122847 -395.885501) (xy 45.141634 -395.877714) (xy 45.151802 -395.877288) (xy 45.868082 -395.877288)
			(xy 45.878259 -395.87768) (xy 45.897063 -395.885468) (xy 45.91145 -395.899864) (xy 45.919227 -395.918673)
			(xy 45.919644 -395.92885) (xy 45.919644 -396.214854) (xy 45.919848 -396.221726) (xy 45.923447 -396.234989)
			(xy 45.926756 -396.241016) (xy 45.94307 -396.269382) (xy 45.968789 -396.329552) (xy 45.986198 -396.39263)
			(xy 45.994982 -396.457473) (xy 45.994984 -396.522909) (xy 45.986201 -396.587754) (xy 45.968794 -396.650832)
			(xy 45.943078 -396.711003) (xy 45.926756 -396.739364) (xy 45.923458 -396.745397) (xy 45.919841 -396.758654)
			(xy 45.919644 -396.765526) (xy 45.919644 -397.514826) (xy 45.919821 -397.5217) (xy 45.923439 -397.534963)
			(xy 45.926756 -397.540988) (xy 45.943046 -397.569367) (xy 45.968767 -397.629534) (xy 45.986179 -397.692609)
			(xy 45.994967 -397.75745) (xy 45.994971 -397.822884) (xy 45.986192 -397.887727) (xy 45.968789 -397.950804)
			(xy 45.943076 -398.010975) (xy 45.926756 -398.039336) (xy 45.923433 -398.045357) (xy 45.919832 -398.058623)
			(xy 45.919644 -398.065498) (xy 45.919644 -398.351502) (xy 45.919237 -398.361676) (xy 45.911448 -398.380474)
			(xy 45.897057 -398.39486) (xy 45.878256 -398.402641) (xy 45.868082 -398.403064) (xy 45.151802 -398.403064)
			(xy 45.141645 -398.402565) (xy 45.122876 -398.394792) (xy 45.108511 -398.380427) (xy 45.100736 -398.361659)
			(xy 45.10024 -398.351502) (xy 45.10024 -398.065498) (xy 45.100044 -398.058625) (xy 45.096438 -398.045363)
			(xy 45.093128 -398.039336) (xy 45.076774 -398.010992) (xy 45.05106 -397.950817) (xy 45.033656 -397.887735)
			(xy 45.024876 -397.822887) (xy 43.736016 -397.822887) (xy 43.726608 -397.839184) (xy 43.7233 -397.845212)
			(xy 43.71969 -397.858473) (xy 43.719496 -397.865346) (xy 43.719496 -398.6149) (xy 43.719688 -398.621773)
			(xy 43.723296 -398.635036) (xy 43.726608 -398.641062) (xy 43.742959 -398.669419) (xy 43.768764 -398.729576)
			(xy 43.786258 -398.792653) (xy 43.795123 -398.857508) (xy 43.795696 -398.890236) (xy 43.795124 -398.922965)
			(xy 43.78627 -398.987823) (xy 43.768782 -399.050904) (xy 43.742976 -399.111062) (xy 43.726608 -399.13941)
			(xy 43.72329 -399.145433) (xy 43.719686 -399.158698) (xy 43.719496 -399.165572) (xy 43.719496 -399.451576)
			(xy 43.719064 -399.461697) (xy 43.711323 -399.480401) (xy 43.697011 -399.494717) (xy 43.678309 -399.502462)
			(xy 43.668188 -399.502884) (xy 42.951908 -399.502884) (xy 42.941784 -399.502477) (xy 42.923078 -399.494729)
			(xy 42.908762 -399.480409) (xy 42.90102 -399.4617) (xy 42.9006 -399.451576) (xy 42.9006 -399.165572)
			(xy 42.900419 -399.158698) (xy 42.896803 -399.145435) (xy 42.893488 -399.13941) (xy 42.877125 -399.111059)
			(xy 42.851323 -399.0509) (xy 42.833833 -398.987821) (xy 42.824971 -398.922965) (xy 42.8244 -398.890236)
			(xy 39.395076 -398.890236) (xy 39.395074 -398.922951) (xy 39.386285 -398.987798) (xy 39.36887 -399.050878)
			(xy 39.343146 -399.111049) (xy 39.32682 -399.13941) (xy 39.323503 -399.145434) (xy 39.319898 -399.158698)
			(xy 39.319708 -399.165572) (xy 39.319708 -399.451576) (xy 39.319259 -399.461728) (xy 39.311473 -399.480478)
			(xy 39.297085 -399.494802) (xy 39.278299 -399.502504) (xy 39.268146 -399.502884) (xy 38.551866 -399.502884)
			(xy 38.54174 -399.502402) (xy 38.523023 -399.494668) (xy 38.508668 -399.48038) (xy 38.500846 -399.4617)
			(xy 38.500304 -399.451576) (xy 38.500304 -399.165572) (xy 38.500122 -399.158698) (xy 38.496507 -399.145435)
			(xy 38.493192 -399.13941) (xy 38.476902 -399.111031) (xy 38.451184 -399.050864) (xy 38.433774 -398.987789)
			(xy 38.424988 -398.922948) (xy 38.424983 -398.857514) (xy 38.433762 -398.792672) (xy 38.451163 -398.729595)
			(xy 38.476874 -398.669424) (xy 38.493192 -398.641062) (xy 38.49652 -398.635044) (xy 38.500117 -398.621775)
			(xy 38.500304 -398.6149) (xy 38.500304 -397.865346) (xy 38.500094 -397.858474) (xy 38.496498 -397.845211)
			(xy 38.493192 -397.839184) (xy 38.47688 -397.810818) (xy 38.451164 -397.750647) (xy 38.433756 -397.68757)
			(xy 38.424973 -397.622726) (xy 38.424972 -397.557291) (xy 37.136078 -397.557291) (xy 37.14303 -397.569341)
			(xy 37.168834 -397.629499) (xy 37.186326 -397.692577) (xy 37.195189 -397.757433) (xy 37.19576 -397.790162)
			(xy 37.195192 -397.822891) (xy 37.186335 -397.887749) (xy 37.168846 -397.950829) (xy 37.14304 -398.010988)
			(xy 37.126672 -398.039336) (xy 37.123343 -398.045353) (xy 37.119747 -398.058623) (xy 37.11956 -398.065498)
			(xy 37.11956 -398.351502) (xy 37.119075 -398.361629) (xy 37.111347 -398.38035) (xy 37.09706 -398.394706)
			(xy 37.078376 -398.402525) (xy 37.068252 -398.403064) (xy 36.351972 -398.403064) (xy 36.341812 -398.402701)
			(xy 36.323052 -398.394889) (xy 36.308728 -398.380474) (xy 36.301036 -398.361665) (xy 36.300664 -398.351502)
			(xy 36.300664 -398.065498) (xy 36.300477 -398.058624) (xy 36.296866 -398.045361) (xy 36.293552 -398.039336)
			(xy 36.277206 -398.010976) (xy 36.251398 -397.950821) (xy 36.233903 -397.887745) (xy 36.225037 -397.82289)
			(xy 36.224464 -397.790162) (xy 34.951757 -397.790162) (xy 34.94289 -397.810835) (xy 34.926524 -397.839184)
			(xy 34.923217 -397.845212) (xy 34.919606 -397.858473) (xy 34.919412 -397.865346) (xy 34.919412 -398.6149)
			(xy 34.919603 -398.621773) (xy 34.923212 -398.635036) (xy 34.926524 -398.641062) (xy 34.942877 -398.669418)
			(xy 34.968681 -398.729575) (xy 34.986174 -398.792653) (xy 34.995039 -398.857508) (xy 34.995612 -398.890236)
			(xy 34.995038 -398.922965) (xy 34.986185 -398.987823) (xy 34.968696 -399.050903) (xy 34.942891 -399.111062)
			(xy 34.926524 -399.13941) (xy 34.923207 -399.145434) (xy 34.919602 -399.158698) (xy 34.919412 -399.165572)
			(xy 34.919412 -399.451576) (xy 34.918965 -399.461695) (xy 34.911227 -399.480396) (xy 34.89692 -399.494711)
			(xy 34.878223 -399.502459) (xy 34.868104 -399.502884) (xy 34.151824 -399.502884) (xy 34.141701 -399.502464)
			(xy 34.122995 -399.494721) (xy 34.108679 -399.480405) (xy 34.100936 -399.461699) (xy 34.100516 -399.451576)
			(xy 34.100516 -399.165572) (xy 34.100333 -399.158698) (xy 34.096718 -399.145435) (xy 34.093404 -399.13941)
			(xy 34.077043 -399.111058) (xy 34.05124 -399.0509) (xy 34.033749 -398.987821) (xy 34.024887 -398.922965)
			(xy 34.024316 -398.890236) (xy 30.594989 -398.890236) (xy 30.594987 -398.922951) (xy 30.586199 -398.987797)
			(xy 30.568785 -399.050877) (xy 30.543061 -399.111049) (xy 30.526736 -399.13941) (xy 30.523421 -399.145434)
			(xy 30.519815 -399.158698) (xy 30.519624 -399.165572) (xy 30.519624 -399.451576) (xy 30.519159 -399.461726)
			(xy 30.511376 -399.480473) (xy 30.496993 -399.494796) (xy 30.478213 -399.502501) (xy 30.468062 -399.502884)
			(xy 29.751782 -399.502884) (xy 29.741657 -399.502389) (xy 29.72294 -399.49466) (xy 29.708585 -399.480377)
			(xy 29.700762 -399.461698) (xy 29.70022 -399.451576) (xy 29.70022 -399.165572) (xy 29.700036 -399.158698)
			(xy 29.696422 -399.145436) (xy 29.693108 -399.13941) (xy 29.676817 -399.111032) (xy 29.651098 -399.050864)
			(xy 29.633688 -398.987789) (xy 29.624901 -398.922948) (xy 29.624897 -398.857514) (xy 29.633676 -398.792672)
			(xy 29.651078 -398.729594) (xy 29.676789 -398.669424) (xy 29.693108 -398.641062) (xy 29.696437 -398.635044)
			(xy 29.700033 -398.621775) (xy 29.70022 -398.6149) (xy 29.70022 -397.865346) (xy 29.700008 -397.858474)
			(xy 29.696413 -397.845212) (xy 29.693108 -397.839184) (xy 29.676795 -397.810818) (xy 29.651078 -397.750647)
			(xy 29.633671 -397.68757) (xy 29.624887 -397.622726) (xy 29.624885 -397.557291) (xy 28.335995 -397.557291)
			(xy 28.342948 -397.569341) (xy 28.368751 -397.629499) (xy 28.386243 -397.692577) (xy 28.395105 -397.757433)
			(xy 28.395676 -397.790162) (xy 28.395119 -397.822892) (xy 28.386261 -397.887751) (xy 28.368768 -397.950831)
			(xy 28.342958 -398.010988) (xy 28.326588 -398.039336) (xy 28.32326 -398.045354) (xy 28.319663 -398.058623)
			(xy 28.319476 -398.065498) (xy 28.319476 -398.351502) (xy 28.318975 -398.361627) (xy 28.31125 -398.380345)
			(xy 28.296968 -398.394701) (xy 28.27829 -398.402523) (xy 28.268168 -398.403064) (xy 27.551888 -398.403064)
			(xy 27.541729 -398.402688) (xy 27.522969 -398.394881) (xy 27.508645 -398.38047) (xy 27.500952 -398.361664)
			(xy 27.50058 -398.351502) (xy 27.50058 -398.065498) (xy 27.500391 -398.058625) (xy 27.496781 -398.045362)
			(xy 27.493468 -398.039336) (xy 27.477123 -398.010975) (xy 27.451315 -397.95082) (xy 27.433819 -397.887744)
			(xy 27.424953 -397.82289) (xy 27.42438 -397.790162) (xy 8.835476 -397.790162) (xy 8.850142 -397.906253)
			(xy 8.858264 -398.035359) (xy 8.858264 -398.164721) (xy 8.850142 -398.293827) (xy 8.833928 -398.422169)
			(xy 8.809688 -398.549239) (xy 8.777518 -398.674536) (xy 8.737543 -398.797566) (xy 8.689921 -398.917844)
			(xy 8.634842 -399.034893) (xy 8.572521 -399.148254) (xy 8.503206 -399.257477) (xy 8.427169 -399.362133)
			(xy 8.344711 -399.461808) (xy 8.256157 -399.556108) (xy 8.161856 -399.644662) (xy 8.062181 -399.72712)
			(xy 7.957526 -399.803157) (xy 7.848302 -399.872472) (xy 7.734942 -399.934793) (xy 7.617892 -399.989872)
			(xy 7.497614 -400.037493) (xy 7.374584 -400.077468) (xy 7.249287 -400.109639) (xy 7.122217 -400.133879)
			(xy 6.993875 -400.150092) (xy 6.864769 -400.158214) (xy 6.800088 -400.158712) (xy 5.199888 -400.158712)
			(xy 5.135208 -400.158204) (xy 5.006102 -400.150081) (xy 4.877762 -400.133868) (xy 4.750692 -400.109628)
			(xy 4.625396 -400.077458) (xy 4.502366 -400.037483) (xy 4.38209 -399.989862) (xy 4.265041 -399.934783)
			(xy 4.151681 -399.872463) (xy 4.042458 -399.803148) (xy 3.937803 -399.727112) (xy 3.838129 -399.644654)
			(xy 3.743829 -399.556101) (xy 3.655276 -399.461801) (xy 3.572818 -399.362127) (xy 3.496782 -399.257472)
			(xy 3.427467 -399.148249) (xy 3.365147 -399.034889) (xy 3.310068 -398.91784) (xy 3.262447 -398.797564)
			(xy 3.222472 -398.674534) (xy 3.190302 -398.549238) (xy 3.166062 -398.422168) (xy 3.149849 -398.293828)
			(xy 3.141726 -398.164722) (xy 0.6096 -398.164722) (xy 0.6096 -401.690078) (xy 27.42438 -401.690078)
			(xy 27.424961 -401.657349) (xy 27.433813 -401.592491) (xy 27.451299 -401.529411) (xy 27.477102 -401.469253)
			(xy 27.493468 -401.440904) (xy 27.496779 -401.434877) (xy 27.500387 -401.421615) (xy 27.50058 -401.414742)
			(xy 27.50058 -400.665442) (xy 27.500374 -400.65857) (xy 27.496776 -400.645307) (xy 27.493468 -400.63928)
			(xy 27.477101 -400.610931) (xy 27.451298 -400.550772) (xy 27.433808 -400.487692) (xy 27.424949 -400.422835)
			(xy 27.42438 -400.390106) (xy 27.424929 -400.357376) (xy 27.43379 -400.292517) (xy 27.451285 -400.229437)
			(xy 27.477097 -400.169279) (xy 27.493468 -400.140932) (xy 27.496769 -400.1349) (xy 27.500383 -400.121642)
			(xy 27.50058 -400.11477) (xy 27.50058 -399.828766) (xy 27.501 -399.818632) (xy 27.508746 -399.799903)
			(xy 27.523053 -399.785546) (xy 27.541756 -399.777735) (xy 27.551888 -399.777204) (xy 28.268168 -399.777204)
			(xy 28.278321 -399.777648) (xy 28.297073 -399.785433) (xy 28.311398 -399.799824) (xy 28.319098 -399.818612)
			(xy 28.319476 -399.828766) (xy 28.319476 -400.11477) (xy 28.319682 -400.121642) (xy 28.323281 -400.134905)
			(xy 28.326588 -400.140932) (xy 28.342965 -400.169275) (xy 28.368764 -400.229437) (xy 28.386251 -400.292518)
			(xy 28.395108 -400.357376) (xy 28.395676 -400.390106) (xy 28.395094 -400.422835) (xy 28.386243 -400.487693)
			(xy 28.368758 -400.550773) (xy 28.342955 -400.610932) (xy 28.326588 -400.63928) (xy 28.32328 -400.645308)
			(xy 28.31967 -400.658569) (xy 28.319476 -400.665442) (xy 28.319476 -401.414742) (xy 28.319693 -401.421613)
			(xy 28.323284 -401.434876) (xy 28.326588 -401.440904) (xy 28.342954 -401.469253) (xy 28.368756 -401.529413)
			(xy 28.386246 -401.592492) (xy 28.395106 -401.657349) (xy 28.395676 -401.690078) (xy 28.395126 -401.722808)
			(xy 28.386266 -401.787667) (xy 28.368771 -401.850747) (xy 28.342959 -401.910905) (xy 28.326588 -401.939252)
			(xy 28.323254 -401.945267) (xy 28.319661 -401.958538) (xy 28.319476 -401.965414) (xy 28.319476 -402.251418)
			(xy 28.318989 -402.261544) (xy 28.311258 -402.280263) (xy 28.296972 -402.294618) (xy 28.278291 -402.302439)
			(xy 28.268168 -402.30298) (xy 27.551888 -402.30298) (xy 27.541731 -402.302588) (xy 27.522974 -402.294785)
			(xy 27.50865 -402.280379) (xy 27.500954 -402.261578) (xy 27.50058 -402.251418) (xy 27.50058 -401.965414)
			(xy 27.500385 -401.958541) (xy 27.496779 -401.945278) (xy 27.493468 -401.939252) (xy 27.47709 -401.91091)
			(xy 27.451289 -401.850748) (xy 27.433803 -401.787666) (xy 27.424947 -401.722808) (xy 27.42438 -401.690078)
			(xy 0.6096 -401.690078) (xy 0.6096 -402.232191) (xy 13.656034 -402.232191) (xy 13.656034 -402.177689)
			(xy 13.66379 -402.123741) (xy 13.679145 -402.071446) (xy 13.701786 -402.021868) (xy 13.731253 -401.976018)
			(xy 13.766944 -401.934827) (xy 13.808134 -401.899135) (xy 13.853985 -401.869668) (xy 13.903562 -401.847027)
			(xy 13.955857 -401.831671) (xy 14.009805 -401.823914) (xy 14.037056 -401.823428) (xy 14.063372 -401.823849)
			(xy 14.115503 -401.831092) (xy 14.166146 -401.84542) (xy 14.214345 -401.866561) (xy 14.259188 -401.894115)
			(xy 14.299825 -401.927562) (xy 14.31798 -401.946618) (xy 14.325505 -401.954016) (xy 14.344782 -401.962542)
			(xy 14.355318 -401.963128) (xy 14.429994 -401.963128) (xy 14.440544 -401.962601) (xy 14.459839 -401.954063)
			(xy 14.467332 -401.946618) (xy 14.487152 -401.92583) (xy 14.531924 -401.889855) (xy 14.581582 -401.860995)
			(xy 14.635004 -401.839902) (xy 14.690983 -401.827053) (xy 14.748256 -401.822738) (xy 14.805529 -401.827053)
			(xy 14.861508 -401.839902) (xy 14.91493 -401.860995) (xy 14.964588 -401.889855) (xy 15.00936 -401.92583)
			(xy 15.02918 -401.946618) (xy 15.036705 -401.954016) (xy 15.055982 -401.962542) (xy 15.066518 -401.963128)
			(xy 15.141194 -401.963128) (xy 15.151744 -401.962601) (xy 15.171039 -401.954063) (xy 15.178532 -401.946618)
			(xy 15.196683 -401.927557) (xy 15.237313 -401.8941) (xy 15.282154 -401.866541) (xy 15.330356 -401.845403)
			(xy 15.381005 -401.831088) (xy 15.433139 -401.823865) (xy 15.459456 -401.823428) (xy 15.486709 -401.823899)
			(xy 15.54066 -401.831655) (xy 15.592957 -401.847011) (xy 15.642537 -401.869653) (xy 15.688391 -401.899121)
			(xy 15.729583 -401.934814) (xy 15.765277 -401.976006) (xy 15.794745 -402.021859) (xy 15.817388 -402.071439)
			(xy 15.832744 -402.123737) (xy 15.840501 -402.177687) (xy 15.840501 -402.232193) (xy 15.832744 -402.286143)
			(xy 15.817388 -402.338441) (xy 15.794745 -402.388021) (xy 15.765277 -402.433874) (xy 15.729583 -402.475066)
			(xy 15.688391 -402.510759) (xy 15.642537 -402.540227) (xy 15.592957 -402.562869) (xy 15.54066 -402.578225)
			(xy 15.486709 -402.585981) (xy 15.459456 -402.586444) (xy 15.43314 -402.586024) (xy 15.381009 -402.578782)
			(xy 15.330365 -402.564455) (xy 15.282165 -402.543313) (xy 15.237323 -402.515758) (xy 15.196686 -402.48231)
			(xy 15.178532 -402.463254) (xy 15.170993 -402.455873) (xy 15.151727 -402.447335) (xy 15.141194 -402.446744)
			(xy 15.066518 -402.446744) (xy 15.055966 -402.447256) (xy 15.03667 -402.455802) (xy 15.02918 -402.463254)
			(xy 15.00936 -402.484042) (xy 14.964588 -402.520017) (xy 14.91493 -402.548877) (xy 14.861508 -402.56997)
			(xy 14.805529 -402.582819) (xy 14.748256 -402.587134) (xy 14.690983 -402.582819) (xy 14.635004 -402.56997)
			(xy 14.581582 -402.548877) (xy 14.531924 -402.520017) (xy 14.487152 -402.484042) (xy 14.467332 -402.463254)
			(xy 14.459793 -402.455873) (xy 14.440527 -402.447335) (xy 14.429994 -402.446744) (xy 14.355318 -402.446744)
			(xy 14.344766 -402.447256) (xy 14.32547 -402.455802) (xy 14.31798 -402.463254) (xy 14.299838 -402.482323)
			(xy 14.259204 -402.515776) (xy 14.214361 -402.543332) (xy 14.166157 -402.564468) (xy 14.115508 -402.578783)
			(xy 14.063373 -402.586006) (xy 14.037056 -402.586444) (xy 14.009805 -402.585966) (xy 13.955857 -402.578209)
			(xy 13.903562 -402.562853) (xy 13.853985 -402.540212) (xy 13.808134 -402.510745) (xy 13.766944 -402.475053)
			(xy 13.731253 -402.433862) (xy 13.701786 -402.388012) (xy 13.679145 -402.338434) (xy 13.66379 -402.286139)
			(xy 13.656034 -402.232191) (xy 0.6096 -402.232191) (xy 0.6096 -402.822879) (xy 29.624853 -402.822879)
			(xy 29.624859 -402.757439) (xy 29.633648 -402.692592) (xy 29.651061 -402.629512) (xy 29.676784 -402.56934)
			(xy 29.693108 -402.540978) (xy 29.696431 -402.534958) (xy 29.700031 -402.521691) (xy 29.70022 -402.514816)
			(xy 29.70022 -401.765516) (xy 29.70002 -401.758643) (xy 29.696417 -401.745381) (xy 29.693108 -401.739354)
			(xy 29.67677 -401.711002) (xy 29.651055 -401.650828) (xy 29.63365 -401.587748) (xy 29.624869 -401.522902)
			(xy 29.624872 -401.457464) (xy 29.633657 -401.392619) (xy 29.651067 -401.329539) (xy 29.676785 -401.269368)
			(xy 29.693108 -401.241006) (xy 29.696421 -401.234981) (xy 29.700028 -401.221717) (xy 29.70022 -401.214844)
			(xy 29.70022 -400.92884) (xy 29.700655 -400.918686) (xy 29.708441 -400.899931) (xy 29.722834 -400.885605)
			(xy 29.741626 -400.877908) (xy 29.751782 -400.877532) (xy 30.468062 -400.877532) (xy 30.478185 -400.878058)
			(xy 30.496904 -400.885771) (xy 30.511261 -400.900046) (xy 30.519083 -400.91872) (xy 30.519624 -400.92884)
			(xy 30.519624 -401.214844) (xy 30.519834 -401.221716) (xy 30.52343 -401.234979) (xy 30.526736 -401.241006)
			(xy 30.543042 -401.269376) (xy 30.568763 -401.329545) (xy 30.586173 -401.392622) (xy 30.59496 -401.457465)
			(xy 30.594962 -401.522901) (xy 30.58618 -401.587744) (xy 30.568774 -401.650822) (xy 30.543058 -401.710993)
			(xy 30.536263 -401.7228) (xy 31.82501 -401.7228) (xy 31.825012 -401.657362) (xy 31.833799 -401.592516)
			(xy 31.85121 -401.529437) (xy 31.876932 -401.469265) (xy 31.893256 -401.440904) (xy 31.896566 -401.434877)
			(xy 31.900175 -401.421615) (xy 31.900368 -401.414742) (xy 31.900368 -400.665442) (xy 31.900164 -400.65857)
			(xy 31.896564 -400.645307) (xy 31.893256 -400.63928) (xy 31.876938 -400.610916) (xy 31.851219 -400.550746)
			(xy 31.83381 -400.487668) (xy 31.825026 -400.422823) (xy 31.825025 -400.357387) (xy 31.833808 -400.292543)
			(xy 31.851216 -400.229464) (xy 31.876934 -400.169293) (xy 31.893256 -400.140932) (xy 31.896556 -400.1349)
			(xy 31.900171 -400.121642) (xy 31.900368 -400.11477) (xy 31.900368 -399.828766) (xy 31.900806 -399.818602)
			(xy 31.908597 -399.799827) (xy 31.92298 -399.785462) (xy 31.941766 -399.777694) (xy 31.95193 -399.777204)
			(xy 32.66821 -399.777204) (xy 32.678364 -399.777725) (xy 32.697127 -399.785496) (xy 32.711491 -399.799853)
			(xy 32.719271 -399.818612) (xy 32.719772 -399.828766) (xy 32.719772 -400.11477) (xy 32.719979 -400.121642)
			(xy 32.723577 -400.134905) (xy 32.726884 -400.140932) (xy 32.743211 -400.169291) (xy 32.768927 -400.229463)
			(xy 32.786333 -400.292542) (xy 32.795116 -400.357387) (xy 32.795115 -400.422824) (xy 32.786331 -400.487668)
			(xy 32.768923 -400.550747) (xy 32.743206 -400.610918) (xy 32.726884 -400.63928) (xy 32.723575 -400.645308)
			(xy 32.719966 -400.658569) (xy 32.719772 -400.665442) (xy 32.719772 -401.414742) (xy 32.719989 -401.421613)
			(xy 32.723581 -401.434876) (xy 32.726884 -401.440904) (xy 32.743187 -401.469276) (xy 32.768905 -401.529445)
			(xy 32.786314 -401.592521) (xy 32.7951 -401.657364) (xy 32.795102 -401.722799) (xy 32.786322 -401.787642)
			(xy 32.768918 -401.85072) (xy 32.743204 -401.910891) (xy 32.726884 -401.939252) (xy 32.72355 -401.945267)
			(xy 32.719957 -401.958538) (xy 32.719772 -401.965414) (xy 32.719772 -402.251418) (xy 32.719282 -402.261576)
			(xy 32.711503 -402.280343) (xy 32.697137 -402.294708) (xy 32.678368 -402.302483) (xy 32.66821 -402.30298)
			(xy 31.95193 -402.30298) (xy 31.941763 -402.302512) (xy 31.922972 -402.29474) (xy 31.908587 -402.280368)
			(xy 31.900798 -402.261585) (xy 31.900368 -402.251418) (xy 31.900368 -401.965414) (xy 31.900175 -401.958541)
			(xy 31.896568 -401.945278) (xy 31.893256 -401.939252) (xy 31.876915 -401.910901) (xy 31.851198 -401.850728)
			(xy 31.833791 -401.787647) (xy 31.82501 -401.7228) (xy 30.536263 -401.7228) (xy 30.526736 -401.739354)
			(xy 30.523441 -401.745388) (xy 30.519822 -401.758644) (xy 30.519624 -401.765516) (xy 30.519624 -402.514816)
			(xy 30.519807 -402.52169) (xy 30.523421 -402.534953) (xy 30.526736 -402.540978) (xy 30.543018 -402.569361)
			(xy 30.568741 -402.629527) (xy 30.586155 -402.692601) (xy 30.594944 -402.757442) (xy 30.594946 -402.790152)
			(xy 34.024316 -402.790152) (xy 34.024881 -402.757422) (xy 34.033736 -402.692564) (xy 34.051227 -402.629484)
			(xy 34.077035 -402.569326) (xy 34.093404 -402.540978) (xy 34.096727 -402.534957) (xy 34.100327 -402.521691)
			(xy 34.100516 -402.514816) (xy 34.100516 -401.765516) (xy 34.100316 -401.758643) (xy 34.096713 -401.745381)
			(xy 34.093404 -401.739354) (xy 34.07702 -401.711015) (xy 34.051223 -401.650852) (xy 34.033738 -401.587769)
			(xy 34.024883 -401.52291) (xy 34.024316 -401.49018) (xy 34.024893 -401.457451) (xy 34.033745 -401.392593)
			(xy 34.051232 -401.329513) (xy 34.077037 -401.269354) (xy 34.093404 -401.241006) (xy 34.096717 -401.23498)
			(xy 34.100324 -401.221717) (xy 34.100516 -401.214844) (xy 34.100516 -400.92884) (xy 34.100949 -400.918718)
			(xy 34.108687 -400.900012) (xy 34.122999 -400.885696) (xy 34.141702 -400.877952) (xy 34.151824 -400.877532)
			(xy 34.868104 -400.877532) (xy 34.878231 -400.877914) (xy 34.89694 -400.885669) (xy 34.911256 -400.899997)
			(xy 34.918995 -400.918713) (xy 34.919412 -400.92884) (xy 34.919412 -401.214844) (xy 34.919624 -401.221716)
			(xy 34.923218 -401.234979) (xy 34.926524 -401.241006) (xy 34.942894 -401.269353) (xy 34.968694 -401.329513)
			(xy 34.986183 -401.392594) (xy 34.995042 -401.457451) (xy 34.995612 -401.49018) (xy 34.995058 -401.52291)
			(xy 34.986199 -401.587769) (xy 34.968705 -401.650849) (xy 34.951873 -401.690078) (xy 36.224464 -401.690078)
			(xy 36.225047 -401.657349) (xy 36.233899 -401.592492) (xy 36.251384 -401.529412) (xy 36.277186 -401.469253)
			(xy 36.293552 -401.440904) (xy 36.296861 -401.434877) (xy 36.300471 -401.421615) (xy 36.300664 -401.414742)
			(xy 36.300664 -400.665442) (xy 36.30046 -400.65857) (xy 36.296861 -400.645307) (xy 36.293552 -400.63928)
			(xy 36.277183 -400.610932) (xy 36.251381 -400.550773) (xy 36.233892 -400.487693) (xy 36.225033 -400.422835)
			(xy 36.224464 -400.390106) (xy 36.225015 -400.357376) (xy 36.233876 -400.292517) (xy 36.25137 -400.229437)
			(xy 36.277182 -400.16928) (xy 36.293552 -400.140932) (xy 36.296852 -400.1349) (xy 36.300467 -400.121642)
			(xy 36.300664 -400.11477) (xy 36.300664 -399.828766) (xy 36.301099 -399.818634) (xy 36.308843 -399.799908)
			(xy 36.323145 -399.785552) (xy 36.341842 -399.777738) (xy 36.351972 -399.777204) (xy 37.068252 -399.777204)
			(xy 37.078404 -399.777661) (xy 37.097156 -399.785442) (xy 37.111481 -399.799828) (xy 37.119181 -399.818613)
			(xy 37.11956 -399.828766) (xy 37.11956 -400.11477) (xy 37.119768 -400.121642) (xy 37.123366 -400.134905)
			(xy 37.126672 -400.140932) (xy 37.143048 -400.169276) (xy 37.168848 -400.229437) (xy 37.186335 -400.292518)
			(xy 37.195192 -400.357376) (xy 37.19576 -400.390106) (xy 37.195167 -400.422834) (xy 37.186318 -400.487691)
			(xy 37.168835 -400.550772) (xy 37.143036 -400.610931) (xy 37.126672 -400.63928) (xy 37.123362 -400.645307)
			(xy 37.119754 -400.658569) (xy 37.11956 -400.665442) (xy 37.11956 -401.414742) (xy 37.119779 -401.421613)
			(xy 37.123369 -401.434876) (xy 37.126672 -401.440904) (xy 37.143036 -401.469254) (xy 37.168839 -401.529413)
			(xy 37.186329 -401.592492) (xy 37.19519 -401.657349) (xy 37.19576 -401.690078) (xy 37.195199 -401.722808)
			(xy 37.18634 -401.787666) (xy 37.168849 -401.850746) (xy 37.143041 -401.910904) (xy 37.126672 -401.939252)
			(xy 37.123337 -401.945267) (xy 37.119745 -401.958538) (xy 37.11956 -401.965414) (xy 37.11956 -402.251418)
			(xy 37.119088 -402.261546) (xy 37.111355 -402.280268) (xy 37.097064 -402.294623) (xy 37.078378 -402.302442)
			(xy 37.068252 -402.30298) (xy 36.351972 -402.30298) (xy 36.341814 -402.302601) (xy 36.323057 -402.294792)
			(xy 36.308734 -402.280383) (xy 36.301038 -402.261579) (xy 36.300664 -402.251418) (xy 36.300664 -401.965414)
			(xy 36.300471 -401.958541) (xy 36.296864 -401.945278) (xy 36.293552 -401.939252) (xy 36.277172 -401.91091)
			(xy 36.251373 -401.850748) (xy 36.233887 -401.787667) (xy 36.225031 -401.722808) (xy 36.224464 -401.690078)
			(xy 34.951873 -401.690078) (xy 34.942894 -401.711006) (xy 34.926524 -401.739354) (xy 34.923227 -401.745388)
			(xy 34.91961 -401.758644) (xy 34.919412 -401.765516) (xy 34.919412 -402.514816) (xy 34.919596 -402.52169)
			(xy 34.923209 -402.534953) (xy 34.926524 -402.540978) (xy 34.942883 -402.569331) (xy 34.968686 -402.629489)
			(xy 34.986177 -402.692568) (xy 34.99504 -402.757423) (xy 34.995612 -402.790152) (xy 34.995045 -402.822879)
			(xy 38.42494 -402.822879) (xy 38.424945 -402.757439) (xy 38.433734 -402.692593) (xy 38.451146 -402.629512)
			(xy 38.476868 -402.56934) (xy 38.493192 -402.540978) (xy 38.496514 -402.534957) (xy 38.500115 -402.52169)
			(xy 38.500304 -402.514816) (xy 38.500304 -401.765516) (xy 38.500106 -401.758643) (xy 38.496502 -401.74538)
			(xy 38.493192 -401.739354) (xy 38.476854 -401.711002) (xy 38.451141 -401.650828) (xy 38.433736 -401.587747)
			(xy 38.424956 -401.522902) (xy 38.424958 -401.457464) (xy 38.433743 -401.392619) (xy 38.451152 -401.32954)
			(xy 38.47687 -401.269368) (xy 38.493192 -401.241006) (xy 38.496504 -401.23498) (xy 38.500112 -401.221717)
			(xy 38.500304 -401.214844) (xy 38.500304 -400.92884) (xy 38.500755 -400.918688) (xy 38.508538 -400.899936)
			(xy 38.522926 -400.885611) (xy 38.541712 -400.87791) (xy 38.551866 -400.877532) (xy 39.268146 -400.877532)
			(xy 39.278275 -400.877989) (xy 39.296995 -400.88573) (xy 39.31135 -400.900025) (xy 39.319169 -400.918714)
			(xy 39.319708 -400.92884) (xy 39.319708 -401.214844) (xy 39.31992 -401.221716) (xy 39.323515 -401.234979)
			(xy 39.32682 -401.241006) (xy 39.343127 -401.269376) (xy 39.368848 -401.329545) (xy 39.386259 -401.392622)
			(xy 39.395046 -401.457465) (xy 39.395048 -401.522901) (xy 39.386266 -401.587745) (xy 39.368859 -401.650823)
			(xy 39.352081 -401.690078) (xy 40.624252 -401.690078) (xy 40.624837 -401.657349) (xy 40.633688 -401.592492)
			(xy 40.651173 -401.529412) (xy 40.676974 -401.469253) (xy 40.69334 -401.440904) (xy 40.696649 -401.434876)
			(xy 40.700259 -401.421615) (xy 40.700452 -401.414742) (xy 40.700452 -400.665442) (xy 40.70025 -400.658569)
			(xy 40.696649 -400.645306) (xy 40.69334 -400.63928) (xy 40.67697 -400.610933) (xy 40.651169 -400.550773)
			(xy 40.63368 -400.487693) (xy 40.624821 -400.422835) (xy 40.624252 -400.390106) (xy 40.624804 -400.357376)
			(xy 40.633665 -400.292518) (xy 40.651159 -400.229438) (xy 40.67697 -400.16928) (xy 40.69334 -400.140932)
			(xy 40.696639 -400.134899) (xy 40.700255 -400.121642) (xy 40.700452 -400.11477) (xy 40.700452 -399.828766)
			(xy 40.700899 -399.818636) (xy 40.70864 -399.799911) (xy 40.722939 -399.785556) (xy 40.741632 -399.77774)
			(xy 40.75176 -399.777204) (xy 41.46804 -399.777204) (xy 41.478197 -399.777589) (xy 41.496951 -399.785399)
			(xy 41.511273 -399.799806) (xy 41.518971 -399.818606) (xy 41.519348 -399.828766) (xy 41.519348 -400.11477)
			(xy 41.519545 -400.121643) (xy 41.523149 -400.134906) (xy 41.52646 -400.140932) (xy 41.542834 -400.169276)
			(xy 41.568635 -400.229437) (xy 41.586122 -400.292518) (xy 41.59498 -400.357377) (xy 41.595548 -400.390106)
			(xy 41.594956 -400.422835) (xy 41.586107 -400.487692) (xy 41.568624 -400.550772) (xy 41.542825 -400.610931)
			(xy 41.52646 -400.63928) (xy 41.523157 -400.645311) (xy 41.519543 -400.65857) (xy 41.519348 -400.665442)
			(xy 41.519348 -401.414742) (xy 41.519556 -401.421614) (xy 41.523153 -401.434877) (xy 41.52646 -401.440904)
			(xy 41.542823 -401.469255) (xy 41.568627 -401.529413) (xy 41.586117 -401.592492) (xy 41.594978 -401.657349)
			(xy 41.595548 -401.690078) (xy 41.594988 -401.722808) (xy 41.58613 -401.787666) (xy 41.568638 -401.850746)
			(xy 41.542829 -401.910904) (xy 41.52646 -401.939252) (xy 41.523131 -401.94527) (xy 41.519534 -401.958539)
			(xy 41.519348 -401.965414) (xy 41.519348 -402.251418) (xy 41.518888 -402.261547) (xy 41.511152 -402.280271)
			(xy 41.496858 -402.294627) (xy 41.478167 -402.302444) (xy 41.46804 -402.30298) (xy 40.75176 -402.30298)
			(xy 40.741601 -402.302611) (xy 40.722844 -402.294798) (xy 40.708521 -402.280385) (xy 40.700826 -402.26158)
			(xy 40.700452 -402.251418) (xy 40.700452 -401.965414) (xy 40.700261 -401.958541) (xy 40.696653 -401.945278)
			(xy 40.69334 -401.939252) (xy 40.676959 -401.910911) (xy 40.65116 -401.850749) (xy 40.633675 -401.787667)
			(xy 40.624819 -401.722808) (xy 40.624252 -401.690078) (xy 39.352081 -401.690078) (xy 39.343142 -401.710993)
			(xy 39.32682 -401.739354) (xy 39.323523 -401.745387) (xy 39.319906 -401.758644) (xy 39.319708 -401.765516)
			(xy 39.319708 -402.514816) (xy 39.319893 -402.52169) (xy 39.323506 -402.534953) (xy 39.32682 -402.540978)
			(xy 39.343103 -402.569361) (xy 39.368826 -402.629527) (xy 39.38624 -402.692601) (xy 39.39503 -402.757442)
			(xy 39.395032 -402.790152) (xy 42.8244 -402.790152) (xy 42.824967 -402.757423) (xy 42.833822 -402.692564)
			(xy 42.851312 -402.629484) (xy 42.87712 -402.569326) (xy 42.893488 -402.540978) (xy 42.89681 -402.534957)
			(xy 42.900411 -402.52169) (xy 42.9006 -402.514816) (xy 42.9006 -401.765516) (xy 42.900402 -401.758643)
			(xy 42.896798 -401.74538) (xy 42.893488 -401.739354) (xy 42.877103 -401.711015) (xy 42.851306 -401.650852)
			(xy 42.833822 -401.587769) (xy 42.824967 -401.52291) (xy 42.8244 -401.49018) (xy 42.824979 -401.457451)
			(xy 42.833831 -401.392593) (xy 42.851317 -401.329513) (xy 42.877121 -401.269355) (xy 42.893488 -401.241006)
			(xy 42.8968 -401.23498) (xy 42.900408 -401.221717) (xy 42.9006 -401.214844) (xy 42.9006 -400.92884)
			(xy 42.901049 -400.91872) (xy 42.908784 -400.900017) (xy 42.923091 -400.885702) (xy 42.941788 -400.877955)
			(xy 42.951908 -400.877532) (xy 43.668188 -400.877532) (xy 43.678314 -400.877927) (xy 43.697023 -400.885677)
			(xy 43.711339 -400.9) (xy 43.719079 -400.918714) (xy 43.719496 -400.92884) (xy 43.719496 -401.214844)
			(xy 43.71971 -401.221716) (xy 43.723303 -401.234978) (xy 43.726608 -401.241006) (xy 43.742977 -401.269353)
			(xy 43.768778 -401.329514) (xy 43.786266 -401.392594) (xy 43.795126 -401.457451) (xy 43.795696 -401.49018)
			(xy 43.795144 -401.52291) (xy 43.786284 -401.587769) (xy 43.76879 -401.650849) (xy 43.742978 -401.711006)
			(xy 43.736167 -401.7228) (xy 45.024886 -401.7228) (xy 45.024888 -401.657362) (xy 45.033674 -401.592517)
			(xy 45.051085 -401.529437) (xy 45.076805 -401.469265) (xy 45.093128 -401.440904) (xy 45.096443 -401.43488)
			(xy 45.100048 -401.421616) (xy 45.10024 -401.414742) (xy 45.10024 -400.665442) (xy 45.100027 -400.65857)
			(xy 45.096433 -400.645308) (xy 45.093128 -400.63928) (xy 45.076811 -400.610916) (xy 45.051094 -400.550745)
			(xy 45.033685 -400.487667) (xy 45.024901 -400.422823) (xy 45.024901 -400.357387) (xy 45.033683 -400.292543)
			(xy 45.05109 -400.229465) (xy 45.076807 -400.169293) (xy 45.093128 -400.140932) (xy 45.096433 -400.134903)
			(xy 45.100044 -400.121643) (xy 45.10024 -400.11477) (xy 45.10024 -399.828766) (xy 45.100706 -399.818606)
			(xy 45.108492 -399.799835) (xy 45.122866 -399.785471) (xy 45.141641 -399.777698) (xy 45.151802 -399.777204)
			(xy 45.868082 -399.777204) (xy 45.878234 -399.777747) (xy 45.896997 -399.785509) (xy 45.911361 -399.79986)
			(xy 45.919143 -399.818614) (xy 45.919644 -399.828766) (xy 45.919644 -400.11477) (xy 45.919842 -400.121643)
			(xy 45.923445 -400.134906) (xy 45.926756 -400.140932) (xy 45.943083 -400.16929) (xy 45.968801 -400.229462)
			(xy 45.986209 -400.292541) (xy 45.994992 -400.357387) (xy 45.994991 -400.422824) (xy 45.986207 -400.487669)
			(xy 45.968797 -400.550748) (xy 45.943079 -400.610919) (xy 45.926756 -400.63928) (xy 45.923453 -400.64531)
			(xy 45.919839 -400.65857) (xy 45.919644 -400.665442) (xy 45.919644 -401.414742) (xy 45.919853 -401.421614)
			(xy 45.923449 -401.434877) (xy 45.926756 -401.440904) (xy 45.94306 -401.469275) (xy 45.968779 -401.529444)
			(xy 45.98619 -401.592521) (xy 45.994976 -401.657364) (xy 45.994978 -401.722799) (xy 45.986197 -401.787642)
			(xy 45.968792 -401.85072) (xy 45.943077 -401.910891) (xy 45.926756 -401.939252) (xy 45.923427 -401.94527)
			(xy 45.91983 -401.958539) (xy 45.919644 -401.965414) (xy 45.919644 -402.251418) (xy 45.919181 -402.261579)
			(xy 45.911397 -402.280352) (xy 45.897022 -402.294718) (xy 45.878244 -402.302488) (xy 45.868082 -402.30298)
			(xy 45.151802 -402.30298) (xy 45.141647 -402.302465) (xy 45.122881 -402.294695) (xy 45.108516 -402.280336)
			(xy 45.100739 -402.261573) (xy 45.10024 -402.251418) (xy 45.10024 -401.965414) (xy 45.100038 -401.958542)
			(xy 45.096436 -401.945279) (xy 45.093128 -401.939252) (xy 45.076787 -401.910901) (xy 45.051072 -401.850727)
			(xy 45.033667 -401.787646) (xy 45.024886 -401.7228) (xy 43.736167 -401.7228) (xy 43.726608 -401.739354)
			(xy 43.72331 -401.745387) (xy 43.719694 -401.758644) (xy 43.719496 -401.765516) (xy 43.719496 -402.514816)
			(xy 43.719682 -402.52169) (xy 43.723294 -402.534952) (xy 43.726608 -402.540978) (xy 43.742966 -402.569332)
			(xy 43.768769 -402.62949) (xy 43.786261 -402.692568) (xy 43.795124 -402.757423) (xy 43.795696 -402.790152)
			(xy 43.795132 -402.822882) (xy 43.786275 -402.88774) (xy 43.768785 -402.95082) (xy 43.742977 -403.010978)
			(xy 43.726608 -403.039326) (xy 43.723285 -403.045346) (xy 43.719684 -403.058613) (xy 43.719496 -403.065488)
			(xy 43.719496 -403.351492) (xy 43.719077 -403.361614) (xy 43.711331 -403.380319) (xy 43.697015 -403.394633)
			(xy 43.67831 -403.402378) (xy 43.668188 -403.4028) (xy 42.951908 -403.4028) (xy 42.941786 -403.402377)
			(xy 42.923083 -403.394632) (xy 42.908768 -403.380317) (xy 42.901023 -403.361614) (xy 42.9006 -403.351492)
			(xy 42.9006 -403.065488) (xy 42.900413 -403.058614) (xy 42.896801 -403.045352) (xy 42.893488 -403.039326)
			(xy 42.877132 -403.010972) (xy 42.851328 -402.950814) (xy 42.833836 -402.887736) (xy 42.824972 -402.822881)
			(xy 42.8244 -402.790152) (xy 39.395032 -402.790152) (xy 39.395035 -402.822876) (xy 39.386257 -402.887718)
			(xy 39.368854 -402.950795) (xy 39.34314 -403.010965) (xy 39.32682 -403.039326) (xy 39.323497 -403.045347)
			(xy 39.319896 -403.058613) (xy 39.319708 -403.065488) (xy 39.319708 -403.351492) (xy 39.319272 -403.361645)
			(xy 39.311481 -403.380395) (xy 39.297088 -403.394719) (xy 39.278301 -403.40242) (xy 39.268146 -403.4028)
			(xy 38.551866 -403.4028) (xy 38.541742 -403.402303) (xy 38.523028 -403.394571) (xy 38.508674 -403.380289)
			(xy 38.500849 -403.361613) (xy 38.500304 -403.351492) (xy 38.500304 -403.065488) (xy 38.500116 -403.058614)
			(xy 38.496505 -403.045352) (xy 38.493192 -403.039326) (xy 38.476831 -403.010987) (xy 38.451119 -402.95081)
			(xy 38.433717 -402.887727) (xy 38.42494 -402.822879) (xy 34.995045 -402.822879) (xy 34.995045 -402.822881)
			(xy 34.98619 -402.88774) (xy 34.968699 -402.95082) (xy 34.942892 -403.010978) (xy 34.926524 -403.039326)
			(xy 34.923202 -403.045347) (xy 34.9196 -403.058613) (xy 34.919412 -403.065488) (xy 34.919412 -403.351492)
			(xy 34.918978 -403.361612) (xy 34.911234 -403.380314) (xy 34.896924 -403.394628) (xy 34.878224 -403.402375)
			(xy 34.868104 -403.4028) (xy 34.151824 -403.4028) (xy 34.141703 -403.402365) (xy 34.123 -403.394624)
			(xy 34.108685 -403.380314) (xy 34.100939 -403.361613) (xy 34.100516 -403.351492) (xy 34.100516 -403.065488)
			(xy 34.100327 -403.058615) (xy 34.096716 -403.045352) (xy 34.093404 -403.039326) (xy 34.077049 -403.010971)
			(xy 34.051245 -402.950814) (xy 34.033752 -402.887736) (xy 34.024888 -402.82288) (xy 34.024316 -402.790152)
			(xy 30.594946 -402.790152) (xy 30.594949 -402.822876) (xy 30.586171 -402.887718) (xy 30.568768 -402.950795)
			(xy 30.543056 -403.010965) (xy 30.526736 -403.039326) (xy 30.523415 -403.045348) (xy 30.519813 -403.058614)
			(xy 30.519624 -403.065488) (xy 30.519624 -403.351492) (xy 30.519172 -403.361643) (xy 30.511384 -403.38039)
			(xy 30.496997 -403.394713) (xy 30.478214 -403.402417) (xy 30.468062 -403.4028) (xy 29.751782 -403.4028)
			(xy 29.741659 -403.40229) (xy 29.722945 -403.394563) (xy 29.708591 -403.380285) (xy 29.700765 -403.361612)
			(xy 29.70022 -403.351492) (xy 29.70022 -403.065488) (xy 29.70003 -403.058615) (xy 29.69642 -403.045352)
			(xy 29.693108 -403.039326) (xy 29.676746 -403.010987) (xy 29.651034 -402.95081) (xy 29.633631 -402.887727)
			(xy 29.624853 -402.822879) (xy 0.6096 -402.822879) (xy 0.6096 -404.501858) (xy 17.351246 -404.501858)
			(xy 17.355317 -404.446236) (xy 17.367443 -404.391799) (xy 17.387366 -404.339708) (xy 17.414662 -404.291073)
			(xy 17.448748 -404.24693) (xy 17.488897 -404.208221) (xy 17.534255 -404.17577) (xy 17.583855 -404.150269)
			(xy 17.636639 -404.132262) (xy 17.691482 -404.122132) (xy 17.747216 -404.120095) (xy 17.802653 -404.126195)
			(xy 17.85661 -404.140301) (xy 17.907939 -404.162113) (xy 17.955545 -404.191167) (xy 17.998413 -404.226842)
			(xy 18.03563 -404.268379) (xy 18.066403 -404.314892) (xy 18.090075 -404.365389) (xy 18.106143 -404.418796)
			(xy 18.114263 -404.473972) (xy 18.114772 -404.501858) (xy 18.114263 -404.529744) (xy 18.106143 -404.58492)
			(xy 18.094299 -404.624286) (xy 18.644868 -404.624286) (xy 18.648939 -404.568664) (xy 18.661065 -404.514227)
			(xy 18.680988 -404.462136) (xy 18.708284 -404.413501) (xy 18.74237 -404.369358) (xy 18.782519 -404.330649)
			(xy 18.827877 -404.298198) (xy 18.877477 -404.272697) (xy 18.930261 -404.25469) (xy 18.985104 -404.24456)
			(xy 19.040838 -404.242523) (xy 19.096275 -404.248623) (xy 19.150232 -404.262729) (xy 19.201561 -404.284541)
			(xy 19.249167 -404.313595) (xy 19.292035 -404.34927) (xy 19.329252 -404.390807) (xy 19.360025 -404.43732)
			(xy 19.383697 -404.487817) (xy 19.399765 -404.541224) (xy 19.407885 -404.5964) (xy 19.408394 -404.624286)
			(xy 19.407885 -404.652172) (xy 19.399765 -404.707348) (xy 19.383697 -404.760755) (xy 19.360025 -404.811252)
			(xy 19.329252 -404.857765) (xy 19.292035 -404.899302) (xy 19.249167 -404.934977) (xy 19.201561 -404.964031)
			(xy 19.150232 -404.985843) (xy 19.096275 -404.999949) (xy 19.040838 -405.006049) (xy 18.985104 -405.004012)
			(xy 18.930261 -404.993882) (xy 18.877477 -404.975875) (xy 18.827877 -404.950374) (xy 18.782519 -404.917923)
			(xy 18.74237 -404.879214) (xy 18.708284 -404.835071) (xy 18.680988 -404.786436) (xy 18.661065 -404.734345)
			(xy 18.648939 -404.679908) (xy 18.644868 -404.624286) (xy 18.094299 -404.624286) (xy 18.090075 -404.638327)
			(xy 18.066403 -404.688824) (xy 18.03563 -404.735337) (xy 17.998413 -404.776874) (xy 17.955545 -404.812549)
			(xy 17.907939 -404.841603) (xy 17.85661 -404.863415) (xy 17.802653 -404.877521) (xy 17.747216 -404.883621)
			(xy 17.691482 -404.881584) (xy 17.636639 -404.871454) (xy 17.583855 -404.853447) (xy 17.534255 -404.827946)
			(xy 17.488897 -404.795495) (xy 17.448748 -404.756786) (xy 17.414662 -404.712643) (xy 17.387366 -404.664008)
			(xy 17.367443 -404.611917) (xy 17.355317 -404.55748) (xy 17.351246 -404.501858) (xy 0.6096 -404.501858)
			(xy 0.6096 -405.589994) (xy 27.42438 -405.589994) (xy 27.424968 -405.557265) (xy 27.433818 -405.492408)
			(xy 27.451302 -405.429328) (xy 27.477103 -405.369169) (xy 27.493468 -405.34082) (xy 27.496773 -405.334791)
			(xy 27.500385 -405.321531) (xy 27.50058 -405.314658) (xy 27.50058 -404.565358) (xy 27.500368 -404.558486)
			(xy 27.496774 -404.545223) (xy 27.493468 -404.539196) (xy 27.477107 -404.510844) (xy 27.451303 -404.450686)
			(xy 27.433811 -404.387607) (xy 27.42495 -404.322751) (xy 27.42438 -404.290022) (xy 27.424936 -404.257292)
			(xy 27.433795 -404.192434) (xy 27.451288 -404.129353) (xy 27.477098 -404.069196) (xy 27.493468 -404.040848)
			(xy 27.496799 -404.034831) (xy 27.500394 -404.021561) (xy 27.50058 -404.014686) (xy 27.50058 -403.728682)
			(xy 27.501013 -403.718549) (xy 27.508754 -403.69982) (xy 27.523057 -403.685463) (xy 27.541757 -403.677651)
			(xy 27.551888 -403.67712) (xy 28.268168 -403.67712) (xy 28.278323 -403.677548) (xy 28.297078 -403.685337)
			(xy 28.311404 -403.699732) (xy 28.319101 -403.718525) (xy 28.319476 -403.728682) (xy 28.319476 -404.014686)
			(xy 28.319676 -404.021559) (xy 28.323279 -404.034821) (xy 28.326588 -404.040848) (xy 28.342972 -404.069187)
			(xy 28.368769 -404.12935) (xy 28.386254 -404.192433) (xy 28.395109 -404.257292) (xy 28.395676 -404.290022)
			(xy 28.395101 -404.322751) (xy 28.386248 -404.387609) (xy 28.368761 -404.45069) (xy 28.342956 -404.510848)
			(xy 28.326588 -404.539196) (xy 28.323274 -404.545221) (xy 28.319668 -404.558484) (xy 28.319476 -404.565358)
			(xy 28.319476 -405.314658) (xy 28.319687 -405.32153) (xy 28.323282 -405.334793) (xy 28.326588 -405.34082)
			(xy 28.34296 -405.369166) (xy 28.368761 -405.429326) (xy 28.386249 -405.492407) (xy 28.395107 -405.557265)
			(xy 28.395676 -405.589994) (xy 28.395133 -405.622724) (xy 28.386271 -405.687584) (xy 28.368774 -405.750664)
			(xy 28.34296 -405.810821) (xy 28.326588 -405.839168) (xy 28.323284 -405.845198) (xy 28.319672 -405.858458)
			(xy 28.319476 -405.86533) (xy 28.319476 -406.151334) (xy 28.319002 -406.161461) (xy 28.311266 -406.18018)
			(xy 28.296976 -406.194534) (xy 28.278293 -406.202355) (xy 28.268168 -406.202896) (xy 27.551888 -406.202896)
			(xy 27.541733 -406.202488) (xy 27.522979 -406.194688) (xy 27.508656 -406.180287) (xy 27.500957 -406.161492)
			(xy 27.50058 -406.151334) (xy 27.50058 -405.86533) (xy 27.500379 -405.858457) (xy 27.496777 -405.845195)
			(xy 27.493468 -405.839168) (xy 27.477096 -405.810822) (xy 27.451294 -405.750662) (xy 27.433806 -405.687581)
			(xy 27.424948 -405.622723) (xy 27.42438 -405.589994) (xy 0.6096 -405.589994) (xy 0.6096 -406.722792)
			(xy 29.624863 -406.722792) (xy 29.624866 -406.657353) (xy 29.633653 -406.592507) (xy 29.651064 -406.529428)
			(xy 29.676785 -406.469256) (xy 29.693108 -406.440894) (xy 29.696425 -406.434871) (xy 29.700029 -406.421606)
			(xy 29.70022 -406.414732) (xy 29.70022 -405.665432) (xy 29.700013 -405.65856) (xy 29.696415 -405.645297)
			(xy 29.693108 -405.63927) (xy 29.676783 -405.61091) (xy 29.651068 -405.550738) (xy 29.633661 -405.487659)
			(xy 29.624879 -405.422815) (xy 29.624879 -405.357378) (xy 29.633662 -405.292534) (xy 29.65107 -405.229455)
			(xy 29.676786 -405.169284) (xy 29.693108 -405.140922) (xy 29.696415 -405.134894) (xy 29.700026 -405.121633)
			(xy 29.70022 -405.11476) (xy 29.70022 -404.828756) (xy 29.700586 -404.818597) (xy 29.7084 -404.799839)
			(xy 29.722814 -404.785517) (xy 29.74162 -404.777822) (xy 29.751782 -404.777448) (xy 30.468062 -404.777448)
			(xy 30.478187 -404.777958) (xy 30.496909 -404.785675) (xy 30.511267 -404.799954) (xy 30.519086 -404.818634)
			(xy 30.519624 -404.828756) (xy 30.519624 -405.11476) (xy 30.519828 -405.121632) (xy 30.523428 -405.134895)
			(xy 30.526736 -405.140922) (xy 30.543056 -405.169285) (xy 30.568775 -405.229455) (xy 30.586184 -405.292534)
			(xy 30.594969 -405.357378) (xy 30.594969 -405.422815) (xy 30.586186 -405.48766) (xy 30.568777 -405.550738)
			(xy 30.543059 -405.610909) (xy 30.536265 -405.622714) (xy 31.825019 -405.622714) (xy 31.825019 -405.557276)
			(xy 31.833804 -405.492431) (xy 31.851214 -405.429352) (xy 31.876933 -405.369181) (xy 31.893256 -405.34082)
			(xy 31.89656 -405.33479) (xy 31.900173 -405.32153) (xy 31.900368 -405.314658) (xy 31.900368 -404.565358)
			(xy 31.900158 -404.558486) (xy 31.896562 -404.545223) (xy 31.893256 -404.539196) (xy 31.876952 -404.510825)
			(xy 31.851232 -404.450656) (xy 31.833821 -404.387579) (xy 31.825035 -404.322737) (xy 31.825032 -404.257301)
			(xy 31.833813 -404.192458) (xy 31.851219 -404.12938) (xy 31.876935 -404.069209) (xy 31.893256 -404.040848)
			(xy 31.896586 -404.034831) (xy 31.900182 -404.021561) (xy 31.900368 -404.014686) (xy 31.900368 -403.728682)
			(xy 31.90075 -403.718506) (xy 31.908547 -403.699705) (xy 31.922945 -403.68532) (xy 31.941753 -403.677541)
			(xy 31.95193 -403.67712) (xy 32.66821 -403.67712) (xy 32.678366 -403.677625) (xy 32.697132 -403.685399)
			(xy 32.711496 -403.699761) (xy 32.719273 -403.718526) (xy 32.719772 -403.728682) (xy 32.719772 -404.014686)
			(xy 32.719973 -404.021559) (xy 32.723575 -404.034821) (xy 32.726884 -404.040848) (xy 32.743224 -404.069199)
			(xy 32.768939 -404.129373) (xy 32.786344 -404.192454) (xy 32.795125 -404.2573) (xy 32.795122 -404.322738)
			(xy 32.786336 -404.387583) (xy 32.768926 -404.450663) (xy 32.743207 -404.510834) (xy 32.726884 -404.539196)
			(xy 32.72357 -404.545221) (xy 32.719964 -404.558484) (xy 32.719772 -404.565358) (xy 32.719772 -405.314658)
			(xy 32.719983 -405.32153) (xy 32.723579 -405.334792) (xy 32.726884 -405.34082) (xy 32.7432 -405.369184)
			(xy 32.768917 -405.429355) (xy 32.786325 -405.492433) (xy 32.795109 -405.557277) (xy 32.79511 -405.622713)
			(xy 32.786327 -405.687557) (xy 32.768921 -405.750635) (xy 32.743205 -405.810807) (xy 32.726884 -405.839168)
			(xy 32.72358 -405.845198) (xy 32.719968 -405.858458) (xy 32.719772 -405.86533) (xy 32.719772 -406.151334)
			(xy 32.719295 -406.161493) (xy 32.711511 -406.180261) (xy 32.697141 -406.194624) (xy 32.678369 -406.202399)
			(xy 32.66821 -406.202896) (xy 31.95193 -406.202896) (xy 31.941778 -406.202343) (xy 31.923016 -406.194585)
			(xy 31.908651 -406.180237) (xy 31.900869 -406.161485) (xy 31.900368 -406.151334) (xy 31.900368 -405.86533)
			(xy 31.900169 -405.858457) (xy 31.896566 -405.845194) (xy 31.893256 -405.839168) (xy 31.876928 -405.81081)
			(xy 31.85121 -405.750638) (xy 31.833802 -405.687559) (xy 31.825019 -405.622714) (xy 30.536265 -405.622714)
			(xy 30.526736 -405.63927) (xy 30.523435 -405.645301) (xy 30.51982 -405.65856) (xy 30.519624 -405.665432)
			(xy 30.519624 -406.414732) (xy 30.519801 -406.421606) (xy 30.523419 -406.434869) (xy 30.526736 -406.440894)
			(xy 30.543032 -406.46927) (xy 30.568753 -406.529437) (xy 30.586165 -406.592513) (xy 30.594953 -406.657355)
			(xy 30.594954 -406.690068) (xy 34.024316 -406.690068) (xy 34.024888 -406.657339) (xy 34.033741 -406.592481)
			(xy 34.05123 -406.5294) (xy 34.077036 -406.469242) (xy 34.093404 -406.440894) (xy 34.096721 -406.434871)
			(xy 34.100325 -406.421606) (xy 34.100516 -406.414732) (xy 34.100516 -405.665432) (xy 34.10031 -405.65856)
			(xy 34.096711 -405.645297) (xy 34.093404 -405.63927) (xy 34.077027 -405.610927) (xy 34.051228 -405.550765)
			(xy 34.033741 -405.487684) (xy 34.024884 -405.422826) (xy 34.024316 -405.390096) (xy 34.024856 -405.357366)
			(xy 34.033719 -405.292506) (xy 34.051217 -405.229426) (xy 34.077032 -405.169269) (xy 34.093404 -405.140922)
			(xy 34.096711 -405.134894) (xy 34.100322 -405.121633) (xy 34.100516 -405.11476) (xy 34.100516 -404.828756)
			(xy 34.10095 -404.818642) (xy 34.108705 -404.79996) (xy 34.123017 -404.785666) (xy 34.14171 -404.777936)
			(xy 34.151824 -404.777448) (xy 34.868104 -404.777448) (xy 34.878207 -404.777981) (xy 34.896875 -404.78571)
			(xy 34.911168 -404.799992) (xy 34.918911 -404.818654) (xy 34.919412 -404.828756) (xy 34.919412 -405.11476)
			(xy 34.919618 -405.121632) (xy 34.923217 -405.134895) (xy 34.926524 -405.140922) (xy 34.942901 -405.169265)
			(xy 34.968699 -405.229427) (xy 34.986186 -405.292508) (xy 34.995043 -405.357367) (xy 34.995612 -405.390096)
			(xy 34.995065 -405.422826) (xy 34.986204 -405.487685) (xy 34.968708 -405.550765) (xy 34.951875 -405.589994)
			(xy 36.224464 -405.589994) (xy 36.225055 -405.557265) (xy 36.233904 -405.492408) (xy 36.251387 -405.429328)
			(xy 36.277187 -405.369169) (xy 36.293552 -405.34082) (xy 36.296856 -405.33479) (xy 36.300469 -405.32153)
			(xy 36.300664 -405.314658) (xy 36.300664 -404.565358) (xy 36.300454 -404.558486) (xy 36.296859 -404.545223)
			(xy 36.293552 -404.539196) (xy 36.27719 -404.510845) (xy 36.251386 -404.450686) (xy 36.233895 -404.387607)
			(xy 36.225034 -404.322751) (xy 36.224464 -404.290022) (xy 36.225022 -404.257292) (xy 36.233881 -404.192434)
			(xy 36.251373 -404.129354) (xy 36.277183 -404.069196) (xy 36.293552 -404.040848) (xy 36.296881 -404.03483)
			(xy 36.300478 -404.021561) (xy 36.300664 -404.014686) (xy 36.300664 -403.728682) (xy 36.301112 -403.718551)
			(xy 36.30885 -403.699825) (xy 36.323149 -403.685468) (xy 36.341843 -403.677654) (xy 36.351972 -403.67712)
			(xy 37.068252 -403.67712) (xy 37.078405 -403.677561) (xy 37.097161 -403.685345) (xy 37.111486 -403.699736)
			(xy 37.119184 -403.718527) (xy 37.11956 -403.728682) (xy 37.11956 -404.014686) (xy 37.119762 -404.021558)
			(xy 37.123364 -404.034821) (xy 37.126672 -404.040848) (xy 37.143054 -404.069188) (xy 37.168853 -404.129351)
			(xy 37.186338 -404.192433) (xy 37.195193 -404.257292) (xy 37.19576 -404.290022) (xy 37.195174 -404.322751)
			(xy 37.186323 -404.387608) (xy 37.168838 -404.450688) (xy 37.143037 -404.510847) (xy 37.126672 -404.539196)
			(xy 37.123357 -404.54522) (xy 37.119752 -404.558484) (xy 37.11956 -404.565358) (xy 37.11956 -405.314658)
			(xy 37.119773 -405.32153) (xy 37.123367 -405.334792) (xy 37.126672 -405.34082) (xy 37.143043 -405.369166)
			(xy 37.168844 -405.429327) (xy 37.186332 -405.492407) (xy 37.195191 -405.557265) (xy 37.19576 -405.589994)
			(xy 37.195206 -405.622724) (xy 37.186345 -405.687582) (xy 37.168852 -405.750662) (xy 37.143042 -405.81082)
			(xy 37.126672 -405.839168) (xy 37.123367 -405.845197) (xy 37.119756 -405.858457) (xy 37.11956 -405.86533)
			(xy 37.11956 -406.151334) (xy 37.119101 -406.161463) (xy 37.111362 -406.180185) (xy 37.097068 -406.19454)
			(xy 37.078379 -406.202358) (xy 37.068252 -406.202896) (xy 36.351972 -406.202896) (xy 36.341816 -406.202501)
			(xy 36.323062 -406.194696) (xy 36.308739 -406.180291) (xy 36.301041 -406.161493) (xy 36.300664 -406.151334)
			(xy 36.300664 -405.86533) (xy 36.300465 -405.858457) (xy 36.296862 -405.845194) (xy 36.293552 -405.839168)
			(xy 36.277179 -405.810823) (xy 36.251378 -405.750662) (xy 36.23389 -405.687581) (xy 36.225032 -405.622723)
			(xy 36.224464 -405.589994) (xy 34.951875 -405.589994) (xy 34.942895 -405.610923) (xy 34.926524 -405.63927)
			(xy 34.923222 -405.645301) (xy 34.919608 -405.65856) (xy 34.919412 -405.665432) (xy 34.919412 -406.414732)
			(xy 34.91959 -406.421606) (xy 34.923208 -406.434869) (xy 34.926524 -406.440894) (xy 34.942889 -406.469243)
			(xy 34.968691 -406.529403) (xy 34.98618 -406.592482) (xy 34.995041 -406.657339) (xy 34.995612 -406.690068)
			(xy 34.995053 -406.722792) (xy 38.424949 -406.722792) (xy 38.424953 -406.657353) (xy 38.433739 -406.592508)
			(xy 38.45115 -406.529428) (xy 38.476869 -406.469256) (xy 38.493192 -406.440894) (xy 38.496508 -406.43487)
			(xy 38.500113 -406.421606) (xy 38.500304 -406.414732) (xy 38.500304 -405.665432) (xy 38.500099 -405.65856)
			(xy 38.496499 -405.645297) (xy 38.493192 -405.63927) (xy 38.476868 -405.61091) (xy 38.451153 -405.550738)
			(xy 38.433747 -405.487659) (xy 38.424965 -405.422815) (xy 38.424965 -405.357378) (xy 38.433748 -405.292534)
			(xy 38.451155 -405.229455) (xy 38.476871 -405.169284) (xy 38.493192 -405.140922) (xy 38.496498 -405.134893)
			(xy 38.500109 -405.121633) (xy 38.500304 -405.11476) (xy 38.500304 -404.828756) (xy 38.500686 -404.818599)
			(xy 38.508497 -404.799844) (xy 38.522905 -404.785523) (xy 38.541706 -404.777825) (xy 38.551866 -404.777448)
			(xy 39.268146 -404.777448) (xy 39.278277 -404.777889) (xy 39.297 -404.785634) (xy 39.311355 -404.799934)
			(xy 39.319171 -404.818627) (xy 39.319708 -404.828756) (xy 39.319708 -405.11476) (xy 39.319914 -405.121632)
			(xy 39.323513 -405.134895) (xy 39.32682 -405.140922) (xy 39.34314 -405.169285) (xy 39.36886 -405.229455)
			(xy 39.38627 -405.292533) (xy 39.395055 -405.357378) (xy 39.395055 -405.422815) (xy 39.386272 -405.48766)
			(xy 39.368862 -405.550738) (xy 39.352083 -405.589994) (xy 40.624252 -405.589994) (xy 40.624844 -405.557265)
			(xy 40.633693 -405.492408) (xy 40.651176 -405.429328) (xy 40.676975 -405.369169) (xy 40.69334 -405.34082)
			(xy 40.696643 -405.334789) (xy 40.700257 -405.32153) (xy 40.700452 -405.314658) (xy 40.700452 -404.565358)
			(xy 40.700244 -404.558486) (xy 40.696647 -404.545223) (xy 40.69334 -404.539196) (xy 40.676977 -404.510845)
			(xy 40.651173 -404.450687) (xy 40.633683 -404.387608) (xy 40.624822 -404.322751) (xy 40.624252 -404.290022)
			(xy 40.624812 -404.257292) (xy 40.63367 -404.192434) (xy 40.651162 -404.129354) (xy 40.676971 -404.069196)
			(xy 40.69334 -404.040848) (xy 40.696669 -404.03483) (xy 40.700266 -404.021561) (xy 40.700452 -404.014686)
			(xy 40.700452 -403.728682) (xy 40.700912 -403.718553) (xy 40.708648 -403.699829) (xy 40.722942 -403.685473)
			(xy 40.741633 -403.677656) (xy 40.75176 -403.67712) (xy 41.46804 -403.67712) (xy 41.478199 -403.677489)
			(xy 41.496956 -403.685302) (xy 41.511279 -403.699715) (xy 41.518974 -403.71852) (xy 41.519348 -403.728682)
			(xy 41.519348 -404.014686) (xy 41.519539 -404.021559) (xy 41.523147 -404.034822) (xy 41.52646 -404.040848)
			(xy 41.542841 -404.069189) (xy 41.56864 -404.129351) (xy 41.586125 -404.192433) (xy 41.594981 -404.257292)
			(xy 41.595548 -404.290022) (xy 41.594963 -404.322751) (xy 41.586112 -404.387608) (xy 41.568627 -404.450688)
			(xy 41.542826 -404.510847) (xy 41.52646 -404.539196) (xy 41.523151 -404.545224) (xy 41.519541 -404.558485)
			(xy 41.519348 -404.565358) (xy 41.519348 -405.314658) (xy 41.51955 -405.321531) (xy 41.523151 -405.334794)
			(xy 41.52646 -405.34082) (xy 41.54283 -405.369167) (xy 41.568631 -405.429327) (xy 41.58612 -405.492407)
			(xy 41.594979 -405.557265) (xy 41.595548 -405.589994) (xy 41.594996 -405.622724) (xy 41.586135 -405.687582)
			(xy 41.568641 -405.750662) (xy 41.54283 -405.81082) (xy 41.52646 -405.839168) (xy 41.523161 -405.845201)
			(xy 41.519545 -405.858458) (xy 41.519348 -405.86533) (xy 41.519348 -406.151334) (xy 41.518901 -406.161464)
			(xy 41.51116 -406.180189) (xy 41.496861 -406.194544) (xy 41.478168 -406.20236) (xy 41.46804 -406.202896)
			(xy 40.75176 -406.202896) (xy 40.741603 -406.202511) (xy 40.722849 -406.194701) (xy 40.708527 -406.180294)
			(xy 40.700829 -406.161494) (xy 40.700452 -406.151334) (xy 40.700452 -405.86533) (xy 40.700255 -405.858457)
			(xy 40.696651 -405.845194) (xy 40.69334 -405.839168) (xy 40.676966 -405.810824) (xy 40.651165 -405.750663)
			(xy 40.633678 -405.687582) (xy 40.62482 -405.622723) (xy 40.624252 -405.589994) (xy 39.352083 -405.589994)
			(xy 39.343143 -405.610909) (xy 39.32682 -405.63927) (xy 39.323517 -405.645301) (xy 39.319904 -405.65856)
			(xy 39.319708 -405.665432) (xy 39.319708 -406.414732) (xy 39.319887 -406.421606) (xy 39.323504 -406.434869)
			(xy 39.32682 -406.440894) (xy 39.343116 -406.46927) (xy 39.368839 -406.529437) (xy 39.386251 -406.592513)
			(xy 39.395039 -406.657355) (xy 39.395041 -406.690068) (xy 42.8244 -406.690068) (xy 42.824974 -406.657339)
			(xy 42.833827 -406.592481) (xy 42.851315 -406.529401) (xy 42.877121 -406.469242) (xy 42.893488 -406.440894)
			(xy 42.896804 -406.43487) (xy 42.900409 -406.421606) (xy 42.9006 -406.414732) (xy 42.9006 -405.665432)
			(xy 42.900396 -405.65856) (xy 42.896796 -405.645297) (xy 42.893488 -405.63927) (xy 42.877109 -405.610928)
			(xy 42.851311 -405.550766) (xy 42.833825 -405.487684) (xy 42.824968 -405.422826) (xy 42.8244 -405.390096)
			(xy 42.824941 -405.357366) (xy 42.833804 -405.292506) (xy 42.851302 -405.229426) (xy 42.877116 -405.169269)
			(xy 42.893488 -405.140922) (xy 42.896794 -405.134893) (xy 42.900405 -405.121633) (xy 42.9006 -405.11476)
			(xy 42.9006 -404.828756) (xy 42.901049 -404.818644) (xy 42.908801 -404.799965) (xy 42.923109 -404.785672)
			(xy 42.941796 -404.777939) (xy 42.951908 -404.777448) (xy 43.668188 -404.777448) (xy 43.67829 -404.777994)
			(xy 43.696958 -404.785718) (xy 43.711251 -404.799995) (xy 43.718995 -404.818655) (xy 43.719496 -404.828756)
			(xy 43.719496 -405.11476) (xy 43.719704 -405.121632) (xy 43.723301 -405.134895) (xy 43.726608 -405.140922)
			(xy 43.742983 -405.169266) (xy 43.768782 -405.229427) (xy 43.786269 -405.292509) (xy 43.795127 -405.357367)
			(xy 43.795696 -405.390096) (xy 43.795152 -405.422826) (xy 43.78629 -405.487685) (xy 43.768793 -405.550766)
			(xy 43.74298 -405.610923) (xy 43.726608 -405.63927) (xy 43.723304 -405.6453) (xy 43.719692 -405.65856)
			(xy 43.719496 -405.665432) (xy 43.719496 -406.414732) (xy 43.719676 -406.421606) (xy 43.723292 -406.434869)
			(xy 43.726608 -406.440894) (xy 43.742972 -406.469244) (xy 43.768774 -406.529403) (xy 43.786264 -406.592483)
			(xy 43.795125 -406.657339) (xy 43.795696 -406.690068) (xy 43.795139 -406.722798) (xy 43.78628 -406.787656)
			(xy 43.768788 -406.850737) (xy 43.742978 -406.910894) (xy 43.726608 -406.939242) (xy 43.723279 -406.94526)
			(xy 43.719682 -406.958529) (xy 43.719496 -406.965404) (xy 43.719496 -407.251408) (xy 43.71909 -407.261531)
			(xy 43.711339 -407.280236) (xy 43.697019 -407.29455) (xy 43.678312 -407.302294) (xy 43.668188 -407.302716)
			(xy 42.951908 -407.302716) (xy 42.941802 -407.302209) (xy 42.923127 -407.294477) (xy 42.908832 -407.280187)
			(xy 42.901094 -407.261514) (xy 42.9006 -407.251408) (xy 42.9006 -406.965404) (xy 42.900407 -406.958531)
			(xy 42.8968 -406.945268) (xy 42.893488 -406.939242) (xy 42.877138 -406.910884) (xy 42.851333 -406.850728)
			(xy 42.833839 -406.787651) (xy 42.824973 -406.722796) (xy 42.8244 -406.690068) (xy 39.395041 -406.690068)
			(xy 39.395043 -406.72279) (xy 39.386262 -406.787633) (xy 39.368857 -406.850711) (xy 39.343141 -406.910881)
			(xy 39.32682 -406.939242) (xy 39.323492 -406.94526) (xy 39.319894 -406.958529) (xy 39.319708 -406.965404)
			(xy 39.319708 -407.251408) (xy 39.319285 -407.261562) (xy 39.311488 -407.280313) (xy 39.297092 -407.294635)
			(xy 39.278302 -407.302336) (xy 39.268146 -407.302716) (xy 38.551866 -407.302716) (xy 38.541732 -407.3023)
			(xy 38.523001 -407.294553) (xy 38.508645 -407.280245) (xy 38.500835 -407.261541) (xy 38.500304 -407.251408)
			(xy 38.500304 -406.965404) (xy 38.50011 -406.958531) (xy 38.496503 -406.945268) (xy 38.493192 -406.939242)
			(xy 38.476844 -406.910895) (xy 38.451132 -406.85072) (xy 38.433728 -406.787638) (xy 38.424949 -406.722792)
			(xy 34.995053 -406.722792) (xy 34.995053 -406.722798) (xy 34.986195 -406.787656) (xy 34.968703 -406.850736)
			(xy 34.942894 -406.910894) (xy 34.926524 -406.939242) (xy 34.923196 -406.94526) (xy 34.919598 -406.958529)
			(xy 34.919412 -406.965404) (xy 34.919412 -407.251408) (xy 34.918922 -407.261516) (xy 34.911184 -407.280192)
			(xy 34.896888 -407.294486) (xy 34.878212 -407.302222) (xy 34.868104 -407.302716) (xy 34.151824 -407.302716)
			(xy 34.141705 -407.302265) (xy 34.123005 -407.294528) (xy 34.10869 -407.280222) (xy 34.100941 -407.261527)
			(xy 34.100516 -407.251408) (xy 34.100516 -406.965404) (xy 34.100321 -406.958531) (xy 34.096715 -406.945268)
			(xy 34.093404 -406.939242) (xy 34.077056 -406.910883) (xy 34.051249 -406.850727) (xy 34.033755 -406.787651)
			(xy 34.024889 -406.722796) (xy 34.024316 -406.690068) (xy 30.594954 -406.690068) (xy 30.594956 -406.72279)
			(xy 30.586176 -406.787633) (xy 30.568772 -406.850711) (xy 30.543057 -406.910881) (xy 30.526736 -406.939242)
			(xy 30.523409 -406.945261) (xy 30.519811 -406.958529) (xy 30.519624 -406.965404) (xy 30.519624 -407.251408)
			(xy 30.519185 -407.26156) (xy 30.511392 -407.280307) (xy 30.497001 -407.29463) (xy 30.478216 -407.302333)
			(xy 30.468062 -407.302716) (xy 29.751782 -407.302716) (xy 29.741649 -407.302287) (xy 29.722919 -407.294545)
			(xy 29.708561 -407.280241) (xy 29.700751 -407.261539) (xy 29.70022 -407.251408) (xy 29.70022 -406.965404)
			(xy 29.700024 -406.958531) (xy 29.696418 -406.945268) (xy 29.693108 -406.939242) (xy 29.67676 -406.910895)
			(xy 29.651046 -406.85072) (xy 29.633642 -406.787639) (xy 29.624863 -406.722792) (xy 0.6096 -406.722792)
			(xy 0.6096 -409.490164) (xy 27.42438 -409.490164) (xy 27.424955 -409.457435) (xy 27.433808 -409.392577)
			(xy 27.451296 -409.329497) (xy 27.477101 -409.269339) (xy 27.493468 -409.24099) (xy 27.496784 -409.234966)
			(xy 27.500389 -409.221702) (xy 27.50058 -409.214828) (xy 27.50058 -408.465528) (xy 27.50038 -408.458655)
			(xy 27.496777 -408.445393) (xy 27.493468 -408.439366) (xy 27.477095 -408.411021) (xy 27.451294 -408.35086)
			(xy 27.433806 -408.287779) (xy 27.424948 -408.222921) (xy 27.42438 -408.190192) (xy 27.424967 -408.157463)
			(xy 27.433817 -408.092606) (xy 27.451301 -408.029526) (xy 27.477103 -407.969367) (xy 27.493468 -407.941018)
			(xy 27.496774 -407.934989) (xy 27.500385 -407.921729) (xy 27.50058 -407.914856) (xy 27.50058 -407.628852)
			(xy 27.501045 -407.618743) (xy 27.508795 -407.600067) (xy 27.523098 -407.585775) (xy 27.541778 -407.578038)
			(xy 27.551888 -407.577544) (xy 28.268168 -407.577544) (xy 28.278268 -407.57811) (xy 28.296935 -407.585826)
			(xy 28.311229 -407.600098) (xy 28.318975 -407.618753) (xy 28.319476 -407.628852) (xy 28.319476 -407.914856)
			(xy 28.319688 -407.921728) (xy 28.323283 -407.93499) (xy 28.326588 -407.941018) (xy 28.34296 -407.969364)
			(xy 28.36876 -408.029525) (xy 28.386248 -408.092605) (xy 28.395107 -408.157463) (xy 28.395676 -408.190192)
			(xy 28.395132 -408.222922) (xy 28.38627 -408.287781) (xy 28.368774 -408.350862) (xy 28.34296 -408.411019)
			(xy 28.326588 -408.439366) (xy 28.323285 -408.445396) (xy 28.319672 -408.458656) (xy 28.319476 -408.465528)
			(xy 28.319476 -409.214828) (xy 28.31966 -409.221702) (xy 28.323274 -409.234964) (xy 28.326588 -409.24099)
			(xy 28.342948 -409.269342) (xy 28.368752 -409.3295) (xy 28.386243 -409.392579) (xy 28.395105 -409.457435)
			(xy 28.395676 -409.490164) (xy 28.39512 -409.522894) (xy 28.386262 -409.587753) (xy 28.368769 -409.650833)
			(xy 28.342958 -409.71099) (xy 28.326588 -409.739338) (xy 28.323259 -409.745356) (xy 28.319663 -409.758625)
			(xy 28.319476 -409.7655) (xy 28.319476 -410.051504) (xy 28.319087 -410.06163) (xy 28.311333 -410.080338)
			(xy 28.297008 -410.094653) (xy 28.278294 -410.102394) (xy 28.268168 -410.102812) (xy 27.551888 -410.102812)
			(xy 27.54178 -410.102325) (xy 27.523104 -410.094585) (xy 27.50881 -410.080289) (xy 27.501074 -410.061612)
			(xy 27.50058 -410.051504) (xy 27.50058 -409.7655) (xy 27.50039 -409.758627) (xy 27.496781 -409.745364)
			(xy 27.493468 -409.739338) (xy 27.477124 -409.710977) (xy 27.451315 -409.650822) (xy 27.433819 -409.587746)
			(xy 27.424953 -409.522892) (xy 27.42438 -409.490164) (xy 0.6096 -409.490164) (xy 0.6096 -410.248608)
			(xy 14.998698 -410.248608) (xy 15.002769 -410.192986) (xy 15.014895 -410.138549) (xy 15.034818 -410.086458)
			(xy 15.062114 -410.037823) (xy 15.0962 -409.99368) (xy 15.136349 -409.954971) (xy 15.181707 -409.92252)
			(xy 15.231307 -409.897019) (xy 15.284091 -409.879012) (xy 15.338934 -409.868882) (xy 15.394668 -409.866845)
			(xy 15.450105 -409.872945) (xy 15.504062 -409.887051) (xy 15.555391 -409.908863) (xy 15.602997 -409.937917)
			(xy 15.645865 -409.973592) (xy 15.683082 -410.015129) (xy 15.713855 -410.061642) (xy 15.737527 -410.112139)
			(xy 15.753595 -410.165546) (xy 15.761715 -410.220722) (xy 15.762224 -410.248608) (xy 15.761715 -410.276494)
			(xy 15.753595 -410.33167) (xy 15.737527 -410.385077) (xy 15.713855 -410.435574) (xy 15.683082 -410.482087)
			(xy 15.645865 -410.523624) (xy 15.602997 -410.559299) (xy 15.555391 -410.588353) (xy 15.504062 -410.610165)
			(xy 15.456095 -410.622705) (xy 29.624872 -410.622705) (xy 29.624874 -410.557268) (xy 29.633659 -410.492423)
			(xy 29.651068 -410.429343) (xy 29.676786 -410.369172) (xy 29.693108 -410.34081) (xy 29.69642 -410.334784)
			(xy 29.700027 -410.321521) (xy 29.70022 -410.314648) (xy 29.70022 -409.565348) (xy 29.700007 -409.558476)
			(xy 29.696413 -409.545214) (xy 29.693108 -409.539186) (xy 29.676797 -409.510819) (xy 29.65108 -409.450649)
			(xy 29.633672 -409.387571) (xy 29.624888 -409.322728) (xy 29.624886 -409.257293) (xy 29.633668 -409.192449)
			(xy 29.651073 -409.129371) (xy 29.676788 -409.0692) (xy 29.693108 -409.040838) (xy 29.69641 -409.034807)
			(xy 29.700023 -409.021548) (xy 29.70022 -409.014676) (xy 29.70022 -408.728672) (xy 29.700599 -408.718514)
			(xy 29.708408 -408.699757) (xy 29.722817 -408.685434) (xy 29.741621 -408.677738) (xy 29.751782 -408.677364)
			(xy 30.468062 -408.677364) (xy 30.478189 -408.677859) (xy 30.496914 -408.685578) (xy 30.511272 -408.699863)
			(xy 30.519089 -408.718547) (xy 30.519624 -408.728672) (xy 30.519624 -409.014676) (xy 30.519822 -409.021549)
			(xy 30.523426 -409.034812) (xy 30.526736 -409.040838) (xy 30.543069 -409.069193) (xy 30.568787 -409.129366)
			(xy 30.586195 -409.192446) (xy 30.594978 -409.257291) (xy 30.594976 -409.322729) (xy 30.586191 -409.387575)
			(xy 30.56878 -409.450654) (xy 30.54306 -409.510825) (xy 30.536116 -409.522889) (xy 31.825002 -409.522889)
			(xy 31.825006 -409.457449) (xy 31.833794 -409.392603) (xy 31.851208 -409.329523) (xy 31.876931 -409.269351)
			(xy 31.893256 -409.24099) (xy 31.896571 -409.234965) (xy 31.900177 -409.221702) (xy 31.900368 -409.214828)
			(xy 31.900368 -408.465528) (xy 31.900169 -408.458655) (xy 31.896566 -408.445392) (xy 31.893256 -408.439366)
			(xy 31.876926 -408.411009) (xy 31.851209 -408.350837) (xy 31.833801 -408.287757) (xy 31.825018 -408.222912)
			(xy 31.825019 -408.157474) (xy 31.833803 -408.092629) (xy 31.851213 -408.02955) (xy 31.876933 -407.969379)
			(xy 31.893256 -407.941018) (xy 31.896561 -407.934988) (xy 31.900173 -407.921729) (xy 31.900368 -407.914856)
			(xy 31.900368 -407.628852) (xy 31.900782 -407.618699) (xy 31.908587 -407.599952) (xy 31.922985 -407.585631)
			(xy 31.941775 -407.577927) (xy 31.95193 -407.577544) (xy 32.66821 -407.577544) (xy 32.678338 -407.578019)
			(xy 32.69706 -407.58575) (xy 32.711416 -407.60004) (xy 32.719234 -407.618727) (xy 32.719772 -407.628852)
			(xy 32.719772 -407.914856) (xy 32.719984 -407.921728) (xy 32.723579 -407.93499) (xy 32.726884 -407.941018)
			(xy 32.743199 -407.969383) (xy 32.768916 -408.029554) (xy 32.786324 -408.092632) (xy 32.795108 -408.157475)
			(xy 32.795109 -408.222911) (xy 32.786327 -408.287755) (xy 32.76892 -408.350833) (xy 32.743205 -408.411005)
			(xy 32.726884 -408.439366) (xy 32.72358 -408.445396) (xy 32.719968 -408.458656) (xy 32.719772 -408.465528)
			(xy 32.719772 -409.214828) (xy 32.719957 -409.221702) (xy 32.72357 -409.234964) (xy 32.726884 -409.24099)
			(xy 32.743175 -409.269368) (xy 32.768894 -409.329536) (xy 32.786305 -409.392611) (xy 32.795092 -409.457452)
			(xy 32.795096 -409.522886) (xy 32.786317 -409.587728) (xy 32.768915 -409.650806) (xy 32.743203 -409.710977)
			(xy 32.726884 -409.739338) (xy 32.723555 -409.745355) (xy 32.719959 -409.758625) (xy 32.719772 -409.7655)
			(xy 32.719772 -410.051504) (xy 32.719381 -410.061662) (xy 32.711579 -410.08042) (xy 32.697172 -410.094744)
			(xy 32.67837 -410.102438) (xy 32.66821 -410.102812) (xy 31.95193 -410.102812) (xy 31.941812 -410.102251)
			(xy 31.923101 -410.094542) (xy 31.908745 -410.080279) (xy 31.900916 -410.061619) (xy 31.900368 -410.051504)
			(xy 31.900368 -409.7655) (xy 31.90018 -409.758626) (xy 31.896569 -409.745364) (xy 31.893256 -409.739338)
			(xy 31.876903 -409.710994) (xy 31.851187 -409.650819) (xy 31.833782 -409.587737) (xy 31.825002 -409.522889)
			(xy 30.536116 -409.522889) (xy 30.526736 -409.539186) (xy 30.523429 -409.545215) (xy 30.519818 -409.558475)
			(xy 30.519624 -409.565348) (xy 30.519624 -410.314648) (xy 30.519833 -410.32152) (xy 30.523429 -410.334783)
			(xy 30.526736 -410.34081) (xy 30.543045 -410.369178) (xy 30.568766 -410.429348) (xy 30.586176 -410.492425)
			(xy 30.594962 -410.557268) (xy 30.594963 -410.589984) (xy 34.024316 -410.589984) (xy 34.024895 -410.557255)
			(xy 34.033746 -410.492397) (xy 34.051233 -410.429317) (xy 34.077037 -410.369158) (xy 34.093404 -410.34081)
			(xy 34.096715 -410.334784) (xy 34.100323 -410.321521) (xy 34.100516 -410.314648) (xy 34.100516 -409.565348)
			(xy 34.100303 -409.558476) (xy 34.096709 -409.545214) (xy 34.093404 -409.539186) (xy 34.077033 -409.51084)
			(xy 34.051233 -409.450679) (xy 34.033744 -409.387599) (xy 34.024886 -409.322741) (xy 34.024316 -409.290012)
			(xy 34.024863 -409.257282) (xy 34.033724 -409.192423) (xy 34.05122 -409.129343) (xy 34.077033 -409.069185)
			(xy 34.093404 -409.040838) (xy 34.096706 -409.034807) (xy 34.100319 -409.021548) (xy 34.100516 -409.014676)
			(xy 34.100516 -408.728672) (xy 34.100962 -408.718559) (xy 34.108712 -408.699878) (xy 34.123021 -408.685583)
			(xy 34.141711 -408.677852) (xy 34.151824 -408.677364) (xy 34.868104 -408.677364) (xy 34.878209 -408.677881)
			(xy 34.89688 -408.685613) (xy 34.911173 -408.6999) (xy 34.918914 -408.718568) (xy 34.919412 -408.728672)
			(xy 34.919412 -409.014676) (xy 34.919612 -409.021549) (xy 34.923215 -409.034811) (xy 34.926524 -409.040838)
			(xy 34.942907 -409.069178) (xy 34.968704 -409.129341) (xy 34.986189 -409.192423) (xy 34.995044 -409.257282)
			(xy 34.995612 -409.290012) (xy 34.995027 -409.322741) (xy 34.986177 -409.387598) (xy 34.968692 -409.450678)
			(xy 34.951757 -409.490164) (xy 36.224464 -409.490164) (xy 36.225041 -409.457435) (xy 36.233894 -409.392577)
			(xy 36.251381 -409.329497) (xy 36.277185 -409.269338) (xy 36.293552 -409.24099) (xy 36.296866 -409.234965)
			(xy 36.300473 -409.221702) (xy 36.300664 -409.214828) (xy 36.300664 -408.465528) (xy 36.300466 -408.458655)
			(xy 36.296862 -408.445392) (xy 36.293552 -408.439366) (xy 36.277178 -408.411021) (xy 36.251377 -408.350861)
			(xy 36.233889 -408.28778) (xy 36.225032 -408.222921) (xy 36.224464 -408.190192) (xy 36.225054 -408.157463)
			(xy 36.233903 -408.092606) (xy 36.251387 -408.029526) (xy 36.277187 -407.969367) (xy 36.293552 -407.941018)
			(xy 36.296856 -407.934988) (xy 36.300469 -407.921729) (xy 36.300664 -407.914856) (xy 36.300664 -407.628852)
			(xy 36.301145 -407.618745) (xy 36.308892 -407.600072) (xy 36.323189 -407.585781) (xy 36.341864 -407.578041)
			(xy 36.351972 -407.577544) (xy 37.068252 -407.577544) (xy 37.078351 -407.578123) (xy 37.097017 -407.585835)
			(xy 37.111312 -407.600102) (xy 37.119058 -407.618754) (xy 37.11956 -407.628852) (xy 37.11956 -407.914856)
			(xy 37.119774 -407.921728) (xy 37.123368 -407.93499) (xy 37.126672 -407.941018) (xy 37.143042 -407.969365)
			(xy 37.168843 -408.029525) (xy 37.186332 -408.092605) (xy 37.195191 -408.157463) (xy 37.19576 -408.190192)
			(xy 37.195205 -408.222922) (xy 37.186345 -408.28778) (xy 37.168851 -408.35086) (xy 37.143042 -408.411018)
			(xy 37.126672 -408.439366) (xy 37.123367 -408.445396) (xy 37.119756 -408.458656) (xy 37.11956 -408.465528)
			(xy 37.11956 -409.214828) (xy 37.119746 -409.221702) (xy 37.123359 -409.234964) (xy 37.126672 -409.24099)
			(xy 37.143031 -409.269343) (xy 37.168835 -409.329501) (xy 37.186327 -409.392579) (xy 37.195189 -409.457435)
			(xy 37.19576 -409.490164) (xy 37.195192 -409.522893) (xy 37.186336 -409.587751) (xy 37.168846 -409.650831)
			(xy 37.14304 -409.71099) (xy 37.126672 -409.739338) (xy 37.123342 -409.745355) (xy 37.119746 -409.758625)
			(xy 37.11956 -409.7655) (xy 37.11956 -410.051504) (xy 37.119186 -410.061632) (xy 37.111429 -410.080343)
			(xy 37.097099 -410.094659) (xy 37.07838 -410.102396) (xy 37.068252 -410.102812) (xy 36.351972 -410.102812)
			(xy 36.341863 -410.102338) (xy 36.323186 -410.094594) (xy 36.308893 -410.080293) (xy 36.301157 -410.061613)
			(xy 36.300664 -410.051504) (xy 36.300664 -409.7655) (xy 36.300476 -409.758626) (xy 36.296866 -409.745363)
			(xy 36.293552 -409.739338) (xy 36.277207 -409.710978) (xy 36.251399 -409.650823) (xy 36.233903 -409.587746)
			(xy 36.225037 -409.522892) (xy 36.224464 -409.490164) (xy 34.951757 -409.490164) (xy 34.94289 -409.510837)
			(xy 34.926524 -409.539186) (xy 34.923216 -409.545214) (xy 34.919606 -409.558475) (xy 34.919412 -409.565348)
			(xy 34.919412 -410.314648) (xy 34.919622 -410.32152) (xy 34.923218 -410.334783) (xy 34.926524 -410.34081)
			(xy 34.942896 -410.369156) (xy 34.968696 -410.429317) (xy 34.986183 -410.492397) (xy 34.995042 -410.557255)
			(xy 34.995612 -410.589984) (xy 34.99506 -410.622705) (xy 38.424958 -410.622705) (xy 38.42496 -410.557268)
			(xy 38.433744 -410.492423) (xy 38.451153 -410.429344) (xy 38.47687 -410.369172) (xy 38.493192 -410.34081)
			(xy 38.496503 -410.334783) (xy 38.500111 -410.321521) (xy 38.500304 -410.314648) (xy 38.500304 -409.565348)
			(xy 38.500093 -409.558476) (xy 38.496498 -409.545213) (xy 38.493192 -409.539186) (xy 38.476881 -409.510819)
			(xy 38.451165 -409.450648) (xy 38.433758 -409.387571) (xy 38.424974 -409.322728) (xy 38.424972 -409.257293)
			(xy 38.433754 -409.192449) (xy 38.451159 -409.129371) (xy 38.476872 -409.0692) (xy 38.493192 -409.040838)
			(xy 38.496493 -409.034806) (xy 38.500107 -409.021548) (xy 38.500304 -409.014676) (xy 38.500304 -408.728672)
			(xy 38.500699 -408.718516) (xy 38.508504 -408.699762) (xy 38.522909 -408.685439) (xy 38.541707 -408.677741)
			(xy 38.551866 -408.677364) (xy 39.268146 -408.677364) (xy 39.278279 -408.67779) (xy 39.297005 -408.685537)
			(xy 39.311361 -408.699842) (xy 39.319174 -408.718541) (xy 39.319708 -408.728672) (xy 39.319708 -409.014676)
			(xy 39.319908 -409.021549) (xy 39.323511 -409.034811) (xy 39.32682 -409.040838) (xy 39.343154 -409.069193)
			(xy 39.368872 -409.129365) (xy 39.386281 -409.192445) (xy 39.395064 -409.257291) (xy 39.395063 -409.322729)
			(xy 39.386277 -409.387575) (xy 39.368866 -409.450654) (xy 39.351976 -409.490164) (xy 40.624252 -409.490164)
			(xy 40.62483 -409.457435) (xy 40.633683 -409.392577) (xy 40.65117 -409.329497) (xy 40.676973 -409.269339)
			(xy 40.69334 -409.24099) (xy 40.696654 -409.234965) (xy 40.700261 -409.221702) (xy 40.700452 -409.214828)
			(xy 40.700452 -408.465528) (xy 40.700255 -408.458655) (xy 40.696651 -408.445392) (xy 40.69334 -408.439366)
			(xy 40.676965 -408.411022) (xy 40.651164 -408.350861) (xy 40.633677 -408.28778) (xy 40.62482 -408.222922)
			(xy 40.624252 -408.190192) (xy 40.624843 -408.157463) (xy 40.633692 -408.092606) (xy 40.651175 -408.029526)
			(xy 40.676975 -407.969367) (xy 40.69334 -407.941018) (xy 40.696644 -407.934988) (xy 40.700257 -407.921728)
			(xy 40.700452 -407.914856) (xy 40.700452 -407.628852) (xy 40.700945 -407.618746) (xy 40.708689 -407.600076)
			(xy 40.722983 -407.585785) (xy 40.741654 -407.578043) (xy 40.75176 -407.577544) (xy 41.46804 -407.577544)
			(xy 41.478144 -407.578051) (xy 41.496813 -407.585791) (xy 41.511104 -407.600081) (xy 41.518847 -407.618748)
			(xy 41.519348 -407.628852) (xy 41.519348 -407.914856) (xy 41.519551 -407.921729) (xy 41.523151 -407.934992)
			(xy 41.52646 -407.941018) (xy 41.542829 -407.969365) (xy 41.568631 -408.029525) (xy 41.58612 -408.092605)
			(xy 41.594979 -408.157463) (xy 41.595548 -408.190192) (xy 41.594995 -408.222922) (xy 41.586134 -408.28778)
			(xy 41.56864 -408.35086) (xy 41.54283 -408.411018) (xy 41.52646 -408.439366) (xy 41.523162 -408.445399)
			(xy 41.519545 -408.458656) (xy 41.519348 -408.465528) (xy 41.519348 -409.214828) (xy 41.519523 -409.221703)
			(xy 41.523142 -409.234966) (xy 41.52646 -409.24099) (xy 41.542818 -409.269344) (xy 41.568622 -409.329501)
			(xy 41.586114 -409.392579) (xy 41.594977 -409.457435) (xy 41.595548 -409.490164) (xy 41.594982 -409.522893)
			(xy 41.586125 -409.587751) (xy 41.568635 -409.650832) (xy 41.542828 -409.71099) (xy 41.52646 -409.739338)
			(xy 41.523136 -409.745358) (xy 41.519536 -409.758625) (xy 41.519348 -409.7655) (xy 41.519348 -410.051504)
			(xy 41.518819 -410.061607) (xy 41.511089 -410.080276) (xy 41.496806 -410.094569) (xy 41.478143 -410.102312)
			(xy 41.46804 -410.102812) (xy 40.75176 -410.102812) (xy 40.74165 -410.102348) (xy 40.722973 -410.094599)
			(xy 40.70868 -410.080296) (xy 40.700945 -410.061614) (xy 40.700452 -410.051504) (xy 40.700452 -409.7655)
			(xy 40.700266 -409.758626) (xy 40.696654 -409.745363) (xy 40.69334 -409.739338) (xy 40.676993 -409.710978)
			(xy 40.651186 -409.650823) (xy 40.633691 -409.587747) (xy 40.624825 -409.522892) (xy 40.624252 -409.490164)
			(xy 39.351976 -409.490164) (xy 39.343144 -409.510825) (xy 39.32682 -409.539186) (xy 39.323512 -409.545214)
			(xy 39.319902 -409.558475) (xy 39.319708 -409.565348) (xy 39.319708 -410.314648) (xy 39.319919 -410.32152)
			(xy 39.323514 -410.334783) (xy 39.32682 -410.34081) (xy 39.34313 -410.369178) (xy 39.368851 -410.429347)
			(xy 39.386262 -410.492425) (xy 39.395048 -410.557268) (xy 39.395049 -410.589984) (xy 42.8244 -410.589984)
			(xy 42.824981 -410.557255) (xy 42.833832 -410.492397) (xy 42.851318 -410.429317) (xy 42.877122 -410.369159)
			(xy 42.893488 -410.34081) (xy 42.896798 -410.334783) (xy 42.900407 -410.321521) (xy 42.9006 -410.314648)
			(xy 42.9006 -409.565348) (xy 42.90039 -409.558476) (xy 42.896794 -409.545213) (xy 42.893488 -409.539186)
			(xy 42.877116 -409.51084) (xy 42.851316 -409.45068) (xy 42.833828 -409.387599) (xy 42.82497 -409.322741)
			(xy 42.8244 -409.290012) (xy 42.824948 -409.257282) (xy 42.833809 -409.192423) (xy 42.851305 -409.129343)
			(xy 42.877117 -409.069185) (xy 42.893488 -409.040838) (xy 42.896788 -409.034806) (xy 42.900403 -409.021548)
			(xy 42.9006 -409.014676) (xy 42.9006 -408.728672) (xy 42.901062 -408.718561) (xy 42.908809 -408.699883)
			(xy 42.923113 -408.685589) (xy 42.941797 -408.677855) (xy 42.951908 -408.677364) (xy 43.668188 -408.677364)
			(xy 43.678292 -408.677894) (xy 43.696963 -408.685621) (xy 43.711257 -408.699904) (xy 43.718998 -408.718569)
			(xy 43.719496 -408.728672) (xy 43.719496 -409.014676) (xy 43.719697 -409.021549) (xy 43.723299 -409.034811)
			(xy 43.726608 -409.040838) (xy 43.742989 -409.069178) (xy 43.768787 -409.129341) (xy 43.786272 -409.192423)
			(xy 43.795128 -409.257282) (xy 43.795696 -409.290012) (xy 43.795114 -409.322741) (xy 43.786263 -409.387599)
			(xy 43.768777 -409.450679) (xy 43.742974 -409.510837) (xy 43.726608 -409.539186) (xy 43.723299 -409.545213)
			(xy 43.71969 -409.558475) (xy 43.719496 -409.565348) (xy 43.719496 -410.314648) (xy 43.719709 -410.32152)
			(xy 43.723303 -410.334782) (xy 43.726608 -410.34081) (xy 43.742978 -410.369157) (xy 43.768779 -410.429317)
			(xy 43.786267 -410.492397) (xy 43.795126 -410.557255) (xy 43.795696 -410.589984) (xy 43.795146 -410.622714)
			(xy 43.786285 -410.687573) (xy 43.768791 -410.750653) (xy 43.742979 -410.81081) (xy 43.726608 -410.839158)
			(xy 43.723309 -410.84519) (xy 43.719693 -410.858448) (xy 43.719496 -410.86532) (xy 43.719496 -411.151324)
			(xy 43.719035 -411.161435) (xy 43.711288 -411.180114) (xy 43.696984 -411.194408) (xy 43.678299 -411.202142)
			(xy 43.668188 -411.202632) (xy 42.951908 -411.202632) (xy 42.941804 -411.202109) (xy 42.923132 -411.19438)
			(xy 42.908838 -411.180095) (xy 42.901097 -411.161428) (xy 42.9006 -411.151324) (xy 42.9006 -410.86532)
			(xy 42.9004 -410.858447) (xy 42.896797 -410.845185) (xy 42.893488 -410.839158) (xy 42.877105 -410.810819)
			(xy 42.851307 -410.750655) (xy 42.833823 -410.687573) (xy 42.824968 -410.622714) (xy 42.8244 -410.589984)
			(xy 39.395049 -410.589984) (xy 39.39505 -410.622704) (xy 39.386268 -410.687548) (xy 39.36886 -410.750627)
			(xy 39.343142 -410.810797) (xy 39.32682 -410.839158) (xy 39.323522 -410.845191) (xy 39.319905 -410.858448)
			(xy 39.319708 -410.86532) (xy 39.319708 -411.151324) (xy 39.319298 -411.161479) (xy 39.311496 -411.18023)
			(xy 39.297096 -411.194552) (xy 39.278303 -411.202253) (xy 39.268146 -411.202632) (xy 38.551866 -411.202632)
			(xy 38.541734 -411.202201) (xy 38.523006 -411.194456) (xy 38.50865 -411.180153) (xy 38.500837 -411.161454)
			(xy 38.500304 -411.151324) (xy 38.500304 -410.86532) (xy 38.500104 -410.858447) (xy 38.496501 -410.845185)
			(xy 38.493192 -410.839158) (xy 38.476858 -410.810804) (xy 38.451144 -410.75063) (xy 38.433739 -410.68755)
			(xy 38.424958 -410.622705) (xy 34.99506 -410.622705) (xy 34.99506 -410.622714) (xy 34.9862 -410.687573)
			(xy 34.968706 -410.750653) (xy 34.942895 -410.810811) (xy 34.926524 -410.839158) (xy 34.923226 -410.845191)
			(xy 34.919609 -410.858448) (xy 34.919412 -410.86532) (xy 34.919412 -411.151324) (xy 34.918935 -411.161433)
			(xy 34.911192 -411.180109) (xy 34.896893 -411.194403) (xy 34.878213 -411.202139) (xy 34.868104 -411.202632)
			(xy 34.151824 -411.202632) (xy 34.141721 -411.202096) (xy 34.123049 -411.194372) (xy 34.108755 -411.180091)
			(xy 34.101013 -411.161427) (xy 34.100516 -411.151324) (xy 34.100516 -410.86532) (xy 34.100315 -410.858447)
			(xy 34.096713 -410.845185) (xy 34.093404 -410.839158) (xy 34.077022 -410.810818) (xy 34.051224 -410.750655)
			(xy 34.033739 -410.687573) (xy 34.024884 -410.622714) (xy 34.024316 -410.589984) (xy 30.594963 -410.589984)
			(xy 30.594964 -410.622704) (xy 30.586182 -410.687548) (xy 30.568775 -410.750626) (xy 30.543058 -410.810797)
			(xy 30.526736 -410.839158) (xy 30.523439 -410.845191) (xy 30.519822 -410.858448) (xy 30.519624 -410.86532)
			(xy 30.519624 -411.151324) (xy 30.519199 -411.161477) (xy 30.5114 -411.180225) (xy 30.497005 -411.194547)
			(xy 30.478217 -411.20225) (xy 30.468062 -411.202632) (xy 29.751782 -411.202632) (xy 29.741651 -411.202188)
			(xy 29.722924 -411.194449) (xy 29.708567 -411.180149) (xy 29.700753 -411.161453) (xy 29.70022 -411.151324)
			(xy 29.70022 -410.86532) (xy 29.700018 -410.858448) (xy 29.696416 -410.845185) (xy 29.693108 -410.839158)
			(xy 29.676773 -410.810804) (xy 29.651058 -410.750631) (xy 29.633653 -410.687551) (xy 29.624872 -410.622705)
			(xy 15.456095 -410.622705) (xy 15.450105 -410.624271) (xy 15.394668 -410.630371) (xy 15.338934 -410.628334)
			(xy 15.284091 -410.618204) (xy 15.231307 -410.600197) (xy 15.181707 -410.574696) (xy 15.136349 -410.542245)
			(xy 15.0962 -410.503536) (xy 15.062114 -410.459393) (xy 15.034818 -410.410758) (xy 15.014895 -410.358667)
			(xy 15.002769 -410.30423) (xy 14.998698 -410.248608) (xy 0.6096 -410.248608) (xy 0.6096 -412.752286)
			(xy 17.883122 -412.752286) (xy 17.887193 -412.696664) (xy 17.899319 -412.642227) (xy 17.919242 -412.590136)
			(xy 17.946538 -412.541501) (xy 17.980624 -412.497358) (xy 18.020773 -412.458649) (xy 18.066131 -412.426198)
			(xy 18.115731 -412.400697) (xy 18.168515 -412.38269) (xy 18.223358 -412.37256) (xy 18.279092 -412.370523)
			(xy 18.334529 -412.376623) (xy 18.388486 -412.390729) (xy 18.439815 -412.412541) (xy 18.487421 -412.441595)
			(xy 18.530289 -412.47727) (xy 18.567506 -412.518807) (xy 18.598279 -412.56532) (xy 18.621951 -412.615817)
			(xy 18.638019 -412.669224) (xy 18.646139 -412.7244) (xy 18.646648 -412.752286) (xy 18.646139 -412.780172)
			(xy 18.638019 -412.835348) (xy 18.621951 -412.888755) (xy 18.598527 -412.938722) (xy 19.503896 -412.938722)
			(xy 19.507967 -412.8831) (xy 19.520093 -412.828663) (xy 19.540016 -412.776572) (xy 19.567312 -412.727937)
			(xy 19.601398 -412.683794) (xy 19.641547 -412.645085) (xy 19.686905 -412.612634) (xy 19.736505 -412.587133)
			(xy 19.789289 -412.569126) (xy 19.844132 -412.558996) (xy 19.899866 -412.556959) (xy 19.955303 -412.563059)
			(xy 20.00926 -412.577165) (xy 20.060589 -412.598977) (xy 20.108195 -412.628031) (xy 20.151063 -412.663706)
			(xy 20.1683 -412.682944) (xy 20.874988 -412.682944) (xy 20.879059 -412.627322) (xy 20.891185 -412.572885)
			(xy 20.911108 -412.520794) (xy 20.938404 -412.472159) (xy 20.97249 -412.428016) (xy 21.012639 -412.389307)
			(xy 21.057997 -412.356856) (xy 21.107597 -412.331355) (xy 21.160381 -412.313348) (xy 21.215224 -412.303218)
			(xy 21.270958 -412.301181) (xy 21.326395 -412.307281) (xy 21.380352 -412.321387) (xy 21.431681 -412.343199)
			(xy 21.479287 -412.372253) (xy 21.522155 -412.407928) (xy 21.559372 -412.449465) (xy 21.590145 -412.495978)
			(xy 21.613817 -412.546475) (xy 21.629885 -412.599882) (xy 21.638005 -412.655058) (xy 21.638514 -412.682944)
			(xy 21.638005 -412.71083) (xy 21.629885 -412.766006) (xy 21.613817 -412.819413) (xy 21.590145 -412.86991)
			(xy 21.559372 -412.916423) (xy 21.522155 -412.95796) (xy 21.479287 -412.993635) (xy 21.431681 -413.022689)
			(xy 21.380352 -413.044501) (xy 21.326395 -413.058607) (xy 21.270958 -413.064707) (xy 21.215224 -413.06267)
			(xy 21.160381 -413.05254) (xy 21.107597 -413.034533) (xy 21.057997 -413.009032) (xy 21.012639 -412.976581)
			(xy 20.97249 -412.937872) (xy 20.938404 -412.893729) (xy 20.911108 -412.845094) (xy 20.891185 -412.793003)
			(xy 20.879059 -412.738566) (xy 20.874988 -412.682944) (xy 20.1683 -412.682944) (xy 20.18828 -412.705243)
			(xy 20.219053 -412.751756) (xy 20.242725 -412.802253) (xy 20.258793 -412.85566) (xy 20.266913 -412.910836)
			(xy 20.267422 -412.938722) (xy 20.266913 -412.966608) (xy 20.258793 -413.021784) (xy 20.242725 -413.075191)
			(xy 20.219053 -413.125688) (xy 20.18828 -413.172201) (xy 20.151063 -413.213738) (xy 20.108195 -413.249413)
			(xy 20.060589 -413.278467) (xy 20.00926 -413.300279) (xy 19.955303 -413.314385) (xy 19.899866 -413.320485)
			(xy 19.844132 -413.318448) (xy 19.789289 -413.308318) (xy 19.736505 -413.290311) (xy 19.686905 -413.26481)
			(xy 19.641547 -413.232359) (xy 19.601398 -413.19365) (xy 19.567312 -413.149507) (xy 19.540016 -413.100872)
			(xy 19.520093 -413.048781) (xy 19.507967 -412.994344) (xy 19.503896 -412.938722) (xy 18.598527 -412.938722)
			(xy 18.598279 -412.939252) (xy 18.567506 -412.985765) (xy 18.530289 -413.027302) (xy 18.487421 -413.062977)
			(xy 18.439815 -413.092031) (xy 18.388486 -413.113843) (xy 18.334529 -413.127949) (xy 18.279092 -413.134049)
			(xy 18.223358 -413.132012) (xy 18.168515 -413.121882) (xy 18.115731 -413.103875) (xy 18.066131 -413.078374)
			(xy 18.020773 -413.045923) (xy 17.980624 -413.007214) (xy 17.946538 -412.963071) (xy 17.919242 -412.914436)
			(xy 17.899319 -412.862345) (xy 17.887193 -412.807908) (xy 17.883122 -412.752286) (xy 0.6096 -412.752286)
			(xy 0.6096 -414.985454) (xy 17.471896 -414.985454) (xy 17.475967 -414.929832) (xy 17.488093 -414.875395)
			(xy 17.508016 -414.823304) (xy 17.535312 -414.774669) (xy 17.569398 -414.730526) (xy 17.609547 -414.691817)
			(xy 17.654905 -414.659366) (xy 17.704505 -414.633865) (xy 17.757289 -414.615858) (xy 17.812132 -414.605728)
			(xy 17.867866 -414.603691) (xy 17.923303 -414.609791) (xy 17.97726 -414.623897) (xy 18.028589 -414.645709)
			(xy 18.076195 -414.674763) (xy 18.119063 -414.710438) (xy 18.15628 -414.751975) (xy 18.187053 -414.798488)
			(xy 18.210725 -414.848985) (xy 18.226793 -414.902392) (xy 18.234913 -414.957568) (xy 18.235422 -414.985454)
			(xy 19.503896 -414.985454) (xy 19.507967 -414.929832) (xy 19.520093 -414.875395) (xy 19.540016 -414.823304)
			(xy 19.567312 -414.774669) (xy 19.601398 -414.730526) (xy 19.641547 -414.691817) (xy 19.686905 -414.659366)
			(xy 19.736505 -414.633865) (xy 19.789289 -414.615858) (xy 19.844132 -414.605728) (xy 19.899866 -414.603691)
			(xy 19.955303 -414.609791) (xy 20.00926 -414.623897) (xy 20.060589 -414.645709) (xy 20.108195 -414.674763)
			(xy 20.151063 -414.710438) (xy 20.18828 -414.751975) (xy 20.219053 -414.798488) (xy 20.242725 -414.848985)
			(xy 20.258793 -414.902392) (xy 20.266913 -414.957568) (xy 20.267422 -414.985454) (xy 20.519896 -414.985454)
			(xy 20.523967 -414.929832) (xy 20.536093 -414.875395) (xy 20.556016 -414.823304) (xy 20.583312 -414.774669)
			(xy 20.617398 -414.730526) (xy 20.657547 -414.691817) (xy 20.702905 -414.659366) (xy 20.752505 -414.633865)
			(xy 20.805289 -414.615858) (xy 20.860132 -414.605728) (xy 20.915866 -414.603691) (xy 20.971303 -414.609791)
			(xy 21.02526 -414.623897) (xy 21.076589 -414.645709) (xy 21.124195 -414.674763) (xy 21.167063 -414.710438)
			(xy 21.20428 -414.751975) (xy 21.235053 -414.798488) (xy 21.258725 -414.848985) (xy 21.274793 -414.902392)
			(xy 21.282913 -414.957568) (xy 21.283422 -414.985454) (xy 21.282913 -415.01334) (xy 21.274793 -415.068516)
			(xy 21.258725 -415.121923) (xy 21.235053 -415.17242) (xy 21.20428 -415.218933) (xy 21.167063 -415.26047)
			(xy 21.124195 -415.296145) (xy 21.076589 -415.325199) (xy 21.02526 -415.347011) (xy 20.971303 -415.361117)
			(xy 20.915866 -415.367217) (xy 20.860132 -415.36518) (xy 20.805289 -415.35505) (xy 20.752505 -415.337043)
			(xy 20.702905 -415.311542) (xy 20.657547 -415.279091) (xy 20.617398 -415.240382) (xy 20.583312 -415.196239)
			(xy 20.556016 -415.147604) (xy 20.536093 -415.095513) (xy 20.523967 -415.041076) (xy 20.519896 -414.985454)
			(xy 20.267422 -414.985454) (xy 20.266913 -415.01334) (xy 20.258793 -415.068516) (xy 20.242725 -415.121923)
			(xy 20.219053 -415.17242) (xy 20.18828 -415.218933) (xy 20.151063 -415.26047) (xy 20.108195 -415.296145)
			(xy 20.060589 -415.325199) (xy 20.00926 -415.347011) (xy 19.955303 -415.361117) (xy 19.899866 -415.367217)
			(xy 19.844132 -415.36518) (xy 19.789289 -415.35505) (xy 19.736505 -415.337043) (xy 19.686905 -415.311542)
			(xy 19.641547 -415.279091) (xy 19.601398 -415.240382) (xy 19.567312 -415.196239) (xy 19.540016 -415.147604)
			(xy 19.520093 -415.095513) (xy 19.507967 -415.041076) (xy 19.503896 -414.985454) (xy 18.235422 -414.985454)
			(xy 18.234913 -415.01334) (xy 18.226793 -415.068516) (xy 18.210725 -415.121923) (xy 18.187053 -415.17242)
			(xy 18.15628 -415.218933) (xy 18.119063 -415.26047) (xy 18.076195 -415.296145) (xy 18.028589 -415.325199)
			(xy 17.97726 -415.347011) (xy 17.923303 -415.361117) (xy 17.867866 -415.367217) (xy 17.812132 -415.36518)
			(xy 17.757289 -415.35505) (xy 17.704505 -415.337043) (xy 17.654905 -415.311542) (xy 17.609547 -415.279091)
			(xy 17.569398 -415.240382) (xy 17.535312 -415.196239) (xy 17.508016 -415.147604) (xy 17.488093 -415.095513)
			(xy 17.475967 -415.041076) (xy 17.471896 -414.985454) (xy 0.6096 -414.985454) (xy 0.6096 -416.996118)
			(xy 0.610027 -417.006187) (xy 0.617746 -417.024786) (xy 0.624586 -417.032186) (xy 1.534414 -417.942014)
			(xy 1.541809 -417.948868) (xy 1.560408 -417.95661) (xy 1.570482 -417.957)
		)
		(stroke
			(width 0)
			(type solid)
		)
		(fill yes)
		(layer "In9.Cu")
		(net "GND")
	)
	(gr_poly
		(pts
			(xy 190.986918 -311.658) (xy 190.996987 -311.657573) (xy 191.015586 -311.649854) (xy 191.022986 -311.643014)
			(xy 191.55918 -311.10682) (xy 191.565302 -311.100255) (xy 191.572853 -311.083984) (xy 191.573912 -311.07507)
			(xy 191.573912 -311.074816) (xy 191.576377 -311.049169) (xy 191.588349 -310.999058) (xy 191.608029 -310.951444)
			(xy 191.634932 -310.907504) (xy 191.668391 -310.868325) (xy 191.707579 -310.834878) (xy 191.751526 -310.807987)
			(xy 191.799146 -310.78832) (xy 191.84926 -310.776362) (xy 191.874902 -310.773826) (xy 191.875156 -310.773826)
			(xy 191.884037 -310.772656) (xy 191.90027 -310.765113) (xy 191.906906 -310.759094) (xy 192.534032 -310.131968)
			(xy 192.539469 -310.126034) (xy 192.546715 -310.111673) (xy 192.548256 -310.103774) (xy 192.552358 -310.079906)
			(xy 192.567113 -310.033782) (xy 192.588966 -309.990567) (xy 192.617369 -309.951344) (xy 192.65161 -309.917099)
			(xy 192.690828 -309.88869) (xy 192.73404 -309.86683) (xy 192.780162 -309.852068) (xy 192.804034 -309.847996)
			(xy 192.811949 -309.846505) (xy 192.826316 -309.839243) (xy 192.832228 -309.833772) (xy 192.853056 -309.812944)
			(xy 192.859898 -309.805545) (xy 192.867619 -309.786946) (xy 192.868042 -309.776876) (xy 192.868042 -309.595266)
			(xy 192.867554 -309.585821) (xy 192.860647 -309.568232) (xy 192.85458 -309.560976) (xy 192.835022 -309.53964)
			(xy 192.828863 -309.533419) (xy 192.813403 -309.525236) (xy 192.804796 -309.523638) (xy 192.779086 -309.51954)
			(xy 192.729318 -309.504264) (xy 192.6826 -309.481296) (xy 192.640111 -309.451214) (xy 192.602925 -309.414781)
			(xy 192.571982 -309.372915) (xy 192.548064 -309.326675) (xy 192.531775 -309.27723) (xy 192.523526 -309.225828)
			(xy 192.523526 -309.173769) (xy 192.531776 -309.122367) (xy 192.548065 -309.072922) (xy 192.571984 -309.026682)
			(xy 192.602927 -308.984817) (xy 192.640113 -308.948384) (xy 192.682602 -308.918303) (xy 192.729321 -308.895334)
			(xy 192.779089 -308.880059) (xy 192.804796 -308.875938) (xy 192.813686 -308.874668) (xy 192.828926 -308.86654)
			(xy 192.855342 -308.837838) (xy 192.861484 -308.830631) (xy 192.868384 -308.81301) (xy 192.868804 -308.803548)
			(xy 192.868804 -308.624224) (xy 192.868371 -308.614799) (xy 192.861606 -308.597205) (xy 192.855596 -308.589934)
			(xy 192.82918 -308.561232) (xy 192.81394 -308.553104) (xy 192.805304 -308.551834) (xy 192.781465 -308.547841)
			(xy 192.735365 -308.533322) (xy 192.692129 -308.511721) (xy 192.652835 -308.483577) (xy 192.618466 -308.449595)
			(xy 192.589881 -308.410622) (xy 192.567792 -308.367632) (xy 192.552752 -308.321699) (xy 192.545137 -308.27397)
			(xy 192.545136 -308.225638) (xy 192.55275 -308.177909) (xy 192.567789 -308.131976) (xy 192.589876 -308.088985)
			(xy 192.618461 -308.050012) (xy 192.652829 -308.016028) (xy 192.692122 -307.987884) (xy 192.735358 -307.966281)
			(xy 192.781457 -307.95176) (xy 192.805304 -307.947822) (xy 192.81394 -307.946552) (xy 192.82918 -307.938424)
			(xy 192.855596 -307.909722) (xy 192.861675 -307.902492) (xy 192.868443 -307.884872) (xy 192.868804 -307.875432)
			(xy 192.868804 -307.696108) (xy 192.868307 -307.686666) (xy 192.861392 -307.669086) (xy 192.855342 -307.661818)
			(xy 192.835022 -307.63972) (xy 192.828868 -307.633491) (xy 192.813409 -307.625295) (xy 192.804796 -307.623718)
			(xy 192.779087 -307.61962) (xy 192.729323 -307.604345) (xy 192.682607 -307.581377) (xy 192.640121 -307.551297)
			(xy 192.602938 -307.514865) (xy 192.571998 -307.473002) (xy 192.548081 -307.426765) (xy 192.531793 -307.377323)
			(xy 192.523546 -307.325924) (xy 192.523546 -307.273867) (xy 192.531796 -307.222469) (xy 192.548085 -307.173027)
			(xy 192.572002 -307.12679) (xy 192.602944 -307.084928) (xy 192.640128 -307.048497) (xy 192.682615 -307.018418)
			(xy 192.729331 -306.995452) (xy 192.779096 -306.980178) (xy 192.804796 -306.976018) (xy 192.813686 -306.974748)
			(xy 192.828926 -306.96662) (xy 192.855342 -306.937918) (xy 192.861496 -306.930714) (xy 192.868424 -306.913094)
			(xy 192.868804 -306.903628) (xy 192.868804 -306.724304) (xy 192.868368 -306.714881) (xy 192.861598 -306.697291)
			(xy 192.855596 -306.690014) (xy 192.82918 -306.661312) (xy 192.81394 -306.653184) (xy 192.805304 -306.651914)
			(xy 192.781467 -306.647922) (xy 192.73537 -306.633402) (xy 192.692136 -306.611802) (xy 192.652846 -306.58366)
			(xy 192.618479 -306.549679) (xy 192.589896 -306.510709) (xy 192.567809 -306.467722) (xy 192.552771 -306.421792)
			(xy 192.545156 -306.374066) (xy 192.545156 -306.325736) (xy 192.55277 -306.278011) (xy 192.567808 -306.23208)
			(xy 192.589895 -306.189093) (xy 192.618478 -306.150122) (xy 192.652844 -306.116141) (xy 192.692134 -306.087999)
			(xy 192.735368 -306.066399) (xy 192.781465 -306.051879) (xy 192.805304 -306.047902) (xy 192.81394 -306.046632)
			(xy 192.82918 -306.038504) (xy 192.855596 -306.009802) (xy 192.861687 -306.002576) (xy 192.868483 -305.984956)
			(xy 192.868804 -305.975512) (xy 192.868804 -305.796188) (xy 192.868321 -305.78674) (xy 192.861426 -305.769141)
			(xy 192.855342 -305.761898) (xy 192.835022 -305.7398) (xy 192.828866 -305.733573) (xy 192.813407 -305.72538)
			(xy 192.804796 -305.723798) (xy 192.779081 -305.7197) (xy 192.729304 -305.704423) (xy 192.682576 -305.681451)
			(xy 192.640079 -305.651365) (xy 192.602886 -305.614926) (xy 192.571936 -305.573053) (xy 192.548013 -305.526806)
			(xy 192.531719 -305.477352) (xy 192.523468 -305.425941) (xy 192.523467 -305.373872) (xy 192.531716 -305.322461)
			(xy 192.548007 -305.273006) (xy 192.571929 -305.226758) (xy 192.602877 -305.184884) (xy 192.640069 -305.148443)
			(xy 192.682565 -305.118356) (xy 192.729292 -305.095382) (xy 192.779068 -305.080103) (xy 192.804796 -305.076098)
			(xy 192.813686 -305.074828) (xy 192.828926 -305.0667) (xy 192.855342 -305.037998) (xy 192.861494 -305.030794)
			(xy 192.868414 -305.013173) (xy 192.868804 -305.003708) (xy 192.868804 -304.82413) (xy 192.868372 -304.814705)
			(xy 192.861609 -304.797109) (xy 192.855596 -304.78984) (xy 192.82918 -304.761138) (xy 192.81394 -304.75301)
			(xy 192.805304 -304.75174) (xy 192.781465 -304.747747) (xy 192.735364 -304.733228) (xy 192.692126 -304.711626)
			(xy 192.652832 -304.683482) (xy 192.618462 -304.649499) (xy 192.589876 -304.610526) (xy 192.567787 -304.567535)
			(xy 192.552747 -304.521601) (xy 192.545131 -304.473872) (xy 192.54513 -304.425538) (xy 192.552744 -304.377808)
			(xy 192.567783 -304.331874) (xy 192.589871 -304.288883) (xy 192.618456 -304.249908) (xy 192.652824 -304.215924)
			(xy 192.692118 -304.187779) (xy 192.735355 -304.166176) (xy 192.781455 -304.151655) (xy 192.805304 -304.147728)
			(xy 192.81394 -304.146458) (xy 192.82918 -304.13833) (xy 192.855596 -304.109628) (xy 192.861676 -304.102399)
			(xy 192.868446 -304.084779) (xy 192.868804 -304.075338) (xy 192.868804 -302.92421) (xy 192.868369 -302.914787)
			(xy 192.8616 -302.897195) (xy 192.855596 -302.88992) (xy 192.82918 -302.861218) (xy 192.81394 -302.85309)
			(xy 192.805304 -302.85182) (xy 192.781467 -302.847828) (xy 192.735369 -302.833308) (xy 192.692134 -302.811708)
			(xy 192.652843 -302.783565) (xy 192.618476 -302.749584) (xy 192.589891 -302.710613) (xy 192.567804 -302.667625)
			(xy 192.552765 -302.621694) (xy 192.545151 -302.573967) (xy 192.54515 -302.525637) (xy 192.552764 -302.47791)
			(xy 192.567802 -302.431979) (xy 192.589889 -302.388991) (xy 192.618473 -302.350019) (xy 192.652839 -302.316037)
			(xy 192.692131 -302.287895) (xy 192.735365 -302.266293) (xy 192.781463 -302.251773) (xy 192.805304 -302.247808)
			(xy 192.81394 -302.246538) (xy 192.82918 -302.23841) (xy 192.855596 -302.209708) (xy 192.861688 -302.202483)
			(xy 192.868486 -302.184863) (xy 192.868804 -302.175418) (xy 192.868804 -290.356798) (xy 192.868631 -290.35079)
			(xy 192.865796 -290.339113) (xy 192.863216 -290.333684) (xy 192.861377 -290.330209) (xy 192.856785 -290.323829)
			(xy 192.854072 -290.320984) (xy 192.568068 -290.03498) (xy 192.561957 -290.029694) (xy 192.547338 -290.022833)
			(xy 192.539366 -290.021518) (xy 192.537842 -290.021518) (xy 192.531265 -290.021135) (xy 192.518277 -290.023321)
			(xy 192.512188 -290.025836) (xy 192.510918 -290.026598) (xy 192.508124 -290.027868) (xy 192.50787 -290.027868)
			(xy 192.503044 -290.0299) (xy 192.493703 -290.033712) (xy 192.47464 -290.04032) (xy 192.464944 -290.043108)
			(xy 192.464944 -290.043362) (xy 192.443034 -290.049071) (xy 192.398174 -290.055193) (xy 192.375536 -290.055554)
			(xy 192.375028 -290.055554) (xy 192.349038 -290.055047) (xy 192.297698 -290.04692) (xy 192.24826 -290.030862)
			(xy 192.201944 -290.007268) (xy 192.159888 -289.97672) (xy 192.123128 -289.939969) (xy 192.092571 -289.89792)
			(xy 192.068966 -289.851608) (xy 192.052898 -289.802175) (xy 192.044759 -289.750836) (xy 192.04432 -289.724846)
			(xy 192.04432 -289.724338) (xy 192.044684 -289.702052) (xy 192.050677 -289.657884) (xy 192.06256 -289.614924)
			(xy 192.07099 -289.59429) (xy 192.072006 -289.592004) (xy 192.075054 -289.582606) (xy 192.076832 -289.57397)
			(xy 192.078067 -289.563951) (xy 192.073485 -289.544307) (xy 192.067942 -289.53587) (xy 192.062608 -289.52952)
			(xy 191.618108 -289.08502) (xy 191.611995 -289.079738) (xy 191.597375 -289.072888) (xy 191.589406 -289.071558)
			(xy 191.587882 -289.071558) (xy 191.581304 -289.07117) (xy 191.568311 -289.073344) (xy 191.562228 -289.075876)
			(xy 191.560958 -289.076638) (xy 191.558164 -289.077908) (xy 191.55791 -289.077908) (xy 191.553084 -289.07994)
			(xy 191.543744 -289.083753) (xy 191.52468 -289.090363) (xy 191.514984 -289.093148) (xy 191.514984 -289.093402)
			(xy 191.493074 -289.099106) (xy 191.448214 -289.105219) (xy 191.425576 -289.105594) (xy 191.425068 -289.105594)
			(xy 191.400102 -289.105137) (xy 191.350736 -289.097629) (xy 191.30306 -289.08279) (xy 191.258154 -289.060956)
			(xy 191.217038 -289.032622) (xy 191.180647 -288.998432) (xy 191.149806 -288.959162) (xy 191.125215 -288.915705)
			(xy 191.107433 -288.869045) (xy 191.101726 -288.844736) (xy 191.101218 -288.842196) (xy 191.100964 -288.841434)
			(xy 191.10071 -288.839148) (xy 191.099694 -288.834576) (xy 191.096138 -288.828226) (xy 191.094196 -288.824884)
			(xy 191.089476 -288.818764) (xy 191.08674 -288.816034) (xy 191.064134 -288.794698) (xy 191.06008 -288.791562)
			(xy 191.050995 -288.78682) (xy 191.0461 -288.7853) (xy 191.036702 -288.782506) (xy 191.032892 -288.781998)
			(xy 190.978282 -288.773616) (xy 190.957454 -288.769552) (xy 190.95366 -288.769047) (xy 190.946008 -288.769047)
			(xy 190.942214 -288.769552) (xy 190.922527 -288.773513) (xy 190.88289 -288.779992) (xy 190.862966 -288.782506)
			(xy 190.862712 -288.782506) (xy 190.857378 -288.783522) (xy 190.852298 -288.784538) (xy 190.847218 -288.786824)
			(xy 190.837312 -288.79292) (xy 190.829946 -288.799524) (xy 190.813182 -288.81578) (xy 190.812674 -288.816288)
			(xy 190.810084 -288.818911) (xy 190.805623 -288.824778) (xy 190.803784 -288.827972) (xy 190.800736 -288.833814)
			(xy 190.798704 -288.841942) (xy 190.798704 -288.84245) (xy 190.7931 -288.866913) (xy 190.775504 -288.913911)
			(xy 190.751016 -288.957715) (xy 190.720198 -288.997321) (xy 190.683754 -289.031822) (xy 190.642521 -289.060428)
			(xy 190.597442 -289.082482) (xy 190.549552 -289.097479) (xy 190.499946 -289.105077) (xy 190.474854 -289.105594)
			(xy 190.459525 -289.105444) (xy 190.428995 -289.102643) (xy 190.413894 -289.100006) (xy 190.413132 -289.100006)
			(xy 190.40856 -289.099244) (xy 190.385954 -289.106102) (xy 190.31839 -289.170618) (xy 190.310186 -289.179261)
			(xy 190.302122 -289.201651) (xy 190.302896 -289.213544) (xy 190.303937 -289.222525) (xy 190.305081 -289.240571)
			(xy 190.305182 -289.249612) (xy 190.305182 -289.25012) (xy 190.304973 -289.264175) (xy 190.302299 -289.292159)
			(xy 190.299848 -289.306) (xy 190.299848 -289.306508) (xy 190.298339 -289.318744) (xy 190.30563 -289.342252)
			(xy 190.313818 -289.351466) (xy 190.373508 -289.410902) (xy 190.382748 -289.419049) (xy 190.406236 -289.426345)
			(xy 190.418466 -289.424872) (xy 190.41872 -289.424872) (xy 190.432685 -289.422387) (xy 190.460925 -289.419715)
			(xy 190.475108 -289.419538) (xy 190.499924 -289.420024) (xy 190.548903 -289.428055) (xy 190.595937 -289.443903)
			(xy 190.639787 -289.467152) (xy 190.679299 -289.497188) (xy 190.713432 -289.533221) (xy 190.741285 -289.574301)
			(xy 190.762126 -289.619346) (xy 190.775405 -289.667169) (xy 190.780773 -289.71651) (xy 190.778087 -289.76607)
			(xy 190.76742 -289.814542) (xy 190.749051 -289.86065) (xy 190.723465 -289.903179) (xy 190.691336 -289.941009)
			(xy 190.65351 -289.973143) (xy 190.610984 -289.998734) (xy 190.564878 -290.017109) (xy 190.516407 -290.027782)
			(xy 190.466848 -290.030474) (xy 190.417506 -290.025112) (xy 190.369681 -290.011839) (xy 190.324634 -289.991004)
			(xy 190.283551 -289.963155) (xy 190.247514 -289.929028) (xy 190.217472 -289.889519) (xy 190.194218 -289.845672)
			(xy 190.178364 -289.79864) (xy 190.170327 -289.749662) (xy 190.1698 -289.724846) (xy 190.17 -289.710727)
			(xy 190.172672 -289.682616) (xy 190.175134 -289.668712) (xy 190.175134 -289.668204) (xy 190.176622 -289.655976)
			(xy 190.169301 -289.632499) (xy 190.161164 -289.623246) (xy 190.101474 -289.56381) (xy 190.092234 -289.555665)
			(xy 190.068747 -289.548376) (xy 190.056516 -289.54984) (xy 190.056262 -289.54984) (xy 190.042297 -289.552324)
			(xy 190.014057 -289.554994) (xy 189.999874 -289.555174) (xy 189.985819 -289.554964) (xy 189.957835 -289.55229)
			(xy 189.943994 -289.54984) (xy 189.943486 -289.54984) (xy 189.931251 -289.548333) (xy 189.907744 -289.555624)
			(xy 189.898528 -289.56381) (xy 189.838838 -289.6235) (xy 189.830697 -289.632742) (xy 189.823407 -289.656228)
			(xy 189.824868 -289.668458) (xy 189.824868 -289.668966) (xy 189.827337 -289.682805) (xy 189.830012 -289.71079)
			(xy 189.830202 -289.724846) (xy 189.829712 -289.749665) (xy 189.821675 -289.798649) (xy 189.805818 -289.845688)
			(xy 189.782561 -289.889541) (xy 189.752516 -289.929054) (xy 189.716474 -289.963187) (xy 189.675385 -289.991039)
			(xy 189.630332 -290.011877) (xy 189.582501 -290.025152) (xy 189.533153 -290.030514) (xy 189.483587 -290.027822)
			(xy 189.435109 -290.017147) (xy 189.388997 -289.99877) (xy 189.346466 -289.973175) (xy 189.308635 -289.941037)
			(xy 189.276502 -289.903202) (xy 189.250913 -289.860667) (xy 189.232542 -289.814553) (xy 189.221873 -289.766074)
			(xy 189.219187 -289.716507) (xy 189.224556 -289.66716) (xy 189.237837 -289.61933) (xy 189.258681 -289.57428)
			(xy 189.286538 -289.533195) (xy 189.320675 -289.497157) (xy 189.360193 -289.467117) (xy 189.404049 -289.443866)
			(xy 189.45109 -289.428016) (xy 189.500075 -289.419984) (xy 189.524894 -289.419538) (xy 189.538949 -289.419746)
			(xy 189.566933 -289.422418) (xy 189.580774 -289.424872) (xy 189.581282 -289.424872) (xy 189.593512 -289.426363)
			(xy 189.616997 -289.419051) (xy 189.62624 -289.410902) (xy 189.68593 -289.351212) (xy 189.694078 -289.341972)
			(xy 189.701378 -289.318484) (xy 189.6999 -289.306254) (xy 189.6999 -289.305746) (xy 189.697444 -289.291969)
			(xy 189.694769 -289.264112) (xy 189.694566 -289.25012) (xy 189.694566 -289.249612) (xy 189.694671 -289.240571)
			(xy 189.695815 -289.222526) (xy 189.696852 -289.213544) (xy 189.697639 -289.201655) (xy 189.689545 -289.179277)
			(xy 189.681358 -289.170618) (xy 189.613794 -289.106102) (xy 189.591188 -289.099244) (xy 189.586108 -289.100006)
			(xy 189.570943 -289.102645) (xy 189.540286 -289.105443) (xy 189.524894 -289.105594) (xy 189.498905 -289.10511)
			(xy 189.447568 -289.096978) (xy 189.398136 -289.080915) (xy 189.351824 -289.057317) (xy 189.309775 -289.026765)
			(xy 189.273022 -288.99001) (xy 189.242472 -288.947959) (xy 189.218877 -288.901646) (xy 189.202817 -288.852212)
			(xy 189.194688 -288.800875) (xy 189.194186 -288.774886) (xy 189.194696 -288.748912) (xy 189.20282 -288.697603)
			(xy 189.218867 -288.648196) (xy 189.242441 -288.601905) (xy 189.272963 -288.559869) (xy 189.309682 -288.523123)
			(xy 189.351695 -288.49257) (xy 189.397968 -288.468961) (xy 189.447364 -288.452878) (xy 189.498666 -288.444715)
			(xy 189.52464 -288.444178) (xy 189.525148 -288.444178) (xy 189.532768 -288.444432) (xy 189.54115 -288.444432)
			(xy 189.550781 -288.44396) (xy 189.568658 -288.436774) (xy 189.575948 -288.430462) (xy 189.582806 -288.42335)
			(xy 189.631066 -288.345372) (xy 189.635518 -288.337482) (xy 189.639084 -288.319735) (xy 189.636239 -288.301857)
			(xy 189.632082 -288.29381) (xy 189.625986 -288.28238) (xy 189.61481 -288.261044) (xy 189.607376 -288.246271)
			(xy 189.593405 -288.216292) (xy 189.58687 -288.2011) (xy 189.583822 -288.193988) (xy 189.579758 -288.188908)
			(xy 189.569598 -288.17951) (xy 189.568582 -288.178748) (xy 189.55258 -288.16808) (xy 189.550548 -288.16681)
			(xy 189.542928 -288.163) (xy 189.53988 -288.161984) (xy 189.519814 -288.155634) (xy 189.512956 -288.15538)
			(xy 189.4876 -288.154) (xy 189.43773 -288.14443) (xy 189.389909 -288.12735) (xy 189.345262 -288.10316)
			(xy 189.304837 -288.072429) (xy 189.269585 -288.03588) (xy 189.240334 -287.994371) (xy 189.217772 -287.948879)
			(xy 189.20243 -287.900473) (xy 189.194667 -287.850291) (xy 189.194667 -287.799511) (xy 189.20243 -287.749329)
			(xy 189.217772 -287.700922) (xy 189.240333 -287.65543) (xy 189.269584 -287.613922) (xy 189.304836 -287.577372)
			(xy 189.34526 -287.546641) (xy 189.389908 -287.522451) (xy 189.437728 -287.50537) (xy 189.487598 -287.4958)
			(xy 189.512956 -287.494472) (xy 189.519814 -287.494218) (xy 189.53988 -287.487868) (xy 189.542928 -287.486852)
			(xy 189.55258 -287.481772) (xy 189.568582 -287.471104) (xy 189.569598 -287.470342) (xy 189.579758 -287.460944)
			(xy 189.583822 -287.456118) (xy 189.58687 -287.44926) (xy 189.587124 -287.448244) (xy 189.589918 -287.441132)
			(xy 189.590426 -287.440624) (xy 189.596014 -287.42767) (xy 189.596014 -287.427416) (xy 189.598046 -287.423352)
			(xy 189.599062 -287.42132) (xy 189.600586 -287.417764) (xy 189.600586 -287.41751) (xy 189.604142 -287.410398)
			(xy 189.604142 -287.40989) (xy 189.604904 -287.408874) (xy 189.604904 -287.408366) (xy 189.605158 -287.407858)
			(xy 189.605666 -287.407096) (xy 189.620144 -287.37814) (xy 189.625986 -287.366964) (xy 189.629288 -287.360868)
			(xy 189.632082 -287.349438) (xy 189.632082 -287.320736) (xy 189.631852 -287.313699) (xy 189.627973 -287.30017)
			(xy 189.624462 -287.294066) (xy 189.604396 -287.262062) (xy 189.604396 -287.261554) (xy 189.593474 -287.243774)
			(xy 189.592966 -287.243266) (xy 189.584076 -287.229042) (xy 189.576897 -287.218874) (xy 189.555329 -287.206504)
			(xy 189.542928 -287.20542) (xy 189.532768 -287.20542) (xy 189.525148 -287.205674) (xy 189.52464 -287.205674)
			(xy 189.498667 -287.205145) (xy 189.447366 -287.196982) (xy 189.397972 -287.180898) (xy 189.351702 -287.157287)
			(xy 189.309692 -287.126733) (xy 189.272976 -287.089984) (xy 189.242459 -287.047947) (xy 189.21889 -287.001656)
			(xy 189.202849 -286.952248) (xy 189.194732 -286.900939) (xy 189.194186 -286.874966) (xy 189.194698 -286.84898)
			(xy 189.202833 -286.79765) (xy 189.218897 -286.748223) (xy 189.242494 -286.701918) (xy 189.273045 -286.659874)
			(xy 189.309795 -286.623126) (xy 189.351842 -286.59258) (xy 189.398149 -286.568986) (xy 189.447577 -286.552926)
			(xy 189.498908 -286.544796) (xy 189.524894 -286.544258) (xy 189.536832 -286.544512) (xy 189.54242 -286.544512)
			(xy 189.554789 -286.543451) (xy 189.57643 -286.531371) (xy 189.583822 -286.521398) (xy 189.624716 -286.455358)
			(xy 189.628018 -286.448754) (xy 189.63 -286.443974) (xy 189.632176 -286.43386) (xy 189.632336 -286.428688)
			(xy 189.632336 -286.40913) (xy 189.631828 -286.402526) (xy 189.630304 -286.390334) (xy 189.625732 -286.381952)
			(xy 189.615259 -286.362161) (xy 189.595948 -286.321759) (xy 189.587124 -286.30118) (xy 189.58687 -286.300672)
			(xy 189.583568 -286.293306) (xy 189.57925 -286.288226) (xy 189.570614 -286.280098) (xy 189.553088 -286.26816)
			(xy 189.546738 -286.263842) (xy 189.519814 -286.25546) (xy 189.512956 -286.255206) (xy 189.487605 -286.253826)
			(xy 189.437747 -286.244258) (xy 189.389937 -286.227181) (xy 189.3453 -286.202996) (xy 189.304885 -286.172272)
			(xy 189.269641 -286.13573) (xy 189.240397 -286.094231) (xy 189.21784 -286.048749) (xy 189.202502 -286.000354)
			(xy 189.194741 -285.950182) (xy 189.194742 -285.899414) (xy 189.202503 -285.849243) (xy 189.217842 -285.800848)
			(xy 189.240399 -285.755366) (xy 189.269643 -285.713867) (xy 189.304887 -285.677326) (xy 189.345303 -285.646602)
			(xy 189.389941 -285.622418) (xy 189.43775 -285.605341) (xy 189.487609 -285.595774) (xy 189.512956 -285.594298)
			(xy 189.519814 -285.594044) (xy 189.53988 -285.587694) (xy 189.542928 -285.586678) (xy 189.55258 -285.581598)
			(xy 189.568582 -285.57093) (xy 189.569598 -285.570168) (xy 189.579758 -285.56077) (xy 189.583822 -285.555944)
			(xy 189.58687 -285.549086) (xy 189.587124 -285.54807) (xy 189.589918 -285.540958) (xy 189.590426 -285.54045)
			(xy 189.596014 -285.527496) (xy 189.596014 -285.527242) (xy 189.598046 -285.523178) (xy 189.599062 -285.521146)
			(xy 189.600586 -285.51759) (xy 189.600586 -285.517336) (xy 189.604142 -285.510224) (xy 189.604142 -285.509716)
			(xy 189.604904 -285.5087) (xy 189.604904 -285.508192) (xy 189.605158 -285.507684) (xy 189.605666 -285.506922)
			(xy 189.620144 -285.477966) (xy 189.625986 -285.46679) (xy 189.629288 -285.460694) (xy 189.632082 -285.449264)
			(xy 189.632082 -285.420562) (xy 189.631855 -285.413524) (xy 189.627982 -285.399991) (xy 189.624462 -285.393892)
			(xy 189.604396 -285.361888) (xy 189.604396 -285.36138) (xy 189.593474 -285.3436) (xy 189.592966 -285.343092)
			(xy 189.584076 -285.328868) (xy 189.576899 -285.318696) (xy 189.555331 -285.306319) (xy 189.542928 -285.305246)
			(xy 189.532768 -285.305246) (xy 189.525148 -285.3055) (xy 189.52464 -285.3055) (xy 189.498667 -285.304971)
			(xy 189.447365 -285.296808) (xy 189.39797 -285.280725) (xy 189.351698 -285.257116) (xy 189.309686 -285.226562)
			(xy 189.272969 -285.189816) (xy 189.242448 -285.14778) (xy 189.218875 -285.101489) (xy 189.202831 -285.052082)
			(xy 189.194708 -285.000774) (xy 189.194708 -284.948826) (xy 189.202831 -284.897518) (xy 189.218875 -284.848111)
			(xy 189.242448 -284.80182) (xy 189.272969 -284.759784) (xy 189.309686 -284.723038) (xy 189.351698 -284.692484)
			(xy 189.39797 -284.668875) (xy 189.447365 -284.652792) (xy 189.498667 -284.644629) (xy 189.52464 -284.644084)
			(xy 189.525148 -284.644084) (xy 189.532768 -284.644338) (xy 189.54115 -284.644338) (xy 189.550781 -284.643866)
			(xy 189.568659 -284.636681) (xy 189.575948 -284.630368) (xy 189.582806 -284.623256) (xy 189.631066 -284.545278)
			(xy 189.635519 -284.537389) (xy 189.639088 -284.51964) (xy 189.636244 -284.501761) (xy 189.632082 -284.493716)
			(xy 189.625986 -284.482286) (xy 189.61481 -284.46095) (xy 189.607376 -284.446177) (xy 189.593404 -284.416198)
			(xy 189.58687 -284.401006) (xy 189.583822 -284.393894) (xy 189.579758 -284.388814) (xy 189.569598 -284.379416)
			(xy 189.568582 -284.378654) (xy 189.55258 -284.367986) (xy 189.550548 -284.366716) (xy 189.542928 -284.362906)
			(xy 189.53988 -284.36189) (xy 189.519814 -284.35554) (xy 189.512956 -284.355286) (xy 189.487435 -284.353887)
			(xy 189.43725 -284.344205) (xy 189.389152 -284.326917) (xy 189.344287 -284.302435) (xy 189.303722 -284.271342)
			(xy 189.268425 -284.234377) (xy 189.239234 -284.192423) (xy 189.216846 -284.146477) (xy 189.201794 -284.097633)
			(xy 189.194435 -284.047055) (xy 189.194946 -283.995948) (xy 189.203313 -283.945527) (xy 189.219339 -283.896994)
			(xy 189.24264 -283.851504) (xy 189.272663 -283.810141) (xy 189.308692 -283.773889) (xy 189.349869 -283.743613)
			(xy 189.395214 -283.720031) (xy 189.443648 -283.703708) (xy 189.494016 -283.69503) (xy 189.51956 -283.694124)
			(xy 189.520322 -283.694124) (xy 189.525235 -283.693864) (xy 189.53483 -283.691695) (xy 189.539372 -283.689806)
			(xy 189.546992 -283.685488) (xy 189.569598 -283.670502) (xy 189.569598 -283.670248) (xy 189.573995 -283.667044)
			(xy 189.581431 -283.659104) (xy 189.58433 -283.6545) (xy 189.586616 -283.649166) (xy 189.593425 -283.633256)
			(xy 189.608034 -283.60188) (xy 189.615826 -283.586428) (xy 189.623507 -283.571516) (xy 189.639765 -283.542172)
			(xy 189.648338 -283.527754) (xy 189.648592 -283.5275) (xy 189.650878 -283.52369) (xy 189.65478 -283.51452)
			(xy 189.655962 -283.494646) (xy 189.653164 -283.485082) (xy 189.651386 -283.480764) (xy 189.651132 -283.480256)
			(xy 189.649149 -283.475896) (xy 189.643776 -283.467968) (xy 189.640464 -283.464508) (xy 189.594998 -283.419042)
			(xy 189.588485 -283.412954) (xy 189.572349 -283.405402) (xy 189.563502 -283.40431) (xy 189.556644 -283.40431)
			(xy 189.525148 -283.40558) (xy 189.52464 -283.40558) (xy 189.498667 -283.405051) (xy 189.447366 -283.396888)
			(xy 189.397972 -283.380804) (xy 189.3517 -283.357194) (xy 189.30969 -283.326639) (xy 189.272974 -283.289891)
			(xy 189.242456 -283.247854) (xy 189.218886 -283.201562) (xy 189.202845 -283.152154) (xy 189.194726 -283.100845)
			(xy 189.194186 -283.074872) (xy 189.195456 -283.045154) (xy 189.195831 -283.034001) (xy 189.188192 -283.01306)
			(xy 189.180724 -283.004768) (xy 188.644784 -282.468828) (xy 188.63827 -282.462743) (xy 188.622134 -282.455198)
			(xy 188.613288 -282.454096) (xy 188.60643 -282.454096) (xy 188.574934 -282.455366) (xy 188.574426 -282.455366)
			(xy 188.547249 -282.454792) (xy 188.493633 -282.445853) (xy 188.442203 -282.42826) (xy 188.394345 -282.402487)
			(xy 188.35135 -282.369231) (xy 188.314377 -282.329386) (xy 188.284423 -282.284029) (xy 188.262296 -282.234381)
			(xy 188.254894 -282.208224) (xy 188.25337 -282.202382) (xy 188.24194 -282.181554) (xy 188.241686 -282.1813)
			(xy 188.234191 -282.17386) (xy 188.214896 -282.165337) (xy 188.204348 -282.16479) (xy 187.995052 -282.16479)
			(xy 187.986295 -282.165102) (xy 187.969789 -282.170943) (xy 187.962794 -282.17622) (xy 187.957274 -282.181058)
			(xy 187.949022 -282.193189) (xy 187.946538 -282.200096) (xy 187.945776 -282.203398) (xy 187.939137 -282.228411)
			(xy 187.91915 -282.276143) (xy 187.891969 -282.320178) (xy 187.858259 -282.359439) (xy 187.818843 -282.392968)
			(xy 187.774683 -282.419945) (xy 187.726858 -282.439711) (xy 187.676538 -282.451784) (xy 187.624952 -282.455867)
			(xy 187.573359 -282.451862) (xy 187.523021 -282.439866) (xy 187.475166 -282.420173) (xy 187.430966 -282.393263)
			(xy 187.391498 -282.359794) (xy 187.357728 -282.320584) (xy 187.330481 -282.276591) (xy 187.310421 -282.228889)
			(xy 187.303664 -282.203906) (xy 187.303664 -282.203398) (xy 187.302394 -282.198572) (xy 187.298659 -282.189263)
			(xy 187.285255 -282.17436) (xy 187.267169 -282.165722) (xy 187.257182 -282.16479) (xy 187.045092 -282.16479)
			(xy 187.036332 -282.165096) (xy 187.019818 -282.170926) (xy 187.012834 -282.17622) (xy 187.007339 -282.181079)
			(xy 186.9991 -282.193206) (xy 186.996578 -282.200096) (xy 186.995816 -282.203398) (xy 186.989176 -282.228414)
			(xy 186.969189 -282.276152) (xy 186.942006 -282.320193) (xy 186.908293 -282.35946) (xy 186.868873 -282.392994)
			(xy 186.824709 -282.419976) (xy 186.77688 -282.439745) (xy 186.726554 -282.451821) (xy 186.674961 -282.455906)
			(xy 186.623362 -282.451902) (xy 186.573018 -282.439906) (xy 186.525157 -282.420212) (xy 186.480951 -282.3933)
			(xy 186.441477 -282.359829) (xy 186.407702 -282.320615) (xy 186.38045 -282.276617) (xy 186.360388 -282.22891)
			(xy 186.353704 -282.203906) (xy 186.353704 -282.203398) (xy 186.352434 -282.198572) (xy 186.348696 -282.189269)
			(xy 186.335289 -282.174382) (xy 186.317202 -282.165764) (xy 186.307222 -282.16479) (xy 186.095132 -282.16479)
			(xy 186.086376 -282.165106) (xy 186.069874 -282.170951) (xy 186.062874 -282.17622) (xy 186.057356 -282.181059)
			(xy 186.049106 -282.193191) (xy 186.046618 -282.200096) (xy 186.045856 -282.203398) (xy 186.039216 -282.228417)
			(xy 186.019228 -282.276162) (xy 185.992043 -282.320208) (xy 185.958327 -282.359481) (xy 185.918904 -282.39302)
			(xy 185.874735 -282.420006) (xy 185.826901 -282.439779) (xy 185.776569 -282.451857) (xy 185.724971 -282.455945)
			(xy 185.673366 -282.451942) (xy 185.623015 -282.439946) (xy 185.575148 -282.420251) (xy 185.530936 -282.393337)
			(xy 185.491457 -282.359863) (xy 185.457677 -282.320646) (xy 185.43042 -282.276643) (xy 185.410354 -282.228931)
			(xy 185.403744 -282.203906) (xy 185.403744 -282.203398) (xy 185.402474 -282.198572) (xy 185.398737 -282.189265)
			(xy 185.385333 -282.174368) (xy 185.367246 -282.165736) (xy 185.357262 -282.16479) (xy 185.145172 -282.16479)
			(xy 185.136414 -282.165099) (xy 185.119903 -282.170935) (xy 185.112914 -282.17622) (xy 185.107421 -282.18108)
			(xy 185.099184 -282.193208) (xy 185.096658 -282.200096) (xy 185.095896 -282.203398) (xy 185.089257 -282.228412)
			(xy 185.069269 -282.276148) (xy 185.042088 -282.320186) (xy 185.008376 -282.35945) (xy 184.968958 -282.392981)
			(xy 184.924796 -282.41996) (xy 184.876969 -282.439728) (xy 184.826646 -282.451802) (xy 184.775057 -282.455887)
			(xy 184.723461 -282.451882) (xy 184.673119 -282.439886) (xy 184.625262 -282.420193) (xy 184.581058 -282.393282)
			(xy 184.541588 -282.359812) (xy 184.507815 -282.3206) (xy 184.480565 -282.276604) (xy 184.460504 -282.228899)
			(xy 184.453784 -282.203906) (xy 184.453784 -282.203398) (xy 184.452514 -282.198572) (xy 184.44872 -282.189296)
			(xy 184.435336 -282.174409) (xy 184.417273 -282.165775) (xy 184.407302 -282.16479) (xy 184.195466 -282.16479)
			(xy 184.186708 -282.1651) (xy 184.170199 -282.170937) (xy 184.163208 -282.17622) (xy 184.157688 -282.181057)
			(xy 184.149433 -282.193188) (xy 184.146952 -282.200096) (xy 184.14619 -282.203398) (xy 184.139549 -282.228439)
			(xy 184.119551 -282.276226) (xy 184.09235 -282.320312) (xy 184.05861 -282.359621) (xy 184.019156 -282.393191)
			(xy 183.974953 -282.420202) (xy 183.92708 -282.439993) (xy 183.876707 -282.452082) (xy 183.825066 -282.456173)
			(xy 183.773419 -282.452165) (xy 183.723027 -282.440157) (xy 183.675122 -282.420442) (xy 183.630875 -282.393503)
			(xy 183.591368 -282.359996) (xy 183.557565 -282.320742) (xy 183.530293 -282.276699) (xy 183.510218 -282.228944)
			(xy 183.50357 -282.203906) (xy 183.50357 -282.203398) (xy 183.5023 -282.198572) (xy 183.498565 -282.189262)
			(xy 183.485162 -282.174358) (xy 183.467075 -282.165718) (xy 183.457088 -282.16479) (xy 183.245506 -282.16479)
			(xy 183.236752 -282.16511) (xy 183.220255 -282.170962) (xy 183.213248 -282.17622) (xy 183.207732 -282.181061)
			(xy 183.199487 -282.193194) (xy 183.196992 -282.200096) (xy 183.19623 -282.203398) (xy 183.189589 -282.228434)
			(xy 183.169593 -282.276212) (xy 183.142394 -282.320289) (xy 183.108659 -282.35959) (xy 183.06921 -282.393152)
			(xy 183.025014 -282.420156) (xy 182.977148 -282.439942) (xy 182.926784 -282.452027) (xy 182.875152 -282.456114)
			(xy 182.823513 -282.452105) (xy 182.773131 -282.440097) (xy 182.725236 -282.420384) (xy 182.680998 -282.393447)
			(xy 182.641498 -282.359945) (xy 182.607703 -282.320696) (xy 182.580438 -282.27666) (xy 182.560369 -282.228912)
			(xy 182.55361 -282.203906) (xy 182.55361 -282.203398) (xy 182.55234 -282.198572) (xy 182.548602 -282.189268)
			(xy 182.535195 -282.17438) (xy 182.517109 -282.16576) (xy 182.507128 -282.16479) (xy 182.295546 -282.16479)
			(xy 182.286789 -282.165103) (xy 182.270284 -282.170946) (xy 182.263288 -282.17622) (xy 182.257769 -282.181058)
			(xy 182.249517 -282.193189) (xy 182.247032 -282.200096) (xy 182.24627 -282.203398) (xy 182.239629 -282.228437)
			(xy 182.219632 -282.276221) (xy 182.192431 -282.320305) (xy 182.158693 -282.35961) (xy 182.119241 -282.393178)
			(xy 182.07504 -282.420186) (xy 182.027169 -282.439976) (xy 181.976799 -282.452064) (xy 181.925161 -282.456153)
			(xy 181.873517 -282.452145) (xy 181.823128 -282.440137) (xy 181.775227 -282.420423) (xy 181.730983 -282.393484)
			(xy 181.691478 -282.359979) (xy 181.657678 -282.320727) (xy 181.630408 -282.276686) (xy 181.610335 -282.228933)
			(xy 181.60365 -282.203906) (xy 181.60365 -282.203398) (xy 181.60238 -282.198572) (xy 181.598644 -282.189264)
			(xy 181.58524 -282.174365) (xy 181.567153 -282.165731) (xy 181.557168 -282.16479) (xy 181.345586 -282.16479)
			(xy 181.336827 -282.165097) (xy 181.320313 -282.170929) (xy 181.313328 -282.17622) (xy 181.307833 -282.181079)
			(xy 181.299595 -282.193207) (xy 181.297072 -282.200096) (xy 181.29631 -282.203398) (xy 181.289669 -282.22844)
			(xy 181.26967 -282.27623) (xy 181.242468 -282.32032) (xy 181.208727 -282.359631) (xy 181.169271 -282.393204)
			(xy 181.125066 -282.420217) (xy 181.07719 -282.44001) (xy 181.026815 -282.452101) (xy 180.975171 -282.456192)
			(xy 180.92352 -282.452185) (xy 180.873125 -282.440177) (xy 180.825217 -282.420462) (xy 180.780968 -282.393521)
			(xy 180.741457 -282.360013) (xy 180.707652 -282.320757) (xy 180.680378 -282.276712) (xy 180.660301 -282.228955)
			(xy 180.65369 -282.203906) (xy 180.65369 -282.203398) (xy 180.65242 -282.198572) (xy 180.648681 -282.18927)
			(xy 180.635273 -282.174387) (xy 180.617187 -282.165774) (xy 180.607208 -282.16479) (xy 180.395626 -282.16479)
			(xy 180.386871 -282.165107) (xy 180.37037 -282.170954) (xy 180.363368 -282.17622) (xy 180.357851 -282.18106)
			(xy 180.349602 -282.193192) (xy 180.347112 -282.200096) (xy 180.34635 -282.203398) (xy 180.339709 -282.228436)
			(xy 180.319712 -282.276216) (xy 180.292513 -282.320297) (xy 180.258776 -282.3596) (xy 180.219326 -282.393165)
			(xy 180.175127 -282.420171) (xy 180.127259 -282.439959) (xy 180.076892 -282.452045) (xy 180.025257 -282.456134)
			(xy 179.973615 -282.452125) (xy 179.92323 -282.440117) (xy 179.875331 -282.420403) (xy 179.83109 -282.393465)
			(xy 179.791588 -282.359962) (xy 179.75779 -282.320711) (xy 179.730523 -282.276673) (xy 179.710452 -282.228923)
			(xy 179.70373 -282.203906) (xy 179.70373 -282.203398) (xy 179.70246 -282.198572) (xy 179.698723 -282.189266)
			(xy 179.685317 -282.174372) (xy 179.667231 -282.165746) (xy 179.657248 -282.16479) (xy 179.445666 -282.16479)
			(xy 179.436908 -282.1651) (xy 179.420399 -282.170937) (xy 179.413408 -282.17622) (xy 179.407888 -282.181057)
			(xy 179.399633 -282.193188) (xy 179.397152 -282.200096) (xy 179.39639 -282.203398) (xy 179.389749 -282.228439)
			(xy 179.369751 -282.276226) (xy 179.34255 -282.320312) (xy 179.30881 -282.359621) (xy 179.269356 -282.393191)
			(xy 179.225153 -282.420202) (xy 179.17728 -282.439993) (xy 179.126907 -282.452082) (xy 179.075266 -282.456173)
			(xy 179.023619 -282.452165) (xy 178.973227 -282.440157) (xy 178.925322 -282.420442) (xy 178.881075 -282.393503)
			(xy 178.841568 -282.359996) (xy 178.807765 -282.320742) (xy 178.780493 -282.276699) (xy 178.760418 -282.228944)
			(xy 178.75377 -282.203906) (xy 178.75377 -282.203398) (xy 178.7525 -282.198572) (xy 178.748765 -282.189262)
			(xy 178.735362 -282.174358) (xy 178.717275 -282.165718) (xy 178.707288 -282.16479) (xy 178.495452 -282.16479)
			(xy 178.486695 -282.165102) (xy 178.470189 -282.170943) (xy 178.463194 -282.17622) (xy 178.457674 -282.181058)
			(xy 178.449422 -282.193189) (xy 178.446938 -282.200096) (xy 178.446176 -282.203398) (xy 178.439535 -282.228438)
			(xy 178.419537 -282.276223) (xy 178.392337 -282.320307) (xy 178.358598 -282.359614) (xy 178.319146 -282.393182)
			(xy 178.274944 -282.420191) (xy 178.227072 -282.439981) (xy 178.176702 -282.452069) (xy 178.125063 -282.456159)
			(xy 178.073417 -282.452151) (xy 178.023028 -282.440143) (xy 177.975125 -282.420429) (xy 177.93088 -282.39349)
			(xy 177.891375 -282.359984) (xy 177.857574 -282.320731) (xy 177.830303 -282.27669) (xy 177.81023 -282.228937)
			(xy 177.803556 -282.203906) (xy 177.803556 -282.203398) (xy 177.802286 -282.198572) (xy 177.79855 -282.189264)
			(xy 177.785146 -282.174363) (xy 177.76706 -282.165727) (xy 177.757074 -282.16479) (xy 177.545492 -282.16479)
			(xy 177.536732 -282.165096) (xy 177.520218 -282.170926) (xy 177.513234 -282.17622) (xy 177.507739 -282.181079)
			(xy 177.4995 -282.193206) (xy 177.496978 -282.200096) (xy 177.496216 -282.203398) (xy 177.489575 -282.228441)
			(xy 177.469576 -282.276232) (xy 177.442374 -282.320322) (xy 177.408632 -282.359634) (xy 177.369176 -282.393208)
			(xy 177.32497 -282.420221) (xy 177.277093 -282.440015) (xy 177.226717 -282.452106) (xy 177.175072 -282.456198)
			(xy 177.123421 -282.452191) (xy 177.073025 -282.440183) (xy 177.025116 -282.420468) (xy 176.980865 -282.393527)
			(xy 176.941354 -282.360018) (xy 176.907548 -282.320762) (xy 176.880273 -282.276716) (xy 176.860196 -282.228958)
			(xy 176.853596 -282.203906) (xy 176.853596 -282.203398) (xy 176.852326 -282.198572) (xy 176.848587 -282.18927)
			(xy 176.835179 -282.174385) (xy 176.817093 -282.16577) (xy 176.807114 -282.16479) (xy 176.595532 -282.16479)
			(xy 176.586776 -282.165106) (xy 176.570274 -282.170951) (xy 176.563274 -282.17622) (xy 176.557756 -282.181059)
			(xy 176.549506 -282.193191) (xy 176.547018 -282.200096) (xy 176.546256 -282.203398) (xy 176.539615 -282.228436)
			(xy 176.519618 -282.276218) (xy 176.492418 -282.320299) (xy 176.458681 -282.359603) (xy 176.41923 -282.393169)
			(xy 176.375031 -282.420176) (xy 176.327162 -282.439964) (xy 176.276794 -282.452051) (xy 176.225158 -282.45614)
			(xy 176.173516 -282.452131) (xy 176.123129 -282.440123) (xy 176.07523 -282.420409) (xy 176.030988 -282.393471)
			(xy 175.991485 -282.359967) (xy 175.957687 -282.320716) (xy 175.930418 -282.276677) (xy 175.910347 -282.228926)
			(xy 175.903636 -282.203906) (xy 175.903636 -282.203398) (xy 175.902366 -282.198572) (xy 175.898629 -282.189266)
			(xy 175.885224 -282.17437) (xy 175.867138 -282.165742) (xy 175.857154 -282.16479) (xy 174.695612 -282.16479)
			(xy 174.686858 -282.165109) (xy 174.67036 -282.17096) (xy 174.663354 -282.17622) (xy 174.657838 -282.18106)
			(xy 174.649591 -282.193193) (xy 174.647098 -282.200096) (xy 174.646336 -282.203398) (xy 174.639695 -282.228434)
			(xy 174.619698 -282.276213) (xy 174.5925 -282.320292) (xy 174.558764 -282.359593) (xy 174.519315 -282.393156)
			(xy 174.475117 -282.420161) (xy 174.427251 -282.439947) (xy 174.376886 -282.452032) (xy 174.325253 -282.45612)
			(xy 174.273614 -282.452111) (xy 174.223231 -282.440103) (xy 174.175334 -282.42039) (xy 174.131095 -282.393452)
			(xy 174.091595 -282.35995) (xy 174.057799 -282.3207) (xy 174.030533 -282.276664) (xy 174.010464 -282.228915)
			(xy 174.003716 -282.203906) (xy 174.003716 -282.203398) (xy 174.002446 -282.198572) (xy 173.998708 -282.189268)
			(xy 173.985302 -282.174377) (xy 173.967216 -282.165755) (xy 173.957234 -282.16479) (xy 173.745652 -282.16479)
			(xy 173.736895 -282.165102) (xy 173.720389 -282.170943) (xy 173.713394 -282.17622) (xy 173.707874 -282.181058)
			(xy 173.699622 -282.193189) (xy 173.697138 -282.200096) (xy 173.696376 -282.203398) (xy 173.689735 -282.228438)
			(xy 173.669737 -282.276223) (xy 173.642537 -282.320307) (xy 173.608798 -282.359614) (xy 173.569346 -282.393182)
			(xy 173.525144 -282.420191) (xy 173.477272 -282.439981) (xy 173.426902 -282.452069) (xy 173.375263 -282.456159)
			(xy 173.323617 -282.452151) (xy 173.273228 -282.440143) (xy 173.225325 -282.420429) (xy 173.18108 -282.39349)
			(xy 173.141575 -282.359984) (xy 173.107774 -282.320731) (xy 173.080503 -282.27669) (xy 173.06043 -282.228937)
			(xy 173.053756 -282.203906) (xy 173.053756 -282.203398) (xy 173.052486 -282.198572) (xy 173.04875 -282.189264)
			(xy 173.035346 -282.174363) (xy 173.01726 -282.165727) (xy 173.007274 -282.16479) (xy 172.795438 -282.16479)
			(xy 172.786682 -282.165105) (xy 172.770179 -282.170949) (xy 172.76318 -282.17622) (xy 172.757662 -282.181059)
			(xy 172.749411 -282.19319) (xy 172.746924 -282.200096) (xy 172.746162 -282.203398) (xy 172.739521 -282.228436)
			(xy 172.719524 -282.276219) (xy 172.692324 -282.320302) (xy 172.658586 -282.359606) (xy 172.619135 -282.393173)
			(xy 172.574934 -282.42018) (xy 172.527065 -282.439969) (xy 172.476696 -282.452056) (xy 172.425059 -282.456145)
			(xy 172.373416 -282.452137) (xy 172.323029 -282.440129) (xy 172.275128 -282.420415) (xy 172.230886 -282.393477)
			(xy 172.191382 -282.359972) (xy 172.157583 -282.32072) (xy 172.130314 -282.276681) (xy 172.110242 -282.228929)
			(xy 172.103542 -282.203906) (xy 172.103542 -282.203398) (xy 172.102272 -282.198572) (xy 172.098535 -282.189265)
			(xy 172.085131 -282.174368) (xy 172.067044 -282.165737) (xy 172.05706 -282.16479) (xy 171.845478 -282.16479)
			(xy 171.836719 -282.165098) (xy 171.820208 -282.170932) (xy 171.81322 -282.17622) (xy 171.807726 -282.18108)
			(xy 171.799489 -282.193208) (xy 171.796964 -282.200096) (xy 171.796202 -282.203398) (xy 171.789561 -282.22844)
			(xy 171.769563 -282.276229) (xy 171.742361 -282.320317) (xy 171.70862 -282.359627) (xy 171.669165 -282.393198)
			(xy 171.624961 -282.420211) (xy 171.577086 -282.440003) (xy 171.526712 -282.452093) (xy 171.475069 -282.456184)
			(xy 171.42342 -282.452177) (xy 171.373026 -282.440169) (xy 171.325119 -282.420454) (xy 171.280871 -282.393514)
			(xy 171.241361 -282.360006) (xy 171.207557 -282.320751) (xy 171.180284 -282.276707) (xy 171.160208 -282.228951)
			(xy 171.153582 -282.203906) (xy 171.153582 -282.203398) (xy 171.152312 -282.198572) (xy 171.148518 -282.189297)
			(xy 171.135133 -282.174409) (xy 171.117071 -282.165777) (xy 171.1071 -282.16479) (xy 170.895518 -282.16479)
			(xy 170.886763 -282.165108) (xy 170.870264 -282.170957) (xy 170.86326 -282.17622) (xy 170.857743 -282.18106)
			(xy 170.849496 -282.193192) (xy 170.847004 -282.200096) (xy 170.846242 -282.203398) (xy 170.839601 -282.228435)
			(xy 170.819604 -282.276215) (xy 170.792405 -282.320294) (xy 170.758669 -282.359596) (xy 170.71922 -282.39316)
			(xy 170.675021 -282.420165) (xy 170.627154 -282.439952) (xy 170.576789 -282.452038) (xy 170.525155 -282.456126)
			(xy 170.473515 -282.452117) (xy 170.42313 -282.440109) (xy 170.375233 -282.420396) (xy 170.330993 -282.393458)
			(xy 170.291492 -282.359955) (xy 170.257696 -282.320705) (xy 170.230429 -282.276668) (xy 170.210359 -282.228919)
			(xy 170.203622 -282.203906) (xy 170.203622 -282.203398) (xy 170.202352 -282.198572) (xy 170.198615 -282.189267)
			(xy 170.185208 -282.174375) (xy 170.167122 -282.165751) (xy 170.15714 -282.16479) (xy 169.945558 -282.16479)
			(xy 169.936801 -282.165101) (xy 169.920293 -282.170941) (xy 169.9133 -282.17622) (xy 169.90778 -282.181058)
			(xy 169.899527 -282.193188) (xy 169.897044 -282.200096) (xy 169.896282 -282.203398) (xy 169.889641 -282.228438)
			(xy 169.869643 -282.276224) (xy 169.842442 -282.320309) (xy 169.808703 -282.359617) (xy 169.76925 -282.393186)
			(xy 169.725048 -282.420195) (xy 169.677176 -282.439986) (xy 169.626804 -282.452075) (xy 169.575164 -282.456165)
			(xy 169.523518 -282.452157) (xy 169.473127 -282.440149) (xy 169.425224 -282.420435) (xy 169.380978 -282.393495)
			(xy 169.341472 -282.359989) (xy 169.30767 -282.320736) (xy 169.280399 -282.276694) (xy 169.260325 -282.22894)
			(xy 169.253662 -282.203906) (xy 169.253662 -282.203398) (xy 169.252392 -282.198572) (xy 169.248657 -282.189263)
			(xy 169.235253 -282.174361) (xy 169.217166 -282.165723) (xy 169.20718 -282.16479) (xy 168.995598 -282.16479)
			(xy 168.986844 -282.165111) (xy 168.97035 -282.170966) (xy 168.96334 -282.17622) (xy 168.957844 -282.181079)
			(xy 168.949604 -282.193206) (xy 168.947084 -282.200096) (xy 168.946322 -282.203398) (xy 168.939681 -282.228441)
			(xy 168.919682 -282.276233) (xy 168.892479 -282.320324) (xy 168.858737 -282.359637) (xy 168.819281 -282.393211)
			(xy 168.775074 -282.420226) (xy 168.727197 -282.44002) (xy 168.67682 -282.452112) (xy 168.625174 -282.456204)
			(xy 168.573521 -282.452197) (xy 168.523124 -282.440189) (xy 168.475215 -282.420474) (xy 168.430963 -282.393532)
			(xy 168.391451 -282.360024) (xy 168.357644 -282.320766) (xy 168.330369 -282.27672) (xy 168.310291 -282.228961)
			(xy 168.303702 -282.203906) (xy 168.303702 -282.203398) (xy 168.302432 -282.198572) (xy 168.298694 -282.189269)
			(xy 168.285286 -282.174382) (xy 168.2672 -282.165765) (xy 168.25722 -282.16479) (xy 168.045638 -282.16479)
			(xy 168.036882 -282.165105) (xy 168.020379 -282.170949) (xy 168.01338 -282.17622) (xy 168.007862 -282.181059)
			(xy 167.999611 -282.19319) (xy 167.997124 -282.200096) (xy 167.996362 -282.203398) (xy 167.989721 -282.228436)
			(xy 167.969724 -282.276219) (xy 167.942524 -282.320302) (xy 167.908786 -282.359606) (xy 167.869335 -282.393173)
			(xy 167.825134 -282.42018) (xy 167.777265 -282.439969) (xy 167.726896 -282.452056) (xy 167.675259 -282.456145)
			(xy 167.623616 -282.452137) (xy 167.573229 -282.440129) (xy 167.525328 -282.420415) (xy 167.481086 -282.393477)
			(xy 167.441582 -282.359972) (xy 167.407783 -282.32072) (xy 167.380514 -282.276681) (xy 167.360442 -282.228929)
			(xy 167.353742 -282.203906) (xy 167.353742 -282.203398) (xy 167.352472 -282.198572) (xy 167.348735 -282.189265)
			(xy 167.335331 -282.174368) (xy 167.317244 -282.165737) (xy 167.30726 -282.16479) (xy 167.095678 -282.16479)
			(xy 167.086919 -282.165098) (xy 167.070408 -282.170932) (xy 167.06342 -282.17622) (xy 167.057926 -282.18108)
			(xy 167.049689 -282.193208) (xy 167.047164 -282.200096) (xy 167.046402 -282.203398) (xy 167.039761 -282.22844)
			(xy 167.019763 -282.276229) (xy 166.992561 -282.320317) (xy 166.95882 -282.359627) (xy 166.919365 -282.393198)
			(xy 166.875161 -282.420211) (xy 166.827286 -282.440003) (xy 166.776912 -282.452093) (xy 166.725269 -282.456184)
			(xy 166.67362 -282.452177) (xy 166.623226 -282.440169) (xy 166.575319 -282.420454) (xy 166.531071 -282.393514)
			(xy 166.491561 -282.360006) (xy 166.457757 -282.320751) (xy 166.430484 -282.276707) (xy 166.410408 -282.228951)
			(xy 166.403782 -282.203906) (xy 166.403782 -282.203398) (xy 166.402512 -282.198572) (xy 166.398718 -282.189297)
			(xy 166.385333 -282.174409) (xy 166.367271 -282.165777) (xy 166.3573 -282.16479) (xy 166.145464 -282.16479)
			(xy 166.136706 -282.1651) (xy 166.120197 -282.170938) (xy 166.113206 -282.17622) (xy 166.107686 -282.181058)
			(xy 166.099431 -282.193188) (xy 166.09695 -282.200096) (xy 166.096188 -282.203398) (xy 166.089547 -282.228438)
			(xy 166.069549 -282.276225) (xy 166.042348 -282.320312) (xy 166.008608 -282.35962) (xy 165.969155 -282.393189)
			(xy 165.924951 -282.4202) (xy 165.877079 -282.439992) (xy 165.826706 -282.45208) (xy 165.775066 -282.456171)
			(xy 165.723418 -282.452163) (xy 165.673027 -282.440155) (xy 165.625122 -282.42044) (xy 165.580876 -282.393501)
			(xy 165.541369 -282.359994) (xy 165.507566 -282.32074) (xy 165.480294 -282.276698) (xy 165.46022 -282.228943)
			(xy 165.453568 -282.203906) (xy 165.453568 -282.203398) (xy 165.452298 -282.198572) (xy 165.448563 -282.189263)
			(xy 165.43516 -282.174359) (xy 165.417073 -282.165719) (xy 165.407086 -282.16479) (xy 165.195504 -282.16479)
			(xy 165.18675 -282.16511) (xy 165.170254 -282.170963) (xy 165.163246 -282.17622) (xy 165.157731 -282.181061)
			(xy 165.149485 -282.193194) (xy 165.14699 -282.200096) (xy 165.146228 -282.203398) (xy 165.139587 -282.228434)
			(xy 165.119591 -282.276211) (xy 165.092392 -282.320289) (xy 165.058657 -282.359589) (xy 165.019209 -282.393151)
			(xy 164.975012 -282.420155) (xy 164.927147 -282.43994) (xy 164.876783 -282.452025) (xy 164.825151 -282.456112)
			(xy 164.773513 -282.452103) (xy 164.723131 -282.440095) (xy 164.675236 -282.420382) (xy 164.630998 -282.393445)
			(xy 164.591499 -282.359943) (xy 164.557705 -282.320694) (xy 164.530439 -282.276658) (xy 164.51037 -282.228911)
			(xy 164.503608 -282.203906) (xy 164.503608 -282.203398) (xy 164.502338 -282.198572) (xy 164.4986 -282.189268)
			(xy 164.485193 -282.17438) (xy 164.467107 -282.165761) (xy 164.457126 -282.16479) (xy 164.245544 -282.16479)
			(xy 164.236787 -282.165104) (xy 164.220283 -282.170946) (xy 164.213286 -282.17622) (xy 164.207767 -282.181058)
			(xy 164.199516 -282.19319) (xy 164.19703 -282.200096) (xy 164.196268 -282.203398) (xy 164.189627 -282.228437)
			(xy 164.16963 -282.276221) (xy 164.142429 -282.320304) (xy 164.108691 -282.359609) (xy 164.069239 -282.393176)
			(xy 164.025038 -282.420185) (xy 163.977168 -282.439975) (xy 163.926799 -282.452062) (xy 163.875161 -282.456151)
			(xy 163.823517 -282.452143) (xy 163.773128 -282.440135) (xy 163.725227 -282.420421) (xy 163.680983 -282.393482)
			(xy 163.641479 -282.359977) (xy 163.607679 -282.320725) (xy 163.580409 -282.276685) (xy 163.560337 -282.228932)
			(xy 163.553648 -282.203906) (xy 163.553648 -282.203398) (xy 163.552378 -282.198572) (xy 163.548642 -282.189264)
			(xy 163.535237 -282.174366) (xy 163.517151 -282.165733) (xy 163.507166 -282.16479) (xy 163.295584 -282.16479)
			(xy 163.286825 -282.165097) (xy 163.270312 -282.17093) (xy 163.263326 -282.17622) (xy 163.257831 -282.18108)
			(xy 163.249593 -282.193207) (xy 163.24707 -282.200096) (xy 163.246308 -282.203398) (xy 163.239667 -282.22844)
			(xy 163.219669 -282.27623) (xy 163.192466 -282.320319) (xy 163.158725 -282.35963) (xy 163.11927 -282.393202)
			(xy 163.075064 -282.420215) (xy 163.027189 -282.440009) (xy 162.976814 -282.452099) (xy 162.92517 -282.45619)
			(xy 162.87352 -282.452183) (xy 162.823125 -282.440175) (xy 162.775218 -282.42046) (xy 162.730968 -282.393519)
			(xy 162.691458 -282.360012) (xy 162.657653 -282.320756) (xy 162.630379 -282.276711) (xy 162.610303 -282.228954)
			(xy 162.603688 -282.203906) (xy 162.603688 -282.203398) (xy 162.602418 -282.198572) (xy 162.598679 -282.189271)
			(xy 162.585271 -282.174388) (xy 162.567185 -282.165775) (xy 162.557206 -282.16479) (xy 162.345624 -282.16479)
			(xy 162.336869 -282.165107) (xy 162.320368 -282.170955) (xy 162.313366 -282.17622) (xy 162.307849 -282.18106)
			(xy 162.2996 -282.193192) (xy 162.29711 -282.200096) (xy 162.296348 -282.203398) (xy 162.289707 -282.228435)
			(xy 162.26971 -282.276216) (xy 162.242511 -282.320296) (xy 162.208774 -282.359599) (xy 162.169324 -282.393164)
			(xy 162.125125 -282.42017) (xy 162.077258 -282.439957) (xy 162.026891 -282.452043) (xy 161.975256 -282.456132)
			(xy 161.923615 -282.452123) (xy 161.87323 -282.440115) (xy 161.825331 -282.420401) (xy 161.781091 -282.393464)
			(xy 161.741589 -282.35996) (xy 161.707792 -282.32071) (xy 161.680524 -282.276671) (xy 161.660453 -282.228922)
			(xy 161.653728 -282.203906) (xy 161.653728 -282.203398) (xy 161.652458 -282.198572) (xy 161.648721 -282.189267)
			(xy 161.635315 -282.174373) (xy 161.617229 -282.165747) (xy 161.607246 -282.16479) (xy 161.395664 -282.16479)
			(xy 161.386906 -282.1651) (xy 161.370397 -282.170938) (xy 161.363406 -282.17622) (xy 161.357886 -282.181058)
			(xy 161.349631 -282.193188) (xy 161.34715 -282.200096) (xy 161.346388 -282.203398) (xy 161.339747 -282.228438)
			(xy 161.319749 -282.276225) (xy 161.292548 -282.320312) (xy 161.258808 -282.35962) (xy 161.219355 -282.393189)
			(xy 161.175151 -282.4202) (xy 161.127279 -282.439992) (xy 161.076906 -282.45208) (xy 161.025266 -282.456171)
			(xy 160.973618 -282.452163) (xy 160.923227 -282.440155) (xy 160.875322 -282.42044) (xy 160.831076 -282.393501)
			(xy 160.791569 -282.359994) (xy 160.757766 -282.32074) (xy 160.730494 -282.276698) (xy 160.71042 -282.228943)
			(xy 160.703768 -282.203906) (xy 160.703768 -282.203398) (xy 160.702498 -282.198572) (xy 160.698763 -282.189263)
			(xy 160.68536 -282.174359) (xy 160.667273 -282.165719) (xy 160.657286 -282.16479) (xy 160.44545 -282.16479)
			(xy 160.436693 -282.165103) (xy 160.420187 -282.170944) (xy 160.413192 -282.17622) (xy 160.407673 -282.181058)
			(xy 160.39942 -282.193189) (xy 160.396936 -282.200096) (xy 160.396174 -282.203398) (xy 160.389533 -282.228437)
			(xy 160.369535 -282.276222) (xy 160.342335 -282.320306) (xy 160.308596 -282.359613) (xy 160.269144 -282.39318)
			(xy 160.224942 -282.420189) (xy 160.177071 -282.43998) (xy 160.126701 -282.452067) (xy 160.075062 -282.456157)
			(xy 160.023417 -282.452149) (xy 159.973028 -282.440141) (xy 159.925126 -282.420427) (xy 159.880881 -282.393488)
			(xy 159.841376 -282.359982) (xy 159.807575 -282.32073) (xy 159.780305 -282.276689) (xy 159.760231 -282.228936)
			(xy 159.753554 -282.203906) (xy 159.753554 -282.203398) (xy 159.752284 -282.198572) (xy 159.748548 -282.189264)
			(xy 159.735144 -282.174364) (xy 159.717058 -282.165729) (xy 159.707072 -282.16479) (xy 159.49549 -282.16479)
			(xy 159.486731 -282.165096) (xy 159.470216 -282.170927) (xy 159.463232 -282.17622) (xy 159.457737 -282.181079)
			(xy 159.449498 -282.193207) (xy 159.446976 -282.200096) (xy 159.446214 -282.203398) (xy 159.439573 -282.22844)
			(xy 159.419574 -282.276231) (xy 159.392372 -282.320321) (xy 159.35863 -282.359633) (xy 159.319175 -282.393206)
			(xy 159.274968 -282.42022) (xy 159.227092 -282.440014) (xy 159.176717 -282.452104) (xy 159.125072 -282.456196)
			(xy 159.073421 -282.452189) (xy 159.023025 -282.440181) (xy 158.975117 -282.420466) (xy 158.930866 -282.393525)
			(xy 158.891355 -282.360017) (xy 158.857549 -282.32076) (xy 158.830275 -282.276715) (xy 158.810198 -282.228957)
			(xy 158.803594 -282.203906) (xy 158.803594 -282.203398) (xy 158.802324 -282.198572) (xy 158.798585 -282.18927)
			(xy 158.785177 -282.174386) (xy 158.767091 -282.165771) (xy 158.757112 -282.16479) (xy 158.54553 -282.16479)
			(xy 158.536774 -282.165106) (xy 158.520273 -282.170952) (xy 158.513272 -282.17622) (xy 158.507754 -282.181059)
			(xy 158.499505 -282.193191) (xy 158.497016 -282.200096) (xy 158.496254 -282.203398) (xy 158.489613 -282.228436)
			(xy 158.469616 -282.276217) (xy 158.442416 -282.320299) (xy 158.408679 -282.359602) (xy 158.369229 -282.393167)
			(xy 158.325029 -282.420174) (xy 158.277161 -282.439963) (xy 158.226793 -282.452049) (xy 158.175158 -282.456138)
			(xy 158.123516 -282.452129) (xy 158.073129 -282.440121) (xy 158.02523 -282.420407) (xy 157.980989 -282.393469)
			(xy 157.941486 -282.359965) (xy 157.907688 -282.320714) (xy 157.88042 -282.276675) (xy 157.860348 -282.228925)
			(xy 157.853634 -282.203906) (xy 157.853634 -282.203398) (xy 157.852364 -282.198572) (xy 157.848627 -282.189266)
			(xy 157.835222 -282.174371) (xy 157.817135 -282.165743) (xy 157.807152 -282.16479) (xy 157.59557 -282.16479)
			(xy 157.586812 -282.165099) (xy 157.570302 -282.170936) (xy 157.563312 -282.17622) (xy 157.557791 -282.181057)
			(xy 157.549536 -282.193187) (xy 157.547056 -282.200096) (xy 157.546294 -282.203398) (xy 157.539653 -282.228439)
			(xy 157.519655 -282.276227) (xy 157.492453 -282.320314) (xy 157.458713 -282.359623) (xy 157.419259 -282.393193)
			(xy 157.375055 -282.420205) (xy 157.327182 -282.439997) (xy 157.276809 -282.452086) (xy 157.225167 -282.456177)
			(xy 157.173519 -282.452169) (xy 157.123126 -282.440161) (xy 157.075221 -282.420446) (xy 157.030974 -282.393506)
			(xy 156.991466 -282.36) (xy 156.957662 -282.320745) (xy 156.93039 -282.276702) (xy 156.910314 -282.228946)
			(xy 156.903674 -282.203906) (xy 156.903674 -282.203398) (xy 156.902404 -282.198572) (xy 156.898609 -282.189298)
			(xy 156.885224 -282.174413) (xy 156.867162 -282.165783) (xy 156.857192 -282.16479) (xy 156.64561 -282.16479)
			(xy 156.636856 -282.165109) (xy 156.620358 -282.170961) (xy 156.613352 -282.17622) (xy 156.607836 -282.18106)
			(xy 156.59959 -282.193193) (xy 156.597096 -282.200096) (xy 156.596334 -282.203398) (xy 156.589693 -282.228434)
			(xy 156.569697 -282.276213) (xy 156.542498 -282.320291) (xy 156.508762 -282.359592) (xy 156.469314 -282.393154)
			(xy 156.425116 -282.420159) (xy 156.37725 -282.439946) (xy 156.326886 -282.45203) (xy 156.275253 -282.456118)
			(xy 156.223614 -282.452109) (xy 156.173231 -282.440101) (xy 156.125335 -282.420388) (xy 156.081096 -282.393451)
			(xy 156.041596 -282.359948) (xy 156.007801 -282.320699) (xy 155.980535 -282.276662) (xy 155.960465 -282.228914)
			(xy 155.953714 -282.203906) (xy 155.953714 -282.203398) (xy 155.952444 -282.198572) (xy 155.948706 -282.189268)
			(xy 155.9353 -282.174378) (xy 155.917213 -282.165757) (xy 155.907232 -282.16479) (xy 155.69565 -282.16479)
			(xy 155.686893 -282.165103) (xy 155.670387 -282.170944) (xy 155.663392 -282.17622) (xy 155.657873 -282.181058)
			(xy 155.64962 -282.193189) (xy 155.647136 -282.200096) (xy 155.646374 -282.203398) (xy 155.639733 -282.228437)
			(xy 155.619735 -282.276222) (xy 155.592535 -282.320306) (xy 155.558796 -282.359613) (xy 155.519344 -282.39318)
			(xy 155.475142 -282.420189) (xy 155.427271 -282.43998) (xy 155.376901 -282.452067) (xy 155.325262 -282.456157)
			(xy 155.273617 -282.452149) (xy 155.223228 -282.440141) (xy 155.175326 -282.420427) (xy 155.131081 -282.393488)
			(xy 155.091576 -282.359982) (xy 155.057775 -282.32073) (xy 155.030505 -282.276689) (xy 155.010431 -282.228936)
			(xy 155.003754 -282.203906) (xy 155.003754 -282.203398) (xy 155.002484 -282.198572) (xy 154.998748 -282.189264)
			(xy 154.985344 -282.174364) (xy 154.967258 -282.165729) (xy 154.957272 -282.16479) (xy 154.74569 -282.16479)
			(xy 154.736931 -282.165096) (xy 154.720416 -282.170927) (xy 154.713432 -282.17622) (xy 154.707937 -282.181079)
			(xy 154.699698 -282.193207) (xy 154.697176 -282.200096) (xy 154.696414 -282.203398) (xy 154.690181 -282.227069)
			(xy 154.671692 -282.272391) (xy 154.646723 -282.314491) (xy 154.615819 -282.35245) (xy 154.579658 -282.385439)
			(xy 154.539028 -282.412736) (xy 154.494818 -282.433744) (xy 154.447993 -282.448005) (xy 154.399578 -282.455208)
			(xy 154.375104 -282.45562) (xy 154.347525 -282.455044) (xy 154.293138 -282.445847) (xy 154.2669 -282.437332)
			(xy 154.266646 -282.437332) (xy 154.259857 -282.435254) (xy 154.245683 -282.434489) (xy 154.238706 -282.435808)
			(xy 154.232102 -282.437332) (xy 154.226006 -282.440634) (xy 154.222894 -282.442434) (xy 154.217161 -282.446772)
			(xy 154.214576 -282.44927) (xy 153.752296 -282.91155) (xy 153.748776 -282.915281) (xy 153.743151 -282.923857)
			(xy 153.74112 -282.928568) (xy 153.737564 -282.937204) (xy 153.737564 -282.959302) (xy 153.738072 -282.962858)
			(xy 153.739342 -282.97251) (xy 153.740612 -282.976574) (xy 153.747594 -283.000417) (xy 153.755126 -283.049524)
			(xy 153.755598 -283.074364) (xy 153.755598 -283.074872) (xy 154.0693 -283.074872) (xy 154.07326 -283.025818)
			(xy 154.085037 -282.978034) (xy 154.104328 -282.932758) (xy 154.130631 -282.891162) (xy 154.163266 -282.854325)
			(xy 154.201387 -282.8232) (xy 154.244008 -282.798593) (xy 154.290024 -282.781141) (xy 154.338243 -282.771297)
			(xy 154.387418 -282.769316) (xy 154.436273 -282.775248) (xy 154.483544 -282.78894) (xy 154.528006 -282.810038)
			(xy 154.568509 -282.837994) (xy 154.604002 -282.872086) (xy 154.633567 -282.91143) (xy 154.656438 -282.955007)
			(xy 154.672022 -283.001688) (xy 154.679917 -283.050265) (xy 154.680412 -283.074872) (xy 155.01926 -283.074872)
			(xy 155.02322 -283.025818) (xy 155.034997 -282.978034) (xy 155.054288 -282.932758) (xy 155.080591 -282.891162)
			(xy 155.113226 -282.854325) (xy 155.151347 -282.8232) (xy 155.193968 -282.798593) (xy 155.239984 -282.781141)
			(xy 155.288203 -282.771297) (xy 155.337378 -282.769316) (xy 155.386233 -282.775248) (xy 155.433504 -282.78894)
			(xy 155.477966 -282.810038) (xy 155.518469 -282.837994) (xy 155.553962 -282.872086) (xy 155.583527 -282.91143)
			(xy 155.606398 -282.955007) (xy 155.621982 -283.001688) (xy 155.629877 -283.050265) (xy 155.630372 -283.074872)
			(xy 155.96922 -283.074872) (xy 155.97318 -283.025818) (xy 155.984957 -282.978034) (xy 156.004248 -282.932758)
			(xy 156.030551 -282.891162) (xy 156.063186 -282.854325) (xy 156.101307 -282.8232) (xy 156.143928 -282.798593)
			(xy 156.189944 -282.781141) (xy 156.238163 -282.771297) (xy 156.287338 -282.769316) (xy 156.336193 -282.775248)
			(xy 156.383464 -282.78894) (xy 156.427926 -282.810038) (xy 156.468429 -282.837994) (xy 156.503922 -282.872086)
			(xy 156.533487 -282.91143) (xy 156.556358 -282.955007) (xy 156.571942 -283.001688) (xy 156.579837 -283.050265)
			(xy 156.580332 -283.074872) (xy 156.91918 -283.074872) (xy 156.92314 -283.025818) (xy 156.934917 -282.978034)
			(xy 156.954208 -282.932758) (xy 156.980511 -282.891162) (xy 157.013146 -282.854325) (xy 157.051267 -282.8232)
			(xy 157.093888 -282.798593) (xy 157.139904 -282.781141) (xy 157.188123 -282.771297) (xy 157.237298 -282.769316)
			(xy 157.286153 -282.775248) (xy 157.333424 -282.78894) (xy 157.377886 -282.810038) (xy 157.418389 -282.837994)
			(xy 157.453882 -282.872086) (xy 157.483447 -282.91143) (xy 157.506318 -282.955007) (xy 157.521902 -283.001688)
			(xy 157.529797 -283.050265) (xy 157.530292 -283.074872) (xy 157.86914 -283.074872) (xy 157.8731 -283.025818)
			(xy 157.884877 -282.978034) (xy 157.904168 -282.932758) (xy 157.930471 -282.891162) (xy 157.963106 -282.854325)
			(xy 158.001227 -282.8232) (xy 158.043848 -282.798593) (xy 158.089864 -282.781141) (xy 158.138083 -282.771297)
			(xy 158.187258 -282.769316) (xy 158.236113 -282.775248) (xy 158.283384 -282.78894) (xy 158.327846 -282.810038)
			(xy 158.368349 -282.837994) (xy 158.403842 -282.872086) (xy 158.433407 -282.91143) (xy 158.456278 -282.955007)
			(xy 158.471862 -283.001688) (xy 158.479757 -283.050265) (xy 158.480252 -283.074872) (xy 158.8191 -283.074872)
			(xy 158.82306 -283.025818) (xy 158.834837 -282.978034) (xy 158.854128 -282.932758) (xy 158.880431 -282.891162)
			(xy 158.913066 -282.854325) (xy 158.951187 -282.8232) (xy 158.993808 -282.798593) (xy 159.039824 -282.781141)
			(xy 159.088043 -282.771297) (xy 159.137218 -282.769316) (xy 159.186073 -282.775248) (xy 159.233344 -282.78894)
			(xy 159.277806 -282.810038) (xy 159.318309 -282.837994) (xy 159.353802 -282.872086) (xy 159.383367 -282.91143)
			(xy 159.406238 -282.955007) (xy 159.421822 -283.001688) (xy 159.429717 -283.050265) (xy 159.430212 -283.074872)
			(xy 159.76906 -283.074872) (xy 159.77302 -283.025818) (xy 159.784797 -282.978034) (xy 159.804088 -282.932758)
			(xy 159.830391 -282.891162) (xy 159.863026 -282.854325) (xy 159.901147 -282.8232) (xy 159.943768 -282.798593)
			(xy 159.989784 -282.781141) (xy 160.038003 -282.771297) (xy 160.087178 -282.769316) (xy 160.136033 -282.775248)
			(xy 160.183304 -282.78894) (xy 160.227766 -282.810038) (xy 160.268269 -282.837994) (xy 160.303762 -282.872086)
			(xy 160.333327 -282.91143) (xy 160.356198 -282.955007) (xy 160.371782 -283.001688) (xy 160.379677 -283.050265)
			(xy 160.380172 -283.074872) (xy 160.719274 -283.074872) (xy 160.723234 -283.025818) (xy 160.735011 -282.978034)
			(xy 160.754302 -282.932758) (xy 160.780605 -282.891162) (xy 160.81324 -282.854325) (xy 160.851361 -282.8232)
			(xy 160.893982 -282.798593) (xy 160.939998 -282.781141) (xy 160.988217 -282.771297) (xy 161.037392 -282.769316)
			(xy 161.086247 -282.775248) (xy 161.133518 -282.78894) (xy 161.17798 -282.810038) (xy 161.218483 -282.837994)
			(xy 161.253976 -282.872086) (xy 161.283541 -282.91143) (xy 161.306412 -282.955007) (xy 161.321996 -283.001688)
			(xy 161.329891 -283.050265) (xy 161.330386 -283.074872) (xy 161.669234 -283.074872) (xy 161.673194 -283.025818)
			(xy 161.684971 -282.978034) (xy 161.704262 -282.932758) (xy 161.730565 -282.891162) (xy 161.7632 -282.854325)
			(xy 161.801321 -282.8232) (xy 161.843942 -282.798593) (xy 161.889958 -282.781141) (xy 161.938177 -282.771297)
			(xy 161.987352 -282.769316) (xy 162.036207 -282.775248) (xy 162.083478 -282.78894) (xy 162.12794 -282.810038)
			(xy 162.168443 -282.837994) (xy 162.203936 -282.872086) (xy 162.233501 -282.91143) (xy 162.256372 -282.955007)
			(xy 162.271956 -283.001688) (xy 162.279851 -283.050265) (xy 162.280346 -283.074872) (xy 162.619194 -283.074872)
			(xy 162.623154 -283.025818) (xy 162.634931 -282.978034) (xy 162.654222 -282.932758) (xy 162.680525 -282.891162)
			(xy 162.71316 -282.854325) (xy 162.751281 -282.8232) (xy 162.793902 -282.798593) (xy 162.839918 -282.781141)
			(xy 162.888137 -282.771297) (xy 162.937312 -282.769316) (xy 162.986167 -282.775248) (xy 163.033438 -282.78894)
			(xy 163.0779 -282.810038) (xy 163.118403 -282.837994) (xy 163.153896 -282.872086) (xy 163.183461 -282.91143)
			(xy 163.206332 -282.955007) (xy 163.221916 -283.001688) (xy 163.229811 -283.050265) (xy 163.230306 -283.074872)
			(xy 163.569154 -283.074872) (xy 163.573114 -283.025818) (xy 163.584891 -282.978034) (xy 163.604182 -282.932758)
			(xy 163.630485 -282.891162) (xy 163.66312 -282.854325) (xy 163.701241 -282.8232) (xy 163.743862 -282.798593)
			(xy 163.789878 -282.781141) (xy 163.838097 -282.771297) (xy 163.887272 -282.769316) (xy 163.936127 -282.775248)
			(xy 163.983398 -282.78894) (xy 164.02786 -282.810038) (xy 164.068363 -282.837994) (xy 164.103856 -282.872086)
			(xy 164.133421 -282.91143) (xy 164.156292 -282.955007) (xy 164.171876 -283.001688) (xy 164.179771 -283.050265)
			(xy 164.180266 -283.074872) (xy 164.519114 -283.074872) (xy 164.523074 -283.025818) (xy 164.534851 -282.978034)
			(xy 164.554142 -282.932758) (xy 164.580445 -282.891162) (xy 164.61308 -282.854325) (xy 164.651201 -282.8232)
			(xy 164.693822 -282.798593) (xy 164.739838 -282.781141) (xy 164.788057 -282.771297) (xy 164.837232 -282.769316)
			(xy 164.886087 -282.775248) (xy 164.933358 -282.78894) (xy 164.97782 -282.810038) (xy 165.018323 -282.837994)
			(xy 165.053816 -282.872086) (xy 165.083381 -282.91143) (xy 165.106252 -282.955007) (xy 165.121836 -283.001688)
			(xy 165.129731 -283.050265) (xy 165.130226 -283.074872) (xy 165.469074 -283.074872) (xy 165.473034 -283.025818)
			(xy 165.484811 -282.978034) (xy 165.504102 -282.932758) (xy 165.530405 -282.891162) (xy 165.56304 -282.854325)
			(xy 165.601161 -282.8232) (xy 165.643782 -282.798593) (xy 165.689798 -282.781141) (xy 165.738017 -282.771297)
			(xy 165.787192 -282.769316) (xy 165.836047 -282.775248) (xy 165.883318 -282.78894) (xy 165.92778 -282.810038)
			(xy 165.968283 -282.837994) (xy 166.003776 -282.872086) (xy 166.033341 -282.91143) (xy 166.056212 -282.955007)
			(xy 166.071796 -283.001688) (xy 166.079691 -283.050265) (xy 166.080186 -283.074872) (xy 166.419288 -283.074872)
			(xy 166.423248 -283.025818) (xy 166.435025 -282.978034) (xy 166.454316 -282.932758) (xy 166.480619 -282.891162)
			(xy 166.513254 -282.854325) (xy 166.551375 -282.8232) (xy 166.593996 -282.798593) (xy 166.640012 -282.781141)
			(xy 166.688231 -282.771297) (xy 166.737406 -282.769316) (xy 166.786261 -282.775248) (xy 166.833532 -282.78894)
			(xy 166.877994 -282.810038) (xy 166.918497 -282.837994) (xy 166.95399 -282.872086) (xy 166.983555 -282.91143)
			(xy 167.006426 -282.955007) (xy 167.02201 -283.001688) (xy 167.029905 -283.050265) (xy 167.0304 -283.074872)
			(xy 167.369248 -283.074872) (xy 167.373208 -283.025818) (xy 167.384985 -282.978034) (xy 167.404276 -282.932758)
			(xy 167.430579 -282.891162) (xy 167.463214 -282.854325) (xy 167.501335 -282.8232) (xy 167.543956 -282.798593)
			(xy 167.589972 -282.781141) (xy 167.638191 -282.771297) (xy 167.687366 -282.769316) (xy 167.736221 -282.775248)
			(xy 167.783492 -282.78894) (xy 167.827954 -282.810038) (xy 167.868457 -282.837994) (xy 167.90395 -282.872086)
			(xy 167.933515 -282.91143) (xy 167.956386 -282.955007) (xy 167.97197 -283.001688) (xy 167.979865 -283.050265)
			(xy 167.98036 -283.074872) (xy 168.319208 -283.074872) (xy 168.323168 -283.025818) (xy 168.334945 -282.978034)
			(xy 168.354236 -282.932758) (xy 168.380539 -282.891162) (xy 168.413174 -282.854325) (xy 168.451295 -282.8232)
			(xy 168.493916 -282.798593) (xy 168.539932 -282.781141) (xy 168.588151 -282.771297) (xy 168.637326 -282.769316)
			(xy 168.686181 -282.775248) (xy 168.733452 -282.78894) (xy 168.777914 -282.810038) (xy 168.818417 -282.837994)
			(xy 168.85391 -282.872086) (xy 168.883475 -282.91143) (xy 168.906346 -282.955007) (xy 168.92193 -283.001688)
			(xy 168.929825 -283.050265) (xy 168.93032 -283.074872) (xy 169.269168 -283.074872) (xy 169.273128 -283.025818)
			(xy 169.284905 -282.978034) (xy 169.304196 -282.932758) (xy 169.330499 -282.891162) (xy 169.363134 -282.854325)
			(xy 169.401255 -282.8232) (xy 169.443876 -282.798593) (xy 169.489892 -282.781141) (xy 169.538111 -282.771297)
			(xy 169.587286 -282.769316) (xy 169.636141 -282.775248) (xy 169.683412 -282.78894) (xy 169.727874 -282.810038)
			(xy 169.768377 -282.837994) (xy 169.80387 -282.872086) (xy 169.833435 -282.91143) (xy 169.856306 -282.955007)
			(xy 169.87189 -283.001688) (xy 169.879785 -283.050265) (xy 169.88028 -283.074872) (xy 170.219128 -283.074872)
			(xy 170.223088 -283.025818) (xy 170.234865 -282.978034) (xy 170.254156 -282.932758) (xy 170.280459 -282.891162)
			(xy 170.313094 -282.854325) (xy 170.351215 -282.8232) (xy 170.393836 -282.798593) (xy 170.439852 -282.781141)
			(xy 170.488071 -282.771297) (xy 170.537246 -282.769316) (xy 170.586101 -282.775248) (xy 170.633372 -282.78894)
			(xy 170.677834 -282.810038) (xy 170.718337 -282.837994) (xy 170.75383 -282.872086) (xy 170.783395 -282.91143)
			(xy 170.806266 -282.955007) (xy 170.82185 -283.001688) (xy 170.829745 -283.050265) (xy 170.83024 -283.074872)
			(xy 171.169088 -283.074872) (xy 171.173048 -283.025818) (xy 171.184825 -282.978034) (xy 171.204116 -282.932758)
			(xy 171.230419 -282.891162) (xy 171.263054 -282.854325) (xy 171.301175 -282.8232) (xy 171.343796 -282.798593)
			(xy 171.389812 -282.781141) (xy 171.438031 -282.771297) (xy 171.487206 -282.769316) (xy 171.536061 -282.775248)
			(xy 171.583332 -282.78894) (xy 171.627794 -282.810038) (xy 171.668297 -282.837994) (xy 171.70379 -282.872086)
			(xy 171.733355 -282.91143) (xy 171.756226 -282.955007) (xy 171.77181 -283.001688) (xy 171.779705 -283.050265)
			(xy 171.7802 -283.074872) (xy 172.119302 -283.074872) (xy 172.123262 -283.025818) (xy 172.135039 -282.978034)
			(xy 172.15433 -282.932758) (xy 172.180633 -282.891162) (xy 172.213268 -282.854325) (xy 172.251389 -282.8232)
			(xy 172.29401 -282.798593) (xy 172.340026 -282.781141) (xy 172.388245 -282.771297) (xy 172.43742 -282.769316)
			(xy 172.486275 -282.775248) (xy 172.533546 -282.78894) (xy 172.578008 -282.810038) (xy 172.618511 -282.837994)
			(xy 172.654004 -282.872086) (xy 172.683569 -282.91143) (xy 172.70644 -282.955007) (xy 172.722024 -283.001688)
			(xy 172.729919 -283.050265) (xy 172.730414 -283.074872) (xy 173.069262 -283.074872) (xy 173.073222 -283.025818)
			(xy 173.084999 -282.978034) (xy 173.10429 -282.932758) (xy 173.130593 -282.891162) (xy 173.163228 -282.854325)
			(xy 173.201349 -282.8232) (xy 173.24397 -282.798593) (xy 173.289986 -282.781141) (xy 173.338205 -282.771297)
			(xy 173.38738 -282.769316) (xy 173.436235 -282.775248) (xy 173.483506 -282.78894) (xy 173.527968 -282.810038)
			(xy 173.568471 -282.837994) (xy 173.603964 -282.872086) (xy 173.633529 -282.91143) (xy 173.6564 -282.955007)
			(xy 173.671984 -283.001688) (xy 173.679879 -283.050265) (xy 173.680374 -283.074872) (xy 174.019222 -283.074872)
			(xy 174.023182 -283.025818) (xy 174.034959 -282.978034) (xy 174.05425 -282.932758) (xy 174.080553 -282.891162)
			(xy 174.113188 -282.854325) (xy 174.151309 -282.8232) (xy 174.19393 -282.798593) (xy 174.239946 -282.781141)
			(xy 174.288165 -282.771297) (xy 174.33734 -282.769316) (xy 174.386195 -282.775248) (xy 174.433466 -282.78894)
			(xy 174.477928 -282.810038) (xy 174.518431 -282.837994) (xy 174.553924 -282.872086) (xy 174.583489 -282.91143)
			(xy 174.60636 -282.955007) (xy 174.621944 -283.001688) (xy 174.629839 -283.050265) (xy 174.630334 -283.074872)
			(xy 175.919142 -283.074872) (xy 175.923102 -283.025818) (xy 175.934879 -282.978034) (xy 175.95417 -282.932758)
			(xy 175.980473 -282.891162) (xy 176.013108 -282.854325) (xy 176.051229 -282.8232) (xy 176.09385 -282.798593)
			(xy 176.139866 -282.781141) (xy 176.188085 -282.771297) (xy 176.23726 -282.769316) (xy 176.286115 -282.775248)
			(xy 176.333386 -282.78894) (xy 176.377848 -282.810038) (xy 176.418351 -282.837994) (xy 176.453844 -282.872086)
			(xy 176.483409 -282.91143) (xy 176.50628 -282.955007) (xy 176.521864 -283.001688) (xy 176.529759 -283.050265)
			(xy 176.530254 -283.074872) (xy 176.869102 -283.074872) (xy 176.873062 -283.025818) (xy 176.884839 -282.978034)
			(xy 176.90413 -282.932758) (xy 176.930433 -282.891162) (xy 176.963068 -282.854325) (xy 177.001189 -282.8232)
			(xy 177.04381 -282.798593) (xy 177.089826 -282.781141) (xy 177.138045 -282.771297) (xy 177.18722 -282.769316)
			(xy 177.236075 -282.775248) (xy 177.283346 -282.78894) (xy 177.327808 -282.810038) (xy 177.368311 -282.837994)
			(xy 177.403804 -282.872086) (xy 177.433369 -282.91143) (xy 177.45624 -282.955007) (xy 177.471824 -283.001688)
			(xy 177.479719 -283.050265) (xy 177.480214 -283.074872) (xy 177.819062 -283.074872) (xy 177.823022 -283.025818)
			(xy 177.834799 -282.978034) (xy 177.85409 -282.932758) (xy 177.880393 -282.891162) (xy 177.913028 -282.854325)
			(xy 177.951149 -282.8232) (xy 177.99377 -282.798593) (xy 178.039786 -282.781141) (xy 178.088005 -282.771297)
			(xy 178.13718 -282.769316) (xy 178.186035 -282.775248) (xy 178.233306 -282.78894) (xy 178.277768 -282.810038)
			(xy 178.318271 -282.837994) (xy 178.353764 -282.872086) (xy 178.383329 -282.91143) (xy 178.4062 -282.955007)
			(xy 178.421784 -283.001688) (xy 178.429679 -283.050265) (xy 178.430174 -283.074872) (xy 178.769276 -283.074872)
			(xy 178.773236 -283.025818) (xy 178.785013 -282.978034) (xy 178.804304 -282.932758) (xy 178.830607 -282.891162)
			(xy 178.863242 -282.854325) (xy 178.901363 -282.8232) (xy 178.943984 -282.798593) (xy 178.99 -282.781141)
			(xy 179.038219 -282.771297) (xy 179.087394 -282.769316) (xy 179.136249 -282.775248) (xy 179.18352 -282.78894)
			(xy 179.227982 -282.810038) (xy 179.268485 -282.837994) (xy 179.303978 -282.872086) (xy 179.333543 -282.91143)
			(xy 179.356414 -282.955007) (xy 179.371998 -283.001688) (xy 179.379893 -283.050265) (xy 179.380388 -283.074872)
			(xy 179.719236 -283.074872) (xy 179.723196 -283.025818) (xy 179.734973 -282.978034) (xy 179.754264 -282.932758)
			(xy 179.780567 -282.891162) (xy 179.813202 -282.854325) (xy 179.851323 -282.8232) (xy 179.893944 -282.798593)
			(xy 179.93996 -282.781141) (xy 179.988179 -282.771297) (xy 180.037354 -282.769316) (xy 180.086209 -282.775248)
			(xy 180.13348 -282.78894) (xy 180.177942 -282.810038) (xy 180.218445 -282.837994) (xy 180.253938 -282.872086)
			(xy 180.283503 -282.91143) (xy 180.306374 -282.955007) (xy 180.321958 -283.001688) (xy 180.329853 -283.050265)
			(xy 180.330348 -283.074872) (xy 180.669196 -283.074872) (xy 180.673156 -283.025818) (xy 180.684933 -282.978034)
			(xy 180.704224 -282.932758) (xy 180.730527 -282.891162) (xy 180.763162 -282.854325) (xy 180.801283 -282.8232)
			(xy 180.843904 -282.798593) (xy 180.88992 -282.781141) (xy 180.938139 -282.771297) (xy 180.987314 -282.769316)
			(xy 181.036169 -282.775248) (xy 181.08344 -282.78894) (xy 181.127902 -282.810038) (xy 181.168405 -282.837994)
			(xy 181.203898 -282.872086) (xy 181.233463 -282.91143) (xy 181.256334 -282.955007) (xy 181.271918 -283.001688)
			(xy 181.279813 -283.050265) (xy 181.280308 -283.074872) (xy 181.619156 -283.074872) (xy 181.623116 -283.025818)
			(xy 181.634893 -282.978034) (xy 181.654184 -282.932758) (xy 181.680487 -282.891162) (xy 181.713122 -282.854325)
			(xy 181.751243 -282.8232) (xy 181.793864 -282.798593) (xy 181.83988 -282.781141) (xy 181.888099 -282.771297)
			(xy 181.937274 -282.769316) (xy 181.986129 -282.775248) (xy 182.0334 -282.78894) (xy 182.077862 -282.810038)
			(xy 182.118365 -282.837994) (xy 182.153858 -282.872086) (xy 182.183423 -282.91143) (xy 182.206294 -282.955007)
			(xy 182.221878 -283.001688) (xy 182.229773 -283.050265) (xy 182.230268 -283.074872) (xy 182.569116 -283.074872)
			(xy 182.573076 -283.025818) (xy 182.584853 -282.978034) (xy 182.604144 -282.932758) (xy 182.630447 -282.891162)
			(xy 182.663082 -282.854325) (xy 182.701203 -282.8232) (xy 182.743824 -282.798593) (xy 182.78984 -282.781141)
			(xy 182.838059 -282.771297) (xy 182.887234 -282.769316) (xy 182.936089 -282.775248) (xy 182.98336 -282.78894)
			(xy 183.027822 -282.810038) (xy 183.068325 -282.837994) (xy 183.103818 -282.872086) (xy 183.133383 -282.91143)
			(xy 183.156254 -282.955007) (xy 183.171838 -283.001688) (xy 183.179733 -283.050265) (xy 183.180228 -283.074872)
			(xy 184.469036 -283.074872) (xy 184.472996 -283.025818) (xy 184.484773 -282.978034) (xy 184.504064 -282.932758)
			(xy 184.530367 -282.891162) (xy 184.563002 -282.854325) (xy 184.601123 -282.8232) (xy 184.643744 -282.798593)
			(xy 184.68976 -282.781141) (xy 184.737979 -282.771297) (xy 184.787154 -282.769316) (xy 184.836009 -282.775248)
			(xy 184.88328 -282.78894) (xy 184.927742 -282.810038) (xy 184.968245 -282.837994) (xy 185.003738 -282.872086)
			(xy 185.033303 -282.91143) (xy 185.056174 -282.955007) (xy 185.071758 -283.001688) (xy 185.079653 -283.050265)
			(xy 185.080148 -283.074872) (xy 185.41925 -283.074872) (xy 185.42321 -283.025818) (xy 185.434987 -282.978034)
			(xy 185.454278 -282.932758) (xy 185.480581 -282.891162) (xy 185.513216 -282.854325) (xy 185.551337 -282.8232)
			(xy 185.593958 -282.798593) (xy 185.639974 -282.781141) (xy 185.688193 -282.771297) (xy 185.737368 -282.769316)
			(xy 185.786223 -282.775248) (xy 185.833494 -282.78894) (xy 185.877956 -282.810038) (xy 185.918459 -282.837994)
			(xy 185.953952 -282.872086) (xy 185.983517 -282.91143) (xy 186.006388 -282.955007) (xy 186.021972 -283.001688)
			(xy 186.029867 -283.050265) (xy 186.030362 -283.074872) (xy 186.36921 -283.074872) (xy 186.37317 -283.025818)
			(xy 186.384947 -282.978034) (xy 186.404238 -282.932758) (xy 186.430541 -282.891162) (xy 186.463176 -282.854325)
			(xy 186.501297 -282.8232) (xy 186.543918 -282.798593) (xy 186.589934 -282.781141) (xy 186.638153 -282.771297)
			(xy 186.687328 -282.769316) (xy 186.736183 -282.775248) (xy 186.783454 -282.78894) (xy 186.827916 -282.810038)
			(xy 186.868419 -282.837994) (xy 186.903912 -282.872086) (xy 186.933477 -282.91143) (xy 186.956348 -282.955007)
			(xy 186.971932 -283.001688) (xy 186.979827 -283.050265) (xy 186.980322 -283.074872) (xy 187.31917 -283.074872)
			(xy 187.32313 -283.025818) (xy 187.334907 -282.978034) (xy 187.354198 -282.932758) (xy 187.380501 -282.891162)
			(xy 187.413136 -282.854325) (xy 187.451257 -282.8232) (xy 187.493878 -282.798593) (xy 187.539894 -282.781141)
			(xy 187.588113 -282.771297) (xy 187.637288 -282.769316) (xy 187.686143 -282.775248) (xy 187.733414 -282.78894)
			(xy 187.777876 -282.810038) (xy 187.818379 -282.837994) (xy 187.853872 -282.872086) (xy 187.883437 -282.91143)
			(xy 187.906308 -282.955007) (xy 187.921892 -283.001688) (xy 187.929787 -283.050265) (xy 187.930282 -283.074872)
			(xy 188.26913 -283.074872) (xy 188.27309 -283.025818) (xy 188.284867 -282.978034) (xy 188.304158 -282.932758)
			(xy 188.330461 -282.891162) (xy 188.363096 -282.854325) (xy 188.401217 -282.8232) (xy 188.443838 -282.798593)
			(xy 188.489854 -282.781141) (xy 188.538073 -282.771297) (xy 188.587248 -282.769316) (xy 188.636103 -282.775248)
			(xy 188.683374 -282.78894) (xy 188.727836 -282.810038) (xy 188.768339 -282.837994) (xy 188.803832 -282.872086)
			(xy 188.833397 -282.91143) (xy 188.856268 -282.955007) (xy 188.871852 -283.001688) (xy 188.879747 -283.050265)
			(xy 188.880242 -283.074872) (xy 188.879747 -283.099479) (xy 188.871852 -283.148056) (xy 188.856268 -283.194737)
			(xy 188.833397 -283.238314) (xy 188.803832 -283.277658) (xy 188.768339 -283.31175) (xy 188.727836 -283.339706)
			(xy 188.683374 -283.360804) (xy 188.636103 -283.374496) (xy 188.587248 -283.380428) (xy 188.538073 -283.378447)
			(xy 188.489854 -283.368603) (xy 188.443838 -283.351151) (xy 188.401217 -283.326544) (xy 188.363096 -283.295419)
			(xy 188.330461 -283.258582) (xy 188.304158 -283.216986) (xy 188.284867 -283.17171) (xy 188.27309 -283.123926)
			(xy 188.26913 -283.074872) (xy 187.930282 -283.074872) (xy 187.929787 -283.099479) (xy 187.921892 -283.148056)
			(xy 187.906308 -283.194737) (xy 187.883437 -283.238314) (xy 187.853872 -283.277658) (xy 187.818379 -283.31175)
			(xy 187.777876 -283.339706) (xy 187.733414 -283.360804) (xy 187.686143 -283.374496) (xy 187.637288 -283.380428)
			(xy 187.588113 -283.378447) (xy 187.539894 -283.368603) (xy 187.493878 -283.351151) (xy 187.451257 -283.326544)
			(xy 187.413136 -283.295419) (xy 187.380501 -283.258582) (xy 187.354198 -283.216986) (xy 187.334907 -283.17171)
			(xy 187.32313 -283.123926) (xy 187.31917 -283.074872) (xy 186.980322 -283.074872) (xy 186.979827 -283.099479)
			(xy 186.971932 -283.148056) (xy 186.956348 -283.194737) (xy 186.933477 -283.238314) (xy 186.903912 -283.277658)
			(xy 186.868419 -283.31175) (xy 186.827916 -283.339706) (xy 186.783454 -283.360804) (xy 186.736183 -283.374496)
			(xy 186.687328 -283.380428) (xy 186.638153 -283.378447) (xy 186.589934 -283.368603) (xy 186.543918 -283.351151)
			(xy 186.501297 -283.326544) (xy 186.463176 -283.295419) (xy 186.430541 -283.258582) (xy 186.404238 -283.216986)
			(xy 186.384947 -283.17171) (xy 186.37317 -283.123926) (xy 186.36921 -283.074872) (xy 186.030362 -283.074872)
			(xy 186.029867 -283.099479) (xy 186.021972 -283.148056) (xy 186.006388 -283.194737) (xy 185.983517 -283.238314)
			(xy 185.953952 -283.277658) (xy 185.918459 -283.31175) (xy 185.877956 -283.339706) (xy 185.833494 -283.360804)
			(xy 185.786223 -283.374496) (xy 185.737368 -283.380428) (xy 185.688193 -283.378447) (xy 185.639974 -283.368603)
			(xy 185.593958 -283.351151) (xy 185.551337 -283.326544) (xy 185.513216 -283.295419) (xy 185.480581 -283.258582)
			(xy 185.454278 -283.216986) (xy 185.434987 -283.17171) (xy 185.42321 -283.123926) (xy 185.41925 -283.074872)
			(xy 185.080148 -283.074872) (xy 185.079653 -283.099479) (xy 185.071758 -283.148056) (xy 185.056174 -283.194737)
			(xy 185.033303 -283.238314) (xy 185.003738 -283.277658) (xy 184.968245 -283.31175) (xy 184.927742 -283.339706)
			(xy 184.88328 -283.360804) (xy 184.836009 -283.374496) (xy 184.787154 -283.380428) (xy 184.737979 -283.378447)
			(xy 184.68976 -283.368603) (xy 184.643744 -283.351151) (xy 184.601123 -283.326544) (xy 184.563002 -283.295419)
			(xy 184.530367 -283.258582) (xy 184.504064 -283.216986) (xy 184.484773 -283.17171) (xy 184.472996 -283.123926)
			(xy 184.469036 -283.074872) (xy 183.180228 -283.074872) (xy 183.179733 -283.099479) (xy 183.171838 -283.148056)
			(xy 183.156254 -283.194737) (xy 183.133383 -283.238314) (xy 183.103818 -283.277658) (xy 183.068325 -283.31175)
			(xy 183.027822 -283.339706) (xy 182.98336 -283.360804) (xy 182.936089 -283.374496) (xy 182.887234 -283.380428)
			(xy 182.838059 -283.378447) (xy 182.78984 -283.368603) (xy 182.743824 -283.351151) (xy 182.701203 -283.326544)
			(xy 182.663082 -283.295419) (xy 182.630447 -283.258582) (xy 182.604144 -283.216986) (xy 182.584853 -283.17171)
			(xy 182.573076 -283.123926) (xy 182.569116 -283.074872) (xy 182.230268 -283.074872) (xy 182.229773 -283.099479)
			(xy 182.221878 -283.148056) (xy 182.206294 -283.194737) (xy 182.183423 -283.238314) (xy 182.153858 -283.277658)
			(xy 182.118365 -283.31175) (xy 182.077862 -283.339706) (xy 182.0334 -283.360804) (xy 181.986129 -283.374496)
			(xy 181.937274 -283.380428) (xy 181.888099 -283.378447) (xy 181.83988 -283.368603) (xy 181.793864 -283.351151)
			(xy 181.751243 -283.326544) (xy 181.713122 -283.295419) (xy 181.680487 -283.258582) (xy 181.654184 -283.216986)
			(xy 181.634893 -283.17171) (xy 181.623116 -283.123926) (xy 181.619156 -283.074872) (xy 181.280308 -283.074872)
			(xy 181.279813 -283.099479) (xy 181.271918 -283.148056) (xy 181.256334 -283.194737) (xy 181.233463 -283.238314)
			(xy 181.203898 -283.277658) (xy 181.168405 -283.31175) (xy 181.127902 -283.339706) (xy 181.08344 -283.360804)
			(xy 181.036169 -283.374496) (xy 180.987314 -283.380428) (xy 180.938139 -283.378447) (xy 180.88992 -283.368603)
			(xy 180.843904 -283.351151) (xy 180.801283 -283.326544) (xy 180.763162 -283.295419) (xy 180.730527 -283.258582)
			(xy 180.704224 -283.216986) (xy 180.684933 -283.17171) (xy 180.673156 -283.123926) (xy 180.669196 -283.074872)
			(xy 180.330348 -283.074872) (xy 180.329853 -283.099479) (xy 180.321958 -283.148056) (xy 180.306374 -283.194737)
			(xy 180.283503 -283.238314) (xy 180.253938 -283.277658) (xy 180.218445 -283.31175) (xy 180.177942 -283.339706)
			(xy 180.13348 -283.360804) (xy 180.086209 -283.374496) (xy 180.037354 -283.380428) (xy 179.988179 -283.378447)
			(xy 179.93996 -283.368603) (xy 179.893944 -283.351151) (xy 179.851323 -283.326544) (xy 179.813202 -283.295419)
			(xy 179.780567 -283.258582) (xy 179.754264 -283.216986) (xy 179.734973 -283.17171) (xy 179.723196 -283.123926)
			(xy 179.719236 -283.074872) (xy 179.380388 -283.074872) (xy 179.379893 -283.099479) (xy 179.371998 -283.148056)
			(xy 179.356414 -283.194737) (xy 179.333543 -283.238314) (xy 179.303978 -283.277658) (xy 179.268485 -283.31175)
			(xy 179.227982 -283.339706) (xy 179.18352 -283.360804) (xy 179.136249 -283.374496) (xy 179.087394 -283.380428)
			(xy 179.038219 -283.378447) (xy 178.99 -283.368603) (xy 178.943984 -283.351151) (xy 178.901363 -283.326544)
			(xy 178.863242 -283.295419) (xy 178.830607 -283.258582) (xy 178.804304 -283.216986) (xy 178.785013 -283.17171)
			(xy 178.773236 -283.123926) (xy 178.769276 -283.074872) (xy 178.430174 -283.074872) (xy 178.429679 -283.099479)
			(xy 178.421784 -283.148056) (xy 178.4062 -283.194737) (xy 178.383329 -283.238314) (xy 178.353764 -283.277658)
			(xy 178.318271 -283.31175) (xy 178.277768 -283.339706) (xy 178.233306 -283.360804) (xy 178.186035 -283.374496)
			(xy 178.13718 -283.380428) (xy 178.088005 -283.378447) (xy 178.039786 -283.368603) (xy 177.99377 -283.351151)
			(xy 177.951149 -283.326544) (xy 177.913028 -283.295419) (xy 177.880393 -283.258582) (xy 177.85409 -283.216986)
			(xy 177.834799 -283.17171) (xy 177.823022 -283.123926) (xy 177.819062 -283.074872) (xy 177.480214 -283.074872)
			(xy 177.479719 -283.099479) (xy 177.471824 -283.148056) (xy 177.45624 -283.194737) (xy 177.433369 -283.238314)
			(xy 177.403804 -283.277658) (xy 177.368311 -283.31175) (xy 177.327808 -283.339706) (xy 177.283346 -283.360804)
			(xy 177.236075 -283.374496) (xy 177.18722 -283.380428) (xy 177.138045 -283.378447) (xy 177.089826 -283.368603)
			(xy 177.04381 -283.351151) (xy 177.001189 -283.326544) (xy 176.963068 -283.295419) (xy 176.930433 -283.258582)
			(xy 176.90413 -283.216986) (xy 176.884839 -283.17171) (xy 176.873062 -283.123926) (xy 176.869102 -283.074872)
			(xy 176.530254 -283.074872) (xy 176.529759 -283.099479) (xy 176.521864 -283.148056) (xy 176.50628 -283.194737)
			(xy 176.483409 -283.238314) (xy 176.453844 -283.277658) (xy 176.418351 -283.31175) (xy 176.377848 -283.339706)
			(xy 176.333386 -283.360804) (xy 176.286115 -283.374496) (xy 176.23726 -283.380428) (xy 176.188085 -283.378447)
			(xy 176.139866 -283.368603) (xy 176.09385 -283.351151) (xy 176.051229 -283.326544) (xy 176.013108 -283.295419)
			(xy 175.980473 -283.258582) (xy 175.95417 -283.216986) (xy 175.934879 -283.17171) (xy 175.923102 -283.123926)
			(xy 175.919142 -283.074872) (xy 174.630334 -283.074872) (xy 174.629839 -283.099479) (xy 174.621944 -283.148056)
			(xy 174.60636 -283.194737) (xy 174.583489 -283.238314) (xy 174.553924 -283.277658) (xy 174.518431 -283.31175)
			(xy 174.477928 -283.339706) (xy 174.433466 -283.360804) (xy 174.386195 -283.374496) (xy 174.33734 -283.380428)
			(xy 174.288165 -283.378447) (xy 174.239946 -283.368603) (xy 174.19393 -283.351151) (xy 174.151309 -283.326544)
			(xy 174.113188 -283.295419) (xy 174.080553 -283.258582) (xy 174.05425 -283.216986) (xy 174.034959 -283.17171)
			(xy 174.023182 -283.123926) (xy 174.019222 -283.074872) (xy 173.680374 -283.074872) (xy 173.679879 -283.099479)
			(xy 173.671984 -283.148056) (xy 173.6564 -283.194737) (xy 173.633529 -283.238314) (xy 173.603964 -283.277658)
			(xy 173.568471 -283.31175) (xy 173.527968 -283.339706) (xy 173.483506 -283.360804) (xy 173.436235 -283.374496)
			(xy 173.38738 -283.380428) (xy 173.338205 -283.378447) (xy 173.289986 -283.368603) (xy 173.24397 -283.351151)
			(xy 173.201349 -283.326544) (xy 173.163228 -283.295419) (xy 173.130593 -283.258582) (xy 173.10429 -283.216986)
			(xy 173.084999 -283.17171) (xy 173.073222 -283.123926) (xy 173.069262 -283.074872) (xy 172.730414 -283.074872)
			(xy 172.729919 -283.099479) (xy 172.722024 -283.148056) (xy 172.70644 -283.194737) (xy 172.683569 -283.238314)
			(xy 172.654004 -283.277658) (xy 172.618511 -283.31175) (xy 172.578008 -283.339706) (xy 172.533546 -283.360804)
			(xy 172.486275 -283.374496) (xy 172.43742 -283.380428) (xy 172.388245 -283.378447) (xy 172.340026 -283.368603)
			(xy 172.29401 -283.351151) (xy 172.251389 -283.326544) (xy 172.213268 -283.295419) (xy 172.180633 -283.258582)
			(xy 172.15433 -283.216986) (xy 172.135039 -283.17171) (xy 172.123262 -283.123926) (xy 172.119302 -283.074872)
			(xy 171.7802 -283.074872) (xy 171.779705 -283.099479) (xy 171.77181 -283.148056) (xy 171.756226 -283.194737)
			(xy 171.733355 -283.238314) (xy 171.70379 -283.277658) (xy 171.668297 -283.31175) (xy 171.627794 -283.339706)
			(xy 171.583332 -283.360804) (xy 171.536061 -283.374496) (xy 171.487206 -283.380428) (xy 171.438031 -283.378447)
			(xy 171.389812 -283.368603) (xy 171.343796 -283.351151) (xy 171.301175 -283.326544) (xy 171.263054 -283.295419)
			(xy 171.230419 -283.258582) (xy 171.204116 -283.216986) (xy 171.184825 -283.17171) (xy 171.173048 -283.123926)
			(xy 171.169088 -283.074872) (xy 170.83024 -283.074872) (xy 170.829745 -283.099479) (xy 170.82185 -283.148056)
			(xy 170.806266 -283.194737) (xy 170.783395 -283.238314) (xy 170.75383 -283.277658) (xy 170.718337 -283.31175)
			(xy 170.677834 -283.339706) (xy 170.633372 -283.360804) (xy 170.586101 -283.374496) (xy 170.537246 -283.380428)
			(xy 170.488071 -283.378447) (xy 170.439852 -283.368603) (xy 170.393836 -283.351151) (xy 170.351215 -283.326544)
			(xy 170.313094 -283.295419) (xy 170.280459 -283.258582) (xy 170.254156 -283.216986) (xy 170.234865 -283.17171)
			(xy 170.223088 -283.123926) (xy 170.219128 -283.074872) (xy 169.88028 -283.074872) (xy 169.879785 -283.099479)
			(xy 169.87189 -283.148056) (xy 169.856306 -283.194737) (xy 169.833435 -283.238314) (xy 169.80387 -283.277658)
			(xy 169.768377 -283.31175) (xy 169.727874 -283.339706) (xy 169.683412 -283.360804) (xy 169.636141 -283.374496)
			(xy 169.587286 -283.380428) (xy 169.538111 -283.378447) (xy 169.489892 -283.368603) (xy 169.443876 -283.351151)
			(xy 169.401255 -283.326544) (xy 169.363134 -283.295419) (xy 169.330499 -283.258582) (xy 169.304196 -283.216986)
			(xy 169.284905 -283.17171) (xy 169.273128 -283.123926) (xy 169.269168 -283.074872) (xy 168.93032 -283.074872)
			(xy 168.929825 -283.099479) (xy 168.92193 -283.148056) (xy 168.906346 -283.194737) (xy 168.883475 -283.238314)
			(xy 168.85391 -283.277658) (xy 168.818417 -283.31175) (xy 168.777914 -283.339706) (xy 168.733452 -283.360804)
			(xy 168.686181 -283.374496) (xy 168.637326 -283.380428) (xy 168.588151 -283.378447) (xy 168.539932 -283.368603)
			(xy 168.493916 -283.351151) (xy 168.451295 -283.326544) (xy 168.413174 -283.295419) (xy 168.380539 -283.258582)
			(xy 168.354236 -283.216986) (xy 168.334945 -283.17171) (xy 168.323168 -283.123926) (xy 168.319208 -283.074872)
			(xy 167.98036 -283.074872) (xy 167.979865 -283.099479) (xy 167.97197 -283.148056) (xy 167.956386 -283.194737)
			(xy 167.933515 -283.238314) (xy 167.90395 -283.277658) (xy 167.868457 -283.31175) (xy 167.827954 -283.339706)
			(xy 167.783492 -283.360804) (xy 167.736221 -283.374496) (xy 167.687366 -283.380428) (xy 167.638191 -283.378447)
			(xy 167.589972 -283.368603) (xy 167.543956 -283.351151) (xy 167.501335 -283.326544) (xy 167.463214 -283.295419)
			(xy 167.430579 -283.258582) (xy 167.404276 -283.216986) (xy 167.384985 -283.17171) (xy 167.373208 -283.123926)
			(xy 167.369248 -283.074872) (xy 167.0304 -283.074872) (xy 167.029905 -283.099479) (xy 167.02201 -283.148056)
			(xy 167.006426 -283.194737) (xy 166.983555 -283.238314) (xy 166.95399 -283.277658) (xy 166.918497 -283.31175)
			(xy 166.877994 -283.339706) (xy 166.833532 -283.360804) (xy 166.786261 -283.374496) (xy 166.737406 -283.380428)
			(xy 166.688231 -283.378447) (xy 166.640012 -283.368603) (xy 166.593996 -283.351151) (xy 166.551375 -283.326544)
			(xy 166.513254 -283.295419) (xy 166.480619 -283.258582) (xy 166.454316 -283.216986) (xy 166.435025 -283.17171)
			(xy 166.423248 -283.123926) (xy 166.419288 -283.074872) (xy 166.080186 -283.074872) (xy 166.079691 -283.099479)
			(xy 166.071796 -283.148056) (xy 166.056212 -283.194737) (xy 166.033341 -283.238314) (xy 166.003776 -283.277658)
			(xy 165.968283 -283.31175) (xy 165.92778 -283.339706) (xy 165.883318 -283.360804) (xy 165.836047 -283.374496)
			(xy 165.787192 -283.380428) (xy 165.738017 -283.378447) (xy 165.689798 -283.368603) (xy 165.643782 -283.351151)
			(xy 165.601161 -283.326544) (xy 165.56304 -283.295419) (xy 165.530405 -283.258582) (xy 165.504102 -283.216986)
			(xy 165.484811 -283.17171) (xy 165.473034 -283.123926) (xy 165.469074 -283.074872) (xy 165.130226 -283.074872)
			(xy 165.129731 -283.099479) (xy 165.121836 -283.148056) (xy 165.106252 -283.194737) (xy 165.083381 -283.238314)
			(xy 165.053816 -283.277658) (xy 165.018323 -283.31175) (xy 164.97782 -283.339706) (xy 164.933358 -283.360804)
			(xy 164.886087 -283.374496) (xy 164.837232 -283.380428) (xy 164.788057 -283.378447) (xy 164.739838 -283.368603)
			(xy 164.693822 -283.351151) (xy 164.651201 -283.326544) (xy 164.61308 -283.295419) (xy 164.580445 -283.258582)
			(xy 164.554142 -283.216986) (xy 164.534851 -283.17171) (xy 164.523074 -283.123926) (xy 164.519114 -283.074872)
			(xy 164.180266 -283.074872) (xy 164.179771 -283.099479) (xy 164.171876 -283.148056) (xy 164.156292 -283.194737)
			(xy 164.133421 -283.238314) (xy 164.103856 -283.277658) (xy 164.068363 -283.31175) (xy 164.02786 -283.339706)
			(xy 163.983398 -283.360804) (xy 163.936127 -283.374496) (xy 163.887272 -283.380428) (xy 163.838097 -283.378447)
			(xy 163.789878 -283.368603) (xy 163.743862 -283.351151) (xy 163.701241 -283.326544) (xy 163.66312 -283.295419)
			(xy 163.630485 -283.258582) (xy 163.604182 -283.216986) (xy 163.584891 -283.17171) (xy 163.573114 -283.123926)
			(xy 163.569154 -283.074872) (xy 163.230306 -283.074872) (xy 163.229811 -283.099479) (xy 163.221916 -283.148056)
			(xy 163.206332 -283.194737) (xy 163.183461 -283.238314) (xy 163.153896 -283.277658) (xy 163.118403 -283.31175)
			(xy 163.0779 -283.339706) (xy 163.033438 -283.360804) (xy 162.986167 -283.374496) (xy 162.937312 -283.380428)
			(xy 162.888137 -283.378447) (xy 162.839918 -283.368603) (xy 162.793902 -283.351151) (xy 162.751281 -283.326544)
			(xy 162.71316 -283.295419) (xy 162.680525 -283.258582) (xy 162.654222 -283.216986) (xy 162.634931 -283.17171)
			(xy 162.623154 -283.123926) (xy 162.619194 -283.074872) (xy 162.280346 -283.074872) (xy 162.279851 -283.099479)
			(xy 162.271956 -283.148056) (xy 162.256372 -283.194737) (xy 162.233501 -283.238314) (xy 162.203936 -283.277658)
			(xy 162.168443 -283.31175) (xy 162.12794 -283.339706) (xy 162.083478 -283.360804) (xy 162.036207 -283.374496)
			(xy 161.987352 -283.380428) (xy 161.938177 -283.378447) (xy 161.889958 -283.368603) (xy 161.843942 -283.351151)
			(xy 161.801321 -283.326544) (xy 161.7632 -283.295419) (xy 161.730565 -283.258582) (xy 161.704262 -283.216986)
			(xy 161.684971 -283.17171) (xy 161.673194 -283.123926) (xy 161.669234 -283.074872) (xy 161.330386 -283.074872)
			(xy 161.329891 -283.099479) (xy 161.321996 -283.148056) (xy 161.306412 -283.194737) (xy 161.283541 -283.238314)
			(xy 161.253976 -283.277658) (xy 161.218483 -283.31175) (xy 161.17798 -283.339706) (xy 161.133518 -283.360804)
			(xy 161.086247 -283.374496) (xy 161.037392 -283.380428) (xy 160.988217 -283.378447) (xy 160.939998 -283.368603)
			(xy 160.893982 -283.351151) (xy 160.851361 -283.326544) (xy 160.81324 -283.295419) (xy 160.780605 -283.258582)
			(xy 160.754302 -283.216986) (xy 160.735011 -283.17171) (xy 160.723234 -283.123926) (xy 160.719274 -283.074872)
			(xy 160.380172 -283.074872) (xy 160.379677 -283.099479) (xy 160.371782 -283.148056) (xy 160.356198 -283.194737)
			(xy 160.333327 -283.238314) (xy 160.303762 -283.277658) (xy 160.268269 -283.31175) (xy 160.227766 -283.339706)
			(xy 160.183304 -283.360804) (xy 160.136033 -283.374496) (xy 160.087178 -283.380428) (xy 160.038003 -283.378447)
			(xy 159.989784 -283.368603) (xy 159.943768 -283.351151) (xy 159.901147 -283.326544) (xy 159.863026 -283.295419)
			(xy 159.830391 -283.258582) (xy 159.804088 -283.216986) (xy 159.784797 -283.17171) (xy 159.77302 -283.123926)
			(xy 159.76906 -283.074872) (xy 159.430212 -283.074872) (xy 159.429717 -283.099479) (xy 159.421822 -283.148056)
			(xy 159.406238 -283.194737) (xy 159.383367 -283.238314) (xy 159.353802 -283.277658) (xy 159.318309 -283.31175)
			(xy 159.277806 -283.339706) (xy 159.233344 -283.360804) (xy 159.186073 -283.374496) (xy 159.137218 -283.380428)
			(xy 159.088043 -283.378447) (xy 159.039824 -283.368603) (xy 158.993808 -283.351151) (xy 158.951187 -283.326544)
			(xy 158.913066 -283.295419) (xy 158.880431 -283.258582) (xy 158.854128 -283.216986) (xy 158.834837 -283.17171)
			(xy 158.82306 -283.123926) (xy 158.8191 -283.074872) (xy 158.480252 -283.074872) (xy 158.479757 -283.099479)
			(xy 158.471862 -283.148056) (xy 158.456278 -283.194737) (xy 158.433407 -283.238314) (xy 158.403842 -283.277658)
			(xy 158.368349 -283.31175) (xy 158.327846 -283.339706) (xy 158.283384 -283.360804) (xy 158.236113 -283.374496)
			(xy 158.187258 -283.380428) (xy 158.138083 -283.378447) (xy 158.089864 -283.368603) (xy 158.043848 -283.351151)
			(xy 158.001227 -283.326544) (xy 157.963106 -283.295419) (xy 157.930471 -283.258582) (xy 157.904168 -283.216986)
			(xy 157.884877 -283.17171) (xy 157.8731 -283.123926) (xy 157.86914 -283.074872) (xy 157.530292 -283.074872)
			(xy 157.529797 -283.099479) (xy 157.521902 -283.148056) (xy 157.506318 -283.194737) (xy 157.483447 -283.238314)
			(xy 157.453882 -283.277658) (xy 157.418389 -283.31175) (xy 157.377886 -283.339706) (xy 157.333424 -283.360804)
			(xy 157.286153 -283.374496) (xy 157.237298 -283.380428) (xy 157.188123 -283.378447) (xy 157.139904 -283.368603)
			(xy 157.093888 -283.351151) (xy 157.051267 -283.326544) (xy 157.013146 -283.295419) (xy 156.980511 -283.258582)
			(xy 156.954208 -283.216986) (xy 156.934917 -283.17171) (xy 156.92314 -283.123926) (xy 156.91918 -283.074872)
			(xy 156.580332 -283.074872) (xy 156.579837 -283.099479) (xy 156.571942 -283.148056) (xy 156.556358 -283.194737)
			(xy 156.533487 -283.238314) (xy 156.503922 -283.277658) (xy 156.468429 -283.31175) (xy 156.427926 -283.339706)
			(xy 156.383464 -283.360804) (xy 156.336193 -283.374496) (xy 156.287338 -283.380428) (xy 156.238163 -283.378447)
			(xy 156.189944 -283.368603) (xy 156.143928 -283.351151) (xy 156.101307 -283.326544) (xy 156.063186 -283.295419)
			(xy 156.030551 -283.258582) (xy 156.004248 -283.216986) (xy 155.984957 -283.17171) (xy 155.97318 -283.123926)
			(xy 155.96922 -283.074872) (xy 155.630372 -283.074872) (xy 155.629877 -283.099479) (xy 155.621982 -283.148056)
			(xy 155.606398 -283.194737) (xy 155.583527 -283.238314) (xy 155.553962 -283.277658) (xy 155.518469 -283.31175)
			(xy 155.477966 -283.339706) (xy 155.433504 -283.360804) (xy 155.386233 -283.374496) (xy 155.337378 -283.380428)
			(xy 155.288203 -283.378447) (xy 155.239984 -283.368603) (xy 155.193968 -283.351151) (xy 155.151347 -283.326544)
			(xy 155.113226 -283.295419) (xy 155.080591 -283.258582) (xy 155.054288 -283.216986) (xy 155.034997 -283.17171)
			(xy 155.02322 -283.123926) (xy 155.01926 -283.074872) (xy 154.680412 -283.074872) (xy 154.679917 -283.099479)
			(xy 154.672022 -283.148056) (xy 154.656438 -283.194737) (xy 154.633567 -283.238314) (xy 154.604002 -283.277658)
			(xy 154.568509 -283.31175) (xy 154.528006 -283.339706) (xy 154.483544 -283.360804) (xy 154.436273 -283.374496)
			(xy 154.387418 -283.380428) (xy 154.338243 -283.378447) (xy 154.290024 -283.368603) (xy 154.244008 -283.351151)
			(xy 154.201387 -283.326544) (xy 154.163266 -283.295419) (xy 154.130631 -283.258582) (xy 154.104328 -283.216986)
			(xy 154.085037 -283.17171) (xy 154.07326 -283.123926) (xy 154.0693 -283.074872) (xy 153.755598 -283.074872)
			(xy 153.755117 -283.100862) (xy 153.746989 -283.152204) (xy 153.730929 -283.201641) (xy 153.707333 -283.247958)
			(xy 153.676781 -283.290012) (xy 153.640026 -283.326769) (xy 153.597973 -283.357323) (xy 153.551658 -283.380922)
			(xy 153.502221 -283.396985) (xy 153.45088 -283.405116) (xy 153.42489 -283.40558) (xy 153.424128 -283.40558)
			(xy 153.396815 -283.404979) (xy 153.342945 -283.395918) (xy 153.31694 -283.387546) (xy 153.316432 -283.387546)
			(xy 153.316178 -283.387292) (xy 153.307104 -283.384683) (xy 153.28826 -283.385625) (xy 153.271032 -283.393318)
			(xy 153.264108 -283.399738) (xy 152.802336 -283.86151) (xy 152.798811 -283.865238) (xy 152.793176 -283.87381)
			(xy 152.79116 -283.878528) (xy 152.787604 -283.887164) (xy 152.787604 -283.909262) (xy 152.788112 -283.912818)
			(xy 152.789382 -283.92247) (xy 152.790652 -283.926534) (xy 152.79763 -283.950378) (xy 152.805155 -283.999485)
			(xy 152.805638 -284.024324) (xy 152.805638 -284.024832) (xy 153.119086 -284.024832) (xy 153.123046 -283.975778)
			(xy 153.134823 -283.927994) (xy 153.154114 -283.882718) (xy 153.180417 -283.841122) (xy 153.213052 -283.804285)
			(xy 153.251173 -283.77316) (xy 153.293794 -283.748553) (xy 153.33981 -283.731101) (xy 153.388029 -283.721257)
			(xy 153.437204 -283.719276) (xy 153.486059 -283.725208) (xy 153.53333 -283.7389) (xy 153.577792 -283.759998)
			(xy 153.618295 -283.787954) (xy 153.653788 -283.822046) (xy 153.683353 -283.86139) (xy 153.706224 -283.904967)
			(xy 153.721808 -283.951648) (xy 153.729703 -284.000225) (xy 153.730198 -284.024832) (xy 154.0693 -284.024832)
			(xy 154.07326 -283.975778) (xy 154.085037 -283.927994) (xy 154.104328 -283.882718) (xy 154.130631 -283.841122)
			(xy 154.163266 -283.804285) (xy 154.201387 -283.77316) (xy 154.244008 -283.748553) (xy 154.290024 -283.731101)
			(xy 154.338243 -283.721257) (xy 154.387418 -283.719276) (xy 154.436273 -283.725208) (xy 154.483544 -283.7389)
			(xy 154.528006 -283.759998) (xy 154.568509 -283.787954) (xy 154.604002 -283.822046) (xy 154.633567 -283.86139)
			(xy 154.656438 -283.904967) (xy 154.672022 -283.951648) (xy 154.679917 -284.000225) (xy 154.680412 -284.024832)
			(xy 155.01926 -284.024832) (xy 155.02322 -283.975778) (xy 155.034997 -283.927994) (xy 155.054288 -283.882718)
			(xy 155.080591 -283.841122) (xy 155.113226 -283.804285) (xy 155.151347 -283.77316) (xy 155.193968 -283.748553)
			(xy 155.239984 -283.731101) (xy 155.288203 -283.721257) (xy 155.337378 -283.719276) (xy 155.386233 -283.725208)
			(xy 155.433504 -283.7389) (xy 155.477966 -283.759998) (xy 155.518469 -283.787954) (xy 155.553962 -283.822046)
			(xy 155.583527 -283.86139) (xy 155.606398 -283.904967) (xy 155.621982 -283.951648) (xy 155.629877 -284.000225)
			(xy 155.630372 -284.024832) (xy 155.96922 -284.024832) (xy 155.97318 -283.975778) (xy 155.984957 -283.927994)
			(xy 156.004248 -283.882718) (xy 156.030551 -283.841122) (xy 156.063186 -283.804285) (xy 156.101307 -283.77316)
			(xy 156.143928 -283.748553) (xy 156.189944 -283.731101) (xy 156.238163 -283.721257) (xy 156.287338 -283.719276)
			(xy 156.336193 -283.725208) (xy 156.383464 -283.7389) (xy 156.427926 -283.759998) (xy 156.468429 -283.787954)
			(xy 156.503922 -283.822046) (xy 156.533487 -283.86139) (xy 156.556358 -283.904967) (xy 156.571942 -283.951648)
			(xy 156.579837 -284.000225) (xy 156.580332 -284.024832) (xy 156.91918 -284.024832) (xy 156.92314 -283.975778)
			(xy 156.934917 -283.927994) (xy 156.954208 -283.882718) (xy 156.980511 -283.841122) (xy 157.013146 -283.804285)
			(xy 157.051267 -283.77316) (xy 157.093888 -283.748553) (xy 157.139904 -283.731101) (xy 157.188123 -283.721257)
			(xy 157.237298 -283.719276) (xy 157.286153 -283.725208) (xy 157.333424 -283.7389) (xy 157.377886 -283.759998)
			(xy 157.418389 -283.787954) (xy 157.453882 -283.822046) (xy 157.483447 -283.86139) (xy 157.506318 -283.904967)
			(xy 157.521902 -283.951648) (xy 157.529797 -284.000225) (xy 157.530292 -284.024832) (xy 157.86914 -284.024832)
			(xy 157.8731 -283.975778) (xy 157.884877 -283.927994) (xy 157.904168 -283.882718) (xy 157.930471 -283.841122)
			(xy 157.963106 -283.804285) (xy 158.001227 -283.77316) (xy 158.043848 -283.748553) (xy 158.089864 -283.731101)
			(xy 158.138083 -283.721257) (xy 158.187258 -283.719276) (xy 158.236113 -283.725208) (xy 158.283384 -283.7389)
			(xy 158.327846 -283.759998) (xy 158.368349 -283.787954) (xy 158.403842 -283.822046) (xy 158.433407 -283.86139)
			(xy 158.456278 -283.904967) (xy 158.471862 -283.951648) (xy 158.479757 -284.000225) (xy 158.480252 -284.024832)
			(xy 158.8191 -284.024832) (xy 158.82306 -283.975778) (xy 158.834837 -283.927994) (xy 158.854128 -283.882718)
			(xy 158.880431 -283.841122) (xy 158.913066 -283.804285) (xy 158.951187 -283.77316) (xy 158.993808 -283.748553)
			(xy 159.039824 -283.731101) (xy 159.088043 -283.721257) (xy 159.137218 -283.719276) (xy 159.186073 -283.725208)
			(xy 159.233344 -283.7389) (xy 159.277806 -283.759998) (xy 159.318309 -283.787954) (xy 159.353802 -283.822046)
			(xy 159.383367 -283.86139) (xy 159.406238 -283.904967) (xy 159.421822 -283.951648) (xy 159.429717 -284.000225)
			(xy 159.430212 -284.024832) (xy 159.76906 -284.024832) (xy 159.77302 -283.975778) (xy 159.784797 -283.927994)
			(xy 159.804088 -283.882718) (xy 159.830391 -283.841122) (xy 159.863026 -283.804285) (xy 159.901147 -283.77316)
			(xy 159.943768 -283.748553) (xy 159.989784 -283.731101) (xy 160.038003 -283.721257) (xy 160.087178 -283.719276)
			(xy 160.136033 -283.725208) (xy 160.183304 -283.7389) (xy 160.227766 -283.759998) (xy 160.268269 -283.787954)
			(xy 160.303762 -283.822046) (xy 160.333327 -283.86139) (xy 160.356198 -283.904967) (xy 160.371782 -283.951648)
			(xy 160.379677 -284.000225) (xy 160.380172 -284.024832) (xy 160.719274 -284.024832) (xy 160.723234 -283.975778)
			(xy 160.735011 -283.927994) (xy 160.754302 -283.882718) (xy 160.780605 -283.841122) (xy 160.81324 -283.804285)
			(xy 160.851361 -283.77316) (xy 160.893982 -283.748553) (xy 160.939998 -283.731101) (xy 160.988217 -283.721257)
			(xy 161.037392 -283.719276) (xy 161.086247 -283.725208) (xy 161.133518 -283.7389) (xy 161.17798 -283.759998)
			(xy 161.218483 -283.787954) (xy 161.253976 -283.822046) (xy 161.283541 -283.86139) (xy 161.306412 -283.904967)
			(xy 161.321996 -283.951648) (xy 161.329891 -284.000225) (xy 161.330386 -284.024832) (xy 161.669234 -284.024832)
			(xy 161.673194 -283.975778) (xy 161.684971 -283.927994) (xy 161.704262 -283.882718) (xy 161.730565 -283.841122)
			(xy 161.7632 -283.804285) (xy 161.801321 -283.77316) (xy 161.843942 -283.748553) (xy 161.889958 -283.731101)
			(xy 161.938177 -283.721257) (xy 161.987352 -283.719276) (xy 162.036207 -283.725208) (xy 162.083478 -283.7389)
			(xy 162.12794 -283.759998) (xy 162.168443 -283.787954) (xy 162.203936 -283.822046) (xy 162.233501 -283.86139)
			(xy 162.256372 -283.904967) (xy 162.271956 -283.951648) (xy 162.279851 -284.000225) (xy 162.280346 -284.024832)
			(xy 162.619194 -284.024832) (xy 162.623154 -283.975778) (xy 162.634931 -283.927994) (xy 162.654222 -283.882718)
			(xy 162.680525 -283.841122) (xy 162.71316 -283.804285) (xy 162.751281 -283.77316) (xy 162.793902 -283.748553)
			(xy 162.839918 -283.731101) (xy 162.888137 -283.721257) (xy 162.937312 -283.719276) (xy 162.986167 -283.725208)
			(xy 163.033438 -283.7389) (xy 163.0779 -283.759998) (xy 163.118403 -283.787954) (xy 163.153896 -283.822046)
			(xy 163.183461 -283.86139) (xy 163.206332 -283.904967) (xy 163.221916 -283.951648) (xy 163.229811 -284.000225)
			(xy 163.230306 -284.024832) (xy 163.569154 -284.024832) (xy 163.573114 -283.975778) (xy 163.584891 -283.927994)
			(xy 163.604182 -283.882718) (xy 163.630485 -283.841122) (xy 163.66312 -283.804285) (xy 163.701241 -283.77316)
			(xy 163.743862 -283.748553) (xy 163.789878 -283.731101) (xy 163.838097 -283.721257) (xy 163.887272 -283.719276)
			(xy 163.936127 -283.725208) (xy 163.983398 -283.7389) (xy 164.02786 -283.759998) (xy 164.068363 -283.787954)
			(xy 164.103856 -283.822046) (xy 164.133421 -283.86139) (xy 164.156292 -283.904967) (xy 164.171876 -283.951648)
			(xy 164.179771 -284.000225) (xy 164.180266 -284.024832) (xy 164.519114 -284.024832) (xy 164.523074 -283.975778)
			(xy 164.534851 -283.927994) (xy 164.554142 -283.882718) (xy 164.580445 -283.841122) (xy 164.61308 -283.804285)
			(xy 164.651201 -283.77316) (xy 164.693822 -283.748553) (xy 164.739838 -283.731101) (xy 164.788057 -283.721257)
			(xy 164.837232 -283.719276) (xy 164.886087 -283.725208) (xy 164.933358 -283.7389) (xy 164.97782 -283.759998)
			(xy 165.018323 -283.787954) (xy 165.053816 -283.822046) (xy 165.083381 -283.86139) (xy 165.106252 -283.904967)
			(xy 165.121836 -283.951648) (xy 165.129731 -284.000225) (xy 165.130226 -284.024832) (xy 165.469074 -284.024832)
			(xy 165.473034 -283.975778) (xy 165.484811 -283.927994) (xy 165.504102 -283.882718) (xy 165.530405 -283.841122)
			(xy 165.56304 -283.804285) (xy 165.601161 -283.77316) (xy 165.643782 -283.748553) (xy 165.689798 -283.731101)
			(xy 165.738017 -283.721257) (xy 165.787192 -283.719276) (xy 165.836047 -283.725208) (xy 165.883318 -283.7389)
			(xy 165.92778 -283.759998) (xy 165.968283 -283.787954) (xy 166.003776 -283.822046) (xy 166.033341 -283.86139)
			(xy 166.056212 -283.904967) (xy 166.071796 -283.951648) (xy 166.079691 -284.000225) (xy 166.080186 -284.024832)
			(xy 166.419288 -284.024832) (xy 166.423248 -283.975778) (xy 166.435025 -283.927994) (xy 166.454316 -283.882718)
			(xy 166.480619 -283.841122) (xy 166.513254 -283.804285) (xy 166.551375 -283.77316) (xy 166.593996 -283.748553)
			(xy 166.640012 -283.731101) (xy 166.688231 -283.721257) (xy 166.737406 -283.719276) (xy 166.786261 -283.725208)
			(xy 166.833532 -283.7389) (xy 166.877994 -283.759998) (xy 166.918497 -283.787954) (xy 166.95399 -283.822046)
			(xy 166.983555 -283.86139) (xy 167.006426 -283.904967) (xy 167.02201 -283.951648) (xy 167.029905 -284.000225)
			(xy 167.0304 -284.024832) (xy 167.369248 -284.024832) (xy 167.373208 -283.975778) (xy 167.384985 -283.927994)
			(xy 167.404276 -283.882718) (xy 167.430579 -283.841122) (xy 167.463214 -283.804285) (xy 167.501335 -283.77316)
			(xy 167.543956 -283.748553) (xy 167.589972 -283.731101) (xy 167.638191 -283.721257) (xy 167.687366 -283.719276)
			(xy 167.736221 -283.725208) (xy 167.783492 -283.7389) (xy 167.827954 -283.759998) (xy 167.868457 -283.787954)
			(xy 167.90395 -283.822046) (xy 167.933515 -283.86139) (xy 167.956386 -283.904967) (xy 167.97197 -283.951648)
			(xy 167.979865 -284.000225) (xy 167.98036 -284.024832) (xy 168.319208 -284.024832) (xy 168.323168 -283.975778)
			(xy 168.334945 -283.927994) (xy 168.354236 -283.882718) (xy 168.380539 -283.841122) (xy 168.413174 -283.804285)
			(xy 168.451295 -283.77316) (xy 168.493916 -283.748553) (xy 168.539932 -283.731101) (xy 168.588151 -283.721257)
			(xy 168.637326 -283.719276) (xy 168.686181 -283.725208) (xy 168.733452 -283.7389) (xy 168.777914 -283.759998)
			(xy 168.818417 -283.787954) (xy 168.85391 -283.822046) (xy 168.883475 -283.86139) (xy 168.906346 -283.904967)
			(xy 168.92193 -283.951648) (xy 168.929825 -284.000225) (xy 168.93032 -284.024832) (xy 169.269168 -284.024832)
			(xy 169.273128 -283.975778) (xy 169.284905 -283.927994) (xy 169.304196 -283.882718) (xy 169.330499 -283.841122)
			(xy 169.363134 -283.804285) (xy 169.401255 -283.77316) (xy 169.443876 -283.748553) (xy 169.489892 -283.731101)
			(xy 169.538111 -283.721257) (xy 169.587286 -283.719276) (xy 169.636141 -283.725208) (xy 169.683412 -283.7389)
			(xy 169.727874 -283.759998) (xy 169.768377 -283.787954) (xy 169.80387 -283.822046) (xy 169.833435 -283.86139)
			(xy 169.856306 -283.904967) (xy 169.87189 -283.951648) (xy 169.879785 -284.000225) (xy 169.88028 -284.024832)
			(xy 170.219128 -284.024832) (xy 170.223088 -283.975778) (xy 170.234865 -283.927994) (xy 170.254156 -283.882718)
			(xy 170.280459 -283.841122) (xy 170.313094 -283.804285) (xy 170.351215 -283.77316) (xy 170.393836 -283.748553)
			(xy 170.439852 -283.731101) (xy 170.488071 -283.721257) (xy 170.537246 -283.719276) (xy 170.586101 -283.725208)
			(xy 170.633372 -283.7389) (xy 170.677834 -283.759998) (xy 170.718337 -283.787954) (xy 170.75383 -283.822046)
			(xy 170.783395 -283.86139) (xy 170.806266 -283.904967) (xy 170.82185 -283.951648) (xy 170.829745 -284.000225)
			(xy 170.83024 -284.024832) (xy 171.169088 -284.024832) (xy 171.173048 -283.975778) (xy 171.184825 -283.927994)
			(xy 171.204116 -283.882718) (xy 171.230419 -283.841122) (xy 171.263054 -283.804285) (xy 171.301175 -283.77316)
			(xy 171.343796 -283.748553) (xy 171.389812 -283.731101) (xy 171.438031 -283.721257) (xy 171.487206 -283.719276)
			(xy 171.536061 -283.725208) (xy 171.583332 -283.7389) (xy 171.627794 -283.759998) (xy 171.668297 -283.787954)
			(xy 171.70379 -283.822046) (xy 171.733355 -283.86139) (xy 171.756226 -283.904967) (xy 171.77181 -283.951648)
			(xy 171.779705 -284.000225) (xy 171.7802 -284.024832) (xy 172.119048 -284.024832) (xy 172.123008 -283.975778)
			(xy 172.134785 -283.927994) (xy 172.154076 -283.882718) (xy 172.180379 -283.841122) (xy 172.213014 -283.804285)
			(xy 172.251135 -283.77316) (xy 172.293756 -283.748553) (xy 172.339772 -283.731101) (xy 172.387991 -283.721257)
			(xy 172.437166 -283.719276) (xy 172.486021 -283.725208) (xy 172.533292 -283.7389) (xy 172.577754 -283.759998)
			(xy 172.618257 -283.787954) (xy 172.65375 -283.822046) (xy 172.683315 -283.86139) (xy 172.706186 -283.904967)
			(xy 172.72177 -283.951648) (xy 172.729665 -284.000225) (xy 172.73016 -284.024832) (xy 173.069262 -284.024832)
			(xy 173.073222 -283.975778) (xy 173.084999 -283.927994) (xy 173.10429 -283.882718) (xy 173.130593 -283.841122)
			(xy 173.163228 -283.804285) (xy 173.201349 -283.77316) (xy 173.24397 -283.748553) (xy 173.289986 -283.731101)
			(xy 173.338205 -283.721257) (xy 173.38738 -283.719276) (xy 173.436235 -283.725208) (xy 173.483506 -283.7389)
			(xy 173.527968 -283.759998) (xy 173.568471 -283.787954) (xy 173.603964 -283.822046) (xy 173.633529 -283.86139)
			(xy 173.6564 -283.904967) (xy 173.671984 -283.951648) (xy 173.679879 -284.000225) (xy 173.680374 -284.024832)
			(xy 174.019222 -284.024832) (xy 174.023182 -283.975778) (xy 174.034959 -283.927994) (xy 174.05425 -283.882718)
			(xy 174.080553 -283.841122) (xy 174.113188 -283.804285) (xy 174.151309 -283.77316) (xy 174.19393 -283.748553)
			(xy 174.239946 -283.731101) (xy 174.288165 -283.721257) (xy 174.33734 -283.719276) (xy 174.386195 -283.725208)
			(xy 174.433466 -283.7389) (xy 174.477928 -283.759998) (xy 174.518431 -283.787954) (xy 174.553924 -283.822046)
			(xy 174.583489 -283.86139) (xy 174.60636 -283.904967) (xy 174.621944 -283.951648) (xy 174.629839 -284.000225)
			(xy 174.630334 -284.024832) (xy 175.919142 -284.024832) (xy 175.923102 -283.975778) (xy 175.934879 -283.927994)
			(xy 175.95417 -283.882718) (xy 175.980473 -283.841122) (xy 176.013108 -283.804285) (xy 176.051229 -283.77316)
			(xy 176.09385 -283.748553) (xy 176.139866 -283.731101) (xy 176.188085 -283.721257) (xy 176.23726 -283.719276)
			(xy 176.286115 -283.725208) (xy 176.333386 -283.7389) (xy 176.377848 -283.759998) (xy 176.418351 -283.787954)
			(xy 176.453844 -283.822046) (xy 176.483409 -283.86139) (xy 176.50628 -283.904967) (xy 176.521864 -283.951648)
			(xy 176.529759 -284.000225) (xy 176.530254 -284.024832) (xy 176.869102 -284.024832) (xy 176.873062 -283.975778)
			(xy 176.884839 -283.927994) (xy 176.90413 -283.882718) (xy 176.930433 -283.841122) (xy 176.963068 -283.804285)
			(xy 177.001189 -283.77316) (xy 177.04381 -283.748553) (xy 177.089826 -283.731101) (xy 177.138045 -283.721257)
			(xy 177.18722 -283.719276) (xy 177.236075 -283.725208) (xy 177.283346 -283.7389) (xy 177.327808 -283.759998)
			(xy 177.368311 -283.787954) (xy 177.403804 -283.822046) (xy 177.433369 -283.86139) (xy 177.45624 -283.904967)
			(xy 177.471824 -283.951648) (xy 177.479719 -284.000225) (xy 177.480214 -284.024832) (xy 177.819062 -284.024832)
			(xy 177.823022 -283.975778) (xy 177.834799 -283.927994) (xy 177.85409 -283.882718) (xy 177.880393 -283.841122)
			(xy 177.913028 -283.804285) (xy 177.951149 -283.77316) (xy 177.99377 -283.748553) (xy 178.039786 -283.731101)
			(xy 178.088005 -283.721257) (xy 178.13718 -283.719276) (xy 178.186035 -283.725208) (xy 178.233306 -283.7389)
			(xy 178.277768 -283.759998) (xy 178.318271 -283.787954) (xy 178.353764 -283.822046) (xy 178.383329 -283.86139)
			(xy 178.4062 -283.904967) (xy 178.421784 -283.951648) (xy 178.429679 -284.000225) (xy 178.430174 -284.024832)
			(xy 178.769276 -284.024832) (xy 178.773236 -283.975778) (xy 178.785013 -283.927994) (xy 178.804304 -283.882718)
			(xy 178.830607 -283.841122) (xy 178.863242 -283.804285) (xy 178.901363 -283.77316) (xy 178.943984 -283.748553)
			(xy 178.99 -283.731101) (xy 179.038219 -283.721257) (xy 179.087394 -283.719276) (xy 179.136249 -283.725208)
			(xy 179.18352 -283.7389) (xy 179.227982 -283.759998) (xy 179.268485 -283.787954) (xy 179.303978 -283.822046)
			(xy 179.333543 -283.86139) (xy 179.356414 -283.904967) (xy 179.371998 -283.951648) (xy 179.379893 -284.000225)
			(xy 179.380388 -284.024832) (xy 179.719236 -284.024832) (xy 179.723196 -283.975778) (xy 179.734973 -283.927994)
			(xy 179.754264 -283.882718) (xy 179.780567 -283.841122) (xy 179.813202 -283.804285) (xy 179.851323 -283.77316)
			(xy 179.893944 -283.748553) (xy 179.93996 -283.731101) (xy 179.988179 -283.721257) (xy 180.037354 -283.719276)
			(xy 180.086209 -283.725208) (xy 180.13348 -283.7389) (xy 180.177942 -283.759998) (xy 180.218445 -283.787954)
			(xy 180.253938 -283.822046) (xy 180.283503 -283.86139) (xy 180.306374 -283.904967) (xy 180.321958 -283.951648)
			(xy 180.329853 -284.000225) (xy 180.330348 -284.024832) (xy 180.669196 -284.024832) (xy 180.673156 -283.975778)
			(xy 180.684933 -283.927994) (xy 180.704224 -283.882718) (xy 180.730527 -283.841122) (xy 180.763162 -283.804285)
			(xy 180.801283 -283.77316) (xy 180.843904 -283.748553) (xy 180.88992 -283.731101) (xy 180.938139 -283.721257)
			(xy 180.987314 -283.719276) (xy 181.036169 -283.725208) (xy 181.08344 -283.7389) (xy 181.127902 -283.759998)
			(xy 181.168405 -283.787954) (xy 181.203898 -283.822046) (xy 181.233463 -283.86139) (xy 181.256334 -283.904967)
			(xy 181.271918 -283.951648) (xy 181.279813 -284.000225) (xy 181.280308 -284.024832) (xy 181.619156 -284.024832)
			(xy 181.623116 -283.975778) (xy 181.634893 -283.927994) (xy 181.654184 -283.882718) (xy 181.680487 -283.841122)
			(xy 181.713122 -283.804285) (xy 181.751243 -283.77316) (xy 181.793864 -283.748553) (xy 181.83988 -283.731101)
			(xy 181.888099 -283.721257) (xy 181.937274 -283.719276) (xy 181.986129 -283.725208) (xy 182.0334 -283.7389)
			(xy 182.077862 -283.759998) (xy 182.118365 -283.787954) (xy 182.153858 -283.822046) (xy 182.183423 -283.86139)
			(xy 182.206294 -283.904967) (xy 182.221878 -283.951648) (xy 182.229773 -284.000225) (xy 182.230268 -284.024832)
			(xy 182.569116 -284.024832) (xy 182.573076 -283.975778) (xy 182.584853 -283.927994) (xy 182.604144 -283.882718)
			(xy 182.630447 -283.841122) (xy 182.663082 -283.804285) (xy 182.701203 -283.77316) (xy 182.743824 -283.748553)
			(xy 182.78984 -283.731101) (xy 182.838059 -283.721257) (xy 182.887234 -283.719276) (xy 182.936089 -283.725208)
			(xy 182.98336 -283.7389) (xy 183.027822 -283.759998) (xy 183.068325 -283.787954) (xy 183.103818 -283.822046)
			(xy 183.133383 -283.86139) (xy 183.156254 -283.904967) (xy 183.171838 -283.951648) (xy 183.179733 -284.000225)
			(xy 183.180228 -284.024832) (xy 184.469036 -284.024832) (xy 184.472996 -283.975778) (xy 184.484773 -283.927994)
			(xy 184.504064 -283.882718) (xy 184.530367 -283.841122) (xy 184.563002 -283.804285) (xy 184.601123 -283.77316)
			(xy 184.643744 -283.748553) (xy 184.68976 -283.731101) (xy 184.737979 -283.721257) (xy 184.787154 -283.719276)
			(xy 184.836009 -283.725208) (xy 184.88328 -283.7389) (xy 184.927742 -283.759998) (xy 184.968245 -283.787954)
			(xy 185.003738 -283.822046) (xy 185.033303 -283.86139) (xy 185.056174 -283.904967) (xy 185.071758 -283.951648)
			(xy 185.079653 -284.000225) (xy 185.080148 -284.024832) (xy 185.41925 -284.024832) (xy 185.42321 -283.975778)
			(xy 185.434987 -283.927994) (xy 185.454278 -283.882718) (xy 185.480581 -283.841122) (xy 185.513216 -283.804285)
			(xy 185.551337 -283.77316) (xy 185.593958 -283.748553) (xy 185.639974 -283.731101) (xy 185.688193 -283.721257)
			(xy 185.737368 -283.719276) (xy 185.786223 -283.725208) (xy 185.833494 -283.7389) (xy 185.877956 -283.759998)
			(xy 185.918459 -283.787954) (xy 185.953952 -283.822046) (xy 185.983517 -283.86139) (xy 186.006388 -283.904967)
			(xy 186.021972 -283.951648) (xy 186.029867 -284.000225) (xy 186.030362 -284.024832) (xy 186.36921 -284.024832)
			(xy 186.37317 -283.975778) (xy 186.384947 -283.927994) (xy 186.404238 -283.882718) (xy 186.430541 -283.841122)
			(xy 186.463176 -283.804285) (xy 186.501297 -283.77316) (xy 186.543918 -283.748553) (xy 186.589934 -283.731101)
			(xy 186.638153 -283.721257) (xy 186.687328 -283.719276) (xy 186.736183 -283.725208) (xy 186.783454 -283.7389)
			(xy 186.827916 -283.759998) (xy 186.868419 -283.787954) (xy 186.903912 -283.822046) (xy 186.933477 -283.86139)
			(xy 186.956348 -283.904967) (xy 186.971932 -283.951648) (xy 186.979827 -284.000225) (xy 186.980322 -284.024832)
			(xy 187.31917 -284.024832) (xy 187.32313 -283.975778) (xy 187.334907 -283.927994) (xy 187.354198 -283.882718)
			(xy 187.380501 -283.841122) (xy 187.413136 -283.804285) (xy 187.451257 -283.77316) (xy 187.493878 -283.748553)
			(xy 187.539894 -283.731101) (xy 187.588113 -283.721257) (xy 187.637288 -283.719276) (xy 187.686143 -283.725208)
			(xy 187.733414 -283.7389) (xy 187.777876 -283.759998) (xy 187.818379 -283.787954) (xy 187.853872 -283.822046)
			(xy 187.883437 -283.86139) (xy 187.906308 -283.904967) (xy 187.921892 -283.951648) (xy 187.929787 -284.000225)
			(xy 187.930282 -284.024832) (xy 188.26913 -284.024832) (xy 188.27309 -283.975778) (xy 188.284867 -283.927994)
			(xy 188.304158 -283.882718) (xy 188.330461 -283.841122) (xy 188.363096 -283.804285) (xy 188.401217 -283.77316)
			(xy 188.443838 -283.748553) (xy 188.489854 -283.731101) (xy 188.538073 -283.721257) (xy 188.587248 -283.719276)
			(xy 188.636103 -283.725208) (xy 188.683374 -283.7389) (xy 188.727836 -283.759998) (xy 188.768339 -283.787954)
			(xy 188.803832 -283.822046) (xy 188.833397 -283.86139) (xy 188.856268 -283.904967) (xy 188.871852 -283.951648)
			(xy 188.879747 -284.000225) (xy 188.880242 -284.024832) (xy 188.879747 -284.049439) (xy 188.871852 -284.098016)
			(xy 188.856268 -284.144697) (xy 188.833397 -284.188274) (xy 188.803832 -284.227618) (xy 188.768339 -284.26171)
			(xy 188.727836 -284.289666) (xy 188.683374 -284.310764) (xy 188.636103 -284.324456) (xy 188.587248 -284.330388)
			(xy 188.538073 -284.328407) (xy 188.489854 -284.318563) (xy 188.443838 -284.301111) (xy 188.401217 -284.276504)
			(xy 188.363096 -284.245379) (xy 188.330461 -284.208542) (xy 188.304158 -284.166946) (xy 188.284867 -284.12167)
			(xy 188.27309 -284.073886) (xy 188.26913 -284.024832) (xy 187.930282 -284.024832) (xy 187.929787 -284.049439)
			(xy 187.921892 -284.098016) (xy 187.906308 -284.144697) (xy 187.883437 -284.188274) (xy 187.853872 -284.227618)
			(xy 187.818379 -284.26171) (xy 187.777876 -284.289666) (xy 187.733414 -284.310764) (xy 187.686143 -284.324456)
			(xy 187.637288 -284.330388) (xy 187.588113 -284.328407) (xy 187.539894 -284.318563) (xy 187.493878 -284.301111)
			(xy 187.451257 -284.276504) (xy 187.413136 -284.245379) (xy 187.380501 -284.208542) (xy 187.354198 -284.166946)
			(xy 187.334907 -284.12167) (xy 187.32313 -284.073886) (xy 187.31917 -284.024832) (xy 186.980322 -284.024832)
			(xy 186.979827 -284.049439) (xy 186.971932 -284.098016) (xy 186.956348 -284.144697) (xy 186.933477 -284.188274)
			(xy 186.903912 -284.227618) (xy 186.868419 -284.26171) (xy 186.827916 -284.289666) (xy 186.783454 -284.310764)
			(xy 186.736183 -284.324456) (xy 186.687328 -284.330388) (xy 186.638153 -284.328407) (xy 186.589934 -284.318563)
			(xy 186.543918 -284.301111) (xy 186.501297 -284.276504) (xy 186.463176 -284.245379) (xy 186.430541 -284.208542)
			(xy 186.404238 -284.166946) (xy 186.384947 -284.12167) (xy 186.37317 -284.073886) (xy 186.36921 -284.024832)
			(xy 186.030362 -284.024832) (xy 186.029867 -284.049439) (xy 186.021972 -284.098016) (xy 186.006388 -284.144697)
			(xy 185.983517 -284.188274) (xy 185.953952 -284.227618) (xy 185.918459 -284.26171) (xy 185.877956 -284.289666)
			(xy 185.833494 -284.310764) (xy 185.786223 -284.324456) (xy 185.737368 -284.330388) (xy 185.688193 -284.328407)
			(xy 185.639974 -284.318563) (xy 185.593958 -284.301111) (xy 185.551337 -284.276504) (xy 185.513216 -284.245379)
			(xy 185.480581 -284.208542) (xy 185.454278 -284.166946) (xy 185.434987 -284.12167) (xy 185.42321 -284.073886)
			(xy 185.41925 -284.024832) (xy 185.080148 -284.024832) (xy 185.079653 -284.049439) (xy 185.071758 -284.098016)
			(xy 185.056174 -284.144697) (xy 185.033303 -284.188274) (xy 185.003738 -284.227618) (xy 184.968245 -284.26171)
			(xy 184.927742 -284.289666) (xy 184.88328 -284.310764) (xy 184.836009 -284.324456) (xy 184.787154 -284.330388)
			(xy 184.737979 -284.328407) (xy 184.68976 -284.318563) (xy 184.643744 -284.301111) (xy 184.601123 -284.276504)
			(xy 184.563002 -284.245379) (xy 184.530367 -284.208542) (xy 184.504064 -284.166946) (xy 184.484773 -284.12167)
			(xy 184.472996 -284.073886) (xy 184.469036 -284.024832) (xy 183.180228 -284.024832) (xy 183.179733 -284.049439)
			(xy 183.171838 -284.098016) (xy 183.156254 -284.144697) (xy 183.133383 -284.188274) (xy 183.103818 -284.227618)
			(xy 183.068325 -284.26171) (xy 183.027822 -284.289666) (xy 182.98336 -284.310764) (xy 182.936089 -284.324456)
			(xy 182.887234 -284.330388) (xy 182.838059 -284.328407) (xy 182.78984 -284.318563) (xy 182.743824 -284.301111)
			(xy 182.701203 -284.276504) (xy 182.663082 -284.245379) (xy 182.630447 -284.208542) (xy 182.604144 -284.166946)
			(xy 182.584853 -284.12167) (xy 182.573076 -284.073886) (xy 182.569116 -284.024832) (xy 182.230268 -284.024832)
			(xy 182.229773 -284.049439) (xy 182.221878 -284.098016) (xy 182.206294 -284.144697) (xy 182.183423 -284.188274)
			(xy 182.153858 -284.227618) (xy 182.118365 -284.26171) (xy 182.077862 -284.289666) (xy 182.0334 -284.310764)
			(xy 181.986129 -284.324456) (xy 181.937274 -284.330388) (xy 181.888099 -284.328407) (xy 181.83988 -284.318563)
			(xy 181.793864 -284.301111) (xy 181.751243 -284.276504) (xy 181.713122 -284.245379) (xy 181.680487 -284.208542)
			(xy 181.654184 -284.166946) (xy 181.634893 -284.12167) (xy 181.623116 -284.073886) (xy 181.619156 -284.024832)
			(xy 181.280308 -284.024832) (xy 181.279813 -284.049439) (xy 181.271918 -284.098016) (xy 181.256334 -284.144697)
			(xy 181.233463 -284.188274) (xy 181.203898 -284.227618) (xy 181.168405 -284.26171) (xy 181.127902 -284.289666)
			(xy 181.08344 -284.310764) (xy 181.036169 -284.324456) (xy 180.987314 -284.330388) (xy 180.938139 -284.328407)
			(xy 180.88992 -284.318563) (xy 180.843904 -284.301111) (xy 180.801283 -284.276504) (xy 180.763162 -284.245379)
			(xy 180.730527 -284.208542) (xy 180.704224 -284.166946) (xy 180.684933 -284.12167) (xy 180.673156 -284.073886)
			(xy 180.669196 -284.024832) (xy 180.330348 -284.024832) (xy 180.329853 -284.049439) (xy 180.321958 -284.098016)
			(xy 180.306374 -284.144697) (xy 180.283503 -284.188274) (xy 180.253938 -284.227618) (xy 180.218445 -284.26171)
			(xy 180.177942 -284.289666) (xy 180.13348 -284.310764) (xy 180.086209 -284.324456) (xy 180.037354 -284.330388)
			(xy 179.988179 -284.328407) (xy 179.93996 -284.318563) (xy 179.893944 -284.301111) (xy 179.851323 -284.276504)
			(xy 179.813202 -284.245379) (xy 179.780567 -284.208542) (xy 179.754264 -284.166946) (xy 179.734973 -284.12167)
			(xy 179.723196 -284.073886) (xy 179.719236 -284.024832) (xy 179.380388 -284.024832) (xy 179.379893 -284.049439)
			(xy 179.371998 -284.098016) (xy 179.356414 -284.144697) (xy 179.333543 -284.188274) (xy 179.303978 -284.227618)
			(xy 179.268485 -284.26171) (xy 179.227982 -284.289666) (xy 179.18352 -284.310764) (xy 179.136249 -284.324456)
			(xy 179.087394 -284.330388) (xy 179.038219 -284.328407) (xy 178.99 -284.318563) (xy 178.943984 -284.301111)
			(xy 178.901363 -284.276504) (xy 178.863242 -284.245379) (xy 178.830607 -284.208542) (xy 178.804304 -284.166946)
			(xy 178.785013 -284.12167) (xy 178.773236 -284.073886) (xy 178.769276 -284.024832) (xy 178.430174 -284.024832)
			(xy 178.429679 -284.049439) (xy 178.421784 -284.098016) (xy 178.4062 -284.144697) (xy 178.383329 -284.188274)
			(xy 178.353764 -284.227618) (xy 178.318271 -284.26171) (xy 178.277768 -284.289666) (xy 178.233306 -284.310764)
			(xy 178.186035 -284.324456) (xy 178.13718 -284.330388) (xy 178.088005 -284.328407) (xy 178.039786 -284.318563)
			(xy 177.99377 -284.301111) (xy 177.951149 -284.276504) (xy 177.913028 -284.245379) (xy 177.880393 -284.208542)
			(xy 177.85409 -284.166946) (xy 177.834799 -284.12167) (xy 177.823022 -284.073886) (xy 177.819062 -284.024832)
			(xy 177.480214 -284.024832) (xy 177.479719 -284.049439) (xy 177.471824 -284.098016) (xy 177.45624 -284.144697)
			(xy 177.433369 -284.188274) (xy 177.403804 -284.227618) (xy 177.368311 -284.26171) (xy 177.327808 -284.289666)
			(xy 177.283346 -284.310764) (xy 177.236075 -284.324456) (xy 177.18722 -284.330388) (xy 177.138045 -284.328407)
			(xy 177.089826 -284.318563) (xy 177.04381 -284.301111) (xy 177.001189 -284.276504) (xy 176.963068 -284.245379)
			(xy 176.930433 -284.208542) (xy 176.90413 -284.166946) (xy 176.884839 -284.12167) (xy 176.873062 -284.073886)
			(xy 176.869102 -284.024832) (xy 176.530254 -284.024832) (xy 176.529759 -284.049439) (xy 176.521864 -284.098016)
			(xy 176.50628 -284.144697) (xy 176.483409 -284.188274) (xy 176.453844 -284.227618) (xy 176.418351 -284.26171)
			(xy 176.377848 -284.289666) (xy 176.333386 -284.310764) (xy 176.286115 -284.324456) (xy 176.23726 -284.330388)
			(xy 176.188085 -284.328407) (xy 176.139866 -284.318563) (xy 176.09385 -284.301111) (xy 176.051229 -284.276504)
			(xy 176.013108 -284.245379) (xy 175.980473 -284.208542) (xy 175.95417 -284.166946) (xy 175.934879 -284.12167)
			(xy 175.923102 -284.073886) (xy 175.919142 -284.024832) (xy 174.630334 -284.024832) (xy 174.629839 -284.049439)
			(xy 174.621944 -284.098016) (xy 174.60636 -284.144697) (xy 174.583489 -284.188274) (xy 174.553924 -284.227618)
			(xy 174.518431 -284.26171) (xy 174.477928 -284.289666) (xy 174.433466 -284.310764) (xy 174.386195 -284.324456)
			(xy 174.33734 -284.330388) (xy 174.288165 -284.328407) (xy 174.239946 -284.318563) (xy 174.19393 -284.301111)
			(xy 174.151309 -284.276504) (xy 174.113188 -284.245379) (xy 174.080553 -284.208542) (xy 174.05425 -284.166946)
			(xy 174.034959 -284.12167) (xy 174.023182 -284.073886) (xy 174.019222 -284.024832) (xy 173.680374 -284.024832)
			(xy 173.679879 -284.049439) (xy 173.671984 -284.098016) (xy 173.6564 -284.144697) (xy 173.633529 -284.188274)
			(xy 173.603964 -284.227618) (xy 173.568471 -284.26171) (xy 173.527968 -284.289666) (xy 173.483506 -284.310764)
			(xy 173.436235 -284.324456) (xy 173.38738 -284.330388) (xy 173.338205 -284.328407) (xy 173.289986 -284.318563)
			(xy 173.24397 -284.301111) (xy 173.201349 -284.276504) (xy 173.163228 -284.245379) (xy 173.130593 -284.208542)
			(xy 173.10429 -284.166946) (xy 173.084999 -284.12167) (xy 173.073222 -284.073886) (xy 173.069262 -284.024832)
			(xy 172.73016 -284.024832) (xy 172.729665 -284.049439) (xy 172.72177 -284.098016) (xy 172.706186 -284.144697)
			(xy 172.683315 -284.188274) (xy 172.65375 -284.227618) (xy 172.618257 -284.26171) (xy 172.577754 -284.289666)
			(xy 172.533292 -284.310764) (xy 172.486021 -284.324456) (xy 172.437166 -284.330388) (xy 172.387991 -284.328407)
			(xy 172.339772 -284.318563) (xy 172.293756 -284.301111) (xy 172.251135 -284.276504) (xy 172.213014 -284.245379)
			(xy 172.180379 -284.208542) (xy 172.154076 -284.166946) (xy 172.134785 -284.12167) (xy 172.123008 -284.073886)
			(xy 172.119048 -284.024832) (xy 171.7802 -284.024832) (xy 171.779705 -284.049439) (xy 171.77181 -284.098016)
			(xy 171.756226 -284.144697) (xy 171.733355 -284.188274) (xy 171.70379 -284.227618) (xy 171.668297 -284.26171)
			(xy 171.627794 -284.289666) (xy 171.583332 -284.310764) (xy 171.536061 -284.324456) (xy 171.487206 -284.330388)
			(xy 171.438031 -284.328407) (xy 171.389812 -284.318563) (xy 171.343796 -284.301111) (xy 171.301175 -284.276504)
			(xy 171.263054 -284.245379) (xy 171.230419 -284.208542) (xy 171.204116 -284.166946) (xy 171.184825 -284.12167)
			(xy 171.173048 -284.073886) (xy 171.169088 -284.024832) (xy 170.83024 -284.024832) (xy 170.829745 -284.049439)
			(xy 170.82185 -284.098016) (xy 170.806266 -284.144697) (xy 170.783395 -284.188274) (xy 170.75383 -284.227618)
			(xy 170.718337 -284.26171) (xy 170.677834 -284.289666) (xy 170.633372 -284.310764) (xy 170.586101 -284.324456)
			(xy 170.537246 -284.330388) (xy 170.488071 -284.328407) (xy 170.439852 -284.318563) (xy 170.393836 -284.301111)
			(xy 170.351215 -284.276504) (xy 170.313094 -284.245379) (xy 170.280459 -284.208542) (xy 170.254156 -284.166946)
			(xy 170.234865 -284.12167) (xy 170.223088 -284.073886) (xy 170.219128 -284.024832) (xy 169.88028 -284.024832)
			(xy 169.879785 -284.049439) (xy 169.87189 -284.098016) (xy 169.856306 -284.144697) (xy 169.833435 -284.188274)
			(xy 169.80387 -284.227618) (xy 169.768377 -284.26171) (xy 169.727874 -284.289666) (xy 169.683412 -284.310764)
			(xy 169.636141 -284.324456) (xy 169.587286 -284.330388) (xy 169.538111 -284.328407) (xy 169.489892 -284.318563)
			(xy 169.443876 -284.301111) (xy 169.401255 -284.276504) (xy 169.363134 -284.245379) (xy 169.330499 -284.208542)
			(xy 169.304196 -284.166946) (xy 169.284905 -284.12167) (xy 169.273128 -284.073886) (xy 169.269168 -284.024832)
			(xy 168.93032 -284.024832) (xy 168.929825 -284.049439) (xy 168.92193 -284.098016) (xy 168.906346 -284.144697)
			(xy 168.883475 -284.188274) (xy 168.85391 -284.227618) (xy 168.818417 -284.26171) (xy 168.777914 -284.289666)
			(xy 168.733452 -284.310764) (xy 168.686181 -284.324456) (xy 168.637326 -284.330388) (xy 168.588151 -284.328407)
			(xy 168.539932 -284.318563) (xy 168.493916 -284.301111) (xy 168.451295 -284.276504) (xy 168.413174 -284.245379)
			(xy 168.380539 -284.208542) (xy 168.354236 -284.166946) (xy 168.334945 -284.12167) (xy 168.323168 -284.073886)
			(xy 168.319208 -284.024832) (xy 167.98036 -284.024832) (xy 167.979865 -284.049439) (xy 167.97197 -284.098016)
			(xy 167.956386 -284.144697) (xy 167.933515 -284.188274) (xy 167.90395 -284.227618) (xy 167.868457 -284.26171)
			(xy 167.827954 -284.289666) (xy 167.783492 -284.310764) (xy 167.736221 -284.324456) (xy 167.687366 -284.330388)
			(xy 167.638191 -284.328407) (xy 167.589972 -284.318563) (xy 167.543956 -284.301111) (xy 167.501335 -284.276504)
			(xy 167.463214 -284.245379) (xy 167.430579 -284.208542) (xy 167.404276 -284.166946) (xy 167.384985 -284.12167)
			(xy 167.373208 -284.073886) (xy 167.369248 -284.024832) (xy 167.0304 -284.024832) (xy 167.029905 -284.049439)
			(xy 167.02201 -284.098016) (xy 167.006426 -284.144697) (xy 166.983555 -284.188274) (xy 166.95399 -284.227618)
			(xy 166.918497 -284.26171) (xy 166.877994 -284.289666) (xy 166.833532 -284.310764) (xy 166.786261 -284.324456)
			(xy 166.737406 -284.330388) (xy 166.688231 -284.328407) (xy 166.640012 -284.318563) (xy 166.593996 -284.301111)
			(xy 166.551375 -284.276504) (xy 166.513254 -284.245379) (xy 166.480619 -284.208542) (xy 166.454316 -284.166946)
			(xy 166.435025 -284.12167) (xy 166.423248 -284.073886) (xy 166.419288 -284.024832) (xy 166.080186 -284.024832)
			(xy 166.079691 -284.049439) (xy 166.071796 -284.098016) (xy 166.056212 -284.144697) (xy 166.033341 -284.188274)
			(xy 166.003776 -284.227618) (xy 165.968283 -284.26171) (xy 165.92778 -284.289666) (xy 165.883318 -284.310764)
			(xy 165.836047 -284.324456) (xy 165.787192 -284.330388) (xy 165.738017 -284.328407) (xy 165.689798 -284.318563)
			(xy 165.643782 -284.301111) (xy 165.601161 -284.276504) (xy 165.56304 -284.245379) (xy 165.530405 -284.208542)
			(xy 165.504102 -284.166946) (xy 165.484811 -284.12167) (xy 165.473034 -284.073886) (xy 165.469074 -284.024832)
			(xy 165.130226 -284.024832) (xy 165.129731 -284.049439) (xy 165.121836 -284.098016) (xy 165.106252 -284.144697)
			(xy 165.083381 -284.188274) (xy 165.053816 -284.227618) (xy 165.018323 -284.26171) (xy 164.97782 -284.289666)
			(xy 164.933358 -284.310764) (xy 164.886087 -284.324456) (xy 164.837232 -284.330388) (xy 164.788057 -284.328407)
			(xy 164.739838 -284.318563) (xy 164.693822 -284.301111) (xy 164.651201 -284.276504) (xy 164.61308 -284.245379)
			(xy 164.580445 -284.208542) (xy 164.554142 -284.166946) (xy 164.534851 -284.12167) (xy 164.523074 -284.073886)
			(xy 164.519114 -284.024832) (xy 164.180266 -284.024832) (xy 164.179771 -284.049439) (xy 164.171876 -284.098016)
			(xy 164.156292 -284.144697) (xy 164.133421 -284.188274) (xy 164.103856 -284.227618) (xy 164.068363 -284.26171)
			(xy 164.02786 -284.289666) (xy 163.983398 -284.310764) (xy 163.936127 -284.324456) (xy 163.887272 -284.330388)
			(xy 163.838097 -284.328407) (xy 163.789878 -284.318563) (xy 163.743862 -284.301111) (xy 163.701241 -284.276504)
			(xy 163.66312 -284.245379) (xy 163.630485 -284.208542) (xy 163.604182 -284.166946) (xy 163.584891 -284.12167)
			(xy 163.573114 -284.073886) (xy 163.569154 -284.024832) (xy 163.230306 -284.024832) (xy 163.229811 -284.049439)
			(xy 163.221916 -284.098016) (xy 163.206332 -284.144697) (xy 163.183461 -284.188274) (xy 163.153896 -284.227618)
			(xy 163.118403 -284.26171) (xy 163.0779 -284.289666) (xy 163.033438 -284.310764) (xy 162.986167 -284.324456)
			(xy 162.937312 -284.330388) (xy 162.888137 -284.328407) (xy 162.839918 -284.318563) (xy 162.793902 -284.301111)
			(xy 162.751281 -284.276504) (xy 162.71316 -284.245379) (xy 162.680525 -284.208542) (xy 162.654222 -284.166946)
			(xy 162.634931 -284.12167) (xy 162.623154 -284.073886) (xy 162.619194 -284.024832) (xy 162.280346 -284.024832)
			(xy 162.279851 -284.049439) (xy 162.271956 -284.098016) (xy 162.256372 -284.144697) (xy 162.233501 -284.188274)
			(xy 162.203936 -284.227618) (xy 162.168443 -284.26171) (xy 162.12794 -284.289666) (xy 162.083478 -284.310764)
			(xy 162.036207 -284.324456) (xy 161.987352 -284.330388) (xy 161.938177 -284.328407) (xy 161.889958 -284.318563)
			(xy 161.843942 -284.301111) (xy 161.801321 -284.276504) (xy 161.7632 -284.245379) (xy 161.730565 -284.208542)
			(xy 161.704262 -284.166946) (xy 161.684971 -284.12167) (xy 161.673194 -284.073886) (xy 161.669234 -284.024832)
			(xy 161.330386 -284.024832) (xy 161.329891 -284.049439) (xy 161.321996 -284.098016) (xy 161.306412 -284.144697)
			(xy 161.283541 -284.188274) (xy 161.253976 -284.227618) (xy 161.218483 -284.26171) (xy 161.17798 -284.289666)
			(xy 161.133518 -284.310764) (xy 161.086247 -284.324456) (xy 161.037392 -284.330388) (xy 160.988217 -284.328407)
			(xy 160.939998 -284.318563) (xy 160.893982 -284.301111) (xy 160.851361 -284.276504) (xy 160.81324 -284.245379)
			(xy 160.780605 -284.208542) (xy 160.754302 -284.166946) (xy 160.735011 -284.12167) (xy 160.723234 -284.073886)
			(xy 160.719274 -284.024832) (xy 160.380172 -284.024832) (xy 160.379677 -284.049439) (xy 160.371782 -284.098016)
			(xy 160.356198 -284.144697) (xy 160.333327 -284.188274) (xy 160.303762 -284.227618) (xy 160.268269 -284.26171)
			(xy 160.227766 -284.289666) (xy 160.183304 -284.310764) (xy 160.136033 -284.324456) (xy 160.087178 -284.330388)
			(xy 160.038003 -284.328407) (xy 159.989784 -284.318563) (xy 159.943768 -284.301111) (xy 159.901147 -284.276504)
			(xy 159.863026 -284.245379) (xy 159.830391 -284.208542) (xy 159.804088 -284.166946) (xy 159.784797 -284.12167)
			(xy 159.77302 -284.073886) (xy 159.76906 -284.024832) (xy 159.430212 -284.024832) (xy 159.429717 -284.049439)
			(xy 159.421822 -284.098016) (xy 159.406238 -284.144697) (xy 159.383367 -284.188274) (xy 159.353802 -284.227618)
			(xy 159.318309 -284.26171) (xy 159.277806 -284.289666) (xy 159.233344 -284.310764) (xy 159.186073 -284.324456)
			(xy 159.137218 -284.330388) (xy 159.088043 -284.328407) (xy 159.039824 -284.318563) (xy 158.993808 -284.301111)
			(xy 158.951187 -284.276504) (xy 158.913066 -284.245379) (xy 158.880431 -284.208542) (xy 158.854128 -284.166946)
			(xy 158.834837 -284.12167) (xy 158.82306 -284.073886) (xy 158.8191 -284.024832) (xy 158.480252 -284.024832)
			(xy 158.479757 -284.049439) (xy 158.471862 -284.098016) (xy 158.456278 -284.144697) (xy 158.433407 -284.188274)
			(xy 158.403842 -284.227618) (xy 158.368349 -284.26171) (xy 158.327846 -284.289666) (xy 158.283384 -284.310764)
			(xy 158.236113 -284.324456) (xy 158.187258 -284.330388) (xy 158.138083 -284.328407) (xy 158.089864 -284.318563)
			(xy 158.043848 -284.301111) (xy 158.001227 -284.276504) (xy 157.963106 -284.245379) (xy 157.930471 -284.208542)
			(xy 157.904168 -284.166946) (xy 157.884877 -284.12167) (xy 157.8731 -284.073886) (xy 157.86914 -284.024832)
			(xy 157.530292 -284.024832) (xy 157.529797 -284.049439) (xy 157.521902 -284.098016) (xy 157.506318 -284.144697)
			(xy 157.483447 -284.188274) (xy 157.453882 -284.227618) (xy 157.418389 -284.26171) (xy 157.377886 -284.289666)
			(xy 157.333424 -284.310764) (xy 157.286153 -284.324456) (xy 157.237298 -284.330388) (xy 157.188123 -284.328407)
			(xy 157.139904 -284.318563) (xy 157.093888 -284.301111) (xy 157.051267 -284.276504) (xy 157.013146 -284.245379)
			(xy 156.980511 -284.208542) (xy 156.954208 -284.166946) (xy 156.934917 -284.12167) (xy 156.92314 -284.073886)
			(xy 156.91918 -284.024832) (xy 156.580332 -284.024832) (xy 156.579837 -284.049439) (xy 156.571942 -284.098016)
			(xy 156.556358 -284.144697) (xy 156.533487 -284.188274) (xy 156.503922 -284.227618) (xy 156.468429 -284.26171)
			(xy 156.427926 -284.289666) (xy 156.383464 -284.310764) (xy 156.336193 -284.324456) (xy 156.287338 -284.330388)
			(xy 156.238163 -284.328407) (xy 156.189944 -284.318563) (xy 156.143928 -284.301111) (xy 156.101307 -284.276504)
			(xy 156.063186 -284.245379) (xy 156.030551 -284.208542) (xy 156.004248 -284.166946) (xy 155.984957 -284.12167)
			(xy 155.97318 -284.073886) (xy 155.96922 -284.024832) (xy 155.630372 -284.024832) (xy 155.629877 -284.049439)
			(xy 155.621982 -284.098016) (xy 155.606398 -284.144697) (xy 155.583527 -284.188274) (xy 155.553962 -284.227618)
			(xy 155.518469 -284.26171) (xy 155.477966 -284.289666) (xy 155.433504 -284.310764) (xy 155.386233 -284.324456)
			(xy 155.337378 -284.330388) (xy 155.288203 -284.328407) (xy 155.239984 -284.318563) (xy 155.193968 -284.301111)
			(xy 155.151347 -284.276504) (xy 155.113226 -284.245379) (xy 155.080591 -284.208542) (xy 155.054288 -284.166946)
			(xy 155.034997 -284.12167) (xy 155.02322 -284.073886) (xy 155.01926 -284.024832) (xy 154.680412 -284.024832)
			(xy 154.679917 -284.049439) (xy 154.672022 -284.098016) (xy 154.656438 -284.144697) (xy 154.633567 -284.188274)
			(xy 154.604002 -284.227618) (xy 154.568509 -284.26171) (xy 154.528006 -284.289666) (xy 154.483544 -284.310764)
			(xy 154.436273 -284.324456) (xy 154.387418 -284.330388) (xy 154.338243 -284.328407) (xy 154.290024 -284.318563)
			(xy 154.244008 -284.301111) (xy 154.201387 -284.276504) (xy 154.163266 -284.245379) (xy 154.130631 -284.208542)
			(xy 154.104328 -284.166946) (xy 154.085037 -284.12167) (xy 154.07326 -284.073886) (xy 154.0693 -284.024832)
			(xy 153.730198 -284.024832) (xy 153.729703 -284.049439) (xy 153.721808 -284.098016) (xy 153.706224 -284.144697)
			(xy 153.683353 -284.188274) (xy 153.653788 -284.227618) (xy 153.618295 -284.26171) (xy 153.577792 -284.289666)
			(xy 153.53333 -284.310764) (xy 153.486059 -284.324456) (xy 153.437204 -284.330388) (xy 153.388029 -284.328407)
			(xy 153.33981 -284.318563) (xy 153.293794 -284.301111) (xy 153.251173 -284.276504) (xy 153.213052 -284.245379)
			(xy 153.180417 -284.208542) (xy 153.154114 -284.166946) (xy 153.134823 -284.12167) (xy 153.123046 -284.073886)
			(xy 153.119086 -284.024832) (xy 152.805638 -284.024832) (xy 152.805126 -284.050818) (xy 152.796992 -284.102151)
			(xy 152.780928 -284.151579) (xy 152.757331 -284.197886) (xy 152.726781 -284.239932) (xy 152.690031 -284.276683)
			(xy 152.647984 -284.307232) (xy 152.601677 -284.330829) (xy 152.552249 -284.346892) (xy 152.500916 -284.355026)
			(xy 152.47493 -284.35554) (xy 152.474168 -284.35554) (xy 152.446856 -284.354933) (xy 152.392989 -284.345863)
			(xy 152.36698 -284.337506) (xy 152.366472 -284.337506) (xy 152.366218 -284.337252) (xy 152.357142 -284.334636)
			(xy 152.338289 -284.335566) (xy 152.321046 -284.343247) (xy 152.314148 -284.349698) (xy 152.190196 -284.47365)
			(xy 152.188926 -284.47492) (xy 152.182322 -284.489906) (xy 152.178004 -284.50032) (xy 152.178004 -284.587188)
			(xy 152.178067 -284.590995) (xy 152.17921 -284.598523) (xy 152.18029 -284.602174) (xy 152.182576 -284.60954)
			(xy 152.189688 -284.625288) (xy 152.195784 -284.630622) (xy 152.199086 -284.633162) (xy 152.276048 -284.680406)
			(xy 152.290526 -284.68066) (xy 152.30602 -284.68066) (xy 152.312624 -284.680152) (xy 152.332944 -284.675834)
			(xy 152.338024 -284.673548) (xy 152.359549 -284.664252) (xy 152.404564 -284.651135) (xy 152.450979 -284.644498)
			(xy 152.474422 -284.644084) (xy 152.47493 -284.644084) (xy 152.500916 -284.644596) (xy 152.552248 -284.65273)
			(xy 152.601676 -284.668794) (xy 152.647983 -284.692392) (xy 152.690028 -284.722943) (xy 152.726776 -284.759695)
			(xy 152.757323 -284.801743) (xy 152.780917 -284.848052) (xy 152.796977 -284.897481) (xy 152.805107 -284.948814)
			(xy 152.805107 -284.974792) (xy 153.119086 -284.974792) (xy 153.123046 -284.925738) (xy 153.134823 -284.877954)
			(xy 153.154114 -284.832678) (xy 153.180417 -284.791082) (xy 153.213052 -284.754245) (xy 153.251173 -284.72312)
			(xy 153.293794 -284.698513) (xy 153.33981 -284.681061) (xy 153.388029 -284.671217) (xy 153.437204 -284.669236)
			(xy 153.486059 -284.675168) (xy 153.53333 -284.68886) (xy 153.577792 -284.709958) (xy 153.618295 -284.737914)
			(xy 153.653788 -284.772006) (xy 153.683353 -284.81135) (xy 153.706224 -284.854927) (xy 153.721808 -284.901608)
			(xy 153.729703 -284.950185) (xy 153.730198 -284.974792) (xy 154.0693 -284.974792) (xy 154.07326 -284.925738)
			(xy 154.085037 -284.877954) (xy 154.104328 -284.832678) (xy 154.130631 -284.791082) (xy 154.163266 -284.754245)
			(xy 154.201387 -284.72312) (xy 154.244008 -284.698513) (xy 154.290024 -284.681061) (xy 154.338243 -284.671217)
			(xy 154.387418 -284.669236) (xy 154.436273 -284.675168) (xy 154.483544 -284.68886) (xy 154.528006 -284.709958)
			(xy 154.568509 -284.737914) (xy 154.604002 -284.772006) (xy 154.633567 -284.81135) (xy 154.656438 -284.854927)
			(xy 154.672022 -284.901608) (xy 154.679917 -284.950185) (xy 154.680412 -284.974792) (xy 155.01926 -284.974792)
			(xy 155.02322 -284.925738) (xy 155.034997 -284.877954) (xy 155.054288 -284.832678) (xy 155.080591 -284.791082)
			(xy 155.113226 -284.754245) (xy 155.151347 -284.72312) (xy 155.193968 -284.698513) (xy 155.239984 -284.681061)
			(xy 155.288203 -284.671217) (xy 155.337378 -284.669236) (xy 155.386233 -284.675168) (xy 155.433504 -284.68886)
			(xy 155.477966 -284.709958) (xy 155.518469 -284.737914) (xy 155.553962 -284.772006) (xy 155.583527 -284.81135)
			(xy 155.606398 -284.854927) (xy 155.621982 -284.901608) (xy 155.629877 -284.950185) (xy 155.630372 -284.974792)
			(xy 155.96922 -284.974792) (xy 155.97318 -284.925738) (xy 155.984957 -284.877954) (xy 156.004248 -284.832678)
			(xy 156.030551 -284.791082) (xy 156.063186 -284.754245) (xy 156.101307 -284.72312) (xy 156.143928 -284.698513)
			(xy 156.189944 -284.681061) (xy 156.238163 -284.671217) (xy 156.287338 -284.669236) (xy 156.336193 -284.675168)
			(xy 156.383464 -284.68886) (xy 156.427926 -284.709958) (xy 156.468429 -284.737914) (xy 156.503922 -284.772006)
			(xy 156.533487 -284.81135) (xy 156.556358 -284.854927) (xy 156.571942 -284.901608) (xy 156.579837 -284.950185)
			(xy 156.580332 -284.974792) (xy 156.91918 -284.974792) (xy 156.92314 -284.925738) (xy 156.934917 -284.877954)
			(xy 156.954208 -284.832678) (xy 156.980511 -284.791082) (xy 157.013146 -284.754245) (xy 157.051267 -284.72312)
			(xy 157.093888 -284.698513) (xy 157.139904 -284.681061) (xy 157.188123 -284.671217) (xy 157.237298 -284.669236)
			(xy 157.286153 -284.675168) (xy 157.333424 -284.68886) (xy 157.377886 -284.709958) (xy 157.418389 -284.737914)
			(xy 157.453882 -284.772006) (xy 157.483447 -284.81135) (xy 157.506318 -284.854927) (xy 157.521902 -284.901608)
			(xy 157.529797 -284.950185) (xy 157.530292 -284.974792) (xy 158.8191 -284.974792) (xy 158.82306 -284.925738)
			(xy 158.834837 -284.877954) (xy 158.854128 -284.832678) (xy 158.880431 -284.791082) (xy 158.913066 -284.754245)
			(xy 158.951187 -284.72312) (xy 158.993808 -284.698513) (xy 159.039824 -284.681061) (xy 159.088043 -284.671217)
			(xy 159.137218 -284.669236) (xy 159.186073 -284.675168) (xy 159.233344 -284.68886) (xy 159.277806 -284.709958)
			(xy 159.318309 -284.737914) (xy 159.353802 -284.772006) (xy 159.383367 -284.81135) (xy 159.406238 -284.854927)
			(xy 159.421822 -284.901608) (xy 159.429717 -284.950185) (xy 159.430212 -284.974792) (xy 160.719274 -284.974792)
			(xy 160.723234 -284.925738) (xy 160.735011 -284.877954) (xy 160.754302 -284.832678) (xy 160.780605 -284.791082)
			(xy 160.81324 -284.754245) (xy 160.851361 -284.72312) (xy 160.893982 -284.698513) (xy 160.939998 -284.681061)
			(xy 160.988217 -284.671217) (xy 161.037392 -284.669236) (xy 161.086247 -284.675168) (xy 161.133518 -284.68886)
			(xy 161.17798 -284.709958) (xy 161.218483 -284.737914) (xy 161.253976 -284.772006) (xy 161.283541 -284.81135)
			(xy 161.306412 -284.854927) (xy 161.321996 -284.901608) (xy 161.329891 -284.950185) (xy 161.330386 -284.974792)
			(xy 161.669234 -284.974792) (xy 161.673194 -284.925738) (xy 161.684971 -284.877954) (xy 161.704262 -284.832678)
			(xy 161.730565 -284.791082) (xy 161.7632 -284.754245) (xy 161.801321 -284.72312) (xy 161.843942 -284.698513)
			(xy 161.889958 -284.681061) (xy 161.938177 -284.671217) (xy 161.987352 -284.669236) (xy 162.036207 -284.675168)
			(xy 162.083478 -284.68886) (xy 162.12794 -284.709958) (xy 162.168443 -284.737914) (xy 162.203936 -284.772006)
			(xy 162.233501 -284.81135) (xy 162.256372 -284.854927) (xy 162.271956 -284.901608) (xy 162.279851 -284.950185)
			(xy 162.280346 -284.974792) (xy 162.619194 -284.974792) (xy 162.623154 -284.925738) (xy 162.634931 -284.877954)
			(xy 162.654222 -284.832678) (xy 162.680525 -284.791082) (xy 162.71316 -284.754245) (xy 162.751281 -284.72312)
			(xy 162.793902 -284.698513) (xy 162.839918 -284.681061) (xy 162.888137 -284.671217) (xy 162.937312 -284.669236)
			(xy 162.986167 -284.675168) (xy 163.033438 -284.68886) (xy 163.0779 -284.709958) (xy 163.118403 -284.737914)
			(xy 163.153896 -284.772006) (xy 163.183461 -284.81135) (xy 163.206332 -284.854927) (xy 163.221916 -284.901608)
			(xy 163.229811 -284.950185) (xy 163.230306 -284.974792) (xy 163.569154 -284.974792) (xy 163.573114 -284.925738)
			(xy 163.584891 -284.877954) (xy 163.604182 -284.832678) (xy 163.630485 -284.791082) (xy 163.66312 -284.754245)
			(xy 163.701241 -284.72312) (xy 163.743862 -284.698513) (xy 163.789878 -284.681061) (xy 163.838097 -284.671217)
			(xy 163.887272 -284.669236) (xy 163.936127 -284.675168) (xy 163.983398 -284.68886) (xy 164.02786 -284.709958)
			(xy 164.068363 -284.737914) (xy 164.103856 -284.772006) (xy 164.133421 -284.81135) (xy 164.156292 -284.854927)
			(xy 164.171876 -284.901608) (xy 164.179771 -284.950185) (xy 164.180266 -284.974792) (xy 164.519114 -284.974792)
			(xy 164.523074 -284.925738) (xy 164.534851 -284.877954) (xy 164.554142 -284.832678) (xy 164.580445 -284.791082)
			(xy 164.61308 -284.754245) (xy 164.651201 -284.72312) (xy 164.693822 -284.698513) (xy 164.739838 -284.681061)
			(xy 164.788057 -284.671217) (xy 164.837232 -284.669236) (xy 164.886087 -284.675168) (xy 164.933358 -284.68886)
			(xy 164.97782 -284.709958) (xy 165.018323 -284.737914) (xy 165.053816 -284.772006) (xy 165.083381 -284.81135)
			(xy 165.106252 -284.854927) (xy 165.121836 -284.901608) (xy 165.129731 -284.950185) (xy 165.130226 -284.974792)
			(xy 165.469074 -284.974792) (xy 165.473034 -284.925738) (xy 165.484811 -284.877954) (xy 165.504102 -284.832678)
			(xy 165.530405 -284.791082) (xy 165.56304 -284.754245) (xy 165.601161 -284.72312) (xy 165.643782 -284.698513)
			(xy 165.689798 -284.681061) (xy 165.738017 -284.671217) (xy 165.787192 -284.669236) (xy 165.836047 -284.675168)
			(xy 165.883318 -284.68886) (xy 165.92778 -284.709958) (xy 165.968283 -284.737914) (xy 166.003776 -284.772006)
			(xy 166.033341 -284.81135) (xy 166.056212 -284.854927) (xy 166.071796 -284.901608) (xy 166.079691 -284.950185)
			(xy 166.080186 -284.974792) (xy 166.419288 -284.974792) (xy 166.423248 -284.925738) (xy 166.435025 -284.877954)
			(xy 166.454316 -284.832678) (xy 166.480619 -284.791082) (xy 166.513254 -284.754245) (xy 166.551375 -284.72312)
			(xy 166.593996 -284.698513) (xy 166.640012 -284.681061) (xy 166.688231 -284.671217) (xy 166.737406 -284.669236)
			(xy 166.786261 -284.675168) (xy 166.833532 -284.68886) (xy 166.877994 -284.709958) (xy 166.918497 -284.737914)
			(xy 166.95399 -284.772006) (xy 166.983555 -284.81135) (xy 167.006426 -284.854927) (xy 167.02201 -284.901608)
			(xy 167.029905 -284.950185) (xy 167.0304 -284.974792) (xy 167.369248 -284.974792) (xy 167.373208 -284.925738)
			(xy 167.384985 -284.877954) (xy 167.404276 -284.832678) (xy 167.430579 -284.791082) (xy 167.463214 -284.754245)
			(xy 167.501335 -284.72312) (xy 167.543956 -284.698513) (xy 167.589972 -284.681061) (xy 167.638191 -284.671217)
			(xy 167.687366 -284.669236) (xy 167.736221 -284.675168) (xy 167.783492 -284.68886) (xy 167.827954 -284.709958)
			(xy 167.868457 -284.737914) (xy 167.90395 -284.772006) (xy 167.933515 -284.81135) (xy 167.956386 -284.854927)
			(xy 167.97197 -284.901608) (xy 167.979865 -284.950185) (xy 167.98036 -284.974792) (xy 168.319208 -284.974792)
			(xy 168.323168 -284.925738) (xy 168.334945 -284.877954) (xy 168.354236 -284.832678) (xy 168.380539 -284.791082)
			(xy 168.413174 -284.754245) (xy 168.451295 -284.72312) (xy 168.493916 -284.698513) (xy 168.539932 -284.681061)
			(xy 168.588151 -284.671217) (xy 168.637326 -284.669236) (xy 168.686181 -284.675168) (xy 168.733452 -284.68886)
			(xy 168.777914 -284.709958) (xy 168.818417 -284.737914) (xy 168.85391 -284.772006) (xy 168.883475 -284.81135)
			(xy 168.906346 -284.854927) (xy 168.92193 -284.901608) (xy 168.929825 -284.950185) (xy 168.93032 -284.974792)
			(xy 169.269168 -284.974792) (xy 169.273128 -284.925738) (xy 169.284905 -284.877954) (xy 169.304196 -284.832678)
			(xy 169.330499 -284.791082) (xy 169.363134 -284.754245) (xy 169.401255 -284.72312) (xy 169.443876 -284.698513)
			(xy 169.489892 -284.681061) (xy 169.538111 -284.671217) (xy 169.587286 -284.669236) (xy 169.636141 -284.675168)
			(xy 169.683412 -284.68886) (xy 169.727874 -284.709958) (xy 169.768377 -284.737914) (xy 169.80387 -284.772006)
			(xy 169.833435 -284.81135) (xy 169.856306 -284.854927) (xy 169.87189 -284.901608) (xy 169.879785 -284.950185)
			(xy 169.88028 -284.974792) (xy 170.219128 -284.974792) (xy 170.223088 -284.925738) (xy 170.234865 -284.877954)
			(xy 170.254156 -284.832678) (xy 170.280459 -284.791082) (xy 170.313094 -284.754245) (xy 170.351215 -284.72312)
			(xy 170.393836 -284.698513) (xy 170.439852 -284.681061) (xy 170.488071 -284.671217) (xy 170.537246 -284.669236)
			(xy 170.586101 -284.675168) (xy 170.633372 -284.68886) (xy 170.677834 -284.709958) (xy 170.718337 -284.737914)
			(xy 170.75383 -284.772006) (xy 170.783395 -284.81135) (xy 170.806266 -284.854927) (xy 170.82185 -284.901608)
			(xy 170.829745 -284.950185) (xy 170.83024 -284.974792) (xy 171.169088 -284.974792) (xy 171.173048 -284.925738)
			(xy 171.184825 -284.877954) (xy 171.204116 -284.832678) (xy 171.230419 -284.791082) (xy 171.263054 -284.754245)
			(xy 171.301175 -284.72312) (xy 171.343796 -284.698513) (xy 171.389812 -284.681061) (xy 171.438031 -284.671217)
			(xy 171.487206 -284.669236) (xy 171.536061 -284.675168) (xy 171.583332 -284.68886) (xy 171.627794 -284.709958)
			(xy 171.668297 -284.737914) (xy 171.70379 -284.772006) (xy 171.733355 -284.81135) (xy 171.756226 -284.854927)
			(xy 171.77181 -284.901608) (xy 171.779705 -284.950185) (xy 171.7802 -284.974792) (xy 172.119048 -284.974792)
			(xy 172.123008 -284.925738) (xy 172.134785 -284.877954) (xy 172.154076 -284.832678) (xy 172.180379 -284.791082)
			(xy 172.213014 -284.754245) (xy 172.251135 -284.72312) (xy 172.293756 -284.698513) (xy 172.339772 -284.681061)
			(xy 172.387991 -284.671217) (xy 172.437166 -284.669236) (xy 172.486021 -284.675168) (xy 172.533292 -284.68886)
			(xy 172.577754 -284.709958) (xy 172.618257 -284.737914) (xy 172.65375 -284.772006) (xy 172.683315 -284.81135)
			(xy 172.706186 -284.854927) (xy 172.72177 -284.901608) (xy 172.729665 -284.950185) (xy 172.73016 -284.974792)
			(xy 173.069262 -284.974792) (xy 173.073222 -284.925738) (xy 173.084999 -284.877954) (xy 173.10429 -284.832678)
			(xy 173.130593 -284.791082) (xy 173.163228 -284.754245) (xy 173.201349 -284.72312) (xy 173.24397 -284.698513)
			(xy 173.289986 -284.681061) (xy 173.338205 -284.671217) (xy 173.38738 -284.669236) (xy 173.436235 -284.675168)
			(xy 173.483506 -284.68886) (xy 173.527968 -284.709958) (xy 173.568471 -284.737914) (xy 173.603964 -284.772006)
			(xy 173.633529 -284.81135) (xy 173.6564 -284.854927) (xy 173.671984 -284.901608) (xy 173.679879 -284.950185)
			(xy 173.680374 -284.974792) (xy 174.019222 -284.974792) (xy 174.023182 -284.925738) (xy 174.034959 -284.877954)
			(xy 174.05425 -284.832678) (xy 174.080553 -284.791082) (xy 174.113188 -284.754245) (xy 174.151309 -284.72312)
			(xy 174.19393 -284.698513) (xy 174.239946 -284.681061) (xy 174.288165 -284.671217) (xy 174.33734 -284.669236)
			(xy 174.386195 -284.675168) (xy 174.433466 -284.68886) (xy 174.477928 -284.709958) (xy 174.518431 -284.737914)
			(xy 174.553924 -284.772006) (xy 174.583489 -284.81135) (xy 174.60636 -284.854927) (xy 174.621944 -284.901608)
			(xy 174.629839 -284.950185) (xy 174.630334 -284.974792) (xy 175.919142 -284.974792) (xy 175.923102 -284.925738)
			(xy 175.934879 -284.877954) (xy 175.95417 -284.832678) (xy 175.980473 -284.791082) (xy 176.013108 -284.754245)
			(xy 176.051229 -284.72312) (xy 176.09385 -284.698513) (xy 176.139866 -284.681061) (xy 176.188085 -284.671217)
			(xy 176.23726 -284.669236) (xy 176.286115 -284.675168) (xy 176.333386 -284.68886) (xy 176.377848 -284.709958)
			(xy 176.418351 -284.737914) (xy 176.453844 -284.772006) (xy 176.483409 -284.81135) (xy 176.50628 -284.854927)
			(xy 176.521864 -284.901608) (xy 176.529759 -284.950185) (xy 176.530254 -284.974792) (xy 176.869102 -284.974792)
			(xy 176.873062 -284.925738) (xy 176.884839 -284.877954) (xy 176.90413 -284.832678) (xy 176.930433 -284.791082)
			(xy 176.963068 -284.754245) (xy 177.001189 -284.72312) (xy 177.04381 -284.698513) (xy 177.089826 -284.681061)
			(xy 177.138045 -284.671217) (xy 177.18722 -284.669236) (xy 177.236075 -284.675168) (xy 177.283346 -284.68886)
			(xy 177.327808 -284.709958) (xy 177.368311 -284.737914) (xy 177.403804 -284.772006) (xy 177.433369 -284.81135)
			(xy 177.45624 -284.854927) (xy 177.471824 -284.901608) (xy 177.479719 -284.950185) (xy 177.480214 -284.974792)
			(xy 177.819062 -284.974792) (xy 177.823022 -284.925738) (xy 177.834799 -284.877954) (xy 177.85409 -284.832678)
			(xy 177.880393 -284.791082) (xy 177.913028 -284.754245) (xy 177.951149 -284.72312) (xy 177.99377 -284.698513)
			(xy 178.039786 -284.681061) (xy 178.088005 -284.671217) (xy 178.13718 -284.669236) (xy 178.186035 -284.675168)
			(xy 178.233306 -284.68886) (xy 178.277768 -284.709958) (xy 178.318271 -284.737914) (xy 178.353764 -284.772006)
			(xy 178.383329 -284.81135) (xy 178.4062 -284.854927) (xy 178.421784 -284.901608) (xy 178.429679 -284.950185)
			(xy 178.430174 -284.974792) (xy 178.769276 -284.974792) (xy 178.773236 -284.925738) (xy 178.785013 -284.877954)
			(xy 178.804304 -284.832678) (xy 178.830607 -284.791082) (xy 178.863242 -284.754245) (xy 178.901363 -284.72312)
			(xy 178.943984 -284.698513) (xy 178.99 -284.681061) (xy 179.038219 -284.671217) (xy 179.087394 -284.669236)
			(xy 179.136249 -284.675168) (xy 179.18352 -284.68886) (xy 179.227982 -284.709958) (xy 179.268485 -284.737914)
			(xy 179.303978 -284.772006) (xy 179.333543 -284.81135) (xy 179.356414 -284.854927) (xy 179.371998 -284.901608)
			(xy 179.379893 -284.950185) (xy 179.380388 -284.974792) (xy 179.719236 -284.974792) (xy 179.723196 -284.925738)
			(xy 179.734973 -284.877954) (xy 179.754264 -284.832678) (xy 179.780567 -284.791082) (xy 179.813202 -284.754245)
			(xy 179.851323 -284.72312) (xy 179.893944 -284.698513) (xy 179.93996 -284.681061) (xy 179.988179 -284.671217)
			(xy 180.037354 -284.669236) (xy 180.086209 -284.675168) (xy 180.13348 -284.68886) (xy 180.177942 -284.709958)
			(xy 180.218445 -284.737914) (xy 180.253938 -284.772006) (xy 180.283503 -284.81135) (xy 180.306374 -284.854927)
			(xy 180.321958 -284.901608) (xy 180.329853 -284.950185) (xy 180.330348 -284.974792) (xy 180.669196 -284.974792)
			(xy 180.673156 -284.925738) (xy 180.684933 -284.877954) (xy 180.704224 -284.832678) (xy 180.730527 -284.791082)
			(xy 180.763162 -284.754245) (xy 180.801283 -284.72312) (xy 180.843904 -284.698513) (xy 180.88992 -284.681061)
			(xy 180.938139 -284.671217) (xy 180.987314 -284.669236) (xy 181.036169 -284.675168) (xy 181.08344 -284.68886)
			(xy 181.127902 -284.709958) (xy 181.168405 -284.737914) (xy 181.203898 -284.772006) (xy 181.233463 -284.81135)
			(xy 181.256334 -284.854927) (xy 181.271918 -284.901608) (xy 181.279813 -284.950185) (xy 181.280308 -284.974792)
			(xy 181.619156 -284.974792) (xy 181.623116 -284.925738) (xy 181.634893 -284.877954) (xy 181.654184 -284.832678)
			(xy 181.680487 -284.791082) (xy 181.713122 -284.754245) (xy 181.751243 -284.72312) (xy 181.793864 -284.698513)
			(xy 181.83988 -284.681061) (xy 181.888099 -284.671217) (xy 181.937274 -284.669236) (xy 181.986129 -284.675168)
			(xy 182.0334 -284.68886) (xy 182.077862 -284.709958) (xy 182.118365 -284.737914) (xy 182.153858 -284.772006)
			(xy 182.183423 -284.81135) (xy 182.206294 -284.854927) (xy 182.221878 -284.901608) (xy 182.229773 -284.950185)
			(xy 182.230268 -284.974792) (xy 182.569116 -284.974792) (xy 182.573076 -284.925738) (xy 182.584853 -284.877954)
			(xy 182.604144 -284.832678) (xy 182.630447 -284.791082) (xy 182.663082 -284.754245) (xy 182.701203 -284.72312)
			(xy 182.743824 -284.698513) (xy 182.78984 -284.681061) (xy 182.838059 -284.671217) (xy 182.887234 -284.669236)
			(xy 182.936089 -284.675168) (xy 182.98336 -284.68886) (xy 183.027822 -284.709958) (xy 183.068325 -284.737914)
			(xy 183.103818 -284.772006) (xy 183.133383 -284.81135) (xy 183.156254 -284.854927) (xy 183.171838 -284.901608)
			(xy 183.179733 -284.950185) (xy 183.180228 -284.974792) (xy 183.519076 -284.974792) (xy 183.523036 -284.925738)
			(xy 183.534813 -284.877954) (xy 183.554104 -284.832678) (xy 183.580407 -284.791082) (xy 183.613042 -284.754245)
			(xy 183.651163 -284.72312) (xy 183.693784 -284.698513) (xy 183.7398 -284.681061) (xy 183.788019 -284.671217)
			(xy 183.837194 -284.669236) (xy 183.886049 -284.675168) (xy 183.93332 -284.68886) (xy 183.977782 -284.709958)
			(xy 184.018285 -284.737914) (xy 184.053778 -284.772006) (xy 184.083343 -284.81135) (xy 184.106214 -284.854927)
			(xy 184.121798 -284.901608) (xy 184.129693 -284.950185) (xy 184.130188 -284.974792) (xy 184.469036 -284.974792)
			(xy 184.472996 -284.925738) (xy 184.484773 -284.877954) (xy 184.504064 -284.832678) (xy 184.530367 -284.791082)
			(xy 184.563002 -284.754245) (xy 184.601123 -284.72312) (xy 184.643744 -284.698513) (xy 184.68976 -284.681061)
			(xy 184.737979 -284.671217) (xy 184.787154 -284.669236) (xy 184.836009 -284.675168) (xy 184.88328 -284.68886)
			(xy 184.927742 -284.709958) (xy 184.968245 -284.737914) (xy 185.003738 -284.772006) (xy 185.033303 -284.81135)
			(xy 185.056174 -284.854927) (xy 185.071758 -284.901608) (xy 185.079653 -284.950185) (xy 185.080148 -284.974792)
			(xy 185.41925 -284.974792) (xy 185.42321 -284.925738) (xy 185.434987 -284.877954) (xy 185.454278 -284.832678)
			(xy 185.480581 -284.791082) (xy 185.513216 -284.754245) (xy 185.551337 -284.72312) (xy 185.593958 -284.698513)
			(xy 185.639974 -284.681061) (xy 185.688193 -284.671217) (xy 185.737368 -284.669236) (xy 185.786223 -284.675168)
			(xy 185.833494 -284.68886) (xy 185.877956 -284.709958) (xy 185.918459 -284.737914) (xy 185.953952 -284.772006)
			(xy 185.983517 -284.81135) (xy 186.006388 -284.854927) (xy 186.021972 -284.901608) (xy 186.029867 -284.950185)
			(xy 186.030362 -284.974792) (xy 186.36921 -284.974792) (xy 186.37317 -284.925738) (xy 186.384947 -284.877954)
			(xy 186.404238 -284.832678) (xy 186.430541 -284.791082) (xy 186.463176 -284.754245) (xy 186.501297 -284.72312)
			(xy 186.543918 -284.698513) (xy 186.589934 -284.681061) (xy 186.638153 -284.671217) (xy 186.687328 -284.669236)
			(xy 186.736183 -284.675168) (xy 186.783454 -284.68886) (xy 186.827916 -284.709958) (xy 186.868419 -284.737914)
			(xy 186.903912 -284.772006) (xy 186.933477 -284.81135) (xy 186.956348 -284.854927) (xy 186.971932 -284.901608)
			(xy 186.979827 -284.950185) (xy 186.980322 -284.974792) (xy 186.979827 -284.999399) (xy 186.971932 -285.047976)
			(xy 186.956348 -285.094657) (xy 186.933477 -285.138234) (xy 186.903912 -285.177578) (xy 186.868419 -285.21167)
			(xy 186.827916 -285.239626) (xy 186.783454 -285.260724) (xy 186.736183 -285.274416) (xy 186.687328 -285.280348)
			(xy 186.638153 -285.278367) (xy 186.589934 -285.268523) (xy 186.543918 -285.251071) (xy 186.501297 -285.226464)
			(xy 186.463176 -285.195339) (xy 186.430541 -285.158502) (xy 186.404238 -285.116906) (xy 186.384947 -285.07163)
			(xy 186.37317 -285.023846) (xy 186.36921 -284.974792) (xy 186.030362 -284.974792) (xy 186.029867 -284.999399)
			(xy 186.021972 -285.047976) (xy 186.006388 -285.094657) (xy 185.983517 -285.138234) (xy 185.953952 -285.177578)
			(xy 185.918459 -285.21167) (xy 185.877956 -285.239626) (xy 185.833494 -285.260724) (xy 185.786223 -285.274416)
			(xy 185.737368 -285.280348) (xy 185.688193 -285.278367) (xy 185.639974 -285.268523) (xy 185.593958 -285.251071)
			(xy 185.551337 -285.226464) (xy 185.513216 -285.195339) (xy 185.480581 -285.158502) (xy 185.454278 -285.116906)
			(xy 185.434987 -285.07163) (xy 185.42321 -285.023846) (xy 185.41925 -284.974792) (xy 185.080148 -284.974792)
			(xy 185.079653 -284.999399) (xy 185.071758 -285.047976) (xy 185.056174 -285.094657) (xy 185.033303 -285.138234)
			(xy 185.003738 -285.177578) (xy 184.968245 -285.21167) (xy 184.927742 -285.239626) (xy 184.88328 -285.260724)
			(xy 184.836009 -285.274416) (xy 184.787154 -285.280348) (xy 184.737979 -285.278367) (xy 184.68976 -285.268523)
			(xy 184.643744 -285.251071) (xy 184.601123 -285.226464) (xy 184.563002 -285.195339) (xy 184.530367 -285.158502)
			(xy 184.504064 -285.116906) (xy 184.484773 -285.07163) (xy 184.472996 -285.023846) (xy 184.469036 -284.974792)
			(xy 184.130188 -284.974792) (xy 184.129693 -284.999399) (xy 184.121798 -285.047976) (xy 184.106214 -285.094657)
			(xy 184.083343 -285.138234) (xy 184.053778 -285.177578) (xy 184.018285 -285.21167) (xy 183.977782 -285.239626)
			(xy 183.93332 -285.260724) (xy 183.886049 -285.274416) (xy 183.837194 -285.280348) (xy 183.788019 -285.278367)
			(xy 183.7398 -285.268523) (xy 183.693784 -285.251071) (xy 183.651163 -285.226464) (xy 183.613042 -285.195339)
			(xy 183.580407 -285.158502) (xy 183.554104 -285.116906) (xy 183.534813 -285.07163) (xy 183.523036 -285.023846)
			(xy 183.519076 -284.974792) (xy 183.180228 -284.974792) (xy 183.179733 -284.999399) (xy 183.171838 -285.047976)
			(xy 183.156254 -285.094657) (xy 183.133383 -285.138234) (xy 183.103818 -285.177578) (xy 183.068325 -285.21167)
			(xy 183.027822 -285.239626) (xy 182.98336 -285.260724) (xy 182.936089 -285.274416) (xy 182.887234 -285.280348)
			(xy 182.838059 -285.278367) (xy 182.78984 -285.268523) (xy 182.743824 -285.251071) (xy 182.701203 -285.226464)
			(xy 182.663082 -285.195339) (xy 182.630447 -285.158502) (xy 182.604144 -285.116906) (xy 182.584853 -285.07163)
			(xy 182.573076 -285.023846) (xy 182.569116 -284.974792) (xy 182.230268 -284.974792) (xy 182.229773 -284.999399)
			(xy 182.221878 -285.047976) (xy 182.206294 -285.094657) (xy 182.183423 -285.138234) (xy 182.153858 -285.177578)
			(xy 182.118365 -285.21167) (xy 182.077862 -285.239626) (xy 182.0334 -285.260724) (xy 181.986129 -285.274416)
			(xy 181.937274 -285.280348) (xy 181.888099 -285.278367) (xy 181.83988 -285.268523) (xy 181.793864 -285.251071)
			(xy 181.751243 -285.226464) (xy 181.713122 -285.195339) (xy 181.680487 -285.158502) (xy 181.654184 -285.116906)
			(xy 181.634893 -285.07163) (xy 181.623116 -285.023846) (xy 181.619156 -284.974792) (xy 181.280308 -284.974792)
			(xy 181.279813 -284.999399) (xy 181.271918 -285.047976) (xy 181.256334 -285.094657) (xy 181.233463 -285.138234)
			(xy 181.203898 -285.177578) (xy 181.168405 -285.21167) (xy 181.127902 -285.239626) (xy 181.08344 -285.260724)
			(xy 181.036169 -285.274416) (xy 180.987314 -285.280348) (xy 180.938139 -285.278367) (xy 180.88992 -285.268523)
			(xy 180.843904 -285.251071) (xy 180.801283 -285.226464) (xy 180.763162 -285.195339) (xy 180.730527 -285.158502)
			(xy 180.704224 -285.116906) (xy 180.684933 -285.07163) (xy 180.673156 -285.023846) (xy 180.669196 -284.974792)
			(xy 180.330348 -284.974792) (xy 180.329853 -284.999399) (xy 180.321958 -285.047976) (xy 180.306374 -285.094657)
			(xy 180.283503 -285.138234) (xy 180.253938 -285.177578) (xy 180.218445 -285.21167) (xy 180.177942 -285.239626)
			(xy 180.13348 -285.260724) (xy 180.086209 -285.274416) (xy 180.037354 -285.280348) (xy 179.988179 -285.278367)
			(xy 179.93996 -285.268523) (xy 179.893944 -285.251071) (xy 179.851323 -285.226464) (xy 179.813202 -285.195339)
			(xy 179.780567 -285.158502) (xy 179.754264 -285.116906) (xy 179.734973 -285.07163) (xy 179.723196 -285.023846)
			(xy 179.719236 -284.974792) (xy 179.380388 -284.974792) (xy 179.379893 -284.999399) (xy 179.371998 -285.047976)
			(xy 179.356414 -285.094657) (xy 179.333543 -285.138234) (xy 179.303978 -285.177578) (xy 179.268485 -285.21167)
			(xy 179.227982 -285.239626) (xy 179.18352 -285.260724) (xy 179.136249 -285.274416) (xy 179.087394 -285.280348)
			(xy 179.038219 -285.278367) (xy 178.99 -285.268523) (xy 178.943984 -285.251071) (xy 178.901363 -285.226464)
			(xy 178.863242 -285.195339) (xy 178.830607 -285.158502) (xy 178.804304 -285.116906) (xy 178.785013 -285.07163)
			(xy 178.773236 -285.023846) (xy 178.769276 -284.974792) (xy 178.430174 -284.974792) (xy 178.429679 -284.999399)
			(xy 178.421784 -285.047976) (xy 178.4062 -285.094657) (xy 178.383329 -285.138234) (xy 178.353764 -285.177578)
			(xy 178.318271 -285.21167) (xy 178.277768 -285.239626) (xy 178.233306 -285.260724) (xy 178.186035 -285.274416)
			(xy 178.13718 -285.280348) (xy 178.088005 -285.278367) (xy 178.039786 -285.268523) (xy 177.99377 -285.251071)
			(xy 177.951149 -285.226464) (xy 177.913028 -285.195339) (xy 177.880393 -285.158502) (xy 177.85409 -285.116906)
			(xy 177.834799 -285.07163) (xy 177.823022 -285.023846) (xy 177.819062 -284.974792) (xy 177.480214 -284.974792)
			(xy 177.479719 -284.999399) (xy 177.471824 -285.047976) (xy 177.45624 -285.094657) (xy 177.433369 -285.138234)
			(xy 177.403804 -285.177578) (xy 177.368311 -285.21167) (xy 177.327808 -285.239626) (xy 177.283346 -285.260724)
			(xy 177.236075 -285.274416) (xy 177.18722 -285.280348) (xy 177.138045 -285.278367) (xy 177.089826 -285.268523)
			(xy 177.04381 -285.251071) (xy 177.001189 -285.226464) (xy 176.963068 -285.195339) (xy 176.930433 -285.158502)
			(xy 176.90413 -285.116906) (xy 176.884839 -285.07163) (xy 176.873062 -285.023846) (xy 176.869102 -284.974792)
			(xy 176.530254 -284.974792) (xy 176.529759 -284.999399) (xy 176.521864 -285.047976) (xy 176.50628 -285.094657)
			(xy 176.483409 -285.138234) (xy 176.453844 -285.177578) (xy 176.418351 -285.21167) (xy 176.377848 -285.239626)
			(xy 176.333386 -285.260724) (xy 176.286115 -285.274416) (xy 176.23726 -285.280348) (xy 176.188085 -285.278367)
			(xy 176.139866 -285.268523) (xy 176.09385 -285.251071) (xy 176.051229 -285.226464) (xy 176.013108 -285.195339)
			(xy 175.980473 -285.158502) (xy 175.95417 -285.116906) (xy 175.934879 -285.07163) (xy 175.923102 -285.023846)
			(xy 175.919142 -284.974792) (xy 174.630334 -284.974792) (xy 174.629839 -284.999399) (xy 174.621944 -285.047976)
			(xy 174.60636 -285.094657) (xy 174.583489 -285.138234) (xy 174.553924 -285.177578) (xy 174.518431 -285.21167)
			(xy 174.477928 -285.239626) (xy 174.433466 -285.260724) (xy 174.386195 -285.274416) (xy 174.33734 -285.280348)
			(xy 174.288165 -285.278367) (xy 174.239946 -285.268523) (xy 174.19393 -285.251071) (xy 174.151309 -285.226464)
			(xy 174.113188 -285.195339) (xy 174.080553 -285.158502) (xy 174.05425 -285.116906) (xy 174.034959 -285.07163)
			(xy 174.023182 -285.023846) (xy 174.019222 -284.974792) (xy 173.680374 -284.974792) (xy 173.679879 -284.999399)
			(xy 173.671984 -285.047976) (xy 173.6564 -285.094657) (xy 173.633529 -285.138234) (xy 173.603964 -285.177578)
			(xy 173.568471 -285.21167) (xy 173.527968 -285.239626) (xy 173.483506 -285.260724) (xy 173.436235 -285.274416)
			(xy 173.38738 -285.280348) (xy 173.338205 -285.278367) (xy 173.289986 -285.268523) (xy 173.24397 -285.251071)
			(xy 173.201349 -285.226464) (xy 173.163228 -285.195339) (xy 173.130593 -285.158502) (xy 173.10429 -285.116906)
			(xy 173.084999 -285.07163) (xy 173.073222 -285.023846) (xy 173.069262 -284.974792) (xy 172.73016 -284.974792)
			(xy 172.729665 -284.999399) (xy 172.72177 -285.047976) (xy 172.706186 -285.094657) (xy 172.683315 -285.138234)
			(xy 172.65375 -285.177578) (xy 172.618257 -285.21167) (xy 172.577754 -285.239626) (xy 172.533292 -285.260724)
			(xy 172.486021 -285.274416) (xy 172.437166 -285.280348) (xy 172.387991 -285.278367) (xy 172.339772 -285.268523)
			(xy 172.293756 -285.251071) (xy 172.251135 -285.226464) (xy 172.213014 -285.195339) (xy 172.180379 -285.158502)
			(xy 172.154076 -285.116906) (xy 172.134785 -285.07163) (xy 172.123008 -285.023846) (xy 172.119048 -284.974792)
			(xy 171.7802 -284.974792) (xy 171.779705 -284.999399) (xy 171.77181 -285.047976) (xy 171.756226 -285.094657)
			(xy 171.733355 -285.138234) (xy 171.70379 -285.177578) (xy 171.668297 -285.21167) (xy 171.627794 -285.239626)
			(xy 171.583332 -285.260724) (xy 171.536061 -285.274416) (xy 171.487206 -285.280348) (xy 171.438031 -285.278367)
			(xy 171.389812 -285.268523) (xy 171.343796 -285.251071) (xy 171.301175 -285.226464) (xy 171.263054 -285.195339)
			(xy 171.230419 -285.158502) (xy 171.204116 -285.116906) (xy 171.184825 -285.07163) (xy 171.173048 -285.023846)
			(xy 171.169088 -284.974792) (xy 170.83024 -284.974792) (xy 170.829745 -284.999399) (xy 170.82185 -285.047976)
			(xy 170.806266 -285.094657) (xy 170.783395 -285.138234) (xy 170.75383 -285.177578) (xy 170.718337 -285.21167)
			(xy 170.677834 -285.239626) (xy 170.633372 -285.260724) (xy 170.586101 -285.274416) (xy 170.537246 -285.280348)
			(xy 170.488071 -285.278367) (xy 170.439852 -285.268523) (xy 170.393836 -285.251071) (xy 170.351215 -285.226464)
			(xy 170.313094 -285.195339) (xy 170.280459 -285.158502) (xy 170.254156 -285.116906) (xy 170.234865 -285.07163)
			(xy 170.223088 -285.023846) (xy 170.219128 -284.974792) (xy 169.88028 -284.974792) (xy 169.879785 -284.999399)
			(xy 169.87189 -285.047976) (xy 169.856306 -285.094657) (xy 169.833435 -285.138234) (xy 169.80387 -285.177578)
			(xy 169.768377 -285.21167) (xy 169.727874 -285.239626) (xy 169.683412 -285.260724) (xy 169.636141 -285.274416)
			(xy 169.587286 -285.280348) (xy 169.538111 -285.278367) (xy 169.489892 -285.268523) (xy 169.443876 -285.251071)
			(xy 169.401255 -285.226464) (xy 169.363134 -285.195339) (xy 169.330499 -285.158502) (xy 169.304196 -285.116906)
			(xy 169.284905 -285.07163) (xy 169.273128 -285.023846) (xy 169.269168 -284.974792) (xy 168.93032 -284.974792)
			(xy 168.929825 -284.999399) (xy 168.92193 -285.047976) (xy 168.906346 -285.094657) (xy 168.883475 -285.138234)
			(xy 168.85391 -285.177578) (xy 168.818417 -285.21167) (xy 168.777914 -285.239626) (xy 168.733452 -285.260724)
			(xy 168.686181 -285.274416) (xy 168.637326 -285.280348) (xy 168.588151 -285.278367) (xy 168.539932 -285.268523)
			(xy 168.493916 -285.251071) (xy 168.451295 -285.226464) (xy 168.413174 -285.195339) (xy 168.380539 -285.158502)
			(xy 168.354236 -285.116906) (xy 168.334945 -285.07163) (xy 168.323168 -285.023846) (xy 168.319208 -284.974792)
			(xy 167.98036 -284.974792) (xy 167.979865 -284.999399) (xy 167.97197 -285.047976) (xy 167.956386 -285.094657)
			(xy 167.933515 -285.138234) (xy 167.90395 -285.177578) (xy 167.868457 -285.21167) (xy 167.827954 -285.239626)
			(xy 167.783492 -285.260724) (xy 167.736221 -285.274416) (xy 167.687366 -285.280348) (xy 167.638191 -285.278367)
			(xy 167.589972 -285.268523) (xy 167.543956 -285.251071) (xy 167.501335 -285.226464) (xy 167.463214 -285.195339)
			(xy 167.430579 -285.158502) (xy 167.404276 -285.116906) (xy 167.384985 -285.07163) (xy 167.373208 -285.023846)
			(xy 167.369248 -284.974792) (xy 167.0304 -284.974792) (xy 167.029905 -284.999399) (xy 167.02201 -285.047976)
			(xy 167.006426 -285.094657) (xy 166.983555 -285.138234) (xy 166.95399 -285.177578) (xy 166.918497 -285.21167)
			(xy 166.877994 -285.239626) (xy 166.833532 -285.260724) (xy 166.786261 -285.274416) (xy 166.737406 -285.280348)
			(xy 166.688231 -285.278367) (xy 166.640012 -285.268523) (xy 166.593996 -285.251071) (xy 166.551375 -285.226464)
			(xy 166.513254 -285.195339) (xy 166.480619 -285.158502) (xy 166.454316 -285.116906) (xy 166.435025 -285.07163)
			(xy 166.423248 -285.023846) (xy 166.419288 -284.974792) (xy 166.080186 -284.974792) (xy 166.079691 -284.999399)
			(xy 166.071796 -285.047976) (xy 166.056212 -285.094657) (xy 166.033341 -285.138234) (xy 166.003776 -285.177578)
			(xy 165.968283 -285.21167) (xy 165.92778 -285.239626) (xy 165.883318 -285.260724) (xy 165.836047 -285.274416)
			(xy 165.787192 -285.280348) (xy 165.738017 -285.278367) (xy 165.689798 -285.268523) (xy 165.643782 -285.251071)
			(xy 165.601161 -285.226464) (xy 165.56304 -285.195339) (xy 165.530405 -285.158502) (xy 165.504102 -285.116906)
			(xy 165.484811 -285.07163) (xy 165.473034 -285.023846) (xy 165.469074 -284.974792) (xy 165.130226 -284.974792)
			(xy 165.129731 -284.999399) (xy 165.121836 -285.047976) (xy 165.106252 -285.094657) (xy 165.083381 -285.138234)
			(xy 165.053816 -285.177578) (xy 165.018323 -285.21167) (xy 164.97782 -285.239626) (xy 164.933358 -285.260724)
			(xy 164.886087 -285.274416) (xy 164.837232 -285.280348) (xy 164.788057 -285.278367) (xy 164.739838 -285.268523)
			(xy 164.693822 -285.251071) (xy 164.651201 -285.226464) (xy 164.61308 -285.195339) (xy 164.580445 -285.158502)
			(xy 164.554142 -285.116906) (xy 164.534851 -285.07163) (xy 164.523074 -285.023846) (xy 164.519114 -284.974792)
			(xy 164.180266 -284.974792) (xy 164.179771 -284.999399) (xy 164.171876 -285.047976) (xy 164.156292 -285.094657)
			(xy 164.133421 -285.138234) (xy 164.103856 -285.177578) (xy 164.068363 -285.21167) (xy 164.02786 -285.239626)
			(xy 163.983398 -285.260724) (xy 163.936127 -285.274416) (xy 163.887272 -285.280348) (xy 163.838097 -285.278367)
			(xy 163.789878 -285.268523) (xy 163.743862 -285.251071) (xy 163.701241 -285.226464) (xy 163.66312 -285.195339)
			(xy 163.630485 -285.158502) (xy 163.604182 -285.116906) (xy 163.584891 -285.07163) (xy 163.573114 -285.023846)
			(xy 163.569154 -284.974792) (xy 163.230306 -284.974792) (xy 163.229811 -284.999399) (xy 163.221916 -285.047976)
			(xy 163.206332 -285.094657) (xy 163.183461 -285.138234) (xy 163.153896 -285.177578) (xy 163.118403 -285.21167)
			(xy 163.0779 -285.239626) (xy 163.033438 -285.260724) (xy 162.986167 -285.274416) (xy 162.937312 -285.280348)
			(xy 162.888137 -285.278367) (xy 162.839918 -285.268523) (xy 162.793902 -285.251071) (xy 162.751281 -285.226464)
			(xy 162.71316 -285.195339) (xy 162.680525 -285.158502) (xy 162.654222 -285.116906) (xy 162.634931 -285.07163)
			(xy 162.623154 -285.023846) (xy 162.619194 -284.974792) (xy 162.280346 -284.974792) (xy 162.279851 -284.999399)
			(xy 162.271956 -285.047976) (xy 162.256372 -285.094657) (xy 162.233501 -285.138234) (xy 162.203936 -285.177578)
			(xy 162.168443 -285.21167) (xy 162.12794 -285.239626) (xy 162.083478 -285.260724) (xy 162.036207 -285.274416)
			(xy 161.987352 -285.280348) (xy 161.938177 -285.278367) (xy 161.889958 -285.268523) (xy 161.843942 -285.251071)
			(xy 161.801321 -285.226464) (xy 161.7632 -285.195339) (xy 161.730565 -285.158502) (xy 161.704262 -285.116906)
			(xy 161.684971 -285.07163) (xy 161.673194 -285.023846) (xy 161.669234 -284.974792) (xy 161.330386 -284.974792)
			(xy 161.329891 -284.999399) (xy 161.321996 -285.047976) (xy 161.306412 -285.094657) (xy 161.283541 -285.138234)
			(xy 161.253976 -285.177578) (xy 161.218483 -285.21167) (xy 161.17798 -285.239626) (xy 161.133518 -285.260724)
			(xy 161.086247 -285.274416) (xy 161.037392 -285.280348) (xy 160.988217 -285.278367) (xy 160.939998 -285.268523)
			(xy 160.893982 -285.251071) (xy 160.851361 -285.226464) (xy 160.81324 -285.195339) (xy 160.780605 -285.158502)
			(xy 160.754302 -285.116906) (xy 160.735011 -285.07163) (xy 160.723234 -285.023846) (xy 160.719274 -284.974792)
			(xy 159.430212 -284.974792) (xy 159.429717 -284.999399) (xy 159.421822 -285.047976) (xy 159.406238 -285.094657)
			(xy 159.383367 -285.138234) (xy 159.353802 -285.177578) (xy 159.318309 -285.21167) (xy 159.277806 -285.239626)
			(xy 159.233344 -285.260724) (xy 159.186073 -285.274416) (xy 159.137218 -285.280348) (xy 159.088043 -285.278367)
			(xy 159.039824 -285.268523) (xy 158.993808 -285.251071) (xy 158.951187 -285.226464) (xy 158.913066 -285.195339)
			(xy 158.880431 -285.158502) (xy 158.854128 -285.116906) (xy 158.834837 -285.07163) (xy 158.82306 -285.023846)
			(xy 158.8191 -284.974792) (xy 157.530292 -284.974792) (xy 157.529797 -284.999399) (xy 157.521902 -285.047976)
			(xy 157.506318 -285.094657) (xy 157.483447 -285.138234) (xy 157.453882 -285.177578) (xy 157.418389 -285.21167)
			(xy 157.377886 -285.239626) (xy 157.333424 -285.260724) (xy 157.286153 -285.274416) (xy 157.237298 -285.280348)
			(xy 157.188123 -285.278367) (xy 157.139904 -285.268523) (xy 157.093888 -285.251071) (xy 157.051267 -285.226464)
			(xy 157.013146 -285.195339) (xy 156.980511 -285.158502) (xy 156.954208 -285.116906) (xy 156.934917 -285.07163)
			(xy 156.92314 -285.023846) (xy 156.91918 -284.974792) (xy 156.580332 -284.974792) (xy 156.579837 -284.999399)
			(xy 156.571942 -285.047976) (xy 156.556358 -285.094657) (xy 156.533487 -285.138234) (xy 156.503922 -285.177578)
			(xy 156.468429 -285.21167) (xy 156.427926 -285.239626) (xy 156.383464 -285.260724) (xy 156.336193 -285.274416)
			(xy 156.287338 -285.280348) (xy 156.238163 -285.278367) (xy 156.189944 -285.268523) (xy 156.143928 -285.251071)
			(xy 156.101307 -285.226464) (xy 156.063186 -285.195339) (xy 156.030551 -285.158502) (xy 156.004248 -285.116906)
			(xy 155.984957 -285.07163) (xy 155.97318 -285.023846) (xy 155.96922 -284.974792) (xy 155.630372 -284.974792)
			(xy 155.629877 -284.999399) (xy 155.621982 -285.047976) (xy 155.606398 -285.094657) (xy 155.583527 -285.138234)
			(xy 155.553962 -285.177578) (xy 155.518469 -285.21167) (xy 155.477966 -285.239626) (xy 155.433504 -285.260724)
			(xy 155.386233 -285.274416) (xy 155.337378 -285.280348) (xy 155.288203 -285.278367) (xy 155.239984 -285.268523)
			(xy 155.193968 -285.251071) (xy 155.151347 -285.226464) (xy 155.113226 -285.195339) (xy 155.080591 -285.158502)
			(xy 155.054288 -285.116906) (xy 155.034997 -285.07163) (xy 155.02322 -285.023846) (xy 155.01926 -284.974792)
			(xy 154.680412 -284.974792) (xy 154.679917 -284.999399) (xy 154.672022 -285.047976) (xy 154.656438 -285.094657)
			(xy 154.633567 -285.138234) (xy 154.604002 -285.177578) (xy 154.568509 -285.21167) (xy 154.528006 -285.239626)
			(xy 154.483544 -285.260724) (xy 154.436273 -285.274416) (xy 154.387418 -285.280348) (xy 154.338243 -285.278367)
			(xy 154.290024 -285.268523) (xy 154.244008 -285.251071) (xy 154.201387 -285.226464) (xy 154.163266 -285.195339)
			(xy 154.130631 -285.158502) (xy 154.104328 -285.116906) (xy 154.085037 -285.07163) (xy 154.07326 -285.023846)
			(xy 154.0693 -284.974792) (xy 153.730198 -284.974792) (xy 153.729703 -284.999399) (xy 153.721808 -285.047976)
			(xy 153.706224 -285.094657) (xy 153.683353 -285.138234) (xy 153.653788 -285.177578) (xy 153.618295 -285.21167)
			(xy 153.577792 -285.239626) (xy 153.53333 -285.260724) (xy 153.486059 -285.274416) (xy 153.437204 -285.280348)
			(xy 153.388029 -285.278367) (xy 153.33981 -285.268523) (xy 153.293794 -285.251071) (xy 153.251173 -285.226464)
			(xy 153.213052 -285.195339) (xy 153.180417 -285.158502) (xy 153.154114 -285.116906) (xy 153.134823 -285.07163)
			(xy 153.123046 -285.023846) (xy 153.119086 -284.974792) (xy 152.805107 -284.974792) (xy 152.805107 -285.000786)
			(xy 152.796977 -285.052119) (xy 152.780917 -285.101548) (xy 152.757323 -285.147857) (xy 152.726776 -285.189905)
			(xy 152.690028 -285.226657) (xy 152.647983 -285.257208) (xy 152.601676 -285.280806) (xy 152.552248 -285.29687)
			(xy 152.500916 -285.305004) (xy 152.47493 -285.3055) (xy 152.474422 -285.3055) (xy 152.448246 -285.305002)
			(xy 152.39655 -285.296748) (xy 152.346803 -285.280442) (xy 152.323292 -285.268924) (xy 152.323038 -285.268924)
			(xy 152.317197 -285.266169) (xy 152.304603 -285.263332) (xy 152.298146 -285.263336) (xy 152.284938 -285.263844)
			(xy 152.204928 -285.312866) (xy 152.19553 -285.320232) (xy 152.18664 -285.329122) (xy 152.18283 -285.338266)
			(xy 152.178004 -285.348172) (xy 152.178004 -285.537148) (xy 152.178072 -285.540954) (xy 152.179223 -285.54848)
			(xy 152.18029 -285.552134) (xy 152.182576 -285.5595) (xy 152.189688 -285.575248) (xy 152.195784 -285.580582)
			(xy 152.199086 -285.583122) (xy 152.276048 -285.630366) (xy 152.290526 -285.63062) (xy 152.30602 -285.63062)
			(xy 152.312624 -285.630112) (xy 152.332944 -285.625794) (xy 152.338024 -285.623508) (xy 152.359549 -285.61421)
			(xy 152.404564 -285.601092) (xy 152.450979 -285.594453) (xy 152.474422 -285.594044) (xy 152.47493 -285.594044)
			(xy 152.500919 -285.594556) (xy 152.552258 -285.602691) (xy 152.601691 -285.618757) (xy 152.648003 -285.642358)
			(xy 152.690054 -285.672913) (xy 152.726807 -285.709669) (xy 152.757357 -285.751722) (xy 152.780954 -285.798036)
			(xy 152.797016 -285.847472) (xy 152.805146 -285.898811) (xy 152.805146 -285.924752) (xy 153.119086 -285.924752)
			(xy 153.123046 -285.875698) (xy 153.134823 -285.827914) (xy 153.154114 -285.782638) (xy 153.180417 -285.741042)
			(xy 153.213052 -285.704205) (xy 153.251173 -285.67308) (xy 153.293794 -285.648473) (xy 153.33981 -285.631021)
			(xy 153.388029 -285.621177) (xy 153.437204 -285.619196) (xy 153.486059 -285.625128) (xy 153.53333 -285.63882)
			(xy 153.577792 -285.659918) (xy 153.618295 -285.687874) (xy 153.653788 -285.721966) (xy 153.683353 -285.76131)
			(xy 153.706224 -285.804887) (xy 153.721808 -285.851568) (xy 153.729703 -285.900145) (xy 153.730198 -285.924752)
			(xy 154.0693 -285.924752) (xy 154.07326 -285.875698) (xy 154.085037 -285.827914) (xy 154.104328 -285.782638)
			(xy 154.130631 -285.741042) (xy 154.163266 -285.704205) (xy 154.201387 -285.67308) (xy 154.244008 -285.648473)
			(xy 154.290024 -285.631021) (xy 154.338243 -285.621177) (xy 154.387418 -285.619196) (xy 154.436273 -285.625128)
			(xy 154.483544 -285.63882) (xy 154.528006 -285.659918) (xy 154.568509 -285.687874) (xy 154.604002 -285.721966)
			(xy 154.633567 -285.76131) (xy 154.656438 -285.804887) (xy 154.672022 -285.851568) (xy 154.679917 -285.900145)
			(xy 154.680412 -285.924752) (xy 155.01926 -285.924752) (xy 155.02322 -285.875698) (xy 155.034997 -285.827914)
			(xy 155.054288 -285.782638) (xy 155.080591 -285.741042) (xy 155.113226 -285.704205) (xy 155.151347 -285.67308)
			(xy 155.193968 -285.648473) (xy 155.239984 -285.631021) (xy 155.288203 -285.621177) (xy 155.337378 -285.619196)
			(xy 155.386233 -285.625128) (xy 155.433504 -285.63882) (xy 155.477966 -285.659918) (xy 155.518469 -285.687874)
			(xy 155.553962 -285.721966) (xy 155.583527 -285.76131) (xy 155.606398 -285.804887) (xy 155.621982 -285.851568)
			(xy 155.629877 -285.900145) (xy 155.630372 -285.924752) (xy 155.96922 -285.924752) (xy 155.97318 -285.875698)
			(xy 155.984957 -285.827914) (xy 156.004248 -285.782638) (xy 156.030551 -285.741042) (xy 156.063186 -285.704205)
			(xy 156.101307 -285.67308) (xy 156.143928 -285.648473) (xy 156.189944 -285.631021) (xy 156.238163 -285.621177)
			(xy 156.287338 -285.619196) (xy 156.336193 -285.625128) (xy 156.383464 -285.63882) (xy 156.427926 -285.659918)
			(xy 156.468429 -285.687874) (xy 156.503922 -285.721966) (xy 156.533487 -285.76131) (xy 156.556358 -285.804887)
			(xy 156.571942 -285.851568) (xy 156.579837 -285.900145) (xy 156.580332 -285.924752) (xy 156.91918 -285.924752)
			(xy 156.92314 -285.875698) (xy 156.934917 -285.827914) (xy 156.954208 -285.782638) (xy 156.980511 -285.741042)
			(xy 157.013146 -285.704205) (xy 157.051267 -285.67308) (xy 157.093888 -285.648473) (xy 157.139904 -285.631021)
			(xy 157.188123 -285.621177) (xy 157.237298 -285.619196) (xy 157.286153 -285.625128) (xy 157.333424 -285.63882)
			(xy 157.377886 -285.659918) (xy 157.418389 -285.687874) (xy 157.453882 -285.721966) (xy 157.483447 -285.76131)
			(xy 157.506318 -285.804887) (xy 157.521902 -285.851568) (xy 157.529797 -285.900145) (xy 157.530292 -285.924752)
			(xy 160.719274 -285.924752) (xy 160.723234 -285.875698) (xy 160.735011 -285.827914) (xy 160.754302 -285.782638)
			(xy 160.780605 -285.741042) (xy 160.81324 -285.704205) (xy 160.851361 -285.67308) (xy 160.893982 -285.648473)
			(xy 160.939998 -285.631021) (xy 160.988217 -285.621177) (xy 161.037392 -285.619196) (xy 161.086247 -285.625128)
			(xy 161.133518 -285.63882) (xy 161.17798 -285.659918) (xy 161.218483 -285.687874) (xy 161.253976 -285.721966)
			(xy 161.283541 -285.76131) (xy 161.306412 -285.804887) (xy 161.321996 -285.851568) (xy 161.329891 -285.900145)
			(xy 161.330386 -285.924752) (xy 161.669234 -285.924752) (xy 161.673194 -285.875698) (xy 161.684971 -285.827914)
			(xy 161.704262 -285.782638) (xy 161.730565 -285.741042) (xy 161.7632 -285.704205) (xy 161.801321 -285.67308)
			(xy 161.843942 -285.648473) (xy 161.889958 -285.631021) (xy 161.938177 -285.621177) (xy 161.987352 -285.619196)
			(xy 162.036207 -285.625128) (xy 162.083478 -285.63882) (xy 162.12794 -285.659918) (xy 162.168443 -285.687874)
			(xy 162.203936 -285.721966) (xy 162.233501 -285.76131) (xy 162.256372 -285.804887) (xy 162.271956 -285.851568)
			(xy 162.279851 -285.900145) (xy 162.280346 -285.924752) (xy 162.619194 -285.924752) (xy 162.623154 -285.875698)
			(xy 162.634931 -285.827914) (xy 162.654222 -285.782638) (xy 162.680525 -285.741042) (xy 162.71316 -285.704205)
			(xy 162.751281 -285.67308) (xy 162.793902 -285.648473) (xy 162.839918 -285.631021) (xy 162.888137 -285.621177)
			(xy 162.937312 -285.619196) (xy 162.986167 -285.625128) (xy 163.033438 -285.63882) (xy 163.0779 -285.659918)
			(xy 163.118403 -285.687874) (xy 163.153896 -285.721966) (xy 163.183461 -285.76131) (xy 163.206332 -285.804887)
			(xy 163.221916 -285.851568) (xy 163.229811 -285.900145) (xy 163.230306 -285.924752) (xy 163.569154 -285.924752)
			(xy 163.573114 -285.875698) (xy 163.584891 -285.827914) (xy 163.604182 -285.782638) (xy 163.630485 -285.741042)
			(xy 163.66312 -285.704205) (xy 163.701241 -285.67308) (xy 163.743862 -285.648473) (xy 163.789878 -285.631021)
			(xy 163.838097 -285.621177) (xy 163.887272 -285.619196) (xy 163.936127 -285.625128) (xy 163.983398 -285.63882)
			(xy 164.02786 -285.659918) (xy 164.068363 -285.687874) (xy 164.103856 -285.721966) (xy 164.133421 -285.76131)
			(xy 164.156292 -285.804887) (xy 164.171876 -285.851568) (xy 164.179771 -285.900145) (xy 164.180266 -285.924752)
			(xy 164.519114 -285.924752) (xy 164.523074 -285.875698) (xy 164.534851 -285.827914) (xy 164.554142 -285.782638)
			(xy 164.580445 -285.741042) (xy 164.61308 -285.704205) (xy 164.651201 -285.67308) (xy 164.693822 -285.648473)
			(xy 164.739838 -285.631021) (xy 164.788057 -285.621177) (xy 164.837232 -285.619196) (xy 164.886087 -285.625128)
			(xy 164.933358 -285.63882) (xy 164.97782 -285.659918) (xy 165.018323 -285.687874) (xy 165.053816 -285.721966)
			(xy 165.083381 -285.76131) (xy 165.106252 -285.804887) (xy 165.121836 -285.851568) (xy 165.129731 -285.900145)
			(xy 165.130226 -285.924752) (xy 165.469074 -285.924752) (xy 165.473034 -285.875698) (xy 165.484811 -285.827914)
			(xy 165.504102 -285.782638) (xy 165.530405 -285.741042) (xy 165.56304 -285.704205) (xy 165.601161 -285.67308)
			(xy 165.643782 -285.648473) (xy 165.689798 -285.631021) (xy 165.738017 -285.621177) (xy 165.787192 -285.619196)
			(xy 165.836047 -285.625128) (xy 165.883318 -285.63882) (xy 165.92778 -285.659918) (xy 165.968283 -285.687874)
			(xy 166.003776 -285.721966) (xy 166.033341 -285.76131) (xy 166.056212 -285.804887) (xy 166.071796 -285.851568)
			(xy 166.079691 -285.900145) (xy 166.080186 -285.924752) (xy 166.419288 -285.924752) (xy 166.423248 -285.875698)
			(xy 166.435025 -285.827914) (xy 166.454316 -285.782638) (xy 166.480619 -285.741042) (xy 166.513254 -285.704205)
			(xy 166.551375 -285.67308) (xy 166.593996 -285.648473) (xy 166.640012 -285.631021) (xy 166.688231 -285.621177)
			(xy 166.737406 -285.619196) (xy 166.786261 -285.625128) (xy 166.833532 -285.63882) (xy 166.877994 -285.659918)
			(xy 166.918497 -285.687874) (xy 166.95399 -285.721966) (xy 166.983555 -285.76131) (xy 167.006426 -285.804887)
			(xy 167.02201 -285.851568) (xy 167.029905 -285.900145) (xy 167.0304 -285.924752) (xy 167.369248 -285.924752)
			(xy 167.373208 -285.875698) (xy 167.384985 -285.827914) (xy 167.404276 -285.782638) (xy 167.430579 -285.741042)
			(xy 167.463214 -285.704205) (xy 167.501335 -285.67308) (xy 167.543956 -285.648473) (xy 167.589972 -285.631021)
			(xy 167.638191 -285.621177) (xy 167.687366 -285.619196) (xy 167.736221 -285.625128) (xy 167.783492 -285.63882)
			(xy 167.827954 -285.659918) (xy 167.868457 -285.687874) (xy 167.90395 -285.721966) (xy 167.933515 -285.76131)
			(xy 167.956386 -285.804887) (xy 167.97197 -285.851568) (xy 167.979865 -285.900145) (xy 167.98036 -285.924752)
			(xy 168.319208 -285.924752) (xy 168.323168 -285.875698) (xy 168.334945 -285.827914) (xy 168.354236 -285.782638)
			(xy 168.380539 -285.741042) (xy 168.413174 -285.704205) (xy 168.451295 -285.67308) (xy 168.493916 -285.648473)
			(xy 168.539932 -285.631021) (xy 168.588151 -285.621177) (xy 168.637326 -285.619196) (xy 168.686181 -285.625128)
			(xy 168.733452 -285.63882) (xy 168.777914 -285.659918) (xy 168.818417 -285.687874) (xy 168.85391 -285.721966)
			(xy 168.883475 -285.76131) (xy 168.906346 -285.804887) (xy 168.92193 -285.851568) (xy 168.929825 -285.900145)
			(xy 168.93032 -285.924752) (xy 169.269168 -285.924752) (xy 169.273128 -285.875698) (xy 169.284905 -285.827914)
			(xy 169.304196 -285.782638) (xy 169.330499 -285.741042) (xy 169.363134 -285.704205) (xy 169.401255 -285.67308)
			(xy 169.443876 -285.648473) (xy 169.489892 -285.631021) (xy 169.538111 -285.621177) (xy 169.587286 -285.619196)
			(xy 169.636141 -285.625128) (xy 169.683412 -285.63882) (xy 169.727874 -285.659918) (xy 169.768377 -285.687874)
			(xy 169.80387 -285.721966) (xy 169.833435 -285.76131) (xy 169.856306 -285.804887) (xy 169.87189 -285.851568)
			(xy 169.879785 -285.900145) (xy 169.88028 -285.924752) (xy 170.219128 -285.924752) (xy 170.223088 -285.875698)
			(xy 170.234865 -285.827914) (xy 170.254156 -285.782638) (xy 170.280459 -285.741042) (xy 170.313094 -285.704205)
			(xy 170.351215 -285.67308) (xy 170.393836 -285.648473) (xy 170.439852 -285.631021) (xy 170.488071 -285.621177)
			(xy 170.537246 -285.619196) (xy 170.586101 -285.625128) (xy 170.633372 -285.63882) (xy 170.677834 -285.659918)
			(xy 170.718337 -285.687874) (xy 170.75383 -285.721966) (xy 170.783395 -285.76131) (xy 170.806266 -285.804887)
			(xy 170.82185 -285.851568) (xy 170.829745 -285.900145) (xy 170.83024 -285.924752) (xy 171.169088 -285.924752)
			(xy 171.173048 -285.875698) (xy 171.184825 -285.827914) (xy 171.204116 -285.782638) (xy 171.230419 -285.741042)
			(xy 171.263054 -285.704205) (xy 171.301175 -285.67308) (xy 171.343796 -285.648473) (xy 171.389812 -285.631021)
			(xy 171.438031 -285.621177) (xy 171.487206 -285.619196) (xy 171.536061 -285.625128) (xy 171.583332 -285.63882)
			(xy 171.627794 -285.659918) (xy 171.668297 -285.687874) (xy 171.70379 -285.721966) (xy 171.733355 -285.76131)
			(xy 171.756226 -285.804887) (xy 171.77181 -285.851568) (xy 171.779705 -285.900145) (xy 171.7802 -285.924752)
			(xy 172.119048 -285.924752) (xy 172.123008 -285.875698) (xy 172.134785 -285.827914) (xy 172.154076 -285.782638)
			(xy 172.180379 -285.741042) (xy 172.213014 -285.704205) (xy 172.251135 -285.67308) (xy 172.293756 -285.648473)
			(xy 172.339772 -285.631021) (xy 172.387991 -285.621177) (xy 172.437166 -285.619196) (xy 172.486021 -285.625128)
			(xy 172.533292 -285.63882) (xy 172.577754 -285.659918) (xy 172.618257 -285.687874) (xy 172.65375 -285.721966)
			(xy 172.683315 -285.76131) (xy 172.706186 -285.804887) (xy 172.72177 -285.851568) (xy 172.729665 -285.900145)
			(xy 172.73016 -285.924752) (xy 173.069262 -285.924752) (xy 173.073222 -285.875698) (xy 173.084999 -285.827914)
			(xy 173.10429 -285.782638) (xy 173.130593 -285.741042) (xy 173.163228 -285.704205) (xy 173.201349 -285.67308)
			(xy 173.24397 -285.648473) (xy 173.289986 -285.631021) (xy 173.338205 -285.621177) (xy 173.38738 -285.619196)
			(xy 173.436235 -285.625128) (xy 173.483506 -285.63882) (xy 173.527968 -285.659918) (xy 173.568471 -285.687874)
			(xy 173.603964 -285.721966) (xy 173.633529 -285.76131) (xy 173.6564 -285.804887) (xy 173.671984 -285.851568)
			(xy 173.679879 -285.900145) (xy 173.680374 -285.924752) (xy 174.019222 -285.924752) (xy 174.023182 -285.875698)
			(xy 174.034959 -285.827914) (xy 174.05425 -285.782638) (xy 174.080553 -285.741042) (xy 174.113188 -285.704205)
			(xy 174.151309 -285.67308) (xy 174.19393 -285.648473) (xy 174.239946 -285.631021) (xy 174.288165 -285.621177)
			(xy 174.33734 -285.619196) (xy 174.386195 -285.625128) (xy 174.433466 -285.63882) (xy 174.477928 -285.659918)
			(xy 174.518431 -285.687874) (xy 174.553924 -285.721966) (xy 174.583489 -285.76131) (xy 174.60636 -285.804887)
			(xy 174.621944 -285.851568) (xy 174.629839 -285.900145) (xy 174.630334 -285.924752) (xy 175.919142 -285.924752)
			(xy 175.923102 -285.875698) (xy 175.934879 -285.827914) (xy 175.95417 -285.782638) (xy 175.980473 -285.741042)
			(xy 176.013108 -285.704205) (xy 176.051229 -285.67308) (xy 176.09385 -285.648473) (xy 176.139866 -285.631021)
			(xy 176.188085 -285.621177) (xy 176.23726 -285.619196) (xy 176.286115 -285.625128) (xy 176.333386 -285.63882)
			(xy 176.377848 -285.659918) (xy 176.418351 -285.687874) (xy 176.453844 -285.721966) (xy 176.483409 -285.76131)
			(xy 176.50628 -285.804887) (xy 176.521864 -285.851568) (xy 176.529759 -285.900145) (xy 176.530254 -285.924752)
			(xy 176.869102 -285.924752) (xy 176.873062 -285.875698) (xy 176.884839 -285.827914) (xy 176.90413 -285.782638)
			(xy 176.930433 -285.741042) (xy 176.963068 -285.704205) (xy 177.001189 -285.67308) (xy 177.04381 -285.648473)
			(xy 177.089826 -285.631021) (xy 177.138045 -285.621177) (xy 177.18722 -285.619196) (xy 177.236075 -285.625128)
			(xy 177.283346 -285.63882) (xy 177.327808 -285.659918) (xy 177.368311 -285.687874) (xy 177.403804 -285.721966)
			(xy 177.433369 -285.76131) (xy 177.45624 -285.804887) (xy 177.471824 -285.851568) (xy 177.479719 -285.900145)
			(xy 177.480214 -285.924752) (xy 177.819062 -285.924752) (xy 177.823022 -285.875698) (xy 177.834799 -285.827914)
			(xy 177.85409 -285.782638) (xy 177.880393 -285.741042) (xy 177.913028 -285.704205) (xy 177.951149 -285.67308)
			(xy 177.99377 -285.648473) (xy 178.039786 -285.631021) (xy 178.088005 -285.621177) (xy 178.13718 -285.619196)
			(xy 178.186035 -285.625128) (xy 178.233306 -285.63882) (xy 178.277768 -285.659918) (xy 178.318271 -285.687874)
			(xy 178.353764 -285.721966) (xy 178.383329 -285.76131) (xy 178.4062 -285.804887) (xy 178.421784 -285.851568)
			(xy 178.429679 -285.900145) (xy 178.430174 -285.924752) (xy 178.769276 -285.924752) (xy 178.773236 -285.875698)
			(xy 178.785013 -285.827914) (xy 178.804304 -285.782638) (xy 178.830607 -285.741042) (xy 178.863242 -285.704205)
			(xy 178.901363 -285.67308) (xy 178.943984 -285.648473) (xy 178.99 -285.631021) (xy 179.038219 -285.621177)
			(xy 179.087394 -285.619196) (xy 179.136249 -285.625128) (xy 179.18352 -285.63882) (xy 179.227982 -285.659918)
			(xy 179.268485 -285.687874) (xy 179.303978 -285.721966) (xy 179.333543 -285.76131) (xy 179.356414 -285.804887)
			(xy 179.371998 -285.851568) (xy 179.379893 -285.900145) (xy 179.380388 -285.924752) (xy 179.719236 -285.924752)
			(xy 179.723196 -285.875698) (xy 179.734973 -285.827914) (xy 179.754264 -285.782638) (xy 179.780567 -285.741042)
			(xy 179.813202 -285.704205) (xy 179.851323 -285.67308) (xy 179.893944 -285.648473) (xy 179.93996 -285.631021)
			(xy 179.988179 -285.621177) (xy 180.037354 -285.619196) (xy 180.086209 -285.625128) (xy 180.13348 -285.63882)
			(xy 180.177942 -285.659918) (xy 180.218445 -285.687874) (xy 180.253938 -285.721966) (xy 180.283503 -285.76131)
			(xy 180.306374 -285.804887) (xy 180.321958 -285.851568) (xy 180.329853 -285.900145) (xy 180.330348 -285.924752)
			(xy 180.669196 -285.924752) (xy 180.673156 -285.875698) (xy 180.684933 -285.827914) (xy 180.704224 -285.782638)
			(xy 180.730527 -285.741042) (xy 180.763162 -285.704205) (xy 180.801283 -285.67308) (xy 180.843904 -285.648473)
			(xy 180.88992 -285.631021) (xy 180.938139 -285.621177) (xy 180.987314 -285.619196) (xy 181.036169 -285.625128)
			(xy 181.08344 -285.63882) (xy 181.127902 -285.659918) (xy 181.168405 -285.687874) (xy 181.203898 -285.721966)
			(xy 181.233463 -285.76131) (xy 181.256334 -285.804887) (xy 181.271918 -285.851568) (xy 181.279813 -285.900145)
			(xy 181.280308 -285.924752) (xy 181.619156 -285.924752) (xy 181.623116 -285.875698) (xy 181.634893 -285.827914)
			(xy 181.654184 -285.782638) (xy 181.680487 -285.741042) (xy 181.713122 -285.704205) (xy 181.751243 -285.67308)
			(xy 181.793864 -285.648473) (xy 181.83988 -285.631021) (xy 181.888099 -285.621177) (xy 181.937274 -285.619196)
			(xy 181.986129 -285.625128) (xy 182.0334 -285.63882) (xy 182.077862 -285.659918) (xy 182.118365 -285.687874)
			(xy 182.153858 -285.721966) (xy 182.183423 -285.76131) (xy 182.206294 -285.804887) (xy 182.221878 -285.851568)
			(xy 182.229773 -285.900145) (xy 182.230268 -285.924752) (xy 182.569116 -285.924752) (xy 182.573076 -285.875698)
			(xy 182.584853 -285.827914) (xy 182.604144 -285.782638) (xy 182.630447 -285.741042) (xy 182.663082 -285.704205)
			(xy 182.701203 -285.67308) (xy 182.743824 -285.648473) (xy 182.78984 -285.631021) (xy 182.838059 -285.621177)
			(xy 182.887234 -285.619196) (xy 182.936089 -285.625128) (xy 182.98336 -285.63882) (xy 183.027822 -285.659918)
			(xy 183.068325 -285.687874) (xy 183.103818 -285.721966) (xy 183.133383 -285.76131) (xy 183.156254 -285.804887)
			(xy 183.171838 -285.851568) (xy 183.179733 -285.900145) (xy 183.180228 -285.924752) (xy 183.519076 -285.924752)
			(xy 183.523036 -285.875698) (xy 183.534813 -285.827914) (xy 183.554104 -285.782638) (xy 183.580407 -285.741042)
			(xy 183.613042 -285.704205) (xy 183.651163 -285.67308) (xy 183.693784 -285.648473) (xy 183.7398 -285.631021)
			(xy 183.788019 -285.621177) (xy 183.837194 -285.619196) (xy 183.886049 -285.625128) (xy 183.93332 -285.63882)
			(xy 183.977782 -285.659918) (xy 184.018285 -285.687874) (xy 184.053778 -285.721966) (xy 184.083343 -285.76131)
			(xy 184.106214 -285.804887) (xy 184.121798 -285.851568) (xy 184.129693 -285.900145) (xy 184.130188 -285.924752)
			(xy 184.469036 -285.924752) (xy 184.472996 -285.875698) (xy 184.484773 -285.827914) (xy 184.504064 -285.782638)
			(xy 184.530367 -285.741042) (xy 184.563002 -285.704205) (xy 184.601123 -285.67308) (xy 184.643744 -285.648473)
			(xy 184.68976 -285.631021) (xy 184.737979 -285.621177) (xy 184.787154 -285.619196) (xy 184.836009 -285.625128)
			(xy 184.88328 -285.63882) (xy 184.927742 -285.659918) (xy 184.968245 -285.687874) (xy 185.003738 -285.721966)
			(xy 185.033303 -285.76131) (xy 185.056174 -285.804887) (xy 185.071758 -285.851568) (xy 185.079653 -285.900145)
			(xy 185.080148 -285.924752) (xy 185.41925 -285.924752) (xy 185.42321 -285.875698) (xy 185.434987 -285.827914)
			(xy 185.454278 -285.782638) (xy 185.480581 -285.741042) (xy 185.513216 -285.704205) (xy 185.551337 -285.67308)
			(xy 185.593958 -285.648473) (xy 185.639974 -285.631021) (xy 185.688193 -285.621177) (xy 185.737368 -285.619196)
			(xy 185.786223 -285.625128) (xy 185.833494 -285.63882) (xy 185.877956 -285.659918) (xy 185.918459 -285.687874)
			(xy 185.953952 -285.721966) (xy 185.983517 -285.76131) (xy 186.006388 -285.804887) (xy 186.021972 -285.851568)
			(xy 186.029867 -285.900145) (xy 186.030362 -285.924752) (xy 186.36921 -285.924752) (xy 186.37317 -285.875698)
			(xy 186.384947 -285.827914) (xy 186.404238 -285.782638) (xy 186.430541 -285.741042) (xy 186.463176 -285.704205)
			(xy 186.501297 -285.67308) (xy 186.543918 -285.648473) (xy 186.589934 -285.631021) (xy 186.638153 -285.621177)
			(xy 186.687328 -285.619196) (xy 186.736183 -285.625128) (xy 186.783454 -285.63882) (xy 186.827916 -285.659918)
			(xy 186.868419 -285.687874) (xy 186.903912 -285.721966) (xy 186.933477 -285.76131) (xy 186.956348 -285.804887)
			(xy 186.971932 -285.851568) (xy 186.979827 -285.900145) (xy 186.980322 -285.924752) (xy 186.979827 -285.949359)
			(xy 186.971932 -285.997936) (xy 186.956348 -286.044617) (xy 186.933477 -286.088194) (xy 186.903912 -286.127538)
			(xy 186.868419 -286.16163) (xy 186.827916 -286.189586) (xy 186.783454 -286.210684) (xy 186.736183 -286.224376)
			(xy 186.687328 -286.230308) (xy 186.638153 -286.228327) (xy 186.589934 -286.218483) (xy 186.543918 -286.201031)
			(xy 186.501297 -286.176424) (xy 186.463176 -286.145299) (xy 186.430541 -286.108462) (xy 186.404238 -286.066866)
			(xy 186.384947 -286.02159) (xy 186.37317 -285.973806) (xy 186.36921 -285.924752) (xy 186.030362 -285.924752)
			(xy 186.029867 -285.949359) (xy 186.021972 -285.997936) (xy 186.006388 -286.044617) (xy 185.983517 -286.088194)
			(xy 185.953952 -286.127538) (xy 185.918459 -286.16163) (xy 185.877956 -286.189586) (xy 185.833494 -286.210684)
			(xy 185.786223 -286.224376) (xy 185.737368 -286.230308) (xy 185.688193 -286.228327) (xy 185.639974 -286.218483)
			(xy 185.593958 -286.201031) (xy 185.551337 -286.176424) (xy 185.513216 -286.145299) (xy 185.480581 -286.108462)
			(xy 185.454278 -286.066866) (xy 185.434987 -286.02159) (xy 185.42321 -285.973806) (xy 185.41925 -285.924752)
			(xy 185.080148 -285.924752) (xy 185.079653 -285.949359) (xy 185.071758 -285.997936) (xy 185.056174 -286.044617)
			(xy 185.033303 -286.088194) (xy 185.003738 -286.127538) (xy 184.968245 -286.16163) (xy 184.927742 -286.189586)
			(xy 184.88328 -286.210684) (xy 184.836009 -286.224376) (xy 184.787154 -286.230308) (xy 184.737979 -286.228327)
			(xy 184.68976 -286.218483) (xy 184.643744 -286.201031) (xy 184.601123 -286.176424) (xy 184.563002 -286.145299)
			(xy 184.530367 -286.108462) (xy 184.504064 -286.066866) (xy 184.484773 -286.02159) (xy 184.472996 -285.973806)
			(xy 184.469036 -285.924752) (xy 184.130188 -285.924752) (xy 184.129693 -285.949359) (xy 184.121798 -285.997936)
			(xy 184.106214 -286.044617) (xy 184.083343 -286.088194) (xy 184.053778 -286.127538) (xy 184.018285 -286.16163)
			(xy 183.977782 -286.189586) (xy 183.93332 -286.210684) (xy 183.886049 -286.224376) (xy 183.837194 -286.230308)
			(xy 183.788019 -286.228327) (xy 183.7398 -286.218483) (xy 183.693784 -286.201031) (xy 183.651163 -286.176424)
			(xy 183.613042 -286.145299) (xy 183.580407 -286.108462) (xy 183.554104 -286.066866) (xy 183.534813 -286.02159)
			(xy 183.523036 -285.973806) (xy 183.519076 -285.924752) (xy 183.180228 -285.924752) (xy 183.179733 -285.949359)
			(xy 183.171838 -285.997936) (xy 183.156254 -286.044617) (xy 183.133383 -286.088194) (xy 183.103818 -286.127538)
			(xy 183.068325 -286.16163) (xy 183.027822 -286.189586) (xy 182.98336 -286.210684) (xy 182.936089 -286.224376)
			(xy 182.887234 -286.230308) (xy 182.838059 -286.228327) (xy 182.78984 -286.218483) (xy 182.743824 -286.201031)
			(xy 182.701203 -286.176424) (xy 182.663082 -286.145299) (xy 182.630447 -286.108462) (xy 182.604144 -286.066866)
			(xy 182.584853 -286.02159) (xy 182.573076 -285.973806) (xy 182.569116 -285.924752) (xy 182.230268 -285.924752)
			(xy 182.229773 -285.949359) (xy 182.221878 -285.997936) (xy 182.206294 -286.044617) (xy 182.183423 -286.088194)
			(xy 182.153858 -286.127538) (xy 182.118365 -286.16163) (xy 182.077862 -286.189586) (xy 182.0334 -286.210684)
			(xy 181.986129 -286.224376) (xy 181.937274 -286.230308) (xy 181.888099 -286.228327) (xy 181.83988 -286.218483)
			(xy 181.793864 -286.201031) (xy 181.751243 -286.176424) (xy 181.713122 -286.145299) (xy 181.680487 -286.108462)
			(xy 181.654184 -286.066866) (xy 181.634893 -286.02159) (xy 181.623116 -285.973806) (xy 181.619156 -285.924752)
			(xy 181.280308 -285.924752) (xy 181.279813 -285.949359) (xy 181.271918 -285.997936) (xy 181.256334 -286.044617)
			(xy 181.233463 -286.088194) (xy 181.203898 -286.127538) (xy 181.168405 -286.16163) (xy 181.127902 -286.189586)
			(xy 181.08344 -286.210684) (xy 181.036169 -286.224376) (xy 180.987314 -286.230308) (xy 180.938139 -286.228327)
			(xy 180.88992 -286.218483) (xy 180.843904 -286.201031) (xy 180.801283 -286.176424) (xy 180.763162 -286.145299)
			(xy 180.730527 -286.108462) (xy 180.704224 -286.066866) (xy 180.684933 -286.02159) (xy 180.673156 -285.973806)
			(xy 180.669196 -285.924752) (xy 180.330348 -285.924752) (xy 180.329853 -285.949359) (xy 180.321958 -285.997936)
			(xy 180.306374 -286.044617) (xy 180.283503 -286.088194) (xy 180.253938 -286.127538) (xy 180.218445 -286.16163)
			(xy 180.177942 -286.189586) (xy 180.13348 -286.210684) (xy 180.086209 -286.224376) (xy 180.037354 -286.230308)
			(xy 179.988179 -286.228327) (xy 179.93996 -286.218483) (xy 179.893944 -286.201031) (xy 179.851323 -286.176424)
			(xy 179.813202 -286.145299) (xy 179.780567 -286.108462) (xy 179.754264 -286.066866) (xy 179.734973 -286.02159)
			(xy 179.723196 -285.973806) (xy 179.719236 -285.924752) (xy 179.380388 -285.924752) (xy 179.379893 -285.949359)
			(xy 179.371998 -285.997936) (xy 179.356414 -286.044617) (xy 179.333543 -286.088194) (xy 179.303978 -286.127538)
			(xy 179.268485 -286.16163) (xy 179.227982 -286.189586) (xy 179.18352 -286.210684) (xy 179.136249 -286.224376)
			(xy 179.087394 -286.230308) (xy 179.038219 -286.228327) (xy 178.99 -286.218483) (xy 178.943984 -286.201031)
			(xy 178.901363 -286.176424) (xy 178.863242 -286.145299) (xy 178.830607 -286.108462) (xy 178.804304 -286.066866)
			(xy 178.785013 -286.02159) (xy 178.773236 -285.973806) (xy 178.769276 -285.924752) (xy 178.430174 -285.924752)
			(xy 178.429679 -285.949359) (xy 178.421784 -285.997936) (xy 178.4062 -286.044617) (xy 178.383329 -286.088194)
			(xy 178.353764 -286.127538) (xy 178.318271 -286.16163) (xy 178.277768 -286.189586) (xy 178.233306 -286.210684)
			(xy 178.186035 -286.224376) (xy 178.13718 -286.230308) (xy 178.088005 -286.228327) (xy 178.039786 -286.218483)
			(xy 177.99377 -286.201031) (xy 177.951149 -286.176424) (xy 177.913028 -286.145299) (xy 177.880393 -286.108462)
			(xy 177.85409 -286.066866) (xy 177.834799 -286.02159) (xy 177.823022 -285.973806) (xy 177.819062 -285.924752)
			(xy 177.480214 -285.924752) (xy 177.479719 -285.949359) (xy 177.471824 -285.997936) (xy 177.45624 -286.044617)
			(xy 177.433369 -286.088194) (xy 177.403804 -286.127538) (xy 177.368311 -286.16163) (xy 177.327808 -286.189586)
			(xy 177.283346 -286.210684) (xy 177.236075 -286.224376) (xy 177.18722 -286.230308) (xy 177.138045 -286.228327)
			(xy 177.089826 -286.218483) (xy 177.04381 -286.201031) (xy 177.001189 -286.176424) (xy 176.963068 -286.145299)
			(xy 176.930433 -286.108462) (xy 176.90413 -286.066866) (xy 176.884839 -286.02159) (xy 176.873062 -285.973806)
			(xy 176.869102 -285.924752) (xy 176.530254 -285.924752) (xy 176.529759 -285.949359) (xy 176.521864 -285.997936)
			(xy 176.50628 -286.044617) (xy 176.483409 -286.088194) (xy 176.453844 -286.127538) (xy 176.418351 -286.16163)
			(xy 176.377848 -286.189586) (xy 176.333386 -286.210684) (xy 176.286115 -286.224376) (xy 176.23726 -286.230308)
			(xy 176.188085 -286.228327) (xy 176.139866 -286.218483) (xy 176.09385 -286.201031) (xy 176.051229 -286.176424)
			(xy 176.013108 -286.145299) (xy 175.980473 -286.108462) (xy 175.95417 -286.066866) (xy 175.934879 -286.02159)
			(xy 175.923102 -285.973806) (xy 175.919142 -285.924752) (xy 174.630334 -285.924752) (xy 174.629839 -285.949359)
			(xy 174.621944 -285.997936) (xy 174.60636 -286.044617) (xy 174.583489 -286.088194) (xy 174.553924 -286.127538)
			(xy 174.518431 -286.16163) (xy 174.477928 -286.189586) (xy 174.433466 -286.210684) (xy 174.386195 -286.224376)
			(xy 174.33734 -286.230308) (xy 174.288165 -286.228327) (xy 174.239946 -286.218483) (xy 174.19393 -286.201031)
			(xy 174.151309 -286.176424) (xy 174.113188 -286.145299) (xy 174.080553 -286.108462) (xy 174.05425 -286.066866)
			(xy 174.034959 -286.02159) (xy 174.023182 -285.973806) (xy 174.019222 -285.924752) (xy 173.680374 -285.924752)
			(xy 173.679879 -285.949359) (xy 173.671984 -285.997936) (xy 173.6564 -286.044617) (xy 173.633529 -286.088194)
			(xy 173.603964 -286.127538) (xy 173.568471 -286.16163) (xy 173.527968 -286.189586) (xy 173.483506 -286.210684)
			(xy 173.436235 -286.224376) (xy 173.38738 -286.230308) (xy 173.338205 -286.228327) (xy 173.289986 -286.218483)
			(xy 173.24397 -286.201031) (xy 173.201349 -286.176424) (xy 173.163228 -286.145299) (xy 173.130593 -286.108462)
			(xy 173.10429 -286.066866) (xy 173.084999 -286.02159) (xy 173.073222 -285.973806) (xy 173.069262 -285.924752)
			(xy 172.73016 -285.924752) (xy 172.729665 -285.949359) (xy 172.72177 -285.997936) (xy 172.706186 -286.044617)
			(xy 172.683315 -286.088194) (xy 172.65375 -286.127538) (xy 172.618257 -286.16163) (xy 172.577754 -286.189586)
			(xy 172.533292 -286.210684) (xy 172.486021 -286.224376) (xy 172.437166 -286.230308) (xy 172.387991 -286.228327)
			(xy 172.339772 -286.218483) (xy 172.293756 -286.201031) (xy 172.251135 -286.176424) (xy 172.213014 -286.145299)
			(xy 172.180379 -286.108462) (xy 172.154076 -286.066866) (xy 172.134785 -286.02159) (xy 172.123008 -285.973806)
			(xy 172.119048 -285.924752) (xy 171.7802 -285.924752) (xy 171.779705 -285.949359) (xy 171.77181 -285.997936)
			(xy 171.756226 -286.044617) (xy 171.733355 -286.088194) (xy 171.70379 -286.127538) (xy 171.668297 -286.16163)
			(xy 171.627794 -286.189586) (xy 171.583332 -286.210684) (xy 171.536061 -286.224376) (xy 171.487206 -286.230308)
			(xy 171.438031 -286.228327) (xy 171.389812 -286.218483) (xy 171.343796 -286.201031) (xy 171.301175 -286.176424)
			(xy 171.263054 -286.145299) (xy 171.230419 -286.108462) (xy 171.204116 -286.066866) (xy 171.184825 -286.02159)
			(xy 171.173048 -285.973806) (xy 171.169088 -285.924752) (xy 170.83024 -285.924752) (xy 170.829745 -285.949359)
			(xy 170.82185 -285.997936) (xy 170.806266 -286.044617) (xy 170.783395 -286.088194) (xy 170.75383 -286.127538)
			(xy 170.718337 -286.16163) (xy 170.677834 -286.189586) (xy 170.633372 -286.210684) (xy 170.586101 -286.224376)
			(xy 170.537246 -286.230308) (xy 170.488071 -286.228327) (xy 170.439852 -286.218483) (xy 170.393836 -286.201031)
			(xy 170.351215 -286.176424) (xy 170.313094 -286.145299) (xy 170.280459 -286.108462) (xy 170.254156 -286.066866)
			(xy 170.234865 -286.02159) (xy 170.223088 -285.973806) (xy 170.219128 -285.924752) (xy 169.88028 -285.924752)
			(xy 169.879785 -285.949359) (xy 169.87189 -285.997936) (xy 169.856306 -286.044617) (xy 169.833435 -286.088194)
			(xy 169.80387 -286.127538) (xy 169.768377 -286.16163) (xy 169.727874 -286.189586) (xy 169.683412 -286.210684)
			(xy 169.636141 -286.224376) (xy 169.587286 -286.230308) (xy 169.538111 -286.228327) (xy 169.489892 -286.218483)
			(xy 169.443876 -286.201031) (xy 169.401255 -286.176424) (xy 169.363134 -286.145299) (xy 169.330499 -286.108462)
			(xy 169.304196 -286.066866) (xy 169.284905 -286.02159) (xy 169.273128 -285.973806) (xy 169.269168 -285.924752)
			(xy 168.93032 -285.924752) (xy 168.929825 -285.949359) (xy 168.92193 -285.997936) (xy 168.906346 -286.044617)
			(xy 168.883475 -286.088194) (xy 168.85391 -286.127538) (xy 168.818417 -286.16163) (xy 168.777914 -286.189586)
			(xy 168.733452 -286.210684) (xy 168.686181 -286.224376) (xy 168.637326 -286.230308) (xy 168.588151 -286.228327)
			(xy 168.539932 -286.218483) (xy 168.493916 -286.201031) (xy 168.451295 -286.176424) (xy 168.413174 -286.145299)
			(xy 168.380539 -286.108462) (xy 168.354236 -286.066866) (xy 168.334945 -286.02159) (xy 168.323168 -285.973806)
			(xy 168.319208 -285.924752) (xy 167.98036 -285.924752) (xy 167.979865 -285.949359) (xy 167.97197 -285.997936)
			(xy 167.956386 -286.044617) (xy 167.933515 -286.088194) (xy 167.90395 -286.127538) (xy 167.868457 -286.16163)
			(xy 167.827954 -286.189586) (xy 167.783492 -286.210684) (xy 167.736221 -286.224376) (xy 167.687366 -286.230308)
			(xy 167.638191 -286.228327) (xy 167.589972 -286.218483) (xy 167.543956 -286.201031) (xy 167.501335 -286.176424)
			(xy 167.463214 -286.145299) (xy 167.430579 -286.108462) (xy 167.404276 -286.066866) (xy 167.384985 -286.02159)
			(xy 167.373208 -285.973806) (xy 167.369248 -285.924752) (xy 167.0304 -285.924752) (xy 167.029905 -285.949359)
			(xy 167.02201 -285.997936) (xy 167.006426 -286.044617) (xy 166.983555 -286.088194) (xy 166.95399 -286.127538)
			(xy 166.918497 -286.16163) (xy 166.877994 -286.189586) (xy 166.833532 -286.210684) (xy 166.786261 -286.224376)
			(xy 166.737406 -286.230308) (xy 166.688231 -286.228327) (xy 166.640012 -286.218483) (xy 166.593996 -286.201031)
			(xy 166.551375 -286.176424) (xy 166.513254 -286.145299) (xy 166.480619 -286.108462) (xy 166.454316 -286.066866)
			(xy 166.435025 -286.02159) (xy 166.423248 -285.973806) (xy 166.419288 -285.924752) (xy 166.080186 -285.924752)
			(xy 166.079691 -285.949359) (xy 166.071796 -285.997936) (xy 166.056212 -286.044617) (xy 166.033341 -286.088194)
			(xy 166.003776 -286.127538) (xy 165.968283 -286.16163) (xy 165.92778 -286.189586) (xy 165.883318 -286.210684)
			(xy 165.836047 -286.224376) (xy 165.787192 -286.230308) (xy 165.738017 -286.228327) (xy 165.689798 -286.218483)
			(xy 165.643782 -286.201031) (xy 165.601161 -286.176424) (xy 165.56304 -286.145299) (xy 165.530405 -286.108462)
			(xy 165.504102 -286.066866) (xy 165.484811 -286.02159) (xy 165.473034 -285.973806) (xy 165.469074 -285.924752)
			(xy 165.130226 -285.924752) (xy 165.129731 -285.949359) (xy 165.121836 -285.997936) (xy 165.106252 -286.044617)
			(xy 165.083381 -286.088194) (xy 165.053816 -286.127538) (xy 165.018323 -286.16163) (xy 164.97782 -286.189586)
			(xy 164.933358 -286.210684) (xy 164.886087 -286.224376) (xy 164.837232 -286.230308) (xy 164.788057 -286.228327)
			(xy 164.739838 -286.218483) (xy 164.693822 -286.201031) (xy 164.651201 -286.176424) (xy 164.61308 -286.145299)
			(xy 164.580445 -286.108462) (xy 164.554142 -286.066866) (xy 164.534851 -286.02159) (xy 164.523074 -285.973806)
			(xy 164.519114 -285.924752) (xy 164.180266 -285.924752) (xy 164.179771 -285.949359) (xy 164.171876 -285.997936)
			(xy 164.156292 -286.044617) (xy 164.133421 -286.088194) (xy 164.103856 -286.127538) (xy 164.068363 -286.16163)
			(xy 164.02786 -286.189586) (xy 163.983398 -286.210684) (xy 163.936127 -286.224376) (xy 163.887272 -286.230308)
			(xy 163.838097 -286.228327) (xy 163.789878 -286.218483) (xy 163.743862 -286.201031) (xy 163.701241 -286.176424)
			(xy 163.66312 -286.145299) (xy 163.630485 -286.108462) (xy 163.604182 -286.066866) (xy 163.584891 -286.02159)
			(xy 163.573114 -285.973806) (xy 163.569154 -285.924752) (xy 163.230306 -285.924752) (xy 163.229811 -285.949359)
			(xy 163.221916 -285.997936) (xy 163.206332 -286.044617) (xy 163.183461 -286.088194) (xy 163.153896 -286.127538)
			(xy 163.118403 -286.16163) (xy 163.0779 -286.189586) (xy 163.033438 -286.210684) (xy 162.986167 -286.224376)
			(xy 162.937312 -286.230308) (xy 162.888137 -286.228327) (xy 162.839918 -286.218483) (xy 162.793902 -286.201031)
			(xy 162.751281 -286.176424) (xy 162.71316 -286.145299) (xy 162.680525 -286.108462) (xy 162.654222 -286.066866)
			(xy 162.634931 -286.02159) (xy 162.623154 -285.973806) (xy 162.619194 -285.924752) (xy 162.280346 -285.924752)
			(xy 162.279851 -285.949359) (xy 162.271956 -285.997936) (xy 162.256372 -286.044617) (xy 162.233501 -286.088194)
			(xy 162.203936 -286.127538) (xy 162.168443 -286.16163) (xy 162.12794 -286.189586) (xy 162.083478 -286.210684)
			(xy 162.036207 -286.224376) (xy 161.987352 -286.230308) (xy 161.938177 -286.228327) (xy 161.889958 -286.218483)
			(xy 161.843942 -286.201031) (xy 161.801321 -286.176424) (xy 161.7632 -286.145299) (xy 161.730565 -286.108462)
			(xy 161.704262 -286.066866) (xy 161.684971 -286.02159) (xy 161.673194 -285.973806) (xy 161.669234 -285.924752)
			(xy 161.330386 -285.924752) (xy 161.329891 -285.949359) (xy 161.321996 -285.997936) (xy 161.306412 -286.044617)
			(xy 161.283541 -286.088194) (xy 161.253976 -286.127538) (xy 161.218483 -286.16163) (xy 161.17798 -286.189586)
			(xy 161.133518 -286.210684) (xy 161.086247 -286.224376) (xy 161.037392 -286.230308) (xy 160.988217 -286.228327)
			(xy 160.939998 -286.218483) (xy 160.893982 -286.201031) (xy 160.851361 -286.176424) (xy 160.81324 -286.145299)
			(xy 160.780605 -286.108462) (xy 160.754302 -286.066866) (xy 160.735011 -286.02159) (xy 160.723234 -285.973806)
			(xy 160.719274 -285.924752) (xy 157.530292 -285.924752) (xy 157.529797 -285.949359) (xy 157.521902 -285.997936)
			(xy 157.506318 -286.044617) (xy 157.483447 -286.088194) (xy 157.453882 -286.127538) (xy 157.418389 -286.16163)
			(xy 157.377886 -286.189586) (xy 157.333424 -286.210684) (xy 157.286153 -286.224376) (xy 157.237298 -286.230308)
			(xy 157.188123 -286.228327) (xy 157.139904 -286.218483) (xy 157.093888 -286.201031) (xy 157.051267 -286.176424)
			(xy 157.013146 -286.145299) (xy 156.980511 -286.108462) (xy 156.954208 -286.066866) (xy 156.934917 -286.02159)
			(xy 156.92314 -285.973806) (xy 156.91918 -285.924752) (xy 156.580332 -285.924752) (xy 156.579837 -285.949359)
			(xy 156.571942 -285.997936) (xy 156.556358 -286.044617) (xy 156.533487 -286.088194) (xy 156.503922 -286.127538)
			(xy 156.468429 -286.16163) (xy 156.427926 -286.189586) (xy 156.383464 -286.210684) (xy 156.336193 -286.224376)
			(xy 156.287338 -286.230308) (xy 156.238163 -286.228327) (xy 156.189944 -286.218483) (xy 156.143928 -286.201031)
			(xy 156.101307 -286.176424) (xy 156.063186 -286.145299) (xy 156.030551 -286.108462) (xy 156.004248 -286.066866)
			(xy 155.984957 -286.02159) (xy 155.97318 -285.973806) (xy 155.96922 -285.924752) (xy 155.630372 -285.924752)
			(xy 155.629877 -285.949359) (xy 155.621982 -285.997936) (xy 155.606398 -286.044617) (xy 155.583527 -286.088194)
			(xy 155.553962 -286.127538) (xy 155.518469 -286.16163) (xy 155.477966 -286.189586) (xy 155.433504 -286.210684)
			(xy 155.386233 -286.224376) (xy 155.337378 -286.230308) (xy 155.288203 -286.228327) (xy 155.239984 -286.218483)
			(xy 155.193968 -286.201031) (xy 155.151347 -286.176424) (xy 155.113226 -286.145299) (xy 155.080591 -286.108462)
			(xy 155.054288 -286.066866) (xy 155.034997 -286.02159) (xy 155.02322 -285.973806) (xy 155.01926 -285.924752)
			(xy 154.680412 -285.924752) (xy 154.679917 -285.949359) (xy 154.672022 -285.997936) (xy 154.656438 -286.044617)
			(xy 154.633567 -286.088194) (xy 154.604002 -286.127538) (xy 154.568509 -286.16163) (xy 154.528006 -286.189586)
			(xy 154.483544 -286.210684) (xy 154.436273 -286.224376) (xy 154.387418 -286.230308) (xy 154.338243 -286.228327)
			(xy 154.290024 -286.218483) (xy 154.244008 -286.201031) (xy 154.201387 -286.176424) (xy 154.163266 -286.145299)
			(xy 154.130631 -286.108462) (xy 154.104328 -286.066866) (xy 154.085037 -286.02159) (xy 154.07326 -285.973806)
			(xy 154.0693 -285.924752) (xy 153.730198 -285.924752) (xy 153.729703 -285.949359) (xy 153.721808 -285.997936)
			(xy 153.706224 -286.044617) (xy 153.683353 -286.088194) (xy 153.653788 -286.127538) (xy 153.618295 -286.16163)
			(xy 153.577792 -286.189586) (xy 153.53333 -286.210684) (xy 153.486059 -286.224376) (xy 153.437204 -286.230308)
			(xy 153.388029 -286.228327) (xy 153.33981 -286.218483) (xy 153.293794 -286.201031) (xy 153.251173 -286.176424)
			(xy 153.213052 -286.145299) (xy 153.180417 -286.108462) (xy 153.154114 -286.066866) (xy 153.134823 -286.02159)
			(xy 153.123046 -285.973806) (xy 153.119086 -285.924752) (xy 152.805146 -285.924752) (xy 152.805146 -285.950789)
			(xy 152.797016 -286.002128) (xy 152.780954 -286.051564) (xy 152.757357 -286.097878) (xy 152.726807 -286.139931)
			(xy 152.690054 -286.176687) (xy 152.648003 -286.207242) (xy 152.601691 -286.230843) (xy 152.552258 -286.246909)
			(xy 152.500919 -286.255044) (xy 152.47493 -286.25546) (xy 152.474422 -286.25546) (xy 152.448246 -286.254962)
			(xy 152.396549 -286.246709) (xy 152.346801 -286.230406) (xy 152.323292 -286.218884) (xy 152.323038 -286.218884)
			(xy 152.317197 -286.216131) (xy 152.304603 -286.213296) (xy 152.298146 -286.213296) (xy 152.284938 -286.213804)
			(xy 152.204928 -286.262826) (xy 152.19553 -286.270192) (xy 152.18664 -286.279082) (xy 152.18283 -286.288226)
			(xy 152.178004 -286.298132) (xy 152.178004 -286.487362) (xy 152.178073 -286.491168) (xy 152.179226 -286.498693)
			(xy 152.18029 -286.502348) (xy 152.182576 -286.509714) (xy 152.189688 -286.525462) (xy 152.195784 -286.530796)
			(xy 152.199086 -286.533336) (xy 152.276048 -286.58058) (xy 152.290526 -286.580834) (xy 152.30602 -286.580834)
			(xy 152.312624 -286.580326) (xy 152.332944 -286.576008) (xy 152.338024 -286.573722) (xy 152.359549 -286.564424)
			(xy 152.404563 -286.551305) (xy 152.450979 -286.544666) (xy 152.474422 -286.544258) (xy 152.47493 -286.544258)
			(xy 152.500918 -286.54477) (xy 152.552254 -286.552905) (xy 152.601686 -286.56897) (xy 152.647996 -286.59257)
			(xy 152.690045 -286.623124) (xy 152.726796 -286.659878) (xy 152.757346 -286.701929) (xy 152.780941 -286.748242)
			(xy 152.797002 -286.797675) (xy 152.805132 -286.849012) (xy 152.805132 -286.874966) (xy 153.119086 -286.874966)
			(xy 153.123046 -286.825912) (xy 153.134823 -286.778128) (xy 153.154114 -286.732852) (xy 153.180417 -286.691256)
			(xy 153.213052 -286.654419) (xy 153.251173 -286.623294) (xy 153.293794 -286.598687) (xy 153.33981 -286.581235)
			(xy 153.388029 -286.571391) (xy 153.437204 -286.56941) (xy 153.486059 -286.575342) (xy 153.53333 -286.589034)
			(xy 153.577792 -286.610132) (xy 153.618295 -286.638088) (xy 153.653788 -286.67218) (xy 153.683353 -286.711524)
			(xy 153.706224 -286.755101) (xy 153.721808 -286.801782) (xy 153.729703 -286.850359) (xy 153.730198 -286.874966)
			(xy 154.0693 -286.874966) (xy 154.07326 -286.825912) (xy 154.085037 -286.778128) (xy 154.104328 -286.732852)
			(xy 154.130631 -286.691256) (xy 154.163266 -286.654419) (xy 154.201387 -286.623294) (xy 154.244008 -286.598687)
			(xy 154.290024 -286.581235) (xy 154.338243 -286.571391) (xy 154.387418 -286.56941) (xy 154.436273 -286.575342)
			(xy 154.483544 -286.589034) (xy 154.528006 -286.610132) (xy 154.568509 -286.638088) (xy 154.604002 -286.67218)
			(xy 154.633567 -286.711524) (xy 154.656438 -286.755101) (xy 154.672022 -286.801782) (xy 154.679917 -286.850359)
			(xy 154.680412 -286.874966) (xy 155.01926 -286.874966) (xy 155.02322 -286.825912) (xy 155.034997 -286.778128)
			(xy 155.054288 -286.732852) (xy 155.080591 -286.691256) (xy 155.113226 -286.654419) (xy 155.151347 -286.623294)
			(xy 155.193968 -286.598687) (xy 155.239984 -286.581235) (xy 155.288203 -286.571391) (xy 155.337378 -286.56941)
			(xy 155.386233 -286.575342) (xy 155.433504 -286.589034) (xy 155.477966 -286.610132) (xy 155.518469 -286.638088)
			(xy 155.553962 -286.67218) (xy 155.583527 -286.711524) (xy 155.606398 -286.755101) (xy 155.621982 -286.801782)
			(xy 155.629877 -286.850359) (xy 155.630372 -286.874966) (xy 155.96922 -286.874966) (xy 155.97318 -286.825912)
			(xy 155.984957 -286.778128) (xy 156.004248 -286.732852) (xy 156.030551 -286.691256) (xy 156.063186 -286.654419)
			(xy 156.101307 -286.623294) (xy 156.143928 -286.598687) (xy 156.189944 -286.581235) (xy 156.238163 -286.571391)
			(xy 156.287338 -286.56941) (xy 156.336193 -286.575342) (xy 156.383464 -286.589034) (xy 156.427926 -286.610132)
			(xy 156.468429 -286.638088) (xy 156.503922 -286.67218) (xy 156.533487 -286.711524) (xy 156.556358 -286.755101)
			(xy 156.571942 -286.801782) (xy 156.579837 -286.850359) (xy 156.580332 -286.874966) (xy 156.91918 -286.874966)
			(xy 156.92314 -286.825912) (xy 156.934917 -286.778128) (xy 156.954208 -286.732852) (xy 156.980511 -286.691256)
			(xy 157.013146 -286.654419) (xy 157.051267 -286.623294) (xy 157.093888 -286.598687) (xy 157.139904 -286.581235)
			(xy 157.188123 -286.571391) (xy 157.237298 -286.56941) (xy 157.286153 -286.575342) (xy 157.333424 -286.589034)
			(xy 157.377886 -286.610132) (xy 157.418389 -286.638088) (xy 157.453882 -286.67218) (xy 157.483447 -286.711524)
			(xy 157.506318 -286.755101) (xy 157.521902 -286.801782) (xy 157.529797 -286.850359) (xy 157.530292 -286.874966)
			(xy 157.86914 -286.874966) (xy 157.8731 -286.825912) (xy 157.884877 -286.778128) (xy 157.904168 -286.732852)
			(xy 157.930471 -286.691256) (xy 157.963106 -286.654419) (xy 158.001227 -286.623294) (xy 158.043848 -286.598687)
			(xy 158.089864 -286.581235) (xy 158.138083 -286.571391) (xy 158.187258 -286.56941) (xy 158.236113 -286.575342)
			(xy 158.283384 -286.589034) (xy 158.327846 -286.610132) (xy 158.368349 -286.638088) (xy 158.403842 -286.67218)
			(xy 158.433407 -286.711524) (xy 158.456278 -286.755101) (xy 158.471862 -286.801782) (xy 158.479757 -286.850359)
			(xy 158.480247 -286.874712) (xy 158.8191 -286.874712) (xy 158.82306 -286.825658) (xy 158.834837 -286.777874)
			(xy 158.854128 -286.732598) (xy 158.880431 -286.691002) (xy 158.913066 -286.654165) (xy 158.951187 -286.62304)
			(xy 158.993808 -286.598433) (xy 159.039824 -286.580981) (xy 159.088043 -286.571137) (xy 159.137218 -286.569156)
			(xy 159.186073 -286.575088) (xy 159.233344 -286.58878) (xy 159.277806 -286.609878) (xy 159.318309 -286.637834)
			(xy 159.353802 -286.671926) (xy 159.383367 -286.71127) (xy 159.406238 -286.754847) (xy 159.421822 -286.801528)
			(xy 159.429717 -286.850105) (xy 159.430212 -286.874712) (xy 159.76906 -286.874712) (xy 159.77302 -286.825658)
			(xy 159.784797 -286.777874) (xy 159.804088 -286.732598) (xy 159.830391 -286.691002) (xy 159.863026 -286.654165)
			(xy 159.901147 -286.62304) (xy 159.943768 -286.598433) (xy 159.989784 -286.580981) (xy 160.038003 -286.571137)
			(xy 160.087178 -286.569156) (xy 160.136033 -286.575088) (xy 160.183304 -286.58878) (xy 160.227766 -286.609878)
			(xy 160.268269 -286.637834) (xy 160.303762 -286.671926) (xy 160.333327 -286.71127) (xy 160.356198 -286.754847)
			(xy 160.371782 -286.801528) (xy 160.379677 -286.850105) (xy 160.380172 -286.874712) (xy 160.380167 -286.874966)
			(xy 160.719274 -286.874966) (xy 160.723234 -286.825912) (xy 160.735011 -286.778128) (xy 160.754302 -286.732852)
			(xy 160.780605 -286.691256) (xy 160.81324 -286.654419) (xy 160.851361 -286.623294) (xy 160.893982 -286.598687)
			(xy 160.939998 -286.581235) (xy 160.988217 -286.571391) (xy 161.037392 -286.56941) (xy 161.086247 -286.575342)
			(xy 161.133518 -286.589034) (xy 161.17798 -286.610132) (xy 161.218483 -286.638088) (xy 161.253976 -286.67218)
			(xy 161.283541 -286.711524) (xy 161.306412 -286.755101) (xy 161.321996 -286.801782) (xy 161.329891 -286.850359)
			(xy 161.330386 -286.874966) (xy 161.669234 -286.874966) (xy 161.673194 -286.825912) (xy 161.684971 -286.778128)
			(xy 161.704262 -286.732852) (xy 161.730565 -286.691256) (xy 161.7632 -286.654419) (xy 161.801321 -286.623294)
			(xy 161.843942 -286.598687) (xy 161.889958 -286.581235) (xy 161.938177 -286.571391) (xy 161.987352 -286.56941)
			(xy 162.036207 -286.575342) (xy 162.083478 -286.589034) (xy 162.12794 -286.610132) (xy 162.168443 -286.638088)
			(xy 162.203936 -286.67218) (xy 162.233501 -286.711524) (xy 162.256372 -286.755101) (xy 162.271956 -286.801782)
			(xy 162.279851 -286.850359) (xy 162.280346 -286.874966) (xy 162.619194 -286.874966) (xy 162.623154 -286.825912)
			(xy 162.634931 -286.778128) (xy 162.654222 -286.732852) (xy 162.680525 -286.691256) (xy 162.71316 -286.654419)
			(xy 162.751281 -286.623294) (xy 162.793902 -286.598687) (xy 162.839918 -286.581235) (xy 162.888137 -286.571391)
			(xy 162.937312 -286.56941) (xy 162.986167 -286.575342) (xy 163.033438 -286.589034) (xy 163.0779 -286.610132)
			(xy 163.118403 -286.638088) (xy 163.153896 -286.67218) (xy 163.183461 -286.711524) (xy 163.206332 -286.755101)
			(xy 163.221916 -286.801782) (xy 163.229811 -286.850359) (xy 163.230306 -286.874966) (xy 163.569154 -286.874966)
			(xy 163.573114 -286.825912) (xy 163.584891 -286.778128) (xy 163.604182 -286.732852) (xy 163.630485 -286.691256)
			(xy 163.66312 -286.654419) (xy 163.701241 -286.623294) (xy 163.743862 -286.598687) (xy 163.789878 -286.581235)
			(xy 163.838097 -286.571391) (xy 163.887272 -286.56941) (xy 163.936127 -286.575342) (xy 163.983398 -286.589034)
			(xy 164.02786 -286.610132) (xy 164.068363 -286.638088) (xy 164.103856 -286.67218) (xy 164.133421 -286.711524)
			(xy 164.156292 -286.755101) (xy 164.171876 -286.801782) (xy 164.179771 -286.850359) (xy 164.180266 -286.874966)
			(xy 164.519114 -286.874966) (xy 164.523074 -286.825912) (xy 164.534851 -286.778128) (xy 164.554142 -286.732852)
			(xy 164.580445 -286.691256) (xy 164.61308 -286.654419) (xy 164.651201 -286.623294) (xy 164.693822 -286.598687)
			(xy 164.739838 -286.581235) (xy 164.788057 -286.571391) (xy 164.837232 -286.56941) (xy 164.886087 -286.575342)
			(xy 164.933358 -286.589034) (xy 164.97782 -286.610132) (xy 165.018323 -286.638088) (xy 165.053816 -286.67218)
			(xy 165.083381 -286.711524) (xy 165.106252 -286.755101) (xy 165.121836 -286.801782) (xy 165.129731 -286.850359)
			(xy 165.130226 -286.874966) (xy 165.469074 -286.874966) (xy 165.473034 -286.825912) (xy 165.484811 -286.778128)
			(xy 165.504102 -286.732852) (xy 165.530405 -286.691256) (xy 165.56304 -286.654419) (xy 165.601161 -286.623294)
			(xy 165.643782 -286.598687) (xy 165.689798 -286.581235) (xy 165.738017 -286.571391) (xy 165.787192 -286.56941)
			(xy 165.836047 -286.575342) (xy 165.883318 -286.589034) (xy 165.92778 -286.610132) (xy 165.968283 -286.638088)
			(xy 166.003776 -286.67218) (xy 166.033341 -286.711524) (xy 166.056212 -286.755101) (xy 166.071796 -286.801782)
			(xy 166.079691 -286.850359) (xy 166.080186 -286.874966) (xy 166.419288 -286.874966) (xy 166.423248 -286.825912)
			(xy 166.435025 -286.778128) (xy 166.454316 -286.732852) (xy 166.480619 -286.691256) (xy 166.513254 -286.654419)
			(xy 166.551375 -286.623294) (xy 166.593996 -286.598687) (xy 166.640012 -286.581235) (xy 166.688231 -286.571391)
			(xy 166.737406 -286.56941) (xy 166.786261 -286.575342) (xy 166.833532 -286.589034) (xy 166.877994 -286.610132)
			(xy 166.918497 -286.638088) (xy 166.95399 -286.67218) (xy 166.983555 -286.711524) (xy 167.006426 -286.755101)
			(xy 167.02201 -286.801782) (xy 167.029905 -286.850359) (xy 167.0304 -286.874966) (xy 167.369248 -286.874966)
			(xy 167.373208 -286.825912) (xy 167.384985 -286.778128) (xy 167.404276 -286.732852) (xy 167.430579 -286.691256)
			(xy 167.463214 -286.654419) (xy 167.501335 -286.623294) (xy 167.543956 -286.598687) (xy 167.589972 -286.581235)
			(xy 167.638191 -286.571391) (xy 167.687366 -286.56941) (xy 167.736221 -286.575342) (xy 167.783492 -286.589034)
			(xy 167.827954 -286.610132) (xy 167.868457 -286.638088) (xy 167.90395 -286.67218) (xy 167.933515 -286.711524)
			(xy 167.956386 -286.755101) (xy 167.97197 -286.801782) (xy 167.979865 -286.850359) (xy 167.98036 -286.874966)
			(xy 168.319208 -286.874966) (xy 168.323168 -286.825912) (xy 168.334945 -286.778128) (xy 168.354236 -286.732852)
			(xy 168.380539 -286.691256) (xy 168.413174 -286.654419) (xy 168.451295 -286.623294) (xy 168.493916 -286.598687)
			(xy 168.539932 -286.581235) (xy 168.588151 -286.571391) (xy 168.637326 -286.56941) (xy 168.686181 -286.575342)
			(xy 168.733452 -286.589034) (xy 168.777914 -286.610132) (xy 168.818417 -286.638088) (xy 168.85391 -286.67218)
			(xy 168.883475 -286.711524) (xy 168.906346 -286.755101) (xy 168.92193 -286.801782) (xy 168.929825 -286.850359)
			(xy 168.93032 -286.874966) (xy 169.269168 -286.874966) (xy 169.273128 -286.825912) (xy 169.284905 -286.778128)
			(xy 169.304196 -286.732852) (xy 169.330499 -286.691256) (xy 169.363134 -286.654419) (xy 169.401255 -286.623294)
			(xy 169.443876 -286.598687) (xy 169.489892 -286.581235) (xy 169.538111 -286.571391) (xy 169.587286 -286.56941)
			(xy 169.636141 -286.575342) (xy 169.683412 -286.589034) (xy 169.727874 -286.610132) (xy 169.768377 -286.638088)
			(xy 169.80387 -286.67218) (xy 169.833435 -286.711524) (xy 169.856306 -286.755101) (xy 169.87189 -286.801782)
			(xy 169.879785 -286.850359) (xy 169.88028 -286.874966) (xy 170.219128 -286.874966) (xy 170.223088 -286.825912)
			(xy 170.234865 -286.778128) (xy 170.254156 -286.732852) (xy 170.280459 -286.691256) (xy 170.313094 -286.654419)
			(xy 170.351215 -286.623294) (xy 170.393836 -286.598687) (xy 170.439852 -286.581235) (xy 170.488071 -286.571391)
			(xy 170.537246 -286.56941) (xy 170.586101 -286.575342) (xy 170.633372 -286.589034) (xy 170.677834 -286.610132)
			(xy 170.718337 -286.638088) (xy 170.75383 -286.67218) (xy 170.783395 -286.711524) (xy 170.806266 -286.755101)
			(xy 170.82185 -286.801782) (xy 170.829745 -286.850359) (xy 170.83024 -286.874966) (xy 171.169088 -286.874966)
			(xy 171.173048 -286.825912) (xy 171.184825 -286.778128) (xy 171.204116 -286.732852) (xy 171.230419 -286.691256)
			(xy 171.263054 -286.654419) (xy 171.301175 -286.623294) (xy 171.343796 -286.598687) (xy 171.389812 -286.581235)
			(xy 171.438031 -286.571391) (xy 171.487206 -286.56941) (xy 171.536061 -286.575342) (xy 171.583332 -286.589034)
			(xy 171.627794 -286.610132) (xy 171.668297 -286.638088) (xy 171.70379 -286.67218) (xy 171.733355 -286.711524)
			(xy 171.756226 -286.755101) (xy 171.77181 -286.801782) (xy 171.779705 -286.850359) (xy 171.7802 -286.874966)
			(xy 172.119048 -286.874966) (xy 172.123008 -286.825912) (xy 172.134785 -286.778128) (xy 172.154076 -286.732852)
			(xy 172.180379 -286.691256) (xy 172.213014 -286.654419) (xy 172.251135 -286.623294) (xy 172.293756 -286.598687)
			(xy 172.339772 -286.581235) (xy 172.387991 -286.571391) (xy 172.437166 -286.56941) (xy 172.486021 -286.575342)
			(xy 172.533292 -286.589034) (xy 172.577754 -286.610132) (xy 172.618257 -286.638088) (xy 172.65375 -286.67218)
			(xy 172.683315 -286.711524) (xy 172.706186 -286.755101) (xy 172.72177 -286.801782) (xy 172.729665 -286.850359)
			(xy 172.73016 -286.874966) (xy 173.069262 -286.874966) (xy 173.073222 -286.825912) (xy 173.084999 -286.778128)
			(xy 173.10429 -286.732852) (xy 173.130593 -286.691256) (xy 173.163228 -286.654419) (xy 173.201349 -286.623294)
			(xy 173.24397 -286.598687) (xy 173.289986 -286.581235) (xy 173.338205 -286.571391) (xy 173.38738 -286.56941)
			(xy 173.436235 -286.575342) (xy 173.483506 -286.589034) (xy 173.527968 -286.610132) (xy 173.568471 -286.638088)
			(xy 173.603964 -286.67218) (xy 173.633529 -286.711524) (xy 173.6564 -286.755101) (xy 173.671984 -286.801782)
			(xy 173.679879 -286.850359) (xy 173.680374 -286.874966) (xy 174.019222 -286.874966) (xy 174.023182 -286.825912)
			(xy 174.034959 -286.778128) (xy 174.05425 -286.732852) (xy 174.080553 -286.691256) (xy 174.113188 -286.654419)
			(xy 174.151309 -286.623294) (xy 174.19393 -286.598687) (xy 174.239946 -286.581235) (xy 174.288165 -286.571391)
			(xy 174.33734 -286.56941) (xy 174.386195 -286.575342) (xy 174.433466 -286.589034) (xy 174.477928 -286.610132)
			(xy 174.518431 -286.638088) (xy 174.553924 -286.67218) (xy 174.583489 -286.711524) (xy 174.60636 -286.755101)
			(xy 174.621944 -286.801782) (xy 174.629839 -286.850359) (xy 174.630334 -286.874966) (xy 175.919142 -286.874966)
			(xy 175.923102 -286.825912) (xy 175.934879 -286.778128) (xy 175.95417 -286.732852) (xy 175.980473 -286.691256)
			(xy 176.013108 -286.654419) (xy 176.051229 -286.623294) (xy 176.09385 -286.598687) (xy 176.139866 -286.581235)
			(xy 176.188085 -286.571391) (xy 176.23726 -286.56941) (xy 176.286115 -286.575342) (xy 176.333386 -286.589034)
			(xy 176.377848 -286.610132) (xy 176.418351 -286.638088) (xy 176.453844 -286.67218) (xy 176.483409 -286.711524)
			(xy 176.50628 -286.755101) (xy 176.521864 -286.801782) (xy 176.529759 -286.850359) (xy 176.530254 -286.874966)
			(xy 176.869102 -286.874966) (xy 176.873062 -286.825912) (xy 176.884839 -286.778128) (xy 176.90413 -286.732852)
			(xy 176.930433 -286.691256) (xy 176.963068 -286.654419) (xy 177.001189 -286.623294) (xy 177.04381 -286.598687)
			(xy 177.089826 -286.581235) (xy 177.138045 -286.571391) (xy 177.18722 -286.56941) (xy 177.236075 -286.575342)
			(xy 177.283346 -286.589034) (xy 177.327808 -286.610132) (xy 177.368311 -286.638088) (xy 177.403804 -286.67218)
			(xy 177.433369 -286.711524) (xy 177.45624 -286.755101) (xy 177.471824 -286.801782) (xy 177.479719 -286.850359)
			(xy 177.480214 -286.874966) (xy 177.819062 -286.874966) (xy 177.823022 -286.825912) (xy 177.834799 -286.778128)
			(xy 177.85409 -286.732852) (xy 177.880393 -286.691256) (xy 177.913028 -286.654419) (xy 177.951149 -286.623294)
			(xy 177.99377 -286.598687) (xy 178.039786 -286.581235) (xy 178.088005 -286.571391) (xy 178.13718 -286.56941)
			(xy 178.186035 -286.575342) (xy 178.233306 -286.589034) (xy 178.277768 -286.610132) (xy 178.318271 -286.638088)
			(xy 178.353764 -286.67218) (xy 178.383329 -286.711524) (xy 178.4062 -286.755101) (xy 178.421784 -286.801782)
			(xy 178.429679 -286.850359) (xy 178.430174 -286.874966) (xy 178.769276 -286.874966) (xy 178.773236 -286.825912)
			(xy 178.785013 -286.778128) (xy 178.804304 -286.732852) (xy 178.830607 -286.691256) (xy 178.863242 -286.654419)
			(xy 178.901363 -286.623294) (xy 178.943984 -286.598687) (xy 178.99 -286.581235) (xy 179.038219 -286.571391)
			(xy 179.087394 -286.56941) (xy 179.136249 -286.575342) (xy 179.18352 -286.589034) (xy 179.227982 -286.610132)
			(xy 179.268485 -286.638088) (xy 179.303978 -286.67218) (xy 179.333543 -286.711524) (xy 179.356414 -286.755101)
			(xy 179.371998 -286.801782) (xy 179.379893 -286.850359) (xy 179.380388 -286.874966) (xy 179.719236 -286.874966)
			(xy 179.723196 -286.825912) (xy 179.734973 -286.778128) (xy 179.754264 -286.732852) (xy 179.780567 -286.691256)
			(xy 179.813202 -286.654419) (xy 179.851323 -286.623294) (xy 179.893944 -286.598687) (xy 179.93996 -286.581235)
			(xy 179.988179 -286.571391) (xy 180.037354 -286.56941) (xy 180.086209 -286.575342) (xy 180.13348 -286.589034)
			(xy 180.177942 -286.610132) (xy 180.218445 -286.638088) (xy 180.253938 -286.67218) (xy 180.283503 -286.711524)
			(xy 180.306374 -286.755101) (xy 180.321958 -286.801782) (xy 180.329853 -286.850359) (xy 180.330348 -286.874966)
			(xy 180.669196 -286.874966) (xy 180.673156 -286.825912) (xy 180.684933 -286.778128) (xy 180.704224 -286.732852)
			(xy 180.730527 -286.691256) (xy 180.763162 -286.654419) (xy 180.801283 -286.623294) (xy 180.843904 -286.598687)
			(xy 180.88992 -286.581235) (xy 180.938139 -286.571391) (xy 180.987314 -286.56941) (xy 181.036169 -286.575342)
			(xy 181.08344 -286.589034) (xy 181.127902 -286.610132) (xy 181.168405 -286.638088) (xy 181.203898 -286.67218)
			(xy 181.233463 -286.711524) (xy 181.256334 -286.755101) (xy 181.271918 -286.801782) (xy 181.279813 -286.850359)
			(xy 181.280308 -286.874966) (xy 181.619156 -286.874966) (xy 181.623116 -286.825912) (xy 181.634893 -286.778128)
			(xy 181.654184 -286.732852) (xy 181.680487 -286.691256) (xy 181.713122 -286.654419) (xy 181.751243 -286.623294)
			(xy 181.793864 -286.598687) (xy 181.83988 -286.581235) (xy 181.888099 -286.571391) (xy 181.937274 -286.56941)
			(xy 181.986129 -286.575342) (xy 182.0334 -286.589034) (xy 182.077862 -286.610132) (xy 182.118365 -286.638088)
			(xy 182.153858 -286.67218) (xy 182.183423 -286.711524) (xy 182.206294 -286.755101) (xy 182.221878 -286.801782)
			(xy 182.229773 -286.850359) (xy 182.230268 -286.874966) (xy 182.569116 -286.874966) (xy 182.573076 -286.825912)
			(xy 182.584853 -286.778128) (xy 182.604144 -286.732852) (xy 182.630447 -286.691256) (xy 182.663082 -286.654419)
			(xy 182.701203 -286.623294) (xy 182.743824 -286.598687) (xy 182.78984 -286.581235) (xy 182.838059 -286.571391)
			(xy 182.887234 -286.56941) (xy 182.936089 -286.575342) (xy 182.98336 -286.589034) (xy 183.027822 -286.610132)
			(xy 183.068325 -286.638088) (xy 183.103818 -286.67218) (xy 183.133383 -286.711524) (xy 183.156254 -286.755101)
			(xy 183.171838 -286.801782) (xy 183.179733 -286.850359) (xy 183.180228 -286.874966) (xy 183.519076 -286.874966)
			(xy 183.523036 -286.825912) (xy 183.534813 -286.778128) (xy 183.554104 -286.732852) (xy 183.580407 -286.691256)
			(xy 183.613042 -286.654419) (xy 183.651163 -286.623294) (xy 183.693784 -286.598687) (xy 183.7398 -286.581235)
			(xy 183.788019 -286.571391) (xy 183.837194 -286.56941) (xy 183.886049 -286.575342) (xy 183.93332 -286.589034)
			(xy 183.977782 -286.610132) (xy 184.018285 -286.638088) (xy 184.053778 -286.67218) (xy 184.083343 -286.711524)
			(xy 184.106214 -286.755101) (xy 184.121798 -286.801782) (xy 184.129693 -286.850359) (xy 184.130188 -286.874966)
			(xy 184.469036 -286.874966) (xy 184.472996 -286.825912) (xy 184.484773 -286.778128) (xy 184.504064 -286.732852)
			(xy 184.530367 -286.691256) (xy 184.563002 -286.654419) (xy 184.601123 -286.623294) (xy 184.643744 -286.598687)
			(xy 184.68976 -286.581235) (xy 184.737979 -286.571391) (xy 184.787154 -286.56941) (xy 184.836009 -286.575342)
			(xy 184.88328 -286.589034) (xy 184.927742 -286.610132) (xy 184.968245 -286.638088) (xy 185.003738 -286.67218)
			(xy 185.033303 -286.711524) (xy 185.056174 -286.755101) (xy 185.071758 -286.801782) (xy 185.079653 -286.850359)
			(xy 185.080148 -286.874966) (xy 186.36921 -286.874966) (xy 186.37317 -286.825912) (xy 186.384947 -286.778128)
			(xy 186.404238 -286.732852) (xy 186.430541 -286.691256) (xy 186.463176 -286.654419) (xy 186.501297 -286.623294)
			(xy 186.543918 -286.598687) (xy 186.589934 -286.581235) (xy 186.638153 -286.571391) (xy 186.687328 -286.56941)
			(xy 186.736183 -286.575342) (xy 186.783454 -286.589034) (xy 186.827916 -286.610132) (xy 186.868419 -286.638088)
			(xy 186.903912 -286.67218) (xy 186.933477 -286.711524) (xy 186.956348 -286.755101) (xy 186.971932 -286.801782)
			(xy 186.979827 -286.850359) (xy 186.980322 -286.874966) (xy 186.979827 -286.899573) (xy 186.971932 -286.94815)
			(xy 186.956348 -286.994831) (xy 186.933477 -287.038408) (xy 186.903912 -287.077752) (xy 186.868419 -287.111844)
			(xy 186.827916 -287.1398) (xy 186.783454 -287.160898) (xy 186.736183 -287.17459) (xy 186.687328 -287.180522)
			(xy 186.638153 -287.178541) (xy 186.589934 -287.168697) (xy 186.543918 -287.151245) (xy 186.501297 -287.126638)
			(xy 186.463176 -287.095513) (xy 186.430541 -287.058676) (xy 186.404238 -287.01708) (xy 186.384947 -286.971804)
			(xy 186.37317 -286.92402) (xy 186.36921 -286.874966) (xy 185.080148 -286.874966) (xy 185.079653 -286.899573)
			(xy 185.071758 -286.94815) (xy 185.056174 -286.994831) (xy 185.033303 -287.038408) (xy 185.003738 -287.077752)
			(xy 184.968245 -287.111844) (xy 184.927742 -287.1398) (xy 184.88328 -287.160898) (xy 184.836009 -287.17459)
			(xy 184.787154 -287.180522) (xy 184.737979 -287.178541) (xy 184.68976 -287.168697) (xy 184.643744 -287.151245)
			(xy 184.601123 -287.126638) (xy 184.563002 -287.095513) (xy 184.530367 -287.058676) (xy 184.504064 -287.01708)
			(xy 184.484773 -286.971804) (xy 184.472996 -286.92402) (xy 184.469036 -286.874966) (xy 184.130188 -286.874966)
			(xy 184.129693 -286.899573) (xy 184.121798 -286.94815) (xy 184.106214 -286.994831) (xy 184.083343 -287.038408)
			(xy 184.053778 -287.077752) (xy 184.018285 -287.111844) (xy 183.977782 -287.1398) (xy 183.93332 -287.160898)
			(xy 183.886049 -287.17459) (xy 183.837194 -287.180522) (xy 183.788019 -287.178541) (xy 183.7398 -287.168697)
			(xy 183.693784 -287.151245) (xy 183.651163 -287.126638) (xy 183.613042 -287.095513) (xy 183.580407 -287.058676)
			(xy 183.554104 -287.01708) (xy 183.534813 -286.971804) (xy 183.523036 -286.92402) (xy 183.519076 -286.874966)
			(xy 183.180228 -286.874966) (xy 183.179733 -286.899573) (xy 183.171838 -286.94815) (xy 183.156254 -286.994831)
			(xy 183.133383 -287.038408) (xy 183.103818 -287.077752) (xy 183.068325 -287.111844) (xy 183.027822 -287.1398)
			(xy 182.98336 -287.160898) (xy 182.936089 -287.17459) (xy 182.887234 -287.180522) (xy 182.838059 -287.178541)
			(xy 182.78984 -287.168697) (xy 182.743824 -287.151245) (xy 182.701203 -287.126638) (xy 182.663082 -287.095513)
			(xy 182.630447 -287.058676) (xy 182.604144 -287.01708) (xy 182.584853 -286.971804) (xy 182.573076 -286.92402)
			(xy 182.569116 -286.874966) (xy 182.230268 -286.874966) (xy 182.229773 -286.899573) (xy 182.221878 -286.94815)
			(xy 182.206294 -286.994831) (xy 182.183423 -287.038408) (xy 182.153858 -287.077752) (xy 182.118365 -287.111844)
			(xy 182.077862 -287.1398) (xy 182.0334 -287.160898) (xy 181.986129 -287.17459) (xy 181.937274 -287.180522)
			(xy 181.888099 -287.178541) (xy 181.83988 -287.168697) (xy 181.793864 -287.151245) (xy 181.751243 -287.126638)
			(xy 181.713122 -287.095513) (xy 181.680487 -287.058676) (xy 181.654184 -287.01708) (xy 181.634893 -286.971804)
			(xy 181.623116 -286.92402) (xy 181.619156 -286.874966) (xy 181.280308 -286.874966) (xy 181.279813 -286.899573)
			(xy 181.271918 -286.94815) (xy 181.256334 -286.994831) (xy 181.233463 -287.038408) (xy 181.203898 -287.077752)
			(xy 181.168405 -287.111844) (xy 181.127902 -287.1398) (xy 181.08344 -287.160898) (xy 181.036169 -287.17459)
			(xy 180.987314 -287.180522) (xy 180.938139 -287.178541) (xy 180.88992 -287.168697) (xy 180.843904 -287.151245)
			(xy 180.801283 -287.126638) (xy 180.763162 -287.095513) (xy 180.730527 -287.058676) (xy 180.704224 -287.01708)
			(xy 180.684933 -286.971804) (xy 180.673156 -286.92402) (xy 180.669196 -286.874966) (xy 180.330348 -286.874966)
			(xy 180.329853 -286.899573) (xy 180.321958 -286.94815) (xy 180.306374 -286.994831) (xy 180.283503 -287.038408)
			(xy 180.253938 -287.077752) (xy 180.218445 -287.111844) (xy 180.177942 -287.1398) (xy 180.13348 -287.160898)
			(xy 180.086209 -287.17459) (xy 180.037354 -287.180522) (xy 179.988179 -287.178541) (xy 179.93996 -287.168697)
			(xy 179.893944 -287.151245) (xy 179.851323 -287.126638) (xy 179.813202 -287.095513) (xy 179.780567 -287.058676)
			(xy 179.754264 -287.01708) (xy 179.734973 -286.971804) (xy 179.723196 -286.92402) (xy 179.719236 -286.874966)
			(xy 179.380388 -286.874966) (xy 179.379893 -286.899573) (xy 179.371998 -286.94815) (xy 179.356414 -286.994831)
			(xy 179.333543 -287.038408) (xy 179.303978 -287.077752) (xy 179.268485 -287.111844) (xy 179.227982 -287.1398)
			(xy 179.18352 -287.160898) (xy 179.136249 -287.17459) (xy 179.087394 -287.180522) (xy 179.038219 -287.178541)
			(xy 178.99 -287.168697) (xy 178.943984 -287.151245) (xy 178.901363 -287.126638) (xy 178.863242 -287.095513)
			(xy 178.830607 -287.058676) (xy 178.804304 -287.01708) (xy 178.785013 -286.971804) (xy 178.773236 -286.92402)
			(xy 178.769276 -286.874966) (xy 178.430174 -286.874966) (xy 178.429679 -286.899573) (xy 178.421784 -286.94815)
			(xy 178.4062 -286.994831) (xy 178.383329 -287.038408) (xy 178.353764 -287.077752) (xy 178.318271 -287.111844)
			(xy 178.277768 -287.1398) (xy 178.233306 -287.160898) (xy 178.186035 -287.17459) (xy 178.13718 -287.180522)
			(xy 178.088005 -287.178541) (xy 178.039786 -287.168697) (xy 177.99377 -287.151245) (xy 177.951149 -287.126638)
			(xy 177.913028 -287.095513) (xy 177.880393 -287.058676) (xy 177.85409 -287.01708) (xy 177.834799 -286.971804)
			(xy 177.823022 -286.92402) (xy 177.819062 -286.874966) (xy 177.480214 -286.874966) (xy 177.479719 -286.899573)
			(xy 177.471824 -286.94815) (xy 177.45624 -286.994831) (xy 177.433369 -287.038408) (xy 177.403804 -287.077752)
			(xy 177.368311 -287.111844) (xy 177.327808 -287.1398) (xy 177.283346 -287.160898) (xy 177.236075 -287.17459)
			(xy 177.18722 -287.180522) (xy 177.138045 -287.178541) (xy 177.089826 -287.168697) (xy 177.04381 -287.151245)
			(xy 177.001189 -287.126638) (xy 176.963068 -287.095513) (xy 176.930433 -287.058676) (xy 176.90413 -287.01708)
			(xy 176.884839 -286.971804) (xy 176.873062 -286.92402) (xy 176.869102 -286.874966) (xy 176.530254 -286.874966)
			(xy 176.529759 -286.899573) (xy 176.521864 -286.94815) (xy 176.50628 -286.994831) (xy 176.483409 -287.038408)
			(xy 176.453844 -287.077752) (xy 176.418351 -287.111844) (xy 176.377848 -287.1398) (xy 176.333386 -287.160898)
			(xy 176.286115 -287.17459) (xy 176.23726 -287.180522) (xy 176.188085 -287.178541) (xy 176.139866 -287.168697)
			(xy 176.09385 -287.151245) (xy 176.051229 -287.126638) (xy 176.013108 -287.095513) (xy 175.980473 -287.058676)
			(xy 175.95417 -287.01708) (xy 175.934879 -286.971804) (xy 175.923102 -286.92402) (xy 175.919142 -286.874966)
			(xy 174.630334 -286.874966) (xy 174.629839 -286.899573) (xy 174.621944 -286.94815) (xy 174.60636 -286.994831)
			(xy 174.583489 -287.038408) (xy 174.553924 -287.077752) (xy 174.518431 -287.111844) (xy 174.477928 -287.1398)
			(xy 174.433466 -287.160898) (xy 174.386195 -287.17459) (xy 174.33734 -287.180522) (xy 174.288165 -287.178541)
			(xy 174.239946 -287.168697) (xy 174.19393 -287.151245) (xy 174.151309 -287.126638) (xy 174.113188 -287.095513)
			(xy 174.080553 -287.058676) (xy 174.05425 -287.01708) (xy 174.034959 -286.971804) (xy 174.023182 -286.92402)
			(xy 174.019222 -286.874966) (xy 173.680374 -286.874966) (xy 173.679879 -286.899573) (xy 173.671984 -286.94815)
			(xy 173.6564 -286.994831) (xy 173.633529 -287.038408) (xy 173.603964 -287.077752) (xy 173.568471 -287.111844)
			(xy 173.527968 -287.1398) (xy 173.483506 -287.160898) (xy 173.436235 -287.17459) (xy 173.38738 -287.180522)
			(xy 173.338205 -287.178541) (xy 173.289986 -287.168697) (xy 173.24397 -287.151245) (xy 173.201349 -287.126638)
			(xy 173.163228 -287.095513) (xy 173.130593 -287.058676) (xy 173.10429 -287.01708) (xy 173.084999 -286.971804)
			(xy 173.073222 -286.92402) (xy 173.069262 -286.874966) (xy 172.73016 -286.874966) (xy 172.729665 -286.899573)
			(xy 172.72177 -286.94815) (xy 172.706186 -286.994831) (xy 172.683315 -287.038408) (xy 172.65375 -287.077752)
			(xy 172.618257 -287.111844) (xy 172.577754 -287.1398) (xy 172.533292 -287.160898) (xy 172.486021 -287.17459)
			(xy 172.437166 -287.180522) (xy 172.387991 -287.178541) (xy 172.339772 -287.168697) (xy 172.293756 -287.151245)
			(xy 172.251135 -287.126638) (xy 172.213014 -287.095513) (xy 172.180379 -287.058676) (xy 172.154076 -287.01708)
			(xy 172.134785 -286.971804) (xy 172.123008 -286.92402) (xy 172.119048 -286.874966) (xy 171.7802 -286.874966)
			(xy 171.779705 -286.899573) (xy 171.77181 -286.94815) (xy 171.756226 -286.994831) (xy 171.733355 -287.038408)
			(xy 171.70379 -287.077752) (xy 171.668297 -287.111844) (xy 171.627794 -287.1398) (xy 171.583332 -287.160898)
			(xy 171.536061 -287.17459) (xy 171.487206 -287.180522) (xy 171.438031 -287.178541) (xy 171.389812 -287.168697)
			(xy 171.343796 -287.151245) (xy 171.301175 -287.126638) (xy 171.263054 -287.095513) (xy 171.230419 -287.058676)
			(xy 171.204116 -287.01708) (xy 171.184825 -286.971804) (xy 171.173048 -286.92402) (xy 171.169088 -286.874966)
			(xy 170.83024 -286.874966) (xy 170.829745 -286.899573) (xy 170.82185 -286.94815) (xy 170.806266 -286.994831)
			(xy 170.783395 -287.038408) (xy 170.75383 -287.077752) (xy 170.718337 -287.111844) (xy 170.677834 -287.1398)
			(xy 170.633372 -287.160898) (xy 170.586101 -287.17459) (xy 170.537246 -287.180522) (xy 170.488071 -287.178541)
			(xy 170.439852 -287.168697) (xy 170.393836 -287.151245) (xy 170.351215 -287.126638) (xy 170.313094 -287.095513)
			(xy 170.280459 -287.058676) (xy 170.254156 -287.01708) (xy 170.234865 -286.971804) (xy 170.223088 -286.92402)
			(xy 170.219128 -286.874966) (xy 169.88028 -286.874966) (xy 169.879785 -286.899573) (xy 169.87189 -286.94815)
			(xy 169.856306 -286.994831) (xy 169.833435 -287.038408) (xy 169.80387 -287.077752) (xy 169.768377 -287.111844)
			(xy 169.727874 -287.1398) (xy 169.683412 -287.160898) (xy 169.636141 -287.17459) (xy 169.587286 -287.180522)
			(xy 169.538111 -287.178541) (xy 169.489892 -287.168697) (xy 169.443876 -287.151245) (xy 169.401255 -287.126638)
			(xy 169.363134 -287.095513) (xy 169.330499 -287.058676) (xy 169.304196 -287.01708) (xy 169.284905 -286.971804)
			(xy 169.273128 -286.92402) (xy 169.269168 -286.874966) (xy 168.93032 -286.874966) (xy 168.929825 -286.899573)
			(xy 168.92193 -286.94815) (xy 168.906346 -286.994831) (xy 168.883475 -287.038408) (xy 168.85391 -287.077752)
			(xy 168.818417 -287.111844) (xy 168.777914 -287.1398) (xy 168.733452 -287.160898) (xy 168.686181 -287.17459)
			(xy 168.637326 -287.180522) (xy 168.588151 -287.178541) (xy 168.539932 -287.168697) (xy 168.493916 -287.151245)
			(xy 168.451295 -287.126638) (xy 168.413174 -287.095513) (xy 168.380539 -287.058676) (xy 168.354236 -287.01708)
			(xy 168.334945 -286.971804) (xy 168.323168 -286.92402) (xy 168.319208 -286.874966) (xy 167.98036 -286.874966)
			(xy 167.979865 -286.899573) (xy 167.97197 -286.94815) (xy 167.956386 -286.994831) (xy 167.933515 -287.038408)
			(xy 167.90395 -287.077752) (xy 167.868457 -287.111844) (xy 167.827954 -287.1398) (xy 167.783492 -287.160898)
			(xy 167.736221 -287.17459) (xy 167.687366 -287.180522) (xy 167.638191 -287.178541) (xy 167.589972 -287.168697)
			(xy 167.543956 -287.151245) (xy 167.501335 -287.126638) (xy 167.463214 -287.095513) (xy 167.430579 -287.058676)
			(xy 167.404276 -287.01708) (xy 167.384985 -286.971804) (xy 167.373208 -286.92402) (xy 167.369248 -286.874966)
			(xy 167.0304 -286.874966) (xy 167.029905 -286.899573) (xy 167.02201 -286.94815) (xy 167.006426 -286.994831)
			(xy 166.983555 -287.038408) (xy 166.95399 -287.077752) (xy 166.918497 -287.111844) (xy 166.877994 -287.1398)
			(xy 166.833532 -287.160898) (xy 166.786261 -287.17459) (xy 166.737406 -287.180522) (xy 166.688231 -287.178541)
			(xy 166.640012 -287.168697) (xy 166.593996 -287.151245) (xy 166.551375 -287.126638) (xy 166.513254 -287.095513)
			(xy 166.480619 -287.058676) (xy 166.454316 -287.01708) (xy 166.435025 -286.971804) (xy 166.423248 -286.92402)
			(xy 166.419288 -286.874966) (xy 166.080186 -286.874966) (xy 166.079691 -286.899573) (xy 166.071796 -286.94815)
			(xy 166.056212 -286.994831) (xy 166.033341 -287.038408) (xy 166.003776 -287.077752) (xy 165.968283 -287.111844)
			(xy 165.92778 -287.1398) (xy 165.883318 -287.160898) (xy 165.836047 -287.17459) (xy 165.787192 -287.180522)
			(xy 165.738017 -287.178541) (xy 165.689798 -287.168697) (xy 165.643782 -287.151245) (xy 165.601161 -287.126638)
			(xy 165.56304 -287.095513) (xy 165.530405 -287.058676) (xy 165.504102 -287.01708) (xy 165.484811 -286.971804)
			(xy 165.473034 -286.92402) (xy 165.469074 -286.874966) (xy 165.130226 -286.874966) (xy 165.129731 -286.899573)
			(xy 165.121836 -286.94815) (xy 165.106252 -286.994831) (xy 165.083381 -287.038408) (xy 165.053816 -287.077752)
			(xy 165.018323 -287.111844) (xy 164.97782 -287.1398) (xy 164.933358 -287.160898) (xy 164.886087 -287.17459)
			(xy 164.837232 -287.180522) (xy 164.788057 -287.178541) (xy 164.739838 -287.168697) (xy 164.693822 -287.151245)
			(xy 164.651201 -287.126638) (xy 164.61308 -287.095513) (xy 164.580445 -287.058676) (xy 164.554142 -287.01708)
			(xy 164.534851 -286.971804) (xy 164.523074 -286.92402) (xy 164.519114 -286.874966) (xy 164.180266 -286.874966)
			(xy 164.179771 -286.899573) (xy 164.171876 -286.94815) (xy 164.156292 -286.994831) (xy 164.133421 -287.038408)
			(xy 164.103856 -287.077752) (xy 164.068363 -287.111844) (xy 164.02786 -287.1398) (xy 163.983398 -287.160898)
			(xy 163.936127 -287.17459) (xy 163.887272 -287.180522) (xy 163.838097 -287.178541) (xy 163.789878 -287.168697)
			(xy 163.743862 -287.151245) (xy 163.701241 -287.126638) (xy 163.66312 -287.095513) (xy 163.630485 -287.058676)
			(xy 163.604182 -287.01708) (xy 163.584891 -286.971804) (xy 163.573114 -286.92402) (xy 163.569154 -286.874966)
			(xy 163.230306 -286.874966) (xy 163.229811 -286.899573) (xy 163.221916 -286.94815) (xy 163.206332 -286.994831)
			(xy 163.183461 -287.038408) (xy 163.153896 -287.077752) (xy 163.118403 -287.111844) (xy 163.0779 -287.1398)
			(xy 163.033438 -287.160898) (xy 162.986167 -287.17459) (xy 162.937312 -287.180522) (xy 162.888137 -287.178541)
			(xy 162.839918 -287.168697) (xy 162.793902 -287.151245) (xy 162.751281 -287.126638) (xy 162.71316 -287.095513)
			(xy 162.680525 -287.058676) (xy 162.654222 -287.01708) (xy 162.634931 -286.971804) (xy 162.623154 -286.92402)
			(xy 162.619194 -286.874966) (xy 162.280346 -286.874966) (xy 162.279851 -286.899573) (xy 162.271956 -286.94815)
			(xy 162.256372 -286.994831) (xy 162.233501 -287.038408) (xy 162.203936 -287.077752) (xy 162.168443 -287.111844)
			(xy 162.12794 -287.1398) (xy 162.083478 -287.160898) (xy 162.036207 -287.17459) (xy 161.987352 -287.180522)
			(xy 161.938177 -287.178541) (xy 161.889958 -287.168697) (xy 161.843942 -287.151245) (xy 161.801321 -287.126638)
			(xy 161.7632 -287.095513) (xy 161.730565 -287.058676) (xy 161.704262 -287.01708) (xy 161.684971 -286.971804)
			(xy 161.673194 -286.92402) (xy 161.669234 -286.874966) (xy 161.330386 -286.874966) (xy 161.329891 -286.899573)
			(xy 161.321996 -286.94815) (xy 161.306412 -286.994831) (xy 161.283541 -287.038408) (xy 161.253976 -287.077752)
			(xy 161.218483 -287.111844) (xy 161.17798 -287.1398) (xy 161.133518 -287.160898) (xy 161.086247 -287.17459)
			(xy 161.037392 -287.180522) (xy 160.988217 -287.178541) (xy 160.939998 -287.168697) (xy 160.893982 -287.151245)
			(xy 160.851361 -287.126638) (xy 160.81324 -287.095513) (xy 160.780605 -287.058676) (xy 160.754302 -287.01708)
			(xy 160.735011 -286.971804) (xy 160.723234 -286.92402) (xy 160.719274 -286.874966) (xy 160.380167 -286.874966)
			(xy 160.379677 -286.899319) (xy 160.371782 -286.947896) (xy 160.356198 -286.994577) (xy 160.333327 -287.038154)
			(xy 160.303762 -287.077498) (xy 160.268269 -287.11159) (xy 160.227766 -287.139546) (xy 160.183304 -287.160644)
			(xy 160.136033 -287.174336) (xy 160.087178 -287.180268) (xy 160.038003 -287.178287) (xy 159.989784 -287.168443)
			(xy 159.943768 -287.150991) (xy 159.901147 -287.126384) (xy 159.863026 -287.095259) (xy 159.830391 -287.058422)
			(xy 159.804088 -287.016826) (xy 159.784797 -286.97155) (xy 159.77302 -286.923766) (xy 159.76906 -286.874712)
			(xy 159.430212 -286.874712) (xy 159.429717 -286.899319) (xy 159.421822 -286.947896) (xy 159.406238 -286.994577)
			(xy 159.383367 -287.038154) (xy 159.353802 -287.077498) (xy 159.318309 -287.11159) (xy 159.277806 -287.139546)
			(xy 159.233344 -287.160644) (xy 159.186073 -287.174336) (xy 159.137218 -287.180268) (xy 159.088043 -287.178287)
			(xy 159.039824 -287.168443) (xy 158.993808 -287.150991) (xy 158.951187 -287.126384) (xy 158.913066 -287.095259)
			(xy 158.880431 -287.058422) (xy 158.854128 -287.016826) (xy 158.834837 -286.97155) (xy 158.82306 -286.923766)
			(xy 158.8191 -286.874712) (xy 158.480247 -286.874712) (xy 158.480252 -286.874966) (xy 158.479757 -286.899573)
			(xy 158.471862 -286.94815) (xy 158.456278 -286.994831) (xy 158.433407 -287.038408) (xy 158.403842 -287.077752)
			(xy 158.368349 -287.111844) (xy 158.327846 -287.1398) (xy 158.283384 -287.160898) (xy 158.236113 -287.17459)
			(xy 158.187258 -287.180522) (xy 158.138083 -287.178541) (xy 158.089864 -287.168697) (xy 158.043848 -287.151245)
			(xy 158.001227 -287.126638) (xy 157.963106 -287.095513) (xy 157.930471 -287.058676) (xy 157.904168 -287.01708)
			(xy 157.884877 -286.971804) (xy 157.8731 -286.92402) (xy 157.86914 -286.874966) (xy 157.530292 -286.874966)
			(xy 157.529797 -286.899573) (xy 157.521902 -286.94815) (xy 157.506318 -286.994831) (xy 157.483447 -287.038408)
			(xy 157.453882 -287.077752) (xy 157.418389 -287.111844) (xy 157.377886 -287.1398) (xy 157.333424 -287.160898)
			(xy 157.286153 -287.17459) (xy 157.237298 -287.180522) (xy 157.188123 -287.178541) (xy 157.139904 -287.168697)
			(xy 157.093888 -287.151245) (xy 157.051267 -287.126638) (xy 157.013146 -287.095513) (xy 156.980511 -287.058676)
			(xy 156.954208 -287.01708) (xy 156.934917 -286.971804) (xy 156.92314 -286.92402) (xy 156.91918 -286.874966)
			(xy 156.580332 -286.874966) (xy 156.579837 -286.899573) (xy 156.571942 -286.94815) (xy 156.556358 -286.994831)
			(xy 156.533487 -287.038408) (xy 156.503922 -287.077752) (xy 156.468429 -287.111844) (xy 156.427926 -287.1398)
			(xy 156.383464 -287.160898) (xy 156.336193 -287.17459) (xy 156.287338 -287.180522) (xy 156.238163 -287.178541)
			(xy 156.189944 -287.168697) (xy 156.143928 -287.151245) (xy 156.101307 -287.126638) (xy 156.063186 -287.095513)
			(xy 156.030551 -287.058676) (xy 156.004248 -287.01708) (xy 155.984957 -286.971804) (xy 155.97318 -286.92402)
			(xy 155.96922 -286.874966) (xy 155.630372 -286.874966) (xy 155.629877 -286.899573) (xy 155.621982 -286.94815)
			(xy 155.606398 -286.994831) (xy 155.583527 -287.038408) (xy 155.553962 -287.077752) (xy 155.518469 -287.111844)
			(xy 155.477966 -287.1398) (xy 155.433504 -287.160898) (xy 155.386233 -287.17459) (xy 155.337378 -287.180522)
			(xy 155.288203 -287.178541) (xy 155.239984 -287.168697) (xy 155.193968 -287.151245) (xy 155.151347 -287.126638)
			(xy 155.113226 -287.095513) (xy 155.080591 -287.058676) (xy 155.054288 -287.01708) (xy 155.034997 -286.971804)
			(xy 155.02322 -286.92402) (xy 155.01926 -286.874966) (xy 154.680412 -286.874966) (xy 154.679917 -286.899573)
			(xy 154.672022 -286.94815) (xy 154.656438 -286.994831) (xy 154.633567 -287.038408) (xy 154.604002 -287.077752)
			(xy 154.568509 -287.111844) (xy 154.528006 -287.1398) (xy 154.483544 -287.160898) (xy 154.436273 -287.17459)
			(xy 154.387418 -287.180522) (xy 154.338243 -287.178541) (xy 154.290024 -287.168697) (xy 154.244008 -287.151245)
			(xy 154.201387 -287.126638) (xy 154.163266 -287.095513) (xy 154.130631 -287.058676) (xy 154.104328 -287.01708)
			(xy 154.085037 -286.971804) (xy 154.07326 -286.92402) (xy 154.0693 -286.874966) (xy 153.730198 -286.874966)
			(xy 153.729703 -286.899573) (xy 153.721808 -286.94815) (xy 153.706224 -286.994831) (xy 153.683353 -287.038408)
			(xy 153.653788 -287.077752) (xy 153.618295 -287.111844) (xy 153.577792 -287.1398) (xy 153.53333 -287.160898)
			(xy 153.486059 -287.17459) (xy 153.437204 -287.180522) (xy 153.388029 -287.178541) (xy 153.33981 -287.168697)
			(xy 153.293794 -287.151245) (xy 153.251173 -287.126638) (xy 153.213052 -287.095513) (xy 153.180417 -287.058676)
			(xy 153.154114 -287.01708) (xy 153.134823 -286.971804) (xy 153.123046 -286.92402) (xy 153.119086 -286.874966)
			(xy 152.805132 -286.874966) (xy 152.805132 -286.900988) (xy 152.797002 -286.952325) (xy 152.780941 -287.001758)
			(xy 152.757346 -287.048071) (xy 152.726796 -287.090122) (xy 152.690045 -287.126876) (xy 152.647996 -287.15743)
			(xy 152.601686 -287.18103) (xy 152.552254 -287.197095) (xy 152.500918 -287.20523) (xy 152.47493 -287.205674)
			(xy 152.474422 -287.205674) (xy 152.448246 -287.205176) (xy 152.396549 -287.196923) (xy 152.346801 -287.180621)
			(xy 152.323292 -287.169098) (xy 152.323038 -287.169098) (xy 152.317197 -287.166345) (xy 152.304603 -287.163508)
			(xy 152.298146 -287.16351) (xy 152.284938 -287.164018) (xy 152.204928 -287.21304) (xy 152.19553 -287.220406)
			(xy 152.18664 -287.229296) (xy 152.18283 -287.23844) (xy 152.178004 -287.248346) (xy 152.178004 -287.437322)
			(xy 152.17807 -287.441129) (xy 152.179217 -287.448655) (xy 152.18029 -287.452308) (xy 152.182576 -287.459674)
			(xy 152.189688 -287.475422) (xy 152.195784 -287.480756) (xy 152.199086 -287.483296) (xy 152.276048 -287.53054)
			(xy 152.290526 -287.530794) (xy 152.30602 -287.530794) (xy 152.312624 -287.530286) (xy 152.332944 -287.525968)
			(xy 152.338024 -287.523682) (xy 152.359549 -287.514385) (xy 152.404564 -287.501267) (xy 152.450979 -287.494629)
			(xy 152.474422 -287.494218) (xy 152.47493 -287.494218) (xy 152.500914 -287.49473) (xy 152.55224 -287.502863)
			(xy 152.601663 -287.518926) (xy 152.647965 -287.542521) (xy 152.690006 -287.573069) (xy 152.72675 -287.609817)
			(xy 152.757294 -287.651861) (xy 152.780886 -287.698165) (xy 152.796944 -287.747589) (xy 152.805073 -287.798916)
			(xy 152.805073 -287.824926) (xy 153.119086 -287.824926) (xy 153.123046 -287.775872) (xy 153.134823 -287.728088)
			(xy 153.154114 -287.682812) (xy 153.180417 -287.641216) (xy 153.213052 -287.604379) (xy 153.251173 -287.573254)
			(xy 153.293794 -287.548647) (xy 153.33981 -287.531195) (xy 153.388029 -287.521351) (xy 153.437204 -287.51937)
			(xy 153.486059 -287.525302) (xy 153.53333 -287.538994) (xy 153.577792 -287.560092) (xy 153.618295 -287.588048)
			(xy 153.653788 -287.62214) (xy 153.683353 -287.661484) (xy 153.706224 -287.705061) (xy 153.721808 -287.751742)
			(xy 153.729703 -287.800319) (xy 153.730198 -287.824926) (xy 154.0693 -287.824926) (xy 154.07326 -287.775872)
			(xy 154.085037 -287.728088) (xy 154.104328 -287.682812) (xy 154.130631 -287.641216) (xy 154.163266 -287.604379)
			(xy 154.201387 -287.573254) (xy 154.244008 -287.548647) (xy 154.290024 -287.531195) (xy 154.338243 -287.521351)
			(xy 154.387418 -287.51937) (xy 154.436273 -287.525302) (xy 154.483544 -287.538994) (xy 154.528006 -287.560092)
			(xy 154.568509 -287.588048) (xy 154.604002 -287.62214) (xy 154.633567 -287.661484) (xy 154.656438 -287.705061)
			(xy 154.672022 -287.751742) (xy 154.679917 -287.800319) (xy 154.680412 -287.824926) (xy 156.91918 -287.824926)
			(xy 156.92314 -287.775872) (xy 156.934917 -287.728088) (xy 156.954208 -287.682812) (xy 156.980511 -287.641216)
			(xy 157.013146 -287.604379) (xy 157.051267 -287.573254) (xy 157.093888 -287.548647) (xy 157.139904 -287.531195)
			(xy 157.188123 -287.521351) (xy 157.237298 -287.51937) (xy 157.286153 -287.525302) (xy 157.333424 -287.538994)
			(xy 157.377886 -287.560092) (xy 157.418389 -287.588048) (xy 157.453882 -287.62214) (xy 157.483447 -287.661484)
			(xy 157.506318 -287.705061) (xy 157.521902 -287.751742) (xy 157.529797 -287.800319) (xy 157.530292 -287.824926)
			(xy 160.719274 -287.824926) (xy 160.723234 -287.775872) (xy 160.735011 -287.728088) (xy 160.754302 -287.682812)
			(xy 160.780605 -287.641216) (xy 160.81324 -287.604379) (xy 160.851361 -287.573254) (xy 160.893982 -287.548647)
			(xy 160.939998 -287.531195) (xy 160.988217 -287.521351) (xy 161.037392 -287.51937) (xy 161.086247 -287.525302)
			(xy 161.133518 -287.538994) (xy 161.17798 -287.560092) (xy 161.218483 -287.588048) (xy 161.253976 -287.62214)
			(xy 161.283541 -287.661484) (xy 161.306412 -287.705061) (xy 161.321996 -287.751742) (xy 161.329891 -287.800319)
			(xy 161.330386 -287.824926) (xy 161.669234 -287.824926) (xy 161.673194 -287.775872) (xy 161.684971 -287.728088)
			(xy 161.704262 -287.682812) (xy 161.730565 -287.641216) (xy 161.7632 -287.604379) (xy 161.801321 -287.573254)
			(xy 161.843942 -287.548647) (xy 161.889958 -287.531195) (xy 161.938177 -287.521351) (xy 161.987352 -287.51937)
			(xy 162.036207 -287.525302) (xy 162.083478 -287.538994) (xy 162.12794 -287.560092) (xy 162.168443 -287.588048)
			(xy 162.203936 -287.62214) (xy 162.233501 -287.661484) (xy 162.256372 -287.705061) (xy 162.271956 -287.751742)
			(xy 162.279851 -287.800319) (xy 162.280346 -287.824926) (xy 162.619194 -287.824926) (xy 162.623154 -287.775872)
			(xy 162.634931 -287.728088) (xy 162.654222 -287.682812) (xy 162.680525 -287.641216) (xy 162.71316 -287.604379)
			(xy 162.751281 -287.573254) (xy 162.793902 -287.548647) (xy 162.839918 -287.531195) (xy 162.888137 -287.521351)
			(xy 162.937312 -287.51937) (xy 162.986167 -287.525302) (xy 163.033438 -287.538994) (xy 163.0779 -287.560092)
			(xy 163.118403 -287.588048) (xy 163.153896 -287.62214) (xy 163.183461 -287.661484) (xy 163.206332 -287.705061)
			(xy 163.221916 -287.751742) (xy 163.229811 -287.800319) (xy 163.230306 -287.824926) (xy 163.569154 -287.824926)
			(xy 163.573114 -287.775872) (xy 163.584891 -287.728088) (xy 163.604182 -287.682812) (xy 163.630485 -287.641216)
			(xy 163.66312 -287.604379) (xy 163.701241 -287.573254) (xy 163.743862 -287.548647) (xy 163.789878 -287.531195)
			(xy 163.838097 -287.521351) (xy 163.887272 -287.51937) (xy 163.936127 -287.525302) (xy 163.983398 -287.538994)
			(xy 164.02786 -287.560092) (xy 164.068363 -287.588048) (xy 164.103856 -287.62214) (xy 164.133421 -287.661484)
			(xy 164.156292 -287.705061) (xy 164.171876 -287.751742) (xy 164.179771 -287.800319) (xy 164.180266 -287.824926)
			(xy 164.519114 -287.824926) (xy 164.523074 -287.775872) (xy 164.534851 -287.728088) (xy 164.554142 -287.682812)
			(xy 164.580445 -287.641216) (xy 164.61308 -287.604379) (xy 164.651201 -287.573254) (xy 164.693822 -287.548647)
			(xy 164.739838 -287.531195) (xy 164.788057 -287.521351) (xy 164.837232 -287.51937) (xy 164.886087 -287.525302)
			(xy 164.933358 -287.538994) (xy 164.97782 -287.560092) (xy 165.018323 -287.588048) (xy 165.053816 -287.62214)
			(xy 165.083381 -287.661484) (xy 165.106252 -287.705061) (xy 165.121836 -287.751742) (xy 165.129731 -287.800319)
			(xy 165.130226 -287.824926) (xy 165.469074 -287.824926) (xy 165.473034 -287.775872) (xy 165.484811 -287.728088)
			(xy 165.504102 -287.682812) (xy 165.530405 -287.641216) (xy 165.56304 -287.604379) (xy 165.601161 -287.573254)
			(xy 165.643782 -287.548647) (xy 165.689798 -287.531195) (xy 165.738017 -287.521351) (xy 165.787192 -287.51937)
			(xy 165.836047 -287.525302) (xy 165.883318 -287.538994) (xy 165.92778 -287.560092) (xy 165.968283 -287.588048)
			(xy 166.003776 -287.62214) (xy 166.033341 -287.661484) (xy 166.056212 -287.705061) (xy 166.071796 -287.751742)
			(xy 166.079691 -287.800319) (xy 166.080186 -287.824926) (xy 166.079691 -287.849533) (xy 166.071796 -287.89811)
			(xy 166.056212 -287.944791) (xy 166.033341 -287.988368) (xy 166.003776 -288.027712) (xy 165.968283 -288.061804)
			(xy 165.92778 -288.08976) (xy 165.883318 -288.110858) (xy 165.836047 -288.12455) (xy 165.787192 -288.130482)
			(xy 165.738017 -288.128501) (xy 165.689798 -288.118657) (xy 165.643782 -288.101205) (xy 165.601161 -288.076598)
			(xy 165.56304 -288.045473) (xy 165.530405 -288.008636) (xy 165.504102 -287.96704) (xy 165.484811 -287.921764)
			(xy 165.473034 -287.87398) (xy 165.469074 -287.824926) (xy 165.130226 -287.824926) (xy 165.129731 -287.849533)
			(xy 165.121836 -287.89811) (xy 165.106252 -287.944791) (xy 165.083381 -287.988368) (xy 165.053816 -288.027712)
			(xy 165.018323 -288.061804) (xy 164.97782 -288.08976) (xy 164.933358 -288.110858) (xy 164.886087 -288.12455)
			(xy 164.837232 -288.130482) (xy 164.788057 -288.128501) (xy 164.739838 -288.118657) (xy 164.693822 -288.101205)
			(xy 164.651201 -288.076598) (xy 164.61308 -288.045473) (xy 164.580445 -288.008636) (xy 164.554142 -287.96704)
			(xy 164.534851 -287.921764) (xy 164.523074 -287.87398) (xy 164.519114 -287.824926) (xy 164.180266 -287.824926)
			(xy 164.179771 -287.849533) (xy 164.171876 -287.89811) (xy 164.156292 -287.944791) (xy 164.133421 -287.988368)
			(xy 164.103856 -288.027712) (xy 164.068363 -288.061804) (xy 164.02786 -288.08976) (xy 163.983398 -288.110858)
			(xy 163.936127 -288.12455) (xy 163.887272 -288.130482) (xy 163.838097 -288.128501) (xy 163.789878 -288.118657)
			(xy 163.743862 -288.101205) (xy 163.701241 -288.076598) (xy 163.66312 -288.045473) (xy 163.630485 -288.008636)
			(xy 163.604182 -287.96704) (xy 163.584891 -287.921764) (xy 163.573114 -287.87398) (xy 163.569154 -287.824926)
			(xy 163.230306 -287.824926) (xy 163.229811 -287.849533) (xy 163.221916 -287.89811) (xy 163.206332 -287.944791)
			(xy 163.183461 -287.988368) (xy 163.153896 -288.027712) (xy 163.118403 -288.061804) (xy 163.0779 -288.08976)
			(xy 163.033438 -288.110858) (xy 162.986167 -288.12455) (xy 162.937312 -288.130482) (xy 162.888137 -288.128501)
			(xy 162.839918 -288.118657) (xy 162.793902 -288.101205) (xy 162.751281 -288.076598) (xy 162.71316 -288.045473)
			(xy 162.680525 -288.008636) (xy 162.654222 -287.96704) (xy 162.634931 -287.921764) (xy 162.623154 -287.87398)
			(xy 162.619194 -287.824926) (xy 162.280346 -287.824926) (xy 162.279851 -287.849533) (xy 162.271956 -287.89811)
			(xy 162.256372 -287.944791) (xy 162.233501 -287.988368) (xy 162.203936 -288.027712) (xy 162.168443 -288.061804)
			(xy 162.12794 -288.08976) (xy 162.083478 -288.110858) (xy 162.036207 -288.12455) (xy 161.987352 -288.130482)
			(xy 161.938177 -288.128501) (xy 161.889958 -288.118657) (xy 161.843942 -288.101205) (xy 161.801321 -288.076598)
			(xy 161.7632 -288.045473) (xy 161.730565 -288.008636) (xy 161.704262 -287.96704) (xy 161.684971 -287.921764)
			(xy 161.673194 -287.87398) (xy 161.669234 -287.824926) (xy 161.330386 -287.824926) (xy 161.329891 -287.849533)
			(xy 161.321996 -287.89811) (xy 161.306412 -287.944791) (xy 161.283541 -287.988368) (xy 161.253976 -288.027712)
			(xy 161.218483 -288.061804) (xy 161.17798 -288.08976) (xy 161.133518 -288.110858) (xy 161.086247 -288.12455)
			(xy 161.037392 -288.130482) (xy 160.988217 -288.128501) (xy 160.939998 -288.118657) (xy 160.893982 -288.101205)
			(xy 160.851361 -288.076598) (xy 160.81324 -288.045473) (xy 160.780605 -288.008636) (xy 160.754302 -287.96704)
			(xy 160.735011 -287.921764) (xy 160.723234 -287.87398) (xy 160.719274 -287.824926) (xy 157.530292 -287.824926)
			(xy 157.529797 -287.849533) (xy 157.521902 -287.89811) (xy 157.506318 -287.944791) (xy 157.483447 -287.988368)
			(xy 157.453882 -288.027712) (xy 157.418389 -288.061804) (xy 157.377886 -288.08976) (xy 157.333424 -288.110858)
			(xy 157.286153 -288.12455) (xy 157.237298 -288.130482) (xy 157.188123 -288.128501) (xy 157.139904 -288.118657)
			(xy 157.093888 -288.101205) (xy 157.051267 -288.076598) (xy 157.013146 -288.045473) (xy 156.980511 -288.008636)
			(xy 156.954208 -287.96704) (xy 156.934917 -287.921764) (xy 156.92314 -287.87398) (xy 156.91918 -287.824926)
			(xy 154.680412 -287.824926) (xy 154.679917 -287.849533) (xy 154.672022 -287.89811) (xy 154.656438 -287.944791)
			(xy 154.633567 -287.988368) (xy 154.604002 -288.027712) (xy 154.568509 -288.061804) (xy 154.528006 -288.08976)
			(xy 154.483544 -288.110858) (xy 154.436273 -288.12455) (xy 154.387418 -288.130482) (xy 154.338243 -288.128501)
			(xy 154.290024 -288.118657) (xy 154.244008 -288.101205) (xy 154.201387 -288.076598) (xy 154.163266 -288.045473)
			(xy 154.130631 -288.008636) (xy 154.104328 -287.96704) (xy 154.085037 -287.921764) (xy 154.07326 -287.87398)
			(xy 154.0693 -287.824926) (xy 153.730198 -287.824926) (xy 153.729703 -287.849533) (xy 153.721808 -287.89811)
			(xy 153.706224 -287.944791) (xy 153.683353 -287.988368) (xy 153.653788 -288.027712) (xy 153.618295 -288.061804)
			(xy 153.577792 -288.08976) (xy 153.53333 -288.110858) (xy 153.486059 -288.12455) (xy 153.437204 -288.130482)
			(xy 153.388029 -288.128501) (xy 153.33981 -288.118657) (xy 153.293794 -288.101205) (xy 153.251173 -288.076598)
			(xy 153.213052 -288.045473) (xy 153.180417 -288.008636) (xy 153.154114 -287.96704) (xy 153.134823 -287.921764)
			(xy 153.123046 -287.87398) (xy 153.119086 -287.824926) (xy 152.805073 -287.824926) (xy 152.805073 -287.850884)
			(xy 152.796944 -287.902211) (xy 152.780886 -287.951635) (xy 152.757294 -287.997939) (xy 152.72675 -288.039983)
			(xy 152.690006 -288.076731) (xy 152.647965 -288.107279) (xy 152.601663 -288.130874) (xy 152.55224 -288.146937)
			(xy 152.500914 -288.15507) (xy 152.47493 -288.155634) (xy 152.474422 -288.155634) (xy 152.448246 -288.155136)
			(xy 152.39655 -288.146882) (xy 152.346802 -288.130578) (xy 152.323292 -288.119058) (xy 152.323038 -288.119058)
			(xy 152.317196 -288.116306) (xy 152.304603 -288.113472) (xy 152.298146 -288.11347) (xy 152.284938 -288.113978)
			(xy 152.204928 -288.163) (xy 152.19553 -288.170366) (xy 152.18664 -288.179256) (xy 152.18283 -288.1884)
			(xy 152.178004 -288.198306) (xy 152.178004 -288.387282) (xy 152.178067 -288.391089) (xy 152.179208 -288.398617)
			(xy 152.18029 -288.402268) (xy 152.182576 -288.409634) (xy 152.189688 -288.425382) (xy 152.195784 -288.430716)
			(xy 152.199086 -288.433256) (xy 152.276048 -288.4805) (xy 152.290526 -288.480754) (xy 152.30602 -288.480754)
			(xy 152.312624 -288.480246) (xy 152.332944 -288.475928) (xy 152.338024 -288.473642) (xy 152.359549 -288.464346)
			(xy 152.404564 -288.45123) (xy 152.450979 -288.444593) (xy 152.474422 -288.444178) (xy 152.47493 -288.444178)
			(xy 152.500917 -288.44469) (xy 152.55225 -288.452824) (xy 152.601678 -288.468889) (xy 152.647986 -288.492487)
			(xy 152.690032 -288.523039) (xy 152.726781 -288.559791) (xy 152.757328 -288.60184) (xy 152.780923 -288.648149)
			(xy 152.796983 -288.697579) (xy 152.805113 -288.748913) (xy 152.805113 -288.774886) (xy 153.119086 -288.774886)
			(xy 153.123046 -288.725832) (xy 153.134823 -288.678048) (xy 153.154114 -288.632772) (xy 153.180417 -288.591176)
			(xy 153.213052 -288.554339) (xy 153.251173 -288.523214) (xy 153.293794 -288.498607) (xy 153.33981 -288.481155)
			(xy 153.388029 -288.471311) (xy 153.437204 -288.46933) (xy 153.486059 -288.475262) (xy 153.53333 -288.488954)
			(xy 153.577792 -288.510052) (xy 153.618295 -288.538008) (xy 153.653788 -288.5721) (xy 153.683353 -288.611444)
			(xy 153.706224 -288.655021) (xy 153.721808 -288.701702) (xy 153.729703 -288.750279) (xy 153.730198 -288.774886)
			(xy 154.0693 -288.774886) (xy 154.07326 -288.725832) (xy 154.085037 -288.678048) (xy 154.104328 -288.632772)
			(xy 154.130631 -288.591176) (xy 154.163266 -288.554339) (xy 154.201387 -288.523214) (xy 154.244008 -288.498607)
			(xy 154.290024 -288.481155) (xy 154.338243 -288.471311) (xy 154.387418 -288.46933) (xy 154.436273 -288.475262)
			(xy 154.483544 -288.488954) (xy 154.528006 -288.510052) (xy 154.568509 -288.538008) (xy 154.604002 -288.5721)
			(xy 154.633567 -288.611444) (xy 154.656438 -288.655021) (xy 154.672022 -288.701702) (xy 154.679917 -288.750279)
			(xy 154.680412 -288.774886) (xy 154.679917 -288.799493) (xy 154.672022 -288.84807) (xy 154.656438 -288.894751)
			(xy 154.633567 -288.938328) (xy 154.604002 -288.977672) (xy 154.568509 -289.011764) (xy 154.528006 -289.03972)
			(xy 154.483544 -289.060818) (xy 154.436273 -289.07451) (xy 154.387418 -289.080442) (xy 154.338243 -289.078461)
			(xy 154.290024 -289.068617) (xy 154.244008 -289.051165) (xy 154.201387 -289.026558) (xy 154.163266 -288.995433)
			(xy 154.130631 -288.958596) (xy 154.104328 -288.917) (xy 154.085037 -288.871724) (xy 154.07326 -288.82394)
			(xy 154.0693 -288.774886) (xy 153.730198 -288.774886) (xy 153.729703 -288.799493) (xy 153.721808 -288.84807)
			(xy 153.706224 -288.894751) (xy 153.683353 -288.938328) (xy 153.653788 -288.977672) (xy 153.618295 -289.011764)
			(xy 153.577792 -289.03972) (xy 153.53333 -289.060818) (xy 153.486059 -289.07451) (xy 153.437204 -289.080442)
			(xy 153.388029 -289.078461) (xy 153.33981 -289.068617) (xy 153.293794 -289.051165) (xy 153.251173 -289.026558)
			(xy 153.213052 -288.995433) (xy 153.180417 -288.958596) (xy 153.154114 -288.917) (xy 153.134823 -288.871724)
			(xy 153.123046 -288.82394) (xy 153.119086 -288.774886) (xy 152.805113 -288.774886) (xy 152.805113 -288.800887)
			(xy 152.796983 -288.852221) (xy 152.780923 -288.901651) (xy 152.757328 -288.94796) (xy 152.726781 -288.990009)
			(xy 152.690032 -289.026761) (xy 152.647986 -289.057313) (xy 152.601678 -289.080911) (xy 152.55225 -289.096976)
			(xy 152.500917 -289.10511) (xy 152.47493 -289.105594) (xy 152.474422 -289.105594) (xy 152.448246 -289.105096)
			(xy 152.39655 -289.096841) (xy 152.346803 -289.080535) (xy 152.323292 -289.069018) (xy 152.323038 -289.069018)
			(xy 152.317197 -289.066264) (xy 152.304603 -289.063426) (xy 152.298146 -289.06343) (xy 152.284938 -289.063938)
			(xy 152.204928 -289.11296) (xy 152.19553 -289.120326) (xy 152.18664 -289.129216) (xy 152.18283 -289.13836)
			(xy 152.178004 -289.148266) (xy 152.178004 -289.337242) (xy 152.178072 -289.341048) (xy 152.179222 -289.348574)
			(xy 152.18029 -289.352228) (xy 152.182576 -289.359594) (xy 152.189688 -289.375342) (xy 152.195784 -289.380676)
			(xy 152.199086 -289.383216) (xy 152.276048 -289.43046) (xy 152.290526 -289.430714) (xy 152.30602 -289.430714)
			(xy 152.312624 -289.430206) (xy 152.332944 -289.425888) (xy 152.338024 -289.423602) (xy 152.359549 -289.414304)
			(xy 152.404564 -289.401186) (xy 152.450979 -289.394548) (xy 152.474422 -289.394138) (xy 152.47493 -289.394138)
			(xy 152.500912 -289.39465) (xy 152.552236 -289.402783) (xy 152.601655 -289.418845) (xy 152.647954 -289.442439)
			(xy 152.689992 -289.472985) (xy 152.726735 -289.509731) (xy 152.757277 -289.551772) (xy 152.780867 -289.598073)
			(xy 152.796924 -289.647494) (xy 152.805052 -289.698818) (xy 152.805052 -289.724846) (xy 153.119086 -289.724846)
			(xy 153.123046 -289.675792) (xy 153.134823 -289.628008) (xy 153.154114 -289.582732) (xy 153.180417 -289.541136)
			(xy 153.213052 -289.504299) (xy 153.251173 -289.473174) (xy 153.293794 -289.448567) (xy 153.33981 -289.431115)
			(xy 153.388029 -289.421271) (xy 153.437204 -289.41929) (xy 153.486059 -289.425222) (xy 153.53333 -289.438914)
			(xy 153.577792 -289.460012) (xy 153.618295 -289.487968) (xy 153.653788 -289.52206) (xy 153.683353 -289.561404)
			(xy 153.706224 -289.604981) (xy 153.721808 -289.651662) (xy 153.729703 -289.700239) (xy 153.730198 -289.724846)
			(xy 154.0693 -289.724846) (xy 154.07326 -289.675792) (xy 154.085037 -289.628008) (xy 154.104328 -289.582732)
			(xy 154.130631 -289.541136) (xy 154.163266 -289.504299) (xy 154.201387 -289.473174) (xy 154.244008 -289.448567)
			(xy 154.290024 -289.431115) (xy 154.338243 -289.421271) (xy 154.387418 -289.41929) (xy 154.436273 -289.425222)
			(xy 154.483544 -289.438914) (xy 154.528006 -289.460012) (xy 154.568509 -289.487968) (xy 154.604002 -289.52206)
			(xy 154.633567 -289.561404) (xy 154.656438 -289.604981) (xy 154.672022 -289.651662) (xy 154.679917 -289.700239)
			(xy 154.680412 -289.724846) (xy 155.01926 -289.724846) (xy 155.02322 -289.675792) (xy 155.034997 -289.628008)
			(xy 155.054288 -289.582732) (xy 155.080591 -289.541136) (xy 155.113226 -289.504299) (xy 155.151347 -289.473174)
			(xy 155.193968 -289.448567) (xy 155.239984 -289.431115) (xy 155.288203 -289.421271) (xy 155.337378 -289.41929)
			(xy 155.386233 -289.425222) (xy 155.433504 -289.438914) (xy 155.477966 -289.460012) (xy 155.518469 -289.487968)
			(xy 155.553962 -289.52206) (xy 155.583527 -289.561404) (xy 155.606398 -289.604981) (xy 155.621982 -289.651662)
			(xy 155.629877 -289.700239) (xy 155.630372 -289.724846) (xy 155.96922 -289.724846) (xy 155.97318 -289.675792)
			(xy 155.984957 -289.628008) (xy 156.004248 -289.582732) (xy 156.030551 -289.541136) (xy 156.063186 -289.504299)
			(xy 156.101307 -289.473174) (xy 156.143928 -289.448567) (xy 156.189944 -289.431115) (xy 156.238163 -289.421271)
			(xy 156.287338 -289.41929) (xy 156.336193 -289.425222) (xy 156.383464 -289.438914) (xy 156.427926 -289.460012)
			(xy 156.468429 -289.487968) (xy 156.503922 -289.52206) (xy 156.533487 -289.561404) (xy 156.556358 -289.604981)
			(xy 156.571942 -289.651662) (xy 156.579837 -289.700239) (xy 156.580332 -289.724846) (xy 156.91918 -289.724846)
			(xy 156.92314 -289.675792) (xy 156.934917 -289.628008) (xy 156.954208 -289.582732) (xy 156.980511 -289.541136)
			(xy 157.013146 -289.504299) (xy 157.051267 -289.473174) (xy 157.093888 -289.448567) (xy 157.139904 -289.431115)
			(xy 157.188123 -289.421271) (xy 157.237298 -289.41929) (xy 157.286153 -289.425222) (xy 157.333424 -289.438914)
			(xy 157.377886 -289.460012) (xy 157.418389 -289.487968) (xy 157.453882 -289.52206) (xy 157.483447 -289.561404)
			(xy 157.506318 -289.604981) (xy 157.521902 -289.651662) (xy 157.529797 -289.700239) (xy 157.530292 -289.724846)
			(xy 157.86914 -289.724846) (xy 157.8731 -289.675792) (xy 157.884877 -289.628008) (xy 157.904168 -289.582732)
			(xy 157.930471 -289.541136) (xy 157.963106 -289.504299) (xy 158.001227 -289.473174) (xy 158.043848 -289.448567)
			(xy 158.089864 -289.431115) (xy 158.138083 -289.421271) (xy 158.187258 -289.41929) (xy 158.236113 -289.425222)
			(xy 158.283384 -289.438914) (xy 158.327846 -289.460012) (xy 158.368349 -289.487968) (xy 158.403842 -289.52206)
			(xy 158.433407 -289.561404) (xy 158.456278 -289.604981) (xy 158.471862 -289.651662) (xy 158.479757 -289.700239)
			(xy 158.480252 -289.724846) (xy 158.479757 -289.749453) (xy 158.471862 -289.79803) (xy 158.456278 -289.844711)
			(xy 158.433407 -289.888288) (xy 158.403842 -289.927632) (xy 158.368349 -289.961724) (xy 158.327846 -289.98968)
			(xy 158.283384 -290.010778) (xy 158.236113 -290.02447) (xy 158.187258 -290.030402) (xy 158.138083 -290.028421)
			(xy 158.089864 -290.018577) (xy 158.043848 -290.001125) (xy 158.001227 -289.976518) (xy 157.963106 -289.945393)
			(xy 157.930471 -289.908556) (xy 157.904168 -289.86696) (xy 157.884877 -289.821684) (xy 157.8731 -289.7739)
			(xy 157.86914 -289.724846) (xy 157.530292 -289.724846) (xy 157.529797 -289.749453) (xy 157.521902 -289.79803)
			(xy 157.506318 -289.844711) (xy 157.483447 -289.888288) (xy 157.453882 -289.927632) (xy 157.418389 -289.961724)
			(xy 157.377886 -289.98968) (xy 157.333424 -290.010778) (xy 157.286153 -290.02447) (xy 157.237298 -290.030402)
			(xy 157.188123 -290.028421) (xy 157.139904 -290.018577) (xy 157.093888 -290.001125) (xy 157.051267 -289.976518)
			(xy 157.013146 -289.945393) (xy 156.980511 -289.908556) (xy 156.954208 -289.86696) (xy 156.934917 -289.821684)
			(xy 156.92314 -289.7739) (xy 156.91918 -289.724846) (xy 156.580332 -289.724846) (xy 156.579837 -289.749453)
			(xy 156.571942 -289.79803) (xy 156.556358 -289.844711) (xy 156.533487 -289.888288) (xy 156.503922 -289.927632)
			(xy 156.468429 -289.961724) (xy 156.427926 -289.98968) (xy 156.383464 -290.010778) (xy 156.336193 -290.02447)
			(xy 156.287338 -290.030402) (xy 156.238163 -290.028421) (xy 156.189944 -290.018577) (xy 156.143928 -290.001125)
			(xy 156.101307 -289.976518) (xy 156.063186 -289.945393) (xy 156.030551 -289.908556) (xy 156.004248 -289.86696)
			(xy 155.984957 -289.821684) (xy 155.97318 -289.7739) (xy 155.96922 -289.724846) (xy 155.630372 -289.724846)
			(xy 155.629877 -289.749453) (xy 155.621982 -289.79803) (xy 155.606398 -289.844711) (xy 155.583527 -289.888288)
			(xy 155.553962 -289.927632) (xy 155.518469 -289.961724) (xy 155.477966 -289.98968) (xy 155.433504 -290.010778)
			(xy 155.386233 -290.02447) (xy 155.337378 -290.030402) (xy 155.288203 -290.028421) (xy 155.239984 -290.018577)
			(xy 155.193968 -290.001125) (xy 155.151347 -289.976518) (xy 155.113226 -289.945393) (xy 155.080591 -289.908556)
			(xy 155.054288 -289.86696) (xy 155.034997 -289.821684) (xy 155.02322 -289.7739) (xy 155.01926 -289.724846)
			(xy 154.680412 -289.724846) (xy 154.679917 -289.749453) (xy 154.672022 -289.79803) (xy 154.656438 -289.844711)
			(xy 154.633567 -289.888288) (xy 154.604002 -289.927632) (xy 154.568509 -289.961724) (xy 154.528006 -289.98968)
			(xy 154.483544 -290.010778) (xy 154.436273 -290.02447) (xy 154.387418 -290.030402) (xy 154.338243 -290.028421)
			(xy 154.290024 -290.018577) (xy 154.244008 -290.001125) (xy 154.201387 -289.976518) (xy 154.163266 -289.945393)
			(xy 154.130631 -289.908556) (xy 154.104328 -289.86696) (xy 154.085037 -289.821684) (xy 154.07326 -289.7739)
			(xy 154.0693 -289.724846) (xy 153.730198 -289.724846) (xy 153.729703 -289.749453) (xy 153.721808 -289.79803)
			(xy 153.706224 -289.844711) (xy 153.683353 -289.888288) (xy 153.653788 -289.927632) (xy 153.618295 -289.961724)
			(xy 153.577792 -289.98968) (xy 153.53333 -290.010778) (xy 153.486059 -290.02447) (xy 153.437204 -290.030402)
			(xy 153.388029 -290.028421) (xy 153.33981 -290.018577) (xy 153.293794 -290.001125) (xy 153.251173 -289.976518)
			(xy 153.213052 -289.945393) (xy 153.180417 -289.908556) (xy 153.154114 -289.86696) (xy 153.134823 -289.821684)
			(xy 153.123046 -289.7739) (xy 153.119086 -289.724846) (xy 152.805052 -289.724846) (xy 152.805052 -289.750782)
			(xy 152.796924 -289.802106) (xy 152.780867 -289.851527) (xy 152.757277 -289.897828) (xy 152.726735 -289.939869)
			(xy 152.689992 -289.976615) (xy 152.647954 -290.007161) (xy 152.601655 -290.030755) (xy 152.552236 -290.046817)
			(xy 152.500912 -290.05495) (xy 152.47493 -290.055554) (xy 152.474422 -290.055554) (xy 152.448246 -290.055056)
			(xy 152.396549 -290.046803) (xy 152.346801 -290.030499) (xy 152.323292 -290.018978) (xy 152.323038 -290.018978)
			(xy 152.317197 -290.016226) (xy 152.304603 -290.01339) (xy 152.298146 -290.01339) (xy 152.284938 -290.013898)
			(xy 152.204928 -290.06292) (xy 152.19553 -290.070286) (xy 152.18664 -290.079176) (xy 152.18283 -290.08832)
			(xy 152.178004 -290.098226) (xy 152.178004 -290.287202) (xy 152.178069 -290.291009) (xy 152.179213 -290.298536)
			(xy 152.18029 -290.302188) (xy 152.182576 -290.309554) (xy 152.189688 -290.325302) (xy 152.195784 -290.330636)
			(xy 152.199086 -290.333176) (xy 152.276048 -290.38042) (xy 152.290526 -290.380674) (xy 152.30602 -290.380674)
			(xy 152.312624 -290.380166) (xy 152.332944 -290.375848) (xy 152.338024 -290.373562) (xy 152.359549 -290.364265)
			(xy 152.404564 -290.351149) (xy 152.450979 -290.344511) (xy 152.474422 -290.344098) (xy 152.47493 -290.344098)
			(xy 152.500915 -290.34461) (xy 152.552245 -290.352744) (xy 152.601671 -290.368807) (xy 152.647975 -290.392404)
			(xy 152.690019 -290.422954) (xy 152.726766 -290.459704) (xy 152.757311 -290.50175) (xy 152.780904 -290.548057)
			(xy 152.796963 -290.597484) (xy 152.805093 -290.648815) (xy 152.805093 -290.674806) (xy 153.119086 -290.674806)
			(xy 153.123046 -290.625752) (xy 153.134823 -290.577968) (xy 153.154114 -290.532692) (xy 153.180417 -290.491096)
			(xy 153.213052 -290.454259) (xy 153.251173 -290.423134) (xy 153.293794 -290.398527) (xy 153.33981 -290.381075)
			(xy 153.388029 -290.371231) (xy 153.437204 -290.36925) (xy 153.486059 -290.375182) (xy 153.53333 -290.388874)
			(xy 153.577792 -290.409972) (xy 153.618295 -290.437928) (xy 153.653788 -290.47202) (xy 153.683353 -290.511364)
			(xy 153.706224 -290.554941) (xy 153.721808 -290.601622) (xy 153.729703 -290.650199) (xy 153.730198 -290.674806)
			(xy 154.0693 -290.674806) (xy 154.07326 -290.625752) (xy 154.085037 -290.577968) (xy 154.104328 -290.532692)
			(xy 154.130631 -290.491096) (xy 154.163266 -290.454259) (xy 154.201387 -290.423134) (xy 154.244008 -290.398527)
			(xy 154.290024 -290.381075) (xy 154.338243 -290.371231) (xy 154.387418 -290.36925) (xy 154.436273 -290.375182)
			(xy 154.483544 -290.388874) (xy 154.528006 -290.409972) (xy 154.568509 -290.437928) (xy 154.604002 -290.47202)
			(xy 154.633567 -290.511364) (xy 154.656438 -290.554941) (xy 154.672022 -290.601622) (xy 154.679917 -290.650199)
			(xy 154.680412 -290.674806) (xy 156.91918 -290.674806) (xy 156.92314 -290.625752) (xy 156.934917 -290.577968)
			(xy 156.954208 -290.532692) (xy 156.980511 -290.491096) (xy 157.013146 -290.454259) (xy 157.051267 -290.423134)
			(xy 157.093888 -290.398527) (xy 157.139904 -290.381075) (xy 157.188123 -290.371231) (xy 157.237298 -290.36925)
			(xy 157.286153 -290.375182) (xy 157.333424 -290.388874) (xy 157.377886 -290.409972) (xy 157.418389 -290.437928)
			(xy 157.453882 -290.47202) (xy 157.483447 -290.511364) (xy 157.506318 -290.554941) (xy 157.521902 -290.601622)
			(xy 157.529797 -290.650199) (xy 157.530292 -290.674806) (xy 157.86914 -290.674806) (xy 157.8731 -290.625752)
			(xy 157.884877 -290.577968) (xy 157.904168 -290.532692) (xy 157.930471 -290.491096) (xy 157.963106 -290.454259)
			(xy 158.001227 -290.423134) (xy 158.043848 -290.398527) (xy 158.089864 -290.381075) (xy 158.138083 -290.371231)
			(xy 158.187258 -290.36925) (xy 158.236113 -290.375182) (xy 158.283384 -290.388874) (xy 158.327846 -290.409972)
			(xy 158.368349 -290.437928) (xy 158.403842 -290.47202) (xy 158.433407 -290.511364) (xy 158.456278 -290.554941)
			(xy 158.471862 -290.601622) (xy 158.479757 -290.650199) (xy 158.480252 -290.674806) (xy 158.479757 -290.699413)
			(xy 158.471862 -290.74799) (xy 158.456278 -290.794671) (xy 158.433407 -290.838248) (xy 158.403842 -290.877592)
			(xy 158.368349 -290.911684) (xy 158.327846 -290.93964) (xy 158.283384 -290.960738) (xy 158.236113 -290.97443)
			(xy 158.187258 -290.980362) (xy 158.138083 -290.978381) (xy 158.089864 -290.968537) (xy 158.043848 -290.951085)
			(xy 158.001227 -290.926478) (xy 157.963106 -290.895353) (xy 157.930471 -290.858516) (xy 157.904168 -290.81692)
			(xy 157.884877 -290.771644) (xy 157.8731 -290.72386) (xy 157.86914 -290.674806) (xy 157.530292 -290.674806)
			(xy 157.529797 -290.699413) (xy 157.521902 -290.74799) (xy 157.506318 -290.794671) (xy 157.483447 -290.838248)
			(xy 157.453882 -290.877592) (xy 157.418389 -290.911684) (xy 157.377886 -290.93964) (xy 157.333424 -290.960738)
			(xy 157.286153 -290.97443) (xy 157.237298 -290.980362) (xy 157.188123 -290.978381) (xy 157.139904 -290.968537)
			(xy 157.093888 -290.951085) (xy 157.051267 -290.926478) (xy 157.013146 -290.895353) (xy 156.980511 -290.858516)
			(xy 156.954208 -290.81692) (xy 156.934917 -290.771644) (xy 156.92314 -290.72386) (xy 156.91918 -290.674806)
			(xy 154.680412 -290.674806) (xy 154.679917 -290.699413) (xy 154.672022 -290.74799) (xy 154.656438 -290.794671)
			(xy 154.633567 -290.838248) (xy 154.604002 -290.877592) (xy 154.568509 -290.911684) (xy 154.528006 -290.93964)
			(xy 154.483544 -290.960738) (xy 154.436273 -290.97443) (xy 154.387418 -290.980362) (xy 154.338243 -290.978381)
			(xy 154.290024 -290.968537) (xy 154.244008 -290.951085) (xy 154.201387 -290.926478) (xy 154.163266 -290.895353)
			(xy 154.130631 -290.858516) (xy 154.104328 -290.81692) (xy 154.085037 -290.771644) (xy 154.07326 -290.72386)
			(xy 154.0693 -290.674806) (xy 153.730198 -290.674806) (xy 153.729703 -290.699413) (xy 153.721808 -290.74799)
			(xy 153.706224 -290.794671) (xy 153.683353 -290.838248) (xy 153.653788 -290.877592) (xy 153.618295 -290.911684)
			(xy 153.577792 -290.93964) (xy 153.53333 -290.960738) (xy 153.486059 -290.97443) (xy 153.437204 -290.980362)
			(xy 153.388029 -290.978381) (xy 153.33981 -290.968537) (xy 153.293794 -290.951085) (xy 153.251173 -290.926478)
			(xy 153.213052 -290.895353) (xy 153.180417 -290.858516) (xy 153.154114 -290.81692) (xy 153.134823 -290.771644)
			(xy 153.123046 -290.72386) (xy 153.119086 -290.674806) (xy 152.805093 -290.674806) (xy 152.805093 -290.700785)
			(xy 152.796963 -290.752116) (xy 152.780904 -290.801543) (xy 152.757311 -290.84785) (xy 152.726766 -290.889896)
			(xy 152.690019 -290.926646) (xy 152.647975 -290.957196) (xy 152.601671 -290.980793) (xy 152.552245 -290.996856)
			(xy 152.500915 -291.00499) (xy 152.47493 -291.005514) (xy 152.474422 -291.005514) (xy 152.448246 -291.005016)
			(xy 152.39655 -290.996762) (xy 152.346803 -290.980457) (xy 152.323292 -290.968938) (xy 152.323038 -290.968938)
			(xy 152.317196 -290.966187) (xy 152.304603 -290.963354) (xy 152.298146 -290.96335) (xy 152.284938 -290.963858)
			(xy 152.204928 -291.01288) (xy 152.19553 -291.020246) (xy 152.18664 -291.029136) (xy 152.18283 -291.03828)
			(xy 152.178004 -291.048186) (xy 152.178004 -291.237162) (xy 152.178073 -291.240968) (xy 152.179226 -291.248493)
			(xy 152.18029 -291.252148) (xy 152.182576 -291.259514) (xy 152.189688 -291.275262) (xy 152.195784 -291.280596)
			(xy 152.199086 -291.283136) (xy 152.276048 -291.33038) (xy 152.290526 -291.330634) (xy 152.30602 -291.330634)
			(xy 152.312624 -291.330126) (xy 152.332944 -291.325808) (xy 152.338024 -291.323522) (xy 152.359549 -291.314224)
			(xy 152.404563 -291.301105) (xy 152.450979 -291.294466) (xy 152.474422 -291.294058) (xy 152.47493 -291.294058)
			(xy 152.500918 -291.29457) (xy 152.552254 -291.302705) (xy 152.601686 -291.31877) (xy 152.647996 -291.34237)
			(xy 152.690045 -291.372924) (xy 152.726796 -291.409678) (xy 152.757346 -291.451729) (xy 152.780941 -291.498042)
			(xy 152.797002 -291.547475) (xy 152.805132 -291.598812) (xy 152.805132 -291.624766) (xy 153.119086 -291.624766)
			(xy 153.123046 -291.575712) (xy 153.134823 -291.527928) (xy 153.154114 -291.482652) (xy 153.180417 -291.441056)
			(xy 153.213052 -291.404219) (xy 153.251173 -291.373094) (xy 153.293794 -291.348487) (xy 153.33981 -291.331035)
			(xy 153.388029 -291.321191) (xy 153.437204 -291.31921) (xy 153.486059 -291.325142) (xy 153.53333 -291.338834)
			(xy 153.577792 -291.359932) (xy 153.618295 -291.387888) (xy 153.653788 -291.42198) (xy 153.683353 -291.461324)
			(xy 153.706224 -291.504901) (xy 153.721808 -291.551582) (xy 153.729703 -291.600159) (xy 153.730198 -291.624766)
			(xy 154.0693 -291.624766) (xy 154.07326 -291.575712) (xy 154.085037 -291.527928) (xy 154.104328 -291.482652)
			(xy 154.130631 -291.441056) (xy 154.163266 -291.404219) (xy 154.201387 -291.373094) (xy 154.244008 -291.348487)
			(xy 154.290024 -291.331035) (xy 154.338243 -291.321191) (xy 154.387418 -291.31921) (xy 154.436273 -291.325142)
			(xy 154.483544 -291.338834) (xy 154.528006 -291.359932) (xy 154.568509 -291.387888) (xy 154.604002 -291.42198)
			(xy 154.633567 -291.461324) (xy 154.656438 -291.504901) (xy 154.672022 -291.551582) (xy 154.679917 -291.600159)
			(xy 154.680412 -291.624766) (xy 156.91918 -291.624766) (xy 156.92314 -291.575712) (xy 156.934917 -291.527928)
			(xy 156.954208 -291.482652) (xy 156.980511 -291.441056) (xy 157.013146 -291.404219) (xy 157.051267 -291.373094)
			(xy 157.093888 -291.348487) (xy 157.139904 -291.331035) (xy 157.188123 -291.321191) (xy 157.237298 -291.31921)
			(xy 157.286153 -291.325142) (xy 157.333424 -291.338834) (xy 157.377886 -291.359932) (xy 157.418389 -291.387888)
			(xy 157.453882 -291.42198) (xy 157.483447 -291.461324) (xy 157.506318 -291.504901) (xy 157.521902 -291.551582)
			(xy 157.529797 -291.600159) (xy 157.530292 -291.624766) (xy 157.86914 -291.624766) (xy 157.8731 -291.575712)
			(xy 157.884877 -291.527928) (xy 157.904168 -291.482652) (xy 157.930471 -291.441056) (xy 157.963106 -291.404219)
			(xy 158.001227 -291.373094) (xy 158.043848 -291.348487) (xy 158.089864 -291.331035) (xy 158.138083 -291.321191)
			(xy 158.187258 -291.31921) (xy 158.236113 -291.325142) (xy 158.283384 -291.338834) (xy 158.327846 -291.359932)
			(xy 158.368349 -291.387888) (xy 158.403842 -291.42198) (xy 158.433407 -291.461324) (xy 158.456278 -291.504901)
			(xy 158.471862 -291.551582) (xy 158.479757 -291.600159) (xy 158.480252 -291.624766) (xy 158.479757 -291.649373)
			(xy 158.471862 -291.69795) (xy 158.456278 -291.744631) (xy 158.433407 -291.788208) (xy 158.403842 -291.827552)
			(xy 158.368349 -291.861644) (xy 158.327846 -291.8896) (xy 158.283384 -291.910698) (xy 158.236113 -291.92439)
			(xy 158.187258 -291.930322) (xy 158.138083 -291.928341) (xy 158.089864 -291.918497) (xy 158.043848 -291.901045)
			(xy 158.001227 -291.876438) (xy 157.963106 -291.845313) (xy 157.930471 -291.808476) (xy 157.904168 -291.76688)
			(xy 157.884877 -291.721604) (xy 157.8731 -291.67382) (xy 157.86914 -291.624766) (xy 157.530292 -291.624766)
			(xy 157.529797 -291.649373) (xy 157.521902 -291.69795) (xy 157.506318 -291.744631) (xy 157.483447 -291.788208)
			(xy 157.453882 -291.827552) (xy 157.418389 -291.861644) (xy 157.377886 -291.8896) (xy 157.333424 -291.910698)
			(xy 157.286153 -291.92439) (xy 157.237298 -291.930322) (xy 157.188123 -291.928341) (xy 157.139904 -291.918497)
			(xy 157.093888 -291.901045) (xy 157.051267 -291.876438) (xy 157.013146 -291.845313) (xy 156.980511 -291.808476)
			(xy 156.954208 -291.76688) (xy 156.934917 -291.721604) (xy 156.92314 -291.67382) (xy 156.91918 -291.624766)
			(xy 154.680412 -291.624766) (xy 154.679917 -291.649373) (xy 154.672022 -291.69795) (xy 154.656438 -291.744631)
			(xy 154.633567 -291.788208) (xy 154.604002 -291.827552) (xy 154.568509 -291.861644) (xy 154.528006 -291.8896)
			(xy 154.483544 -291.910698) (xy 154.436273 -291.92439) (xy 154.387418 -291.930322) (xy 154.338243 -291.928341)
			(xy 154.290024 -291.918497) (xy 154.244008 -291.901045) (xy 154.201387 -291.876438) (xy 154.163266 -291.845313)
			(xy 154.130631 -291.808476) (xy 154.104328 -291.76688) (xy 154.085037 -291.721604) (xy 154.07326 -291.67382)
			(xy 154.0693 -291.624766) (xy 153.730198 -291.624766) (xy 153.729703 -291.649373) (xy 153.721808 -291.69795)
			(xy 153.706224 -291.744631) (xy 153.683353 -291.788208) (xy 153.653788 -291.827552) (xy 153.618295 -291.861644)
			(xy 153.577792 -291.8896) (xy 153.53333 -291.910698) (xy 153.486059 -291.92439) (xy 153.437204 -291.930322)
			(xy 153.388029 -291.928341) (xy 153.33981 -291.918497) (xy 153.293794 -291.901045) (xy 153.251173 -291.876438)
			(xy 153.213052 -291.845313) (xy 153.180417 -291.808476) (xy 153.154114 -291.76688) (xy 153.134823 -291.721604)
			(xy 153.123046 -291.67382) (xy 153.119086 -291.624766) (xy 152.805132 -291.624766) (xy 152.805132 -291.650788)
			(xy 152.797002 -291.702125) (xy 152.780941 -291.751558) (xy 152.757346 -291.797871) (xy 152.726796 -291.839922)
			(xy 152.690045 -291.876676) (xy 152.647996 -291.90723) (xy 152.601686 -291.93083) (xy 152.552254 -291.946895)
			(xy 152.500918 -291.95503) (xy 152.47493 -291.955474) (xy 152.474422 -291.955474) (xy 152.448246 -291.954976)
			(xy 152.396549 -291.946723) (xy 152.346801 -291.930421) (xy 152.323292 -291.918898) (xy 152.323038 -291.918898)
			(xy 152.317197 -291.916145) (xy 152.304603 -291.913308) (xy 152.298146 -291.91331) (xy 152.284938 -291.913818)
			(xy 152.204928 -291.96284) (xy 152.19553 -291.970206) (xy 152.18664 -291.979096) (xy 152.18283 -291.98824)
			(xy 152.178004 -291.998146) (xy 152.178004 -292.187376) (xy 152.178067 -292.191183) (xy 152.179207 -292.198712)
			(xy 152.18029 -292.202362) (xy 152.182576 -292.209728) (xy 152.189688 -292.225476) (xy 152.195784 -292.23081)
			(xy 152.199086 -292.23335) (xy 152.276048 -292.280594) (xy 152.290526 -292.280848) (xy 152.30602 -292.280848)
			(xy 152.312624 -292.28034) (xy 152.332944 -292.276022) (xy 152.338024 -292.273736) (xy 152.359549 -292.26444)
			(xy 152.404564 -292.251324) (xy 152.450979 -292.244687) (xy 152.474422 -292.244272) (xy 152.47493 -292.244272)
			(xy 152.500917 -292.244784) (xy 152.552251 -292.252919) (xy 152.601681 -292.268983) (xy 152.647989 -292.292582)
			(xy 152.690035 -292.323134) (xy 152.726785 -292.359887) (xy 152.757334 -292.401937) (xy 152.780928 -292.448247)
			(xy 152.796988 -292.497678) (xy 152.805119 -292.549013) (xy 152.805119 -292.57498) (xy 153.119086 -292.57498)
			(xy 153.123046 -292.525926) (xy 153.134823 -292.478142) (xy 153.154114 -292.432866) (xy 153.180417 -292.39127)
			(xy 153.213052 -292.354433) (xy 153.251173 -292.323308) (xy 153.293794 -292.298701) (xy 153.33981 -292.281249)
			(xy 153.388029 -292.271405) (xy 153.437204 -292.269424) (xy 153.486059 -292.275356) (xy 153.53333 -292.289048)
			(xy 153.577792 -292.310146) (xy 153.618295 -292.338102) (xy 153.653788 -292.372194) (xy 153.683353 -292.411538)
			(xy 153.706224 -292.455115) (xy 153.721808 -292.501796) (xy 153.729703 -292.550373) (xy 153.730198 -292.57498)
			(xy 154.0693 -292.57498) (xy 154.07326 -292.525926) (xy 154.085037 -292.478142) (xy 154.104328 -292.432866)
			(xy 154.130631 -292.39127) (xy 154.163266 -292.354433) (xy 154.201387 -292.323308) (xy 154.244008 -292.298701)
			(xy 154.290024 -292.281249) (xy 154.338243 -292.271405) (xy 154.387418 -292.269424) (xy 154.436273 -292.275356)
			(xy 154.483544 -292.289048) (xy 154.528006 -292.310146) (xy 154.568509 -292.338102) (xy 154.604002 -292.372194)
			(xy 154.633567 -292.411538) (xy 154.656438 -292.455115) (xy 154.672022 -292.501796) (xy 154.679917 -292.550373)
			(xy 154.680407 -292.574726) (xy 155.01926 -292.574726) (xy 155.02322 -292.525672) (xy 155.034997 -292.477888)
			(xy 155.054288 -292.432612) (xy 155.080591 -292.391016) (xy 155.113226 -292.354179) (xy 155.151347 -292.323054)
			(xy 155.193968 -292.298447) (xy 155.239984 -292.280995) (xy 155.288203 -292.271151) (xy 155.337378 -292.26917)
			(xy 155.386233 -292.275102) (xy 155.433504 -292.288794) (xy 155.477966 -292.309892) (xy 155.518469 -292.337848)
			(xy 155.553962 -292.37194) (xy 155.583527 -292.411284) (xy 155.606398 -292.454861) (xy 155.621982 -292.501542)
			(xy 155.629877 -292.550119) (xy 155.630372 -292.574726) (xy 155.96922 -292.574726) (xy 155.97318 -292.525672)
			(xy 155.984957 -292.477888) (xy 156.004248 -292.432612) (xy 156.030551 -292.391016) (xy 156.063186 -292.354179)
			(xy 156.101307 -292.323054) (xy 156.143928 -292.298447) (xy 156.189944 -292.280995) (xy 156.238163 -292.271151)
			(xy 156.287338 -292.26917) (xy 156.336193 -292.275102) (xy 156.383464 -292.288794) (xy 156.427926 -292.309892)
			(xy 156.468429 -292.337848) (xy 156.503922 -292.37194) (xy 156.533487 -292.411284) (xy 156.556358 -292.454861)
			(xy 156.571942 -292.501542) (xy 156.579837 -292.550119) (xy 156.580332 -292.574726) (xy 156.580327 -292.57498)
			(xy 156.91918 -292.57498) (xy 156.92314 -292.525926) (xy 156.934917 -292.478142) (xy 156.954208 -292.432866)
			(xy 156.980511 -292.39127) (xy 157.013146 -292.354433) (xy 157.051267 -292.323308) (xy 157.093888 -292.298701)
			(xy 157.139904 -292.281249) (xy 157.188123 -292.271405) (xy 157.237298 -292.269424) (xy 157.286153 -292.275356)
			(xy 157.333424 -292.289048) (xy 157.377886 -292.310146) (xy 157.418389 -292.338102) (xy 157.453882 -292.372194)
			(xy 157.483447 -292.411538) (xy 157.506318 -292.455115) (xy 157.521902 -292.501796) (xy 157.529797 -292.550373)
			(xy 157.530292 -292.57498) (xy 157.529797 -292.599587) (xy 157.529465 -292.601629) (xy 157.819334 -292.601629)
			(xy 157.819334 -292.548331) (xy 157.827277 -292.495627) (xy 157.842987 -292.444697) (xy 157.866113 -292.396676)
			(xy 157.896137 -292.352639) (xy 157.932389 -292.313568) (xy 157.97406 -292.280337) (xy 158.020218 -292.253688)
			(xy 158.069832 -292.234216) (xy 158.121794 -292.222356) (xy 158.174944 -292.218373) (xy 158.228094 -292.222356)
			(xy 158.280056 -292.234216) (xy 158.32967 -292.253688) (xy 158.375828 -292.280337) (xy 158.417499 -292.313568)
			(xy 158.453751 -292.352639) (xy 158.483775 -292.396676) (xy 158.506901 -292.444697) (xy 158.522611 -292.495627)
			(xy 158.530554 -292.548331) (xy 158.531052 -292.57498) (xy 158.530554 -292.601629) (xy 158.522611 -292.654333)
			(xy 158.506901 -292.705263) (xy 158.483775 -292.753284) (xy 158.453751 -292.797321) (xy 158.417499 -292.836392)
			(xy 158.375828 -292.869623) (xy 158.32967 -292.896272) (xy 158.280056 -292.915744) (xy 158.228094 -292.927604)
			(xy 158.174944 -292.931588) (xy 158.121794 -292.927604) (xy 158.069832 -292.915744) (xy 158.020218 -292.896272)
			(xy 157.97406 -292.869623) (xy 157.932389 -292.836392) (xy 157.896137 -292.797321) (xy 157.866113 -292.753284)
			(xy 157.842987 -292.705263) (xy 157.827277 -292.654333) (xy 157.819334 -292.601629) (xy 157.529465 -292.601629)
			(xy 157.521902 -292.648164) (xy 157.506318 -292.694845) (xy 157.483447 -292.738422) (xy 157.453882 -292.777766)
			(xy 157.418389 -292.811858) (xy 157.377886 -292.839814) (xy 157.333424 -292.860912) (xy 157.286153 -292.874604)
			(xy 157.237298 -292.880536) (xy 157.188123 -292.878555) (xy 157.139904 -292.868711) (xy 157.093888 -292.851259)
			(xy 157.051267 -292.826652) (xy 157.013146 -292.795527) (xy 156.980511 -292.75869) (xy 156.954208 -292.717094)
			(xy 156.934917 -292.671818) (xy 156.92314 -292.624034) (xy 156.91918 -292.57498) (xy 156.580327 -292.57498)
			(xy 156.579837 -292.599333) (xy 156.571942 -292.64791) (xy 156.556358 -292.694591) (xy 156.533487 -292.738168)
			(xy 156.503922 -292.777512) (xy 156.468429 -292.811604) (xy 156.427926 -292.83956) (xy 156.383464 -292.860658)
			(xy 156.336193 -292.87435) (xy 156.287338 -292.880282) (xy 156.238163 -292.878301) (xy 156.189944 -292.868457)
			(xy 156.143928 -292.851005) (xy 156.101307 -292.826398) (xy 156.063186 -292.795273) (xy 156.030551 -292.758436)
			(xy 156.004248 -292.71684) (xy 155.984957 -292.671564) (xy 155.97318 -292.62378) (xy 155.96922 -292.574726)
			(xy 155.630372 -292.574726) (xy 155.629877 -292.599333) (xy 155.621982 -292.64791) (xy 155.606398 -292.694591)
			(xy 155.583527 -292.738168) (xy 155.553962 -292.777512) (xy 155.518469 -292.811604) (xy 155.477966 -292.83956)
			(xy 155.433504 -292.860658) (xy 155.386233 -292.87435) (xy 155.337378 -292.880282) (xy 155.288203 -292.878301)
			(xy 155.239984 -292.868457) (xy 155.193968 -292.851005) (xy 155.151347 -292.826398) (xy 155.113226 -292.795273)
			(xy 155.080591 -292.758436) (xy 155.054288 -292.71684) (xy 155.034997 -292.671564) (xy 155.02322 -292.62378)
			(xy 155.01926 -292.574726) (xy 154.680407 -292.574726) (xy 154.680412 -292.57498) (xy 154.679917 -292.599587)
			(xy 154.672022 -292.648164) (xy 154.656438 -292.694845) (xy 154.633567 -292.738422) (xy 154.604002 -292.777766)
			(xy 154.568509 -292.811858) (xy 154.528006 -292.839814) (xy 154.483544 -292.860912) (xy 154.436273 -292.874604)
			(xy 154.387418 -292.880536) (xy 154.338243 -292.878555) (xy 154.290024 -292.868711) (xy 154.244008 -292.851259)
			(xy 154.201387 -292.826652) (xy 154.163266 -292.795527) (xy 154.130631 -292.75869) (xy 154.104328 -292.717094)
			(xy 154.085037 -292.671818) (xy 154.07326 -292.624034) (xy 154.0693 -292.57498) (xy 153.730198 -292.57498)
			(xy 153.729703 -292.599587) (xy 153.721808 -292.648164) (xy 153.706224 -292.694845) (xy 153.683353 -292.738422)
			(xy 153.653788 -292.777766) (xy 153.618295 -292.811858) (xy 153.577792 -292.839814) (xy 153.53333 -292.860912)
			(xy 153.486059 -292.874604) (xy 153.437204 -292.880536) (xy 153.388029 -292.878555) (xy 153.33981 -292.868711)
			(xy 153.293794 -292.851259) (xy 153.251173 -292.826652) (xy 153.213052 -292.795527) (xy 153.180417 -292.75869)
			(xy 153.154114 -292.717094) (xy 153.134823 -292.671818) (xy 153.123046 -292.624034) (xy 153.119086 -292.57498)
			(xy 152.805119 -292.57498) (xy 152.805119 -292.600987) (xy 152.796988 -292.652322) (xy 152.780928 -292.701753)
			(xy 152.757334 -292.748063) (xy 152.726785 -292.790113) (xy 152.690035 -292.826866) (xy 152.647989 -292.857418)
			(xy 152.601681 -292.881017) (xy 152.552251 -292.897081) (xy 152.500917 -292.905216) (xy 152.47493 -292.905688)
			(xy 152.474422 -292.905688) (xy 152.448246 -292.90519) (xy 152.39655 -292.896935) (xy 152.346803 -292.880629)
			(xy 152.323292 -292.869112) (xy 152.323038 -292.869112) (xy 152.317197 -292.866358) (xy 152.304603 -292.863521)
			(xy 152.298146 -292.863524) (xy 152.284938 -292.864032) (xy 152.204928 -292.913054) (xy 152.19553 -292.92042)
			(xy 152.18664 -292.92931) (xy 152.18283 -292.938454) (xy 152.178004 -292.94836) (xy 152.178004 -293.52494)
			(xy 154.0693 -293.52494) (xy 154.07326 -293.475886) (xy 154.085037 -293.428102) (xy 154.104328 -293.382826)
			(xy 154.130631 -293.34123) (xy 154.163266 -293.304393) (xy 154.201387 -293.273268) (xy 154.244008 -293.248661)
			(xy 154.290024 -293.231209) (xy 154.338243 -293.221365) (xy 154.387418 -293.219384) (xy 154.436273 -293.225316)
			(xy 154.483544 -293.239008) (xy 154.528006 -293.260106) (xy 154.568509 -293.288062) (xy 154.604002 -293.322154)
			(xy 154.633567 -293.361498) (xy 154.656438 -293.405075) (xy 154.672022 -293.451756) (xy 154.679917 -293.500333)
			(xy 154.680412 -293.52494) (xy 155.01926 -293.52494) (xy 155.02322 -293.475886) (xy 155.034997 -293.428102)
			(xy 155.054288 -293.382826) (xy 155.080591 -293.34123) (xy 155.113226 -293.304393) (xy 155.151347 -293.273268)
			(xy 155.193968 -293.248661) (xy 155.239984 -293.231209) (xy 155.288203 -293.221365) (xy 155.337378 -293.219384)
			(xy 155.386233 -293.225316) (xy 155.433504 -293.239008) (xy 155.477966 -293.260106) (xy 155.518469 -293.288062)
			(xy 155.553962 -293.322154) (xy 155.583527 -293.361498) (xy 155.606398 -293.405075) (xy 155.621982 -293.451756)
			(xy 155.629877 -293.500333) (xy 155.630372 -293.52494) (xy 155.96922 -293.52494) (xy 155.97318 -293.475886)
			(xy 155.984957 -293.428102) (xy 156.004248 -293.382826) (xy 156.030551 -293.34123) (xy 156.063186 -293.304393)
			(xy 156.101307 -293.273268) (xy 156.143928 -293.248661) (xy 156.189944 -293.231209) (xy 156.238163 -293.221365)
			(xy 156.287338 -293.219384) (xy 156.336193 -293.225316) (xy 156.383464 -293.239008) (xy 156.427926 -293.260106)
			(xy 156.468429 -293.288062) (xy 156.503922 -293.322154) (xy 156.533487 -293.361498) (xy 156.556358 -293.405075)
			(xy 156.571942 -293.451756) (xy 156.579837 -293.500333) (xy 156.580332 -293.52494) (xy 156.91918 -293.52494)
			(xy 156.92314 -293.475886) (xy 156.934917 -293.428102) (xy 156.954208 -293.382826) (xy 156.980511 -293.34123)
			(xy 157.013146 -293.304393) (xy 157.051267 -293.273268) (xy 157.093888 -293.248661) (xy 157.139904 -293.231209)
			(xy 157.188123 -293.221365) (xy 157.237298 -293.219384) (xy 157.286153 -293.225316) (xy 157.333424 -293.239008)
			(xy 157.377886 -293.260106) (xy 157.418389 -293.288062) (xy 157.453882 -293.322154) (xy 157.483447 -293.361498)
			(xy 157.506318 -293.405075) (xy 157.521902 -293.451756) (xy 157.529797 -293.500333) (xy 157.530292 -293.52494)
			(xy 157.86914 -293.52494) (xy 157.8731 -293.475886) (xy 157.884877 -293.428102) (xy 157.904168 -293.382826)
			(xy 157.930471 -293.34123) (xy 157.963106 -293.304393) (xy 158.001227 -293.273268) (xy 158.043848 -293.248661)
			(xy 158.089864 -293.231209) (xy 158.138083 -293.221365) (xy 158.187258 -293.219384) (xy 158.236113 -293.225316)
			(xy 158.283384 -293.239008) (xy 158.327846 -293.260106) (xy 158.368349 -293.288062) (xy 158.403842 -293.322154)
			(xy 158.433407 -293.361498) (xy 158.456278 -293.405075) (xy 158.471862 -293.451756) (xy 158.479757 -293.500333)
			(xy 158.480252 -293.524923) (xy 158.767921 -293.524923) (xy 158.771776 -293.47258) (xy 158.783264 -293.421369)
			(xy 158.802137 -293.372395) (xy 158.827986 -293.326717) (xy 158.860254 -293.285324) (xy 158.898243 -293.249109)
			(xy 158.919418 -293.233602) (xy 158.928981 -293.226011) (xy 158.940248 -293.204387) (xy 158.941008 -293.1922)
			(xy 158.941008 -292.930834) (xy 158.941245 -292.913355) (xy 158.945068 -292.878606) (xy 158.948628 -292.861492)
			(xy 158.95028 -292.852275) (xy 158.947512 -292.833769) (xy 158.938304 -292.817479) (xy 158.931356 -292.8112)
			(xy 158.912645 -292.795273) (xy 158.880117 -292.758449) (xy 158.853904 -292.716892) (xy 158.834682 -292.671674)
			(xy 158.822948 -292.623962) (xy 158.819004 -292.574987) (xy 158.822952 -292.526012) (xy 158.83469 -292.478301)
			(xy 158.853915 -292.433085) (xy 158.880132 -292.39153) (xy 158.912664 -292.354709) (xy 158.931356 -292.33876)
			(xy 158.938391 -292.332555) (xy 158.94763 -292.316241) (xy 158.950348 -292.297691) (xy 158.948628 -292.288468)
			(xy 158.945065 -292.271354) (xy 158.941251 -292.236605) (xy 158.941008 -292.219126) (xy 158.941008 -291.98062)
			(xy 158.941259 -291.963141) (xy 158.945072 -291.928393) (xy 158.948628 -291.911278) (xy 158.950211 -291.902053)
			(xy 158.947472 -291.883557) (xy 158.938292 -291.867268) (xy 158.931356 -291.860986) (xy 158.912631 -291.845075)
			(xy 158.880103 -291.808249) (xy 158.85389 -291.766689) (xy 158.834669 -291.721469) (xy 158.822936 -291.673755)
			(xy 158.818993 -291.624778) (xy 158.822943 -291.575802) (xy 158.834683 -291.52809) (xy 158.85391 -291.482872)
			(xy 158.880129 -291.441317) (xy 158.912663 -291.404495) (xy 158.931356 -291.388546) (xy 158.938338 -291.382288)
			(xy 158.947589 -291.366001) (xy 158.950332 -291.347471) (xy 158.948628 -291.338254) (xy 158.945079 -291.321138)
			(xy 158.941255 -291.28639) (xy 158.941008 -291.268912) (xy 158.941008 -291.03066) (xy 158.941249 -291.013181)
			(xy 158.945069 -290.978432) (xy 158.948628 -290.961318) (xy 158.950259 -290.952099) (xy 158.9475 -290.933596)
			(xy 158.938301 -290.917306) (xy 158.931356 -290.911026) (xy 158.912672 -290.89507) (xy 158.880143 -290.85825)
			(xy 158.85393 -290.816697) (xy 158.834707 -290.771484) (xy 158.822971 -290.723775) (xy 158.819024 -290.674804)
			(xy 158.82297 -290.625832) (xy 158.834704 -290.578124) (xy 158.853926 -290.532909) (xy 158.880139 -290.491356)
			(xy 158.912666 -290.454535) (xy 158.931356 -290.438586) (xy 158.938375 -290.432365) (xy 158.947618 -290.416059)
			(xy 158.950343 -290.397515) (xy 158.948628 -290.388294) (xy 158.94507 -290.37118) (xy 158.941252 -290.336431)
			(xy 158.941008 -290.318952) (xy 158.941008 -290.192206) (xy 158.941157 -290.187113) (xy 158.943202 -290.177133)
			(xy 158.945072 -290.172394) (xy 158.952184 -290.155122) (xy 158.954085 -290.150391) (xy 158.956134 -290.140407)
			(xy 158.956248 -290.13531) (xy 158.956248 -290.005008) (xy 158.955691 -289.993438) (xy 158.945489 -289.972666)
			(xy 158.93669 -289.96513) (xy 158.9188 -289.950561) (xy 158.887157 -289.916988) (xy 158.86093 -289.879033)
			(xy 158.840715 -289.837563) (xy 158.826975 -289.793521) (xy 158.820022 -289.747913) (xy 158.819596 -289.724846)
			(xy 158.820071 -289.70004) (xy 158.82808 -289.651079) (xy 158.843895 -289.604056) (xy 158.8671 -289.560205)
			(xy 158.897085 -289.52068) (xy 158.933063 -289.48652) (xy 158.974087 -289.458622) (xy 158.99638 -289.447732)
			(xy 159.004748 -289.443514) (xy 159.017824 -289.43011) (xy 159.025164 -289.412882) (xy 159.025844 -289.403536)
			(xy 159.027084 -289.379454) (xy 159.03595 -289.332055) (xy 159.051793 -289.28651) (xy 159.074259 -289.243842)
			(xy 159.102844 -289.205007) (xy 159.11957 -289.187636) (xy 159.12465 -289.182556) (xy 159.139382 -289.168586)
			(xy 159.144716 -289.163506) (xy 159.150523 -289.156009) (xy 159.156789 -289.138133) (xy 159.156138 -289.119202)
			(xy 159.148658 -289.101799) (xy 159.13537 -289.0883) (xy 159.118088 -289.080546) (xy 159.108648 -289.079686)
			(xy 159.08296 -289.077779) (xy 159.032713 -289.066459) (xy 158.98508 -289.046864) (xy 158.941411 -289.019553)
			(xy 158.902946 -288.985298) (xy 158.870777 -288.945073) (xy 158.845817 -288.900019) (xy 158.828773 -288.851415)
			(xy 158.82013 -288.800639) (xy 158.819596 -288.774886) (xy 158.820118 -288.749631) (xy 158.828431 -288.699809)
			(xy 158.844832 -288.652035) (xy 158.868873 -288.607612) (xy 158.899897 -288.567752) (xy 158.937059 -288.533542)
			(xy 158.979345 -288.505916) (xy 159.025601 -288.485626) (xy 159.074566 -288.473226) (xy 159.124904 -288.469055)
			(xy 159.175242 -288.473226) (xy 159.224207 -288.485626) (xy 159.270463 -288.505916) (xy 159.312749 -288.533542)
			(xy 159.349911 -288.567752) (xy 159.380935 -288.607612) (xy 159.404976 -288.652035) (xy 159.421377 -288.699809)
			(xy 159.42969 -288.749631) (xy 159.430212 -288.774886) (xy 159.429594 -288.802727) (xy 159.41951 -288.857487)
			(xy 159.399691 -288.909522) (xy 159.385762 -288.933636) (xy 159.381387 -288.941508) (xy 159.377846 -288.95915)
			(xy 159.380657 -288.976922) (xy 159.384746 -288.984944) (xy 159.42818 -289.06216) (xy 159.432857 -289.06984)
			(xy 159.446523 -289.081513) (xy 159.463389 -289.087722) (xy 159.472376 -289.088068) (xy 159.733234 -289.088068)
			(xy 159.761662 -289.088738) (xy 159.817618 -289.098825) (xy 159.844486 -289.108134) (xy 159.854448 -289.111291)
			(xy 159.875293 -289.110264) (xy 159.894005 -289.101022) (xy 159.907488 -289.085092) (xy 159.913512 -289.06511)
			(xy 159.91108 -289.044382) (xy 159.900595 -289.026337) (xy 159.892492 -289.019742) (xy 159.873747 -289.005249)
			(xy 159.840579 -288.971412) (xy 159.813036 -288.932858) (xy 159.791779 -288.890512) (xy 159.777319 -288.84539)
			(xy 159.770002 -288.798577) (xy 159.769556 -288.774886) (xy 159.770078 -288.749631) (xy 159.778391 -288.699809)
			(xy 159.794792 -288.652035) (xy 159.818833 -288.607612) (xy 159.849857 -288.567752) (xy 159.887019 -288.533542)
			(xy 159.929305 -288.505916) (xy 159.975561 -288.485626) (xy 160.024526 -288.473226) (xy 160.074864 -288.469055)
			(xy 160.125202 -288.473226) (xy 160.174167 -288.485626) (xy 160.220423 -288.505916) (xy 160.262709 -288.533542)
			(xy 160.299871 -288.567752) (xy 160.330895 -288.607612) (xy 160.354936 -288.652035) (xy 160.371337 -288.699809)
			(xy 160.37965 -288.749631) (xy 160.380172 -288.774886) (xy 160.379731 -288.798577) (xy 160.372413 -288.845389)
			(xy 160.35795 -288.890509) (xy 160.336689 -288.932852) (xy 160.309142 -288.971402) (xy 160.275969 -289.005233)
			(xy 160.257236 -289.019742) (xy 160.249125 -289.026306) (xy 160.2387 -289.044363) (xy 160.236305 -289.065075)
			(xy 160.242335 -289.085035) (xy 160.255797 -289.100957) (xy 160.274476 -289.110221) (xy 160.295298 -289.111304)
			(xy 160.305242 -289.108134) (xy 160.332104 -289.0988) (xy 160.388064 -289.088715) (xy 160.416494 -289.088068)
			(xy 160.683448 -289.088068) (xy 160.711876 -289.088735) (xy 160.767832 -289.098824) (xy 160.7947 -289.108134)
			(xy 160.804658 -289.111301) (xy 160.825503 -289.11027) (xy 160.844213 -289.101025) (xy 160.857696 -289.085095)
			(xy 160.86372 -289.065113) (xy 160.86129 -289.044385) (xy 160.850807 -289.026339) (xy 160.842706 -289.019742)
			(xy 160.823963 -289.005245) (xy 160.790795 -288.97141) (xy 160.763251 -288.932856) (xy 160.741994 -288.890511)
			(xy 160.727533 -288.84539) (xy 160.720216 -288.798577) (xy 160.71977 -288.774886) (xy 160.720292 -288.749631)
			(xy 160.728605 -288.699809) (xy 160.745006 -288.652035) (xy 160.769047 -288.607612) (xy 160.800071 -288.567752)
			(xy 160.837233 -288.533542) (xy 160.879519 -288.505916) (xy 160.925775 -288.485626) (xy 160.97474 -288.473226)
			(xy 161.025078 -288.469055) (xy 161.075416 -288.473226) (xy 161.124381 -288.485626) (xy 161.170637 -288.505916)
			(xy 161.212923 -288.533542) (xy 161.250085 -288.567752) (xy 161.281109 -288.607612) (xy 161.30515 -288.652035)
			(xy 161.321551 -288.699809) (xy 161.329864 -288.749631) (xy 161.330386 -288.774886) (xy 161.329939 -288.798576)
			(xy 161.322621 -288.845388) (xy 161.308159 -288.890508) (xy 161.2869 -288.932851) (xy 161.259354 -288.971401)
			(xy 161.226183 -289.005233) (xy 161.20745 -289.019742) (xy 161.199328 -289.026296) (xy 161.188897 -289.044356)
			(xy 161.1865 -289.065073) (xy 161.192531 -289.085038) (xy 161.205997 -289.100963) (xy 161.224682 -289.110228)
			(xy 161.24551 -289.111307) (xy 161.255456 -289.108134) (xy 161.282325 -289.098822) (xy 161.338279 -289.088722)
			(xy 161.366708 -289.088068) (xy 161.633408 -289.088068) (xy 161.661837 -289.088719) (xy 161.717792 -289.098819)
			(xy 161.74466 -289.108134) (xy 161.754601 -289.111344) (xy 161.775445 -289.110297) (xy 161.794151 -289.101042)
			(xy 161.807629 -289.085109) (xy 161.813655 -289.065127) (xy 161.811232 -289.044399) (xy 161.800762 -289.026345)
			(xy 161.792666 -289.019742) (xy 161.773936 -289.005229) (xy 161.740764 -288.971399) (xy 161.713217 -288.932849)
			(xy 161.691957 -288.890507) (xy 161.677494 -288.845388) (xy 161.670176 -288.798576) (xy 161.66973 -288.774886)
			(xy 161.670252 -288.749631) (xy 161.678565 -288.699809) (xy 161.694966 -288.652035) (xy 161.719007 -288.607612)
			(xy 161.750031 -288.567752) (xy 161.787193 -288.533542) (xy 161.829479 -288.505916) (xy 161.875735 -288.485626)
			(xy 161.9247 -288.473226) (xy 161.975038 -288.469055) (xy 162.025376 -288.473226) (xy 162.074341 -288.485626)
			(xy 162.120597 -288.505916) (xy 162.162883 -288.533542) (xy 162.200045 -288.567752) (xy 162.231069 -288.607612)
			(xy 162.25511 -288.652035) (xy 162.271511 -288.699809) (xy 162.279824 -288.749631) (xy 162.280346 -288.774886)
			(xy 162.279875 -288.798575) (xy 162.272559 -288.845385) (xy 162.2581 -288.890502) (xy 162.236845 -288.932845)
			(xy 162.209304 -288.971396) (xy 162.17614 -289.005231) (xy 162.15741 -289.019742) (xy 162.14932 -289.026326)
			(xy 162.138906 -289.044377) (xy 162.136515 -289.065079) (xy 162.142542 -289.085029) (xy 162.155996 -289.100944)
			(xy 162.174664 -289.110208) (xy 162.195475 -289.111298) (xy 162.205416 -289.108134) (xy 162.23228 -289.098807)
			(xy 162.288238 -289.088717) (xy 162.316668 -289.088068) (xy 162.583368 -289.088068) (xy 162.611796 -289.08873)
			(xy 162.667752 -289.098822) (xy 162.69462 -289.108134) (xy 162.704572 -289.111315) (xy 162.725417 -289.110279)
			(xy 162.744126 -289.101031) (xy 162.757607 -289.085099) (xy 162.763631 -289.065118) (xy 162.761204 -289.04439)
			(xy 162.750725 -289.026341) (xy 162.742626 -289.019742) (xy 162.723888 -289.00524) (xy 162.690718 -288.971406)
			(xy 162.663173 -288.932854) (xy 162.641915 -288.890509) (xy 162.627454 -288.845389) (xy 162.620136 -288.798577)
			(xy 162.61969 -288.774886) (xy 162.620212 -288.749631) (xy 162.628525 -288.699809) (xy 162.644926 -288.652035)
			(xy 162.668967 -288.607612) (xy 162.699991 -288.567752) (xy 162.737153 -288.533542) (xy 162.779439 -288.505916)
			(xy 162.825695 -288.485626) (xy 162.87466 -288.473226) (xy 162.924998 -288.469055) (xy 162.975336 -288.473226)
			(xy 163.024301 -288.485626) (xy 163.070557 -288.505916) (xy 163.112843 -288.533542) (xy 163.150005 -288.567752)
			(xy 163.181029 -288.607612) (xy 163.20507 -288.652035) (xy 163.221471 -288.699809) (xy 163.229784 -288.749631)
			(xy 163.230306 -288.774886) (xy 163.229851 -288.798576) (xy 163.222534 -288.845387) (xy 163.208073 -288.890506)
			(xy 163.186815 -288.932849) (xy 163.159271 -288.9714) (xy 163.126102 -289.005232) (xy 163.10737 -289.019742)
			(xy 163.099232 -289.026281) (xy 163.088793 -289.044345) (xy 163.086393 -289.06507) (xy 163.092425 -289.085042)
			(xy 163.105898 -289.100973) (xy 163.124591 -289.110238) (xy 163.145427 -289.111311) (xy 163.155376 -289.108134)
			(xy 163.182243 -289.098817) (xy 163.238199 -289.08872) (xy 163.266628 -289.088068) (xy 163.533328 -289.088068)
			(xy 163.561756 -289.08874) (xy 163.617711 -289.098826) (xy 163.64458 -289.108134) (xy 163.654544 -289.111286)
			(xy 163.675389 -289.110262) (xy 163.694101 -289.10102) (xy 163.707585 -289.08509) (xy 163.713608 -289.065108)
			(xy 163.711176 -289.044381) (xy 163.700689 -289.026336) (xy 163.692586 -289.019742) (xy 163.673839 -289.005251)
			(xy 163.640672 -288.971413) (xy 163.613129 -288.932859) (xy 163.591873 -288.890512) (xy 163.577413 -288.845391)
			(xy 163.570096 -288.798577) (xy 163.56965 -288.774886) (xy 163.570172 -288.749631) (xy 163.578485 -288.699809)
			(xy 163.594886 -288.652035) (xy 163.618927 -288.607612) (xy 163.649951 -288.567752) (xy 163.687113 -288.533542)
			(xy 163.729399 -288.505916) (xy 163.775655 -288.485626) (xy 163.82462 -288.473226) (xy 163.874958 -288.469055)
			(xy 163.925296 -288.473226) (xy 163.974261 -288.485626) (xy 164.020517 -288.505916) (xy 164.062803 -288.533542)
			(xy 164.099965 -288.567752) (xy 164.130989 -288.607612) (xy 164.15503 -288.652035) (xy 164.171431 -288.699809)
			(xy 164.179744 -288.749631) (xy 164.180266 -288.774886) (xy 164.179827 -288.798577) (xy 164.172509 -288.845389)
			(xy 164.158045 -288.890509) (xy 164.136785 -288.932853) (xy 164.109237 -288.971403) (xy 164.076064 -289.005234)
			(xy 164.05733 -289.019742) (xy 164.049224 -289.026311) (xy 164.038801 -289.044366) (xy 164.036407 -289.065076)
			(xy 164.042436 -289.085033) (xy 164.055897 -289.100954) (xy 164.074573 -289.110218) (xy 164.095393 -289.111303)
			(xy 164.105336 -289.108134) (xy 164.132198 -289.098802) (xy 164.188158 -289.088715) (xy 164.216588 -289.088068)
			(xy 164.483288 -289.088068) (xy 164.508854 -289.088556) (xy 164.559326 -289.096767) (xy 164.607864 -289.112855)
			(xy 164.653246 -289.136418) (xy 164.694332 -289.166861) (xy 164.730086 -289.203418) (xy 164.759608 -289.24517)
			(xy 164.771324 -289.2679) (xy 164.785802 -289.297364) (xy 164.81044 -289.312604) (xy 164.824918 -289.312604)
			(xy 164.834345 -289.312214) (xy 164.851924 -289.305395) (xy 164.865851 -289.292684) (xy 164.870384 -289.28441)
			(xy 164.878512 -289.2679) (xy 164.890188 -289.245266) (xy 164.919568 -289.20367) (xy 164.955148 -289.167234)
			(xy 164.996033 -289.136872) (xy 165.041199 -289.113345) (xy 165.065202 -289.104832) (xy 165.076378 -289.101022)
			(xy 165.39337 -288.78403) (xy 165.400004 -288.777903) (xy 165.416406 -288.770369) (xy 165.425374 -288.769298)
			(xy 165.427406 -288.769298) (xy 165.438732 -288.767941) (xy 165.458501 -288.756604) (xy 165.471386 -288.737809)
			(xy 165.473634 -288.726626) (xy 165.477882 -288.703096) (xy 165.492718 -288.657645) (xy 165.514462 -288.615064)
			(xy 165.542582 -288.576396) (xy 165.576389 -288.542588) (xy 165.615056 -288.514467) (xy 165.657636 -288.492722)
			(xy 165.703087 -288.477884) (xy 165.726618 -288.473642) (xy 165.737726 -288.471243) (xy 165.756397 -288.45833)
			(xy 165.767757 -288.438676) (xy 165.76929 -288.427414) (xy 165.76929 -288.425382) (xy 165.770359 -288.416413)
			(xy 165.777895 -288.400013) (xy 165.784022 -288.393378) (xy 165.955218 -288.222182) (xy 165.973427 -288.204657)
			(xy 166.014296 -288.174933) (xy 166.059314 -288.151972) (xy 166.10737 -288.136341) (xy 166.157281 -288.128423)
			(xy 166.182548 -288.127948) (xy 166.39159 -288.127948) (xy 166.412338 -288.128285) (xy 166.453488 -288.133634)
			(xy 166.473632 -288.138616) (xy 166.476426 -288.139124) (xy 166.485792 -288.140706) (xy 166.504497 -288.137451)
			(xy 166.520738 -288.127617) (xy 166.532292 -288.11255) (xy 166.537575 -288.094313) (xy 166.535865 -288.075404)
			(xy 166.527396 -288.058411) (xy 166.520622 -288.051748) (xy 166.501993 -288.034213) (xy 166.470251 -287.994099)
			(xy 166.445634 -287.949257) (xy 166.428828 -287.900942) (xy 166.420304 -287.850503) (xy 166.419784 -287.824926)
			(xy 166.420306 -287.799671) (xy 166.428619 -287.749849) (xy 166.44502 -287.702075) (xy 166.469061 -287.657652)
			(xy 166.500085 -287.617792) (xy 166.537247 -287.583582) (xy 166.579533 -287.555956) (xy 166.625789 -287.535666)
			(xy 166.674754 -287.523266) (xy 166.725092 -287.519095) (xy 166.77543 -287.523266) (xy 166.824395 -287.535666)
			(xy 166.870651 -287.555956) (xy 166.912937 -287.583582) (xy 166.950099 -287.617792) (xy 166.981123 -287.657652)
			(xy 167.005164 -287.702075) (xy 167.021565 -287.749849) (xy 167.029878 -287.799671) (xy 167.0304 -287.824926)
			(xy 167.029874 -287.850503) (xy 167.021352 -287.900943) (xy 167.00455 -287.94926) (xy 166.979937 -287.994105)
			(xy 166.948202 -288.034226) (xy 166.929562 -288.051748) (xy 166.922786 -288.058407) (xy 166.914304 -288.07539)
			(xy 166.912586 -288.094296) (xy 166.917869 -288.112531) (xy 166.929427 -288.127591) (xy 166.945673 -288.13741)
			(xy 166.96438 -288.140642) (xy 166.973758 -288.139124) (xy 166.976552 -288.138616) (xy 166.996692 -288.133617)
			(xy 167.037845 -288.12827) (xy 167.058594 -288.127948) (xy 167.34155 -288.127948) (xy 167.362298 -288.128292)
			(xy 167.403448 -288.133637) (xy 167.423592 -288.138616) (xy 167.426386 -288.139124) (xy 167.435757 -288.140678)
			(xy 167.454465 -288.137434) (xy 167.47071 -288.127607) (xy 167.482266 -288.112542) (xy 167.487549 -288.094305)
			(xy 167.485835 -288.075397) (xy 167.477359 -288.058407) (xy 167.470582 -288.051748) (xy 167.451965 -288.034201)
			(xy 167.420219 -287.994091) (xy 167.395598 -287.949253) (xy 167.37879 -287.90094) (xy 167.370265 -287.850503)
			(xy 167.369744 -287.824926) (xy 167.370266 -287.799671) (xy 167.378579 -287.749849) (xy 167.39498 -287.702075)
			(xy 167.419021 -287.657652) (xy 167.450045 -287.617792) (xy 167.487207 -287.583582) (xy 167.529493 -287.555956)
			(xy 167.575749 -287.535666) (xy 167.624714 -287.523266) (xy 167.675052 -287.519095) (xy 167.72539 -287.523266)
			(xy 167.774355 -287.535666) (xy 167.820611 -287.555956) (xy 167.862897 -287.583582) (xy 167.900059 -287.617792)
			(xy 167.931083 -287.657652) (xy 167.955124 -287.702075) (xy 167.971525 -287.749849) (xy 167.979838 -287.799671)
			(xy 167.98036 -287.824926) (xy 167.979814 -287.850502) (xy 167.971294 -287.90094) (xy 167.954496 -287.949256)
			(xy 167.929888 -287.994101) (xy 167.898158 -288.034224) (xy 167.879522 -288.051748) (xy 167.872699 -288.058369)
			(xy 167.864198 -288.075365) (xy 167.862473 -288.09429) (xy 167.867761 -288.112543) (xy 167.879335 -288.127615)
			(xy 167.895604 -288.137435) (xy 167.914332 -288.140654) (xy 167.923718 -288.139124) (xy 167.926512 -288.138616)
			(xy 167.946654 -288.133624) (xy 167.987805 -288.128273) (xy 168.008554 -288.127948) (xy 168.29151 -288.127948)
			(xy 168.312258 -288.128281) (xy 168.353408 -288.133633) (xy 168.373552 -288.138616) (xy 168.376346 -288.139124)
			(xy 168.385709 -288.14072) (xy 168.404414 -288.13746) (xy 168.420653 -288.127622) (xy 168.432205 -288.112554)
			(xy 168.437489 -288.094317) (xy 168.43578 -288.075407) (xy 168.427314 -288.058412) (xy 168.420542 -288.051748)
			(xy 168.401917 -288.03421) (xy 168.370174 -287.994096) (xy 168.345555 -287.949256) (xy 168.328749 -287.900942)
			(xy 168.320224 -287.850503) (xy 168.319704 -287.824926) (xy 168.320226 -287.799671) (xy 168.328539 -287.749849)
			(xy 168.34494 -287.702075) (xy 168.368981 -287.657652) (xy 168.400005 -287.617792) (xy 168.437167 -287.583582)
			(xy 168.479453 -287.555956) (xy 168.525709 -287.535666) (xy 168.574674 -287.523266) (xy 168.625012 -287.519095)
			(xy 168.67535 -287.523266) (xy 168.724315 -287.535666) (xy 168.770571 -287.555956) (xy 168.812857 -287.583582)
			(xy 168.850019 -287.617792) (xy 168.881043 -287.657652) (xy 168.905084 -287.702075) (xy 168.921485 -287.749849)
			(xy 168.929798 -287.799671) (xy 168.93032 -287.824926) (xy 168.929787 -287.850503) (xy 168.921266 -287.900942)
			(xy 168.904465 -287.949259) (xy 168.879854 -287.994104) (xy 168.848121 -288.034225) (xy 168.829482 -288.051748)
			(xy 168.82269 -288.058394) (xy 168.814202 -288.075382) (xy 168.812482 -288.094294) (xy 168.817766 -288.112534)
			(xy 168.829329 -288.127599) (xy 168.845584 -288.137418) (xy 168.864298 -288.140646) (xy 168.873678 -288.139124)
			(xy 168.876472 -288.138616) (xy 168.896612 -288.133613) (xy 168.937765 -288.128269) (xy 168.958514 -288.127948)
			(xy 169.24147 -288.127948) (xy 169.262218 -288.128289) (xy 169.303368 -288.133635) (xy 169.323512 -288.138616)
			(xy 169.326306 -288.139124) (xy 169.335675 -288.140692) (xy 169.354381 -288.137443) (xy 169.370624 -288.127612)
			(xy 169.382179 -288.112546) (xy 169.387462 -288.094309) (xy 169.38575 -288.0754) (xy 169.377277 -288.058409)
			(xy 169.370502 -288.051748) (xy 169.35187 -288.034217) (xy 169.320129 -287.994101) (xy 169.295512 -287.949259)
			(xy 169.278708 -287.900943) (xy 169.270184 -287.850503) (xy 169.269664 -287.824926) (xy 169.270186 -287.799671)
			(xy 169.278499 -287.749849) (xy 169.2949 -287.702075) (xy 169.318941 -287.657652) (xy 169.349965 -287.617792)
			(xy 169.387127 -287.583582) (xy 169.429413 -287.555956) (xy 169.475669 -287.535666) (xy 169.524634 -287.523266)
			(xy 169.574972 -287.519095) (xy 169.62531 -287.523266) (xy 169.674275 -287.535666) (xy 169.720531 -287.555956)
			(xy 169.762817 -287.583582) (xy 169.799979 -287.617792) (xy 169.831003 -287.657652) (xy 169.855044 -287.702075)
			(xy 169.871445 -287.749849) (xy 169.879758 -287.799671) (xy 169.88028 -287.824926) (xy 169.87976 -287.850504)
			(xy 169.871238 -287.900944) (xy 169.854435 -287.949262) (xy 169.829821 -287.994106) (xy 169.798083 -288.034226)
			(xy 169.779442 -288.051748) (xy 169.772603 -288.058357) (xy 169.764096 -288.075357) (xy 169.762369 -288.094288)
			(xy 169.767658 -288.112547) (xy 169.779237 -288.127623) (xy 169.795514 -288.137443) (xy 169.81425 -288.140658)
			(xy 169.823638 -288.139124) (xy 169.826432 -288.138616) (xy 169.846573 -288.133621) (xy 169.887725 -288.128272)
			(xy 169.908474 -288.127948) (xy 170.19143 -288.127948) (xy 170.212178 -288.128277) (xy 170.253328 -288.133632)
			(xy 170.273472 -288.138616) (xy 170.276266 -288.139124) (xy 170.285626 -288.140734) (xy 170.30433 -288.137468)
			(xy 170.320568 -288.127627) (xy 170.332118 -288.112558) (xy 170.337402 -288.094321) (xy 170.335695 -288.075411)
			(xy 170.327233 -288.058414) (xy 170.320462 -288.051748) (xy 170.301841 -288.034205) (xy 170.270097 -287.994093)
			(xy 170.245477 -287.949254) (xy 170.22867 -287.900941) (xy 170.220145 -287.850503) (xy 170.219624 -287.824926)
			(xy 170.220146 -287.799671) (xy 170.228459 -287.749849) (xy 170.24486 -287.702075) (xy 170.268901 -287.657652)
			(xy 170.299925 -287.617792) (xy 170.337087 -287.583582) (xy 170.379373 -287.555956) (xy 170.425629 -287.535666)
			(xy 170.474594 -287.523266) (xy 170.524932 -287.519095) (xy 170.57527 -287.523266) (xy 170.624235 -287.535666)
			(xy 170.670491 -287.555956) (xy 170.712777 -287.583582) (xy 170.749939 -287.617792) (xy 170.780963 -287.657652)
			(xy 170.805004 -287.702075) (xy 170.821405 -287.749849) (xy 170.829718 -287.799671) (xy 170.83024 -287.824926)
			(xy 170.829701 -287.850503) (xy 170.82118 -287.900941) (xy 170.80438 -287.949258) (xy 170.779771 -287.994102)
			(xy 170.74804 -288.034224) (xy 170.729402 -288.051748) (xy 170.722595 -288.058382) (xy 170.714101 -288.075374)
			(xy 170.712378 -288.094292) (xy 170.717664 -288.112538) (xy 170.729232 -288.127606) (xy 170.745494 -288.137426)
			(xy 170.764215 -288.14065) (xy 170.773598 -288.139124) (xy 170.776392 -288.138616) (xy 170.796535 -288.133628)
			(xy 170.837685 -288.128274) (xy 170.858434 -288.127948) (xy 171.14139 -288.127948) (xy 171.162138 -288.128285)
			(xy 171.203288 -288.133634) (xy 171.223432 -288.138616) (xy 171.226226 -288.139124) (xy 171.235592 -288.140706)
			(xy 171.254297 -288.137451) (xy 171.270538 -288.127617) (xy 171.282092 -288.11255) (xy 171.287375 -288.094313)
			(xy 171.285665 -288.075404) (xy 171.277196 -288.058411) (xy 171.270422 -288.051748) (xy 171.251793 -288.034213)
			(xy 171.220051 -287.994099) (xy 171.195434 -287.949257) (xy 171.178628 -287.900942) (xy 171.170104 -287.850503)
			(xy 171.169584 -287.824926) (xy 171.170106 -287.799671) (xy 171.178419 -287.749849) (xy 171.19482 -287.702075)
			(xy 171.218861 -287.657652) (xy 171.249885 -287.617792) (xy 171.287047 -287.583582) (xy 171.329333 -287.555956)
			(xy 171.375589 -287.535666) (xy 171.424554 -287.523266) (xy 171.474892 -287.519095) (xy 171.52523 -287.523266)
			(xy 171.574195 -287.535666) (xy 171.620451 -287.555956) (xy 171.662737 -287.583582) (xy 171.699899 -287.617792)
			(xy 171.730923 -287.657652) (xy 171.754964 -287.702075) (xy 171.771365 -287.749849) (xy 171.779678 -287.799671)
			(xy 171.7802 -287.824926) (xy 171.779674 -287.850503) (xy 171.771152 -287.900943) (xy 171.75435 -287.94926)
			(xy 171.729737 -287.994105) (xy 171.698002 -288.034226) (xy 171.679362 -288.051748) (xy 171.672586 -288.058407)
			(xy 171.664104 -288.07539) (xy 171.662386 -288.094296) (xy 171.667669 -288.112531) (xy 171.679227 -288.127591)
			(xy 171.695473 -288.13741) (xy 171.71418 -288.140642) (xy 171.723558 -288.139124) (xy 171.726352 -288.138616)
			(xy 171.746492 -288.133617) (xy 171.787645 -288.12827) (xy 171.808394 -288.127948) (xy 172.09135 -288.127948)
			(xy 172.112098 -288.128292) (xy 172.153248 -288.133637) (xy 172.173392 -288.138616) (xy 172.176186 -288.139124)
			(xy 172.185557 -288.140678) (xy 172.204265 -288.137434) (xy 172.22051 -288.127607) (xy 172.232066 -288.112542)
			(xy 172.237349 -288.094305) (xy 172.235635 -288.075397) (xy 172.227159 -288.058407) (xy 172.220382 -288.051748)
			(xy 172.201765 -288.034201) (xy 172.170019 -287.994091) (xy 172.145398 -287.949253) (xy 172.12859 -287.90094)
			(xy 172.120065 -287.850503) (xy 172.119544 -287.824926) (xy 172.120066 -287.799671) (xy 172.128379 -287.749849)
			(xy 172.14478 -287.702075) (xy 172.168821 -287.657652) (xy 172.199845 -287.617792) (xy 172.237007 -287.583582)
			(xy 172.279293 -287.555956) (xy 172.325549 -287.535666) (xy 172.374514 -287.523266) (xy 172.424852 -287.519095)
			(xy 172.47519 -287.523266) (xy 172.524155 -287.535666) (xy 172.570411 -287.555956) (xy 172.612697 -287.583582)
			(xy 172.649859 -287.617792) (xy 172.680883 -287.657652) (xy 172.704924 -287.702075) (xy 172.721325 -287.749849)
			(xy 172.729638 -287.799671) (xy 172.73016 -287.824926) (xy 172.729614 -287.850502) (xy 172.721094 -287.90094)
			(xy 172.704296 -287.949256) (xy 172.679688 -287.994101) (xy 172.647958 -288.034224) (xy 172.629322 -288.051748)
			(xy 172.622499 -288.058369) (xy 172.613998 -288.075365) (xy 172.612273 -288.09429) (xy 172.617561 -288.112543)
			(xy 172.629135 -288.127615) (xy 172.645404 -288.137435) (xy 172.664132 -288.140654) (xy 172.673518 -288.139124)
			(xy 172.676312 -288.138616) (xy 172.696454 -288.133624) (xy 172.737605 -288.128273) (xy 172.758354 -288.127948)
			(xy 173.041564 -288.127948) (xy 173.062312 -288.12829) (xy 173.103462 -288.133636) (xy 173.123606 -288.138616)
			(xy 173.1264 -288.139124) (xy 173.135769 -288.140688) (xy 173.154476 -288.13744) (xy 173.17072 -288.12761)
			(xy 173.182275 -288.112545) (xy 173.187558 -288.094308) (xy 173.185845 -288.075399) (xy 173.177372 -288.058408)
			(xy 173.170596 -288.051748) (xy 173.151982 -288.034199) (xy 173.120235 -287.994089) (xy 173.095613 -287.949252)
			(xy 173.078805 -287.90094) (xy 173.070279 -287.850502) (xy 173.069758 -287.824926) (xy 173.07028 -287.799671)
			(xy 173.078593 -287.749849) (xy 173.094994 -287.702075) (xy 173.119035 -287.657652) (xy 173.150059 -287.617792)
			(xy 173.187221 -287.583582) (xy 173.229507 -287.555956) (xy 173.275763 -287.535666) (xy 173.324728 -287.523266)
			(xy 173.375066 -287.519095) (xy 173.425404 -287.523266) (xy 173.474369 -287.535666) (xy 173.520625 -287.555956)
			(xy 173.562911 -287.583582) (xy 173.600073 -287.617792) (xy 173.631097 -287.657652) (xy 173.653992 -287.699958)
			(xy 174.044114 -287.699958) (xy 174.048074 -287.650904) (xy 174.059851 -287.60312) (xy 174.079142 -287.557844)
			(xy 174.105445 -287.516248) (xy 174.13808 -287.479411) (xy 174.176201 -287.448286) (xy 174.218822 -287.423679)
			(xy 174.264838 -287.406227) (xy 174.313057 -287.396383) (xy 174.362232 -287.394402) (xy 174.411087 -287.400334)
			(xy 174.458358 -287.414026) (xy 174.50282 -287.435124) (xy 174.543323 -287.46308) (xy 174.578816 -287.497172)
			(xy 174.608381 -287.536516) (xy 174.631252 -287.580093) (xy 174.646836 -287.626774) (xy 174.654731 -287.675351)
			(xy 174.655226 -287.699958) (xy 174.654731 -287.724565) (xy 174.646836 -287.773142) (xy 174.631252 -287.819823)
			(xy 174.608381 -287.8634) (xy 174.578816 -287.902744) (xy 174.543323 -287.936836) (xy 174.50282 -287.964792)
			(xy 174.458358 -287.98589) (xy 174.411087 -287.999582) (xy 174.362232 -288.005514) (xy 174.313057 -288.003533)
			(xy 174.264838 -287.993689) (xy 174.218822 -287.976237) (xy 174.176201 -287.95163) (xy 174.13808 -287.920505)
			(xy 174.105445 -287.883668) (xy 174.079142 -287.842072) (xy 174.059851 -287.796796) (xy 174.048074 -287.749012)
			(xy 174.044114 -287.699958) (xy 173.653992 -287.699958) (xy 173.655138 -287.702075) (xy 173.671539 -287.749849)
			(xy 173.679852 -287.799671) (xy 173.680374 -287.824926) (xy 173.679824 -287.850502) (xy 173.671304 -287.90094)
			(xy 173.654506 -287.949255) (xy 173.6299 -287.9941) (xy 173.598172 -288.034223) (xy 173.579536 -288.051748)
			(xy 173.572702 -288.058361) (xy 173.564197 -288.075359) (xy 173.56247 -288.094288) (xy 173.567759 -288.112545)
			(xy 173.579337 -288.12762) (xy 173.595611 -288.137441) (xy 173.614344 -288.140656) (xy 173.623732 -288.139124)
			(xy 173.626526 -288.138616) (xy 173.646668 -288.133622) (xy 173.687819 -288.128272) (xy 173.708568 -288.127948)
			(xy 173.99127 -288.127948) (xy 174.015627 -288.128381) (xy 174.06378 -288.135756) (xy 174.110269 -288.150312)
			(xy 174.154029 -288.171715) (xy 174.19406 -288.199475) (xy 174.229444 -288.232957) (xy 174.244762 -288.2519)
			(xy 174.252396 -288.26068) (xy 174.273276 -288.270879) (xy 174.284894 -288.271458) (xy 174.365158 -288.271458)
			(xy 174.376795 -288.270953) (xy 174.397704 -288.260741) (xy 174.40529 -288.2519) (xy 174.42059 -288.232941)
			(xy 174.455967 -288.199446) (xy 174.495998 -288.17168) (xy 174.539765 -288.150282) (xy 174.586262 -288.135742)
			(xy 174.634423 -288.128393) (xy 174.658782 -288.127948) (xy 175.89119 -288.127948) (xy 175.913034 -288.12871)
			(xy 175.92294 -288.128456) (xy 175.932842 -288.126687) (xy 175.950266 -288.116676) (xy 175.962531 -288.100758)
			(xy 175.967767 -288.081357) (xy 175.965177 -288.061429) (xy 175.960532 -288.05251) (xy 175.947722 -288.029171)
			(xy 175.929512 -287.979148) (xy 175.92024 -287.926727) (xy 175.919638 -287.90011) (xy 175.919638 -287.899856)
			(xy 175.92016 -287.874601) (xy 175.928473 -287.824779) (xy 175.944874 -287.777005) (xy 175.968915 -287.732582)
			(xy 175.999939 -287.692722) (xy 176.037101 -287.658512) (xy 176.079387 -287.630886) (xy 176.125643 -287.610596)
			(xy 176.174608 -287.598196) (xy 176.224946 -287.594025) (xy 176.275284 -287.598196) (xy 176.324249 -287.610596)
			(xy 176.370505 -287.630886) (xy 176.412791 -287.658512) (xy 176.449953 -287.692722) (xy 176.480977 -287.732582)
			(xy 176.505018 -287.777005) (xy 176.521419 -287.824779) (xy 176.529732 -287.874601) (xy 176.530254 -287.899856)
			(xy 176.530254 -287.90011) (xy 176.529706 -287.926732) (xy 176.520447 -287.979165) (xy 176.502212 -288.029189)
			(xy 176.48936 -288.05251) (xy 176.484672 -288.061435) (xy 176.481997 -288.0814) (xy 176.487213 -288.100855)
			(xy 176.499516 -288.116804) (xy 176.51701 -288.126788) (xy 176.526952 -288.128456) (xy 176.536858 -288.12871)
			(xy 176.558702 -288.127948) (xy 176.841404 -288.127948) (xy 176.862152 -288.128282) (xy 176.903302 -288.133633)
			(xy 176.923446 -288.138616) (xy 176.92624 -288.139124) (xy 176.935604 -288.140716) (xy 176.954309 -288.137457)
			(xy 176.970549 -288.127621) (xy 176.982101 -288.112553) (xy 176.987385 -288.094316) (xy 176.985676 -288.075406)
			(xy 176.977209 -288.058412) (xy 176.970436 -288.051748) (xy 176.95181 -288.034211) (xy 176.920067 -287.994097)
			(xy 176.895449 -287.949256) (xy 176.878643 -287.900942) (xy 176.870118 -287.850503) (xy 176.869598 -287.824926)
			(xy 176.87012 -287.799671) (xy 176.878433 -287.749849) (xy 176.894834 -287.702075) (xy 176.918875 -287.657652)
			(xy 176.949899 -287.617792) (xy 176.987061 -287.583582) (xy 177.029347 -287.555956) (xy 177.075603 -287.535666)
			(xy 177.124568 -287.523266) (xy 177.174906 -287.519095) (xy 177.225244 -287.523266) (xy 177.274209 -287.535666)
			(xy 177.320465 -287.555956) (xy 177.362751 -287.583582) (xy 177.399913 -287.617792) (xy 177.430937 -287.657652)
			(xy 177.454978 -287.702075) (xy 177.471379 -287.749849) (xy 177.479692 -287.799671) (xy 177.480214 -287.824926)
			(xy 177.479683 -287.850503) (xy 177.471162 -287.900943) (xy 177.454361 -287.949259) (xy 177.429749 -287.994104)
			(xy 177.398015 -288.034225) (xy 177.379376 -288.051748) (xy 177.372589 -288.058398) (xy 177.364103 -288.075385)
			(xy 177.362384 -288.094295) (xy 177.367667 -288.112533) (xy 177.379228 -288.127596) (xy 177.395481 -288.137416)
			(xy 177.414192 -288.140645) (xy 177.423572 -288.139124) (xy 177.426366 -288.138616) (xy 177.446506 -288.133614)
			(xy 177.487659 -288.128269) (xy 177.508408 -288.127948) (xy 177.791364 -288.127948) (xy 177.812112 -288.12829)
			(xy 177.853262 -288.133636) (xy 177.873406 -288.138616) (xy 177.8762 -288.139124) (xy 177.885569 -288.140688)
			(xy 177.904276 -288.13744) (xy 177.92052 -288.12761) (xy 177.932075 -288.112545) (xy 177.937358 -288.094308)
			(xy 177.935645 -288.075399) (xy 177.927172 -288.058408) (xy 177.920396 -288.051748) (xy 177.901782 -288.034199)
			(xy 177.870035 -287.994089) (xy 177.845413 -287.949252) (xy 177.828605 -287.90094) (xy 177.820079 -287.850502)
			(xy 177.819558 -287.824926) (xy 177.82008 -287.799671) (xy 177.828393 -287.749849) (xy 177.844794 -287.702075)
			(xy 177.868835 -287.657652) (xy 177.899859 -287.617792) (xy 177.937021 -287.583582) (xy 177.979307 -287.555956)
			(xy 178.025563 -287.535666) (xy 178.074528 -287.523266) (xy 178.124866 -287.519095) (xy 178.175204 -287.523266)
			(xy 178.224169 -287.535666) (xy 178.270425 -287.555956) (xy 178.312711 -287.583582) (xy 178.349873 -287.617792)
			(xy 178.380897 -287.657652) (xy 178.404938 -287.702075) (xy 178.421339 -287.749849) (xy 178.429652 -287.799671)
			(xy 178.430174 -287.824926) (xy 178.429624 -287.850502) (xy 178.421104 -287.90094) (xy 178.404306 -287.949255)
			(xy 178.3797 -287.9941) (xy 178.347972 -288.034223) (xy 178.329336 -288.051748) (xy 178.322502 -288.058361)
			(xy 178.313997 -288.075359) (xy 178.31227 -288.094288) (xy 178.317559 -288.112545) (xy 178.329137 -288.12762)
			(xy 178.345411 -288.137441) (xy 178.364144 -288.140656) (xy 178.373532 -288.139124) (xy 178.376326 -288.138616)
			(xy 178.396468 -288.133622) (xy 178.437619 -288.128272) (xy 178.458368 -288.127948) (xy 178.741578 -288.127948)
			(xy 178.762326 -288.128287) (xy 178.803476 -288.133635) (xy 178.82362 -288.138616) (xy 178.826414 -288.139124)
			(xy 178.835781 -288.140698) (xy 178.854487 -288.137446) (xy 178.87073 -288.127614) (xy 178.882284 -288.112547)
			(xy 178.887567 -288.094311) (xy 178.885856 -288.075402) (xy 178.877385 -288.05841) (xy 178.87061 -288.051748)
			(xy 178.851979 -288.034216) (xy 178.820238 -287.9941) (xy 178.795621 -287.949258) (xy 178.778816 -287.900943)
			(xy 178.770292 -287.850503) (xy 178.769772 -287.824926) (xy 178.770294 -287.799671) (xy 178.778607 -287.749849)
			(xy 178.795008 -287.702075) (xy 178.819049 -287.657652) (xy 178.850073 -287.617792) (xy 178.887235 -287.583582)
			(xy 178.929521 -287.555956) (xy 178.975777 -287.535666) (xy 179.024742 -287.523266) (xy 179.07508 -287.519095)
			(xy 179.125418 -287.523266) (xy 179.174383 -287.535666) (xy 179.220639 -287.555956) (xy 179.262925 -287.583582)
			(xy 179.300087 -287.617792) (xy 179.331111 -287.657652) (xy 179.355152 -287.702075) (xy 179.371553 -287.749849)
			(xy 179.379866 -287.799671) (xy 179.380388 -287.824926) (xy 179.379866 -287.850504) (xy 179.371343 -287.900944)
			(xy 179.354541 -287.949261) (xy 179.329927 -287.994106) (xy 179.29819 -288.034226) (xy 179.27955 -288.051748)
			(xy 179.272705 -288.058352) (xy 179.264196 -288.075354) (xy 179.262467 -288.094287) (xy 179.267757 -288.112548)
			(xy 179.279339 -288.127626) (xy 179.295618 -288.137446) (xy 179.314357 -288.140659) (xy 179.323746 -288.139124)
			(xy 179.32654 -288.138616) (xy 179.346681 -288.133619) (xy 179.387833 -288.128271) (xy 179.408582 -288.127948)
			(xy 179.691538 -288.127948) (xy 179.712286 -288.128276) (xy 179.753437 -288.133631) (xy 179.77358 -288.138616)
			(xy 179.776374 -288.139124) (xy 179.785747 -288.14067) (xy 179.804455 -288.13743) (xy 179.820701 -288.127604)
			(xy 179.832258 -288.11254) (xy 179.837541 -288.094303) (xy 179.835826 -288.075394) (xy 179.827348 -288.058406)
			(xy 179.82057 -288.051748) (xy 179.801951 -288.034204) (xy 179.770206 -287.994093) (xy 179.745585 -287.949254)
			(xy 179.728778 -287.900941) (xy 179.720253 -287.850503) (xy 179.719732 -287.824926) (xy 179.720254 -287.799671)
			(xy 179.728567 -287.749849) (xy 179.744968 -287.702075) (xy 179.769009 -287.657652) (xy 179.800033 -287.617792)
			(xy 179.837195 -287.583582) (xy 179.879481 -287.555956) (xy 179.925737 -287.535666) (xy 179.974702 -287.523266)
			(xy 180.02504 -287.519095) (xy 180.075378 -287.523266) (xy 180.124343 -287.535666) (xy 180.170599 -287.555956)
			(xy 180.212885 -287.583582) (xy 180.250047 -287.617792) (xy 180.281071 -287.657652) (xy 180.305112 -287.702075)
			(xy 180.321513 -287.749849) (xy 180.329826 -287.799671) (xy 180.330348 -287.824926) (xy 180.329806 -287.850503)
			(xy 180.321285 -287.900941) (xy 180.304487 -287.949257) (xy 180.279878 -287.994102) (xy 180.248147 -288.034224)
			(xy 180.22951 -288.051748) (xy 180.222697 -288.058377) (xy 180.2142 -288.07537) (xy 180.212476 -288.094291)
			(xy 180.217763 -288.11254) (xy 180.229333 -288.12761) (xy 180.245598 -288.13743) (xy 180.264322 -288.140651)
			(xy 180.273706 -288.139124) (xy 180.2765 -288.138616) (xy 180.296643 -288.133627) (xy 180.337793 -288.128274)
			(xy 180.358542 -288.127948) (xy 180.641498 -288.127948) (xy 180.662246 -288.128283) (xy 180.703396 -288.133634)
			(xy 180.72354 -288.138616) (xy 180.726334 -288.139124) (xy 180.735699 -288.140712) (xy 180.754404 -288.137455)
			(xy 180.770645 -288.127619) (xy 180.782197 -288.112552) (xy 180.787481 -288.094315) (xy 180.785771 -288.075405)
			(xy 180.777303 -288.058411) (xy 180.77053 -288.051748) (xy 180.751903 -288.034212) (xy 180.72016 -287.994098)
			(xy 180.695542 -287.949257) (xy 180.678736 -287.900942) (xy 180.670212 -287.850503) (xy 180.669692 -287.824926)
			(xy 180.670214 -287.799671) (xy 180.678527 -287.749849) (xy 180.694928 -287.702075) (xy 180.718969 -287.657652)
			(xy 180.749993 -287.617792) (xy 180.787155 -287.583582) (xy 180.829441 -287.555956) (xy 180.875697 -287.535666)
			(xy 180.924662 -287.523266) (xy 180.975 -287.519095) (xy 181.025338 -287.523266) (xy 181.074303 -287.535666)
			(xy 181.120559 -287.555956) (xy 181.162845 -287.583582) (xy 181.200007 -287.617792) (xy 181.231031 -287.657652)
			(xy 181.255072 -287.702075) (xy 181.271473 -287.749849) (xy 181.279786 -287.799671) (xy 181.280308 -287.824926)
			(xy 181.279779 -287.850503) (xy 181.271257 -287.900943) (xy 181.254456 -287.94926) (xy 181.229844 -287.994105)
			(xy 181.198109 -288.034225) (xy 181.17947 -288.051748) (xy 181.172688 -288.058402) (xy 181.164203 -288.075387)
			(xy 181.162485 -288.094296) (xy 181.167768 -288.112532) (xy 181.179328 -288.127594) (xy 181.195577 -288.137414)
			(xy 181.214287 -288.140644) (xy 181.223666 -288.139124) (xy 181.22646 -288.138616) (xy 181.2466 -288.133615)
			(xy 181.287753 -288.12827) (xy 181.308502 -288.127948) (xy 181.591458 -288.127948) (xy 181.612206 -288.128291)
			(xy 181.653356 -288.133636) (xy 181.6735 -288.138616) (xy 181.676294 -288.139124) (xy 181.685664 -288.140684)
			(xy 181.704371 -288.137438) (xy 181.720615 -288.127609) (xy 181.732171 -288.112544) (xy 181.737454 -288.094307)
			(xy 181.735741 -288.075398) (xy 181.727266 -288.058408) (xy 181.72049 -288.051748) (xy 181.701875 -288.0342)
			(xy 181.670128 -287.99409) (xy 181.645507 -287.949253) (xy 181.628698 -287.90094) (xy 181.620173 -287.850502)
			(xy 181.619652 -287.824926) (xy 181.620174 -287.799671) (xy 181.628487 -287.749849) (xy 181.644888 -287.702075)
			(xy 181.668929 -287.657652) (xy 181.699953 -287.617792) (xy 181.737115 -287.583582) (xy 181.779401 -287.555956)
			(xy 181.825657 -287.535666) (xy 181.874622 -287.523266) (xy 181.92496 -287.519095) (xy 181.975298 -287.523266)
			(xy 182.024263 -287.535666) (xy 182.070519 -287.555956) (xy 182.112805 -287.583582) (xy 182.149967 -287.617792)
			(xy 182.180991 -287.657652) (xy 182.205032 -287.702075) (xy 182.221433 -287.749849) (xy 182.229746 -287.799671)
			(xy 182.230268 -287.824926) (xy 182.22972 -287.850502) (xy 182.2212 -287.90094) (xy 182.204402 -287.949256)
			(xy 182.179795 -287.994101) (xy 182.148066 -288.034223) (xy 182.12943 -288.051748) (xy 182.122601 -288.058364)
			(xy 182.114097 -288.075362) (xy 182.112372 -288.094289) (xy 182.11766 -288.112544) (xy 182.129236 -288.127618)
			(xy 182.145508 -288.137438) (xy 182.164239 -288.140655) (xy 182.173626 -288.139124) (xy 182.17642 -288.138616)
			(xy 182.196562 -288.133623) (xy 182.237713 -288.128272) (xy 182.258462 -288.127948) (xy 182.541418 -288.127948)
			(xy 182.562166 -288.128279) (xy 182.603316 -288.133632) (xy 182.62346 -288.138616) (xy 182.626254 -288.139124)
			(xy 182.635616 -288.140725) (xy 182.65432 -288.137463) (xy 182.670559 -288.127624) (xy 182.68211 -288.112555)
			(xy 182.687394 -288.094318) (xy 182.685686 -288.075409) (xy 182.677222 -288.058413) (xy 182.67045 -288.051748)
			(xy 182.651827 -288.034208) (xy 182.620083 -287.994095) (xy 182.595464 -287.949255) (xy 182.578657 -287.900941)
			(xy 182.570132 -287.850503) (xy 182.569612 -287.824926) (xy 182.570134 -287.799671) (xy 182.578447 -287.749849)
			(xy 182.594848 -287.702075) (xy 182.618889 -287.657652) (xy 182.649913 -287.617792) (xy 182.687075 -287.583582)
			(xy 182.729361 -287.555956) (xy 182.775617 -287.535666) (xy 182.824582 -287.523266) (xy 182.87492 -287.519095)
			(xy 182.925258 -287.523266) (xy 182.974223 -287.535666) (xy 183.020479 -287.555956) (xy 183.062765 -287.583582)
			(xy 183.099927 -287.617792) (xy 183.130951 -287.657652) (xy 183.154992 -287.702075) (xy 183.171393 -287.749849)
			(xy 183.179706 -287.799671) (xy 183.180228 -287.824926) (xy 183.179693 -287.850503) (xy 183.171171 -287.900942)
			(xy 183.154371 -287.949258) (xy 183.129761 -287.994103) (xy 183.098028 -288.034225) (xy 183.07939 -288.051748)
			(xy 183.072592 -288.058389) (xy 183.064102 -288.075379) (xy 183.062381 -288.094293) (xy 183.067665 -288.112536)
			(xy 183.07923 -288.127602) (xy 183.095488 -288.137422) (xy 183.114204 -288.140647) (xy 183.123586 -288.139124)
			(xy 183.12638 -288.138616) (xy 183.146523 -288.13363) (xy 183.187673 -288.128275) (xy 183.208422 -288.127948)
			(xy 183.491378 -288.127948) (xy 183.512126 -288.128287) (xy 183.553276 -288.133635) (xy 183.57342 -288.138616)
			(xy 183.576214 -288.139124) (xy 183.585581 -288.140698) (xy 183.604287 -288.137446) (xy 183.62053 -288.127614)
			(xy 183.632084 -288.112547) (xy 183.637367 -288.094311) (xy 183.635656 -288.075402) (xy 183.627185 -288.05841)
			(xy 183.62041 -288.051748) (xy 183.601779 -288.034216) (xy 183.570038 -287.9941) (xy 183.545421 -287.949258)
			(xy 183.528616 -287.900943) (xy 183.520092 -287.850503) (xy 183.519572 -287.824926) (xy 183.520094 -287.799671)
			(xy 183.528407 -287.749849) (xy 183.544808 -287.702075) (xy 183.568849 -287.657652) (xy 183.599873 -287.617792)
			(xy 183.637035 -287.583582) (xy 183.679321 -287.555956) (xy 183.725577 -287.535666) (xy 183.774542 -287.523266)
			(xy 183.82488 -287.519095) (xy 183.875218 -287.523266) (xy 183.924183 -287.535666) (xy 183.970439 -287.555956)
			(xy 184.012725 -287.583582) (xy 184.049887 -287.617792) (xy 184.080911 -287.657652) (xy 184.104952 -287.702075)
			(xy 184.121353 -287.749849) (xy 184.129666 -287.799671) (xy 184.130188 -287.824926) (xy 184.129666 -287.850504)
			(xy 184.121143 -287.900944) (xy 184.104341 -287.949261) (xy 184.079727 -287.994106) (xy 184.04799 -288.034226)
			(xy 184.02935 -288.051748) (xy 184.022505 -288.058352) (xy 184.013996 -288.075354) (xy 184.012267 -288.094287)
			(xy 184.017557 -288.112548) (xy 184.029139 -288.127626) (xy 184.045418 -288.137446) (xy 184.064157 -288.140659)
			(xy 184.073546 -288.139124) (xy 184.07634 -288.138616) (xy 184.096481 -288.133619) (xy 184.137633 -288.128271)
			(xy 184.158382 -288.127948) (xy 184.441338 -288.127948) (xy 184.462086 -288.128276) (xy 184.503237 -288.133631)
			(xy 184.52338 -288.138616) (xy 184.532882 -288.140763) (xy 184.55221 -288.138426) (xy 184.569274 -288.129054)
			(xy 184.581616 -288.113998) (xy 184.587459 -288.095427) (xy 184.585959 -288.076016) (xy 184.577334 -288.058563)
			(xy 184.57037 -288.051748) (xy 184.551751 -288.034204) (xy 184.520006 -287.994093) (xy 184.495385 -287.949254)
			(xy 184.478578 -287.900941) (xy 184.470053 -287.850503) (xy 184.469532 -287.824926) (xy 184.470054 -287.799671)
			(xy 184.478367 -287.749849) (xy 184.494768 -287.702075) (xy 184.518809 -287.657652) (xy 184.549833 -287.617792)
			(xy 184.586995 -287.583582) (xy 184.629281 -287.555956) (xy 184.675537 -287.535666) (xy 184.724502 -287.523266)
			(xy 184.77484 -287.519095) (xy 184.825178 -287.523266) (xy 184.874143 -287.535666) (xy 184.920399 -287.555956)
			(xy 184.962685 -287.583582) (xy 184.999847 -287.617792) (xy 185.030871 -287.657652) (xy 185.054912 -287.702075)
			(xy 185.071313 -287.749849) (xy 185.079626 -287.799671) (xy 185.080148 -287.824926) (xy 186.36921 -287.824926)
			(xy 186.37317 -287.775872) (xy 186.384947 -287.728088) (xy 186.404238 -287.682812) (xy 186.430541 -287.641216)
			(xy 186.463176 -287.604379) (xy 186.501297 -287.573254) (xy 186.543918 -287.548647) (xy 186.589934 -287.531195)
			(xy 186.638153 -287.521351) (xy 186.687328 -287.51937) (xy 186.736183 -287.525302) (xy 186.783454 -287.538994)
			(xy 186.827916 -287.560092) (xy 186.868419 -287.588048) (xy 186.903912 -287.62214) (xy 186.933477 -287.661484)
			(xy 186.956348 -287.705061) (xy 186.971932 -287.751742) (xy 186.979827 -287.800319) (xy 186.980322 -287.824926)
			(xy 186.979827 -287.849533) (xy 186.971932 -287.89811) (xy 186.956348 -287.944791) (xy 186.933477 -287.988368)
			(xy 186.903912 -288.027712) (xy 186.868419 -288.061804) (xy 186.827916 -288.08976) (xy 186.783454 -288.110858)
			(xy 186.736183 -288.12455) (xy 186.687328 -288.130482) (xy 186.638153 -288.128501) (xy 186.589934 -288.118657)
			(xy 186.543918 -288.101205) (xy 186.501297 -288.076598) (xy 186.463176 -288.045473) (xy 186.430541 -288.008636)
			(xy 186.404238 -287.96704) (xy 186.384947 -287.921764) (xy 186.37317 -287.87398) (xy 186.36921 -287.824926)
			(xy 185.080148 -287.824926) (xy 185.079606 -287.850503) (xy 185.071085 -287.900941) (xy 185.054287 -287.949257)
			(xy 185.029678 -287.994102) (xy 184.997947 -288.034224) (xy 184.97931 -288.051748) (xy 184.97234 -288.058518)
			(xy 184.96381 -288.075966) (xy 184.962367 -288.095334) (xy 184.968216 -288.113854) (xy 184.980522 -288.128879)
			(xy 184.997526 -288.138263) (xy 185.016798 -288.140665) (xy 185.0263 -288.138616) (xy 185.046443 -288.133627)
			(xy 185.087593 -288.128274) (xy 185.108342 -288.127948) (xy 186.145678 -288.127948) (xy 186.150569 -288.128082)
			(xy 186.160161 -288.130003) (xy 186.164728 -288.131758) (xy 186.266328 -288.172652) (xy 186.271289 -288.174788)
			(xy 186.280257 -288.180803) (xy 186.284108 -288.18459) (xy 186.321446 -288.223452) (xy 186.321954 -288.22396)
			(xy 186.536838 -288.438844) (xy 186.556396 -288.46018) (xy 186.562699 -288.467079) (xy 186.579009 -288.476169)
			(xy 186.597489 -288.478843) (xy 186.606688 -288.477198) (xy 186.623476 -288.473611) (xy 186.657594 -288.469795)
			(xy 186.67476 -288.469578) (xy 186.675014 -288.469578) (xy 186.699005 -288.47005) (xy 186.746396 -288.477557)
			(xy 186.792029 -288.492386) (xy 186.834781 -288.51417) (xy 186.873598 -288.542373) (xy 186.907527 -288.576302)
			(xy 186.93573 -288.615119) (xy 186.957514 -288.657871) (xy 186.972343 -288.703504) (xy 186.97985 -288.750895)
			(xy 186.980322 -288.774886) (xy 187.31917 -288.774886) (xy 187.32313 -288.725832) (xy 187.334907 -288.678048)
			(xy 187.354198 -288.632772) (xy 187.380501 -288.591176) (xy 187.413136 -288.554339) (xy 187.451257 -288.523214)
			(xy 187.493878 -288.498607) (xy 187.539894 -288.481155) (xy 187.588113 -288.471311) (xy 187.637288 -288.46933)
			(xy 187.686143 -288.475262) (xy 187.733414 -288.488954) (xy 187.777876 -288.510052) (xy 187.818379 -288.538008)
			(xy 187.853872 -288.5721) (xy 187.883437 -288.611444) (xy 187.906308 -288.655021) (xy 187.921892 -288.701702)
			(xy 187.929787 -288.750279) (xy 187.930282 -288.774886) (xy 188.26913 -288.774886) (xy 188.27309 -288.725832)
			(xy 188.284867 -288.678048) (xy 188.304158 -288.632772) (xy 188.330461 -288.591176) (xy 188.363096 -288.554339)
			(xy 188.401217 -288.523214) (xy 188.443838 -288.498607) (xy 188.489854 -288.481155) (xy 188.538073 -288.471311)
			(xy 188.587248 -288.46933) (xy 188.636103 -288.475262) (xy 188.683374 -288.488954) (xy 188.727836 -288.510052)
			(xy 188.768339 -288.538008) (xy 188.803832 -288.5721) (xy 188.833397 -288.611444) (xy 188.856268 -288.655021)
			(xy 188.871852 -288.701702) (xy 188.879747 -288.750279) (xy 188.880242 -288.774886) (xy 188.879747 -288.799493)
			(xy 188.871852 -288.84807) (xy 188.856268 -288.894751) (xy 188.833397 -288.938328) (xy 188.803832 -288.977672)
			(xy 188.768339 -289.011764) (xy 188.727836 -289.03972) (xy 188.683374 -289.060818) (xy 188.636103 -289.07451)
			(xy 188.587248 -289.080442) (xy 188.538073 -289.078461) (xy 188.489854 -289.068617) (xy 188.443838 -289.051165)
			(xy 188.401217 -289.026558) (xy 188.363096 -288.995433) (xy 188.330461 -288.958596) (xy 188.304158 -288.917)
			(xy 188.284867 -288.871724) (xy 188.27309 -288.82394) (xy 188.26913 -288.774886) (xy 187.930282 -288.774886)
			(xy 187.929787 -288.799493) (xy 187.921892 -288.84807) (xy 187.906308 -288.894751) (xy 187.883437 -288.938328)
			(xy 187.853872 -288.977672) (xy 187.818379 -289.011764) (xy 187.777876 -289.03972) (xy 187.733414 -289.060818)
			(xy 187.686143 -289.07451) (xy 187.637288 -289.080442) (xy 187.588113 -289.078461) (xy 187.539894 -289.068617)
			(xy 187.493878 -289.051165) (xy 187.451257 -289.026558) (xy 187.413136 -288.995433) (xy 187.380501 -288.958596)
			(xy 187.354198 -288.917) (xy 187.334907 -288.871724) (xy 187.32313 -288.82394) (xy 187.31917 -288.774886)
			(xy 186.980322 -288.774886) (xy 186.979895 -288.797814) (xy 186.972959 -288.843145) (xy 186.959343 -288.886935)
			(xy 186.939352 -288.928207) (xy 186.926728 -288.947352) (xy 186.920831 -288.957005) (xy 186.917198 -288.979298)
			(xy 186.923492 -289.00099) (xy 186.930538 -289.009836) (xy 186.937396 -289.017202) (xy 186.943209 -289.024414)
			(xy 186.949736 -289.041729) (xy 186.950096 -289.050984) (xy 186.950096 -289.448748) (xy 186.949722 -289.458)
			(xy 186.943206 -289.475319) (xy 186.937396 -289.48253) (xy 186.930538 -289.489896) (xy 186.92354 -289.498766)
			(xy 186.917283 -289.520447) (xy 186.920855 -289.542728) (xy 186.926728 -289.55238) (xy 186.941123 -289.57428)
			(xy 186.962906 -289.621943) (xy 186.976234 -289.672625) (xy 186.980716 -289.724838) (xy 186.980715 -289.724846)
			(xy 187.31917 -289.724846) (xy 187.32313 -289.675792) (xy 187.334907 -289.628008) (xy 187.354198 -289.582732)
			(xy 187.380501 -289.541136) (xy 187.413136 -289.504299) (xy 187.451257 -289.473174) (xy 187.493878 -289.448567)
			(xy 187.539894 -289.431115) (xy 187.588113 -289.421271) (xy 187.637288 -289.41929) (xy 187.686143 -289.425222)
			(xy 187.733414 -289.438914) (xy 187.777876 -289.460012) (xy 187.818379 -289.487968) (xy 187.853872 -289.52206)
			(xy 187.883437 -289.561404) (xy 187.906308 -289.604981) (xy 187.921892 -289.651662) (xy 187.929787 -289.700239)
			(xy 187.930282 -289.724846) (xy 188.26913 -289.724846) (xy 188.27309 -289.675792) (xy 188.284867 -289.628008)
			(xy 188.304158 -289.582732) (xy 188.330461 -289.541136) (xy 188.363096 -289.504299) (xy 188.401217 -289.473174)
			(xy 188.443838 -289.448567) (xy 188.489854 -289.431115) (xy 188.538073 -289.421271) (xy 188.587248 -289.41929)
			(xy 188.636103 -289.425222) (xy 188.683374 -289.438914) (xy 188.727836 -289.460012) (xy 188.768339 -289.487968)
			(xy 188.803832 -289.52206) (xy 188.833397 -289.561404) (xy 188.856268 -289.604981) (xy 188.871852 -289.651662)
			(xy 188.879747 -289.700239) (xy 188.880242 -289.724846) (xy 188.879747 -289.749453) (xy 188.871852 -289.79803)
			(xy 188.856268 -289.844711) (xy 188.833397 -289.888288) (xy 188.803832 -289.927632) (xy 188.768339 -289.961724)
			(xy 188.727836 -289.98968) (xy 188.683374 -290.010778) (xy 188.636103 -290.02447) (xy 188.587248 -290.030402)
			(xy 188.538073 -290.028421) (xy 188.489854 -290.018577) (xy 188.443838 -290.001125) (xy 188.401217 -289.976518)
			(xy 188.363096 -289.945393) (xy 188.330461 -289.908556) (xy 188.304158 -289.86696) (xy 188.284867 -289.821684)
			(xy 188.27309 -289.7739) (xy 188.26913 -289.724846) (xy 187.930282 -289.724846) (xy 187.929787 -289.749453)
			(xy 187.921892 -289.79803) (xy 187.906308 -289.844711) (xy 187.883437 -289.888288) (xy 187.853872 -289.927632)
			(xy 187.818379 -289.961724) (xy 187.777876 -289.98968) (xy 187.733414 -290.010778) (xy 187.686143 -290.02447)
			(xy 187.637288 -290.030402) (xy 187.588113 -290.028421) (xy 187.539894 -290.018577) (xy 187.493878 -290.001125)
			(xy 187.451257 -289.976518) (xy 187.413136 -289.945393) (xy 187.380501 -289.908556) (xy 187.354198 -289.86696)
			(xy 187.334907 -289.821684) (xy 187.32313 -289.7739) (xy 187.31917 -289.724846) (xy 186.980715 -289.724846)
			(xy 186.976221 -289.77705) (xy 186.96288 -289.827729) (xy 186.941086 -289.875387) (xy 186.926728 -289.897312)
			(xy 186.920775 -289.906936) (xy 186.91716 -289.929248) (xy 186.923479 -289.95095) (xy 186.930538 -289.959796)
			(xy 186.937396 -289.967162) (xy 186.943235 -289.974356) (xy 186.949746 -289.991685) (xy 186.950096 -290.000944)
			(xy 186.950096 -290.398708) (xy 186.949703 -290.407958) (xy 186.9432 -290.425277) (xy 186.937396 -290.43249)
			(xy 186.930538 -290.439856) (xy 186.923575 -290.44875) (xy 186.917308 -290.470417) (xy 186.920864 -290.492689)
			(xy 186.926728 -290.50234) (xy 186.941087 -290.524262) (xy 186.962873 -290.57192) (xy 186.976206 -290.622596)
			(xy 186.980693 -290.674805) (xy 186.980693 -290.674806) (xy 187.31917 -290.674806) (xy 187.32313 -290.625752)
			(xy 187.334907 -290.577968) (xy 187.354198 -290.532692) (xy 187.380501 -290.491096) (xy 187.413136 -290.454259)
			(xy 187.451257 -290.423134) (xy 187.493878 -290.398527) (xy 187.539894 -290.381075) (xy 187.588113 -290.371231)
			(xy 187.637288 -290.36925) (xy 187.686143 -290.375182) (xy 187.733414 -290.388874) (xy 187.777876 -290.409972)
			(xy 187.818379 -290.437928) (xy 187.853872 -290.47202) (xy 187.883437 -290.511364) (xy 187.906308 -290.554941)
			(xy 187.921892 -290.601622) (xy 187.929787 -290.650199) (xy 187.930282 -290.674806) (xy 188.26913 -290.674806)
			(xy 188.27309 -290.625752) (xy 188.284867 -290.577968) (xy 188.304158 -290.532692) (xy 188.330461 -290.491096)
			(xy 188.363096 -290.454259) (xy 188.401217 -290.423134) (xy 188.443838 -290.398527) (xy 188.489854 -290.381075)
			(xy 188.538073 -290.371231) (xy 188.587248 -290.36925) (xy 188.636103 -290.375182) (xy 188.683374 -290.388874)
			(xy 188.727836 -290.409972) (xy 188.768339 -290.437928) (xy 188.803832 -290.47202) (xy 188.833397 -290.511364)
			(xy 188.856268 -290.554941) (xy 188.871852 -290.601622) (xy 188.879747 -290.650199) (xy 188.880242 -290.674806)
			(xy 189.21909 -290.674806) (xy 189.22305 -290.625752) (xy 189.234827 -290.577968) (xy 189.254118 -290.532692)
			(xy 189.280421 -290.491096) (xy 189.313056 -290.454259) (xy 189.351177 -290.423134) (xy 189.393798 -290.398527)
			(xy 189.439814 -290.381075) (xy 189.488033 -290.371231) (xy 189.537208 -290.36925) (xy 189.586063 -290.375182)
			(xy 189.633334 -290.388874) (xy 189.677796 -290.409972) (xy 189.718299 -290.437928) (xy 189.753792 -290.47202)
			(xy 189.783357 -290.511364) (xy 189.806228 -290.554941) (xy 189.821812 -290.601622) (xy 189.829707 -290.650199)
			(xy 189.830202 -290.674806) (xy 190.16905 -290.674806) (xy 190.17301 -290.625752) (xy 190.184787 -290.577968)
			(xy 190.204078 -290.532692) (xy 190.230381 -290.491096) (xy 190.263016 -290.454259) (xy 190.301137 -290.423134)
			(xy 190.343758 -290.398527) (xy 190.389774 -290.381075) (xy 190.437993 -290.371231) (xy 190.487168 -290.36925)
			(xy 190.536023 -290.375182) (xy 190.583294 -290.388874) (xy 190.627756 -290.409972) (xy 190.668259 -290.437928)
			(xy 190.703752 -290.47202) (xy 190.733317 -290.511364) (xy 190.756188 -290.554941) (xy 190.771772 -290.601622)
			(xy 190.779667 -290.650199) (xy 190.780162 -290.674806) (xy 191.119264 -290.674806) (xy 191.123224 -290.625752)
			(xy 191.135001 -290.577968) (xy 191.154292 -290.532692) (xy 191.180595 -290.491096) (xy 191.21323 -290.454259)
			(xy 191.251351 -290.423134) (xy 191.293972 -290.398527) (xy 191.339988 -290.381075) (xy 191.388207 -290.371231)
			(xy 191.437382 -290.36925) (xy 191.486237 -290.375182) (xy 191.533508 -290.388874) (xy 191.57797 -290.409972)
			(xy 191.618473 -290.437928) (xy 191.653966 -290.47202) (xy 191.683531 -290.511364) (xy 191.706402 -290.554941)
			(xy 191.721986 -290.601622) (xy 191.729881 -290.650199) (xy 191.730376 -290.674806) (xy 192.069224 -290.674806)
			(xy 192.073184 -290.625752) (xy 192.084961 -290.577968) (xy 192.104252 -290.532692) (xy 192.130555 -290.491096)
			(xy 192.16319 -290.454259) (xy 192.201311 -290.423134) (xy 192.243932 -290.398527) (xy 192.289948 -290.381075)
			(xy 192.338167 -290.371231) (xy 192.387342 -290.36925) (xy 192.436197 -290.375182) (xy 192.483468 -290.388874)
			(xy 192.52793 -290.409972) (xy 192.568433 -290.437928) (xy 192.603926 -290.47202) (xy 192.633491 -290.511364)
			(xy 192.656362 -290.554941) (xy 192.671946 -290.601622) (xy 192.679841 -290.650199) (xy 192.680336 -290.674806)
			(xy 192.679841 -290.699413) (xy 192.671946 -290.74799) (xy 192.656362 -290.794671) (xy 192.633491 -290.838248)
			(xy 192.603926 -290.877592) (xy 192.568433 -290.911684) (xy 192.52793 -290.93964) (xy 192.483468 -290.960738)
			(xy 192.436197 -290.97443) (xy 192.387342 -290.980362) (xy 192.338167 -290.978381) (xy 192.289948 -290.968537)
			(xy 192.243932 -290.951085) (xy 192.201311 -290.926478) (xy 192.16319 -290.895353) (xy 192.130555 -290.858516)
			(xy 192.104252 -290.81692) (xy 192.084961 -290.771644) (xy 192.073184 -290.72386) (xy 192.069224 -290.674806)
			(xy 191.730376 -290.674806) (xy 191.729881 -290.699413) (xy 191.721986 -290.74799) (xy 191.706402 -290.794671)
			(xy 191.683531 -290.838248) (xy 191.653966 -290.877592) (xy 191.618473 -290.911684) (xy 191.57797 -290.93964)
			(xy 191.533508 -290.960738) (xy 191.486237 -290.97443) (xy 191.437382 -290.980362) (xy 191.388207 -290.978381)
			(xy 191.339988 -290.968537) (xy 191.293972 -290.951085) (xy 191.251351 -290.926478) (xy 191.21323 -290.895353)
			(xy 191.180595 -290.858516) (xy 191.154292 -290.81692) (xy 191.135001 -290.771644) (xy 191.123224 -290.72386)
			(xy 191.119264 -290.674806) (xy 190.780162 -290.674806) (xy 190.779667 -290.699413) (xy 190.771772 -290.74799)
			(xy 190.756188 -290.794671) (xy 190.733317 -290.838248) (xy 190.703752 -290.877592) (xy 190.668259 -290.911684)
			(xy 190.627756 -290.93964) (xy 190.583294 -290.960738) (xy 190.536023 -290.97443) (xy 190.487168 -290.980362)
			(xy 190.437993 -290.978381) (xy 190.389774 -290.968537) (xy 190.343758 -290.951085) (xy 190.301137 -290.926478)
			(xy 190.263016 -290.895353) (xy 190.230381 -290.858516) (xy 190.204078 -290.81692) (xy 190.184787 -290.771644)
			(xy 190.17301 -290.72386) (xy 190.16905 -290.674806) (xy 189.830202 -290.674806) (xy 189.829707 -290.699413)
			(xy 189.821812 -290.74799) (xy 189.806228 -290.794671) (xy 189.783357 -290.838248) (xy 189.753792 -290.877592)
			(xy 189.718299 -290.911684) (xy 189.677796 -290.93964) (xy 189.633334 -290.960738) (xy 189.586063 -290.97443)
			(xy 189.537208 -290.980362) (xy 189.488033 -290.978381) (xy 189.439814 -290.968537) (xy 189.393798 -290.951085)
			(xy 189.351177 -290.926478) (xy 189.313056 -290.895353) (xy 189.280421 -290.858516) (xy 189.254118 -290.81692)
			(xy 189.234827 -290.771644) (xy 189.22305 -290.72386) (xy 189.21909 -290.674806) (xy 188.880242 -290.674806)
			(xy 188.879747 -290.699413) (xy 188.871852 -290.74799) (xy 188.856268 -290.794671) (xy 188.833397 -290.838248)
			(xy 188.803832 -290.877592) (xy 188.768339 -290.911684) (xy 188.727836 -290.93964) (xy 188.683374 -290.960738)
			(xy 188.636103 -290.97443) (xy 188.587248 -290.980362) (xy 188.538073 -290.978381) (xy 188.489854 -290.968537)
			(xy 188.443838 -290.951085) (xy 188.401217 -290.926478) (xy 188.363096 -290.895353) (xy 188.330461 -290.858516)
			(xy 188.304158 -290.81692) (xy 188.284867 -290.771644) (xy 188.27309 -290.72386) (xy 188.26913 -290.674806)
			(xy 187.930282 -290.674806) (xy 187.929787 -290.699413) (xy 187.921892 -290.74799) (xy 187.906308 -290.794671)
			(xy 187.883437 -290.838248) (xy 187.853872 -290.877592) (xy 187.818379 -290.911684) (xy 187.777876 -290.93964)
			(xy 187.733414 -290.960738) (xy 187.686143 -290.97443) (xy 187.637288 -290.980362) (xy 187.588113 -290.978381)
			(xy 187.539894 -290.968537) (xy 187.493878 -290.951085) (xy 187.451257 -290.926478) (xy 187.413136 -290.895353)
			(xy 187.380501 -290.858516) (xy 187.354198 -290.81692) (xy 187.334907 -290.771644) (xy 187.32313 -290.72386)
			(xy 187.31917 -290.674806) (xy 186.980693 -290.674806) (xy 186.976204 -290.727014) (xy 186.96287 -290.77769)
			(xy 186.941082 -290.825347) (xy 186.926728 -290.847272) (xy 186.920812 -290.856915) (xy 186.917185 -290.879214)
			(xy 186.923487 -290.90091) (xy 186.930538 -290.909756) (xy 186.937396 -290.917122) (xy 186.943218 -290.924328)
			(xy 186.949739 -290.941648) (xy 186.950096 -290.950904) (xy 186.950096 -291.348668) (xy 186.949732 -291.357921)
			(xy 186.943209 -291.37524) (xy 186.937396 -291.38245) (xy 186.930538 -291.389816) (xy 186.923523 -291.398675)
			(xy 186.917271 -291.420363) (xy 186.92085 -291.442648) (xy 186.926728 -291.4523) (xy 186.941051 -291.474244)
			(xy 186.962841 -291.521896) (xy 186.976178 -291.572568) (xy 186.98067 -291.624766) (xy 187.31917 -291.624766)
			(xy 187.32313 -291.575712) (xy 187.334907 -291.527928) (xy 187.354198 -291.482652) (xy 187.380501 -291.441056)
			(xy 187.413136 -291.404219) (xy 187.451257 -291.373094) (xy 187.493878 -291.348487) (xy 187.539894 -291.331035)
			(xy 187.588113 -291.321191) (xy 187.637288 -291.31921) (xy 187.686143 -291.325142) (xy 187.733414 -291.338834)
			(xy 187.777876 -291.359932) (xy 187.818379 -291.387888) (xy 187.853872 -291.42198) (xy 187.883437 -291.461324)
			(xy 187.906308 -291.504901) (xy 187.921892 -291.551582) (xy 187.929787 -291.600159) (xy 187.930282 -291.624766)
			(xy 188.26913 -291.624766) (xy 188.27309 -291.575712) (xy 188.284867 -291.527928) (xy 188.304158 -291.482652)
			(xy 188.330461 -291.441056) (xy 188.363096 -291.404219) (xy 188.401217 -291.373094) (xy 188.443838 -291.348487)
			(xy 188.489854 -291.331035) (xy 188.538073 -291.321191) (xy 188.587248 -291.31921) (xy 188.636103 -291.325142)
			(xy 188.683374 -291.338834) (xy 188.727836 -291.359932) (xy 188.768339 -291.387888) (xy 188.803832 -291.42198)
			(xy 188.833397 -291.461324) (xy 188.856268 -291.504901) (xy 188.871852 -291.551582) (xy 188.879747 -291.600159)
			(xy 188.880242 -291.624766) (xy 189.21909 -291.624766) (xy 189.22305 -291.575712) (xy 189.234827 -291.527928)
			(xy 189.254118 -291.482652) (xy 189.280421 -291.441056) (xy 189.313056 -291.404219) (xy 189.351177 -291.373094)
			(xy 189.393798 -291.348487) (xy 189.439814 -291.331035) (xy 189.488033 -291.321191) (xy 189.537208 -291.31921)
			(xy 189.586063 -291.325142) (xy 189.633334 -291.338834) (xy 189.677796 -291.359932) (xy 189.718299 -291.387888)
			(xy 189.753792 -291.42198) (xy 189.783357 -291.461324) (xy 189.806228 -291.504901) (xy 189.821812 -291.551582)
			(xy 189.829707 -291.600159) (xy 189.830202 -291.624766) (xy 190.169304 -291.624766) (xy 190.173264 -291.575712)
			(xy 190.185041 -291.527928) (xy 190.204332 -291.482652) (xy 190.230635 -291.441056) (xy 190.26327 -291.404219)
			(xy 190.301391 -291.373094) (xy 190.344012 -291.348487) (xy 190.390028 -291.331035) (xy 190.438247 -291.321191)
			(xy 190.487422 -291.31921) (xy 190.536277 -291.325142) (xy 190.583548 -291.338834) (xy 190.62801 -291.359932)
			(xy 190.668513 -291.387888) (xy 190.704006 -291.42198) (xy 190.733571 -291.461324) (xy 190.756442 -291.504901)
			(xy 190.772026 -291.551582) (xy 190.779921 -291.600159) (xy 190.780416 -291.624766) (xy 192.069224 -291.624766)
			(xy 192.073184 -291.575712) (xy 192.084961 -291.527928) (xy 192.104252 -291.482652) (xy 192.130555 -291.441056)
			(xy 192.16319 -291.404219) (xy 192.201311 -291.373094) (xy 192.243932 -291.348487) (xy 192.289948 -291.331035)
			(xy 192.338167 -291.321191) (xy 192.387342 -291.31921) (xy 192.436197 -291.325142) (xy 192.483468 -291.338834)
			(xy 192.52793 -291.359932) (xy 192.568433 -291.387888) (xy 192.603926 -291.42198) (xy 192.633491 -291.461324)
			(xy 192.656362 -291.504901) (xy 192.671946 -291.551582) (xy 192.679841 -291.600159) (xy 192.680336 -291.624766)
			(xy 192.679841 -291.649373) (xy 192.671946 -291.69795) (xy 192.656362 -291.744631) (xy 192.633491 -291.788208)
			(xy 192.603926 -291.827552) (xy 192.568433 -291.861644) (xy 192.52793 -291.8896) (xy 192.483468 -291.910698)
			(xy 192.436197 -291.92439) (xy 192.387342 -291.930322) (xy 192.338167 -291.928341) (xy 192.289948 -291.918497)
			(xy 192.243932 -291.901045) (xy 192.201311 -291.876438) (xy 192.16319 -291.845313) (xy 192.130555 -291.808476)
			(xy 192.104252 -291.76688) (xy 192.084961 -291.721604) (xy 192.073184 -291.67382) (xy 192.069224 -291.624766)
			(xy 190.780416 -291.624766) (xy 190.779921 -291.649373) (xy 190.772026 -291.69795) (xy 190.756442 -291.744631)
			(xy 190.733571 -291.788208) (xy 190.704006 -291.827552) (xy 190.668513 -291.861644) (xy 190.62801 -291.8896)
			(xy 190.583548 -291.910698) (xy 190.536277 -291.92439) (xy 190.487422 -291.930322) (xy 190.438247 -291.928341)
			(xy 190.390028 -291.918497) (xy 190.344012 -291.901045) (xy 190.301391 -291.876438) (xy 190.26327 -291.845313)
			(xy 190.230635 -291.808476) (xy 190.204332 -291.76688) (xy 190.185041 -291.721604) (xy 190.173264 -291.67382)
			(xy 190.169304 -291.624766) (xy 189.830202 -291.624766) (xy 189.829707 -291.649373) (xy 189.821812 -291.69795)
			(xy 189.806228 -291.744631) (xy 189.783357 -291.788208) (xy 189.753792 -291.827552) (xy 189.718299 -291.861644)
			(xy 189.677796 -291.8896) (xy 189.633334 -291.910698) (xy 189.586063 -291.92439) (xy 189.537208 -291.930322)
			(xy 189.488033 -291.928341) (xy 189.439814 -291.918497) (xy 189.393798 -291.901045) (xy 189.351177 -291.876438)
			(xy 189.313056 -291.845313) (xy 189.280421 -291.808476) (xy 189.254118 -291.76688) (xy 189.234827 -291.721604)
			(xy 189.22305 -291.67382) (xy 189.21909 -291.624766) (xy 188.880242 -291.624766) (xy 188.879747 -291.649373)
			(xy 188.871852 -291.69795) (xy 188.856268 -291.744631) (xy 188.833397 -291.788208) (xy 188.803832 -291.827552)
			(xy 188.768339 -291.861644) (xy 188.727836 -291.8896) (xy 188.683374 -291.910698) (xy 188.636103 -291.92439)
			(xy 188.587248 -291.930322) (xy 188.538073 -291.928341) (xy 188.489854 -291.918497) (xy 188.443838 -291.901045)
			(xy 188.401217 -291.876438) (xy 188.363096 -291.845313) (xy 188.330461 -291.808476) (xy 188.304158 -291.76688)
			(xy 188.284867 -291.721604) (xy 188.27309 -291.67382) (xy 188.26913 -291.624766) (xy 187.930282 -291.624766)
			(xy 187.929787 -291.649373) (xy 187.921892 -291.69795) (xy 187.906308 -291.744631) (xy 187.883437 -291.788208)
			(xy 187.853872 -291.827552) (xy 187.818379 -291.861644) (xy 187.777876 -291.8896) (xy 187.733414 -291.910698)
			(xy 187.686143 -291.92439) (xy 187.637288 -291.930322) (xy 187.588113 -291.928341) (xy 187.539894 -291.918497)
			(xy 187.493878 -291.901045) (xy 187.451257 -291.876438) (xy 187.413136 -291.845313) (xy 187.380501 -291.808476)
			(xy 187.354198 -291.76688) (xy 187.334907 -291.721604) (xy 187.32313 -291.67382) (xy 187.31917 -291.624766)
			(xy 186.98067 -291.624766) (xy 186.980671 -291.624772) (xy 186.976187 -291.676977) (xy 186.96286 -291.727651)
			(xy 186.941079 -291.775307) (xy 186.926728 -291.797232) (xy 186.920849 -291.806895) (xy 186.91721 -291.829181)
			(xy 186.923496 -291.85087) (xy 186.930538 -291.859716) (xy 186.937396 -291.867082) (xy 186.943244 -291.87427)
			(xy 186.949749 -291.891604) (xy 186.950096 -291.900864) (xy 186.950096 -292.298882) (xy 186.949739 -292.308136)
			(xy 186.943211 -292.325455) (xy 186.937396 -292.332664) (xy 186.930538 -292.34003) (xy 186.923511 -292.34888)
			(xy 186.917262 -292.370573) (xy 186.920847 -292.392861) (xy 186.926728 -292.402514) (xy 186.941064 -292.42445)
			(xy 186.962852 -292.472104) (xy 186.976188 -292.522778) (xy 186.980656 -292.574726) (xy 187.31917 -292.574726)
			(xy 187.32313 -292.525672) (xy 187.334907 -292.477888) (xy 187.354198 -292.432612) (xy 187.380501 -292.391016)
			(xy 187.413136 -292.354179) (xy 187.451257 -292.323054) (xy 187.493878 -292.298447) (xy 187.539894 -292.280995)
			(xy 187.588113 -292.271151) (xy 187.637288 -292.26917) (xy 187.686143 -292.275102) (xy 187.733414 -292.288794)
			(xy 187.777876 -292.309892) (xy 187.818379 -292.337848) (xy 187.853872 -292.37194) (xy 187.883437 -292.411284)
			(xy 187.906308 -292.454861) (xy 187.921892 -292.501542) (xy 187.929787 -292.550119) (xy 187.930282 -292.574726)
			(xy 188.26913 -292.574726) (xy 188.27309 -292.525672) (xy 188.284867 -292.477888) (xy 188.304158 -292.432612)
			(xy 188.330461 -292.391016) (xy 188.363096 -292.354179) (xy 188.401217 -292.323054) (xy 188.443838 -292.298447)
			(xy 188.489854 -292.280995) (xy 188.538073 -292.271151) (xy 188.587248 -292.26917) (xy 188.636103 -292.275102)
			(xy 188.683374 -292.288794) (xy 188.727836 -292.309892) (xy 188.768339 -292.337848) (xy 188.803832 -292.37194)
			(xy 188.833397 -292.411284) (xy 188.856268 -292.454861) (xy 188.871852 -292.501542) (xy 188.879747 -292.550119)
			(xy 188.880242 -292.574726) (xy 189.21909 -292.574726) (xy 189.22305 -292.525672) (xy 189.234827 -292.477888)
			(xy 189.254118 -292.432612) (xy 189.280421 -292.391016) (xy 189.313056 -292.354179) (xy 189.351177 -292.323054)
			(xy 189.393798 -292.298447) (xy 189.439814 -292.280995) (xy 189.488033 -292.271151) (xy 189.537208 -292.26917)
			(xy 189.586063 -292.275102) (xy 189.633334 -292.288794) (xy 189.677796 -292.309892) (xy 189.718299 -292.337848)
			(xy 189.753792 -292.37194) (xy 189.783357 -292.411284) (xy 189.806228 -292.454861) (xy 189.821812 -292.501542)
			(xy 189.829707 -292.550119) (xy 189.830202 -292.574726) (xy 190.16905 -292.574726) (xy 190.17301 -292.525672)
			(xy 190.184787 -292.477888) (xy 190.204078 -292.432612) (xy 190.230381 -292.391016) (xy 190.263016 -292.354179)
			(xy 190.301137 -292.323054) (xy 190.343758 -292.298447) (xy 190.389774 -292.280995) (xy 190.437993 -292.271151)
			(xy 190.487168 -292.26917) (xy 190.536023 -292.275102) (xy 190.583294 -292.288794) (xy 190.627756 -292.309892)
			(xy 190.668259 -292.337848) (xy 190.703752 -292.37194) (xy 190.733317 -292.411284) (xy 190.756188 -292.454861)
			(xy 190.771772 -292.501542) (xy 190.779667 -292.550119) (xy 190.780162 -292.574726) (xy 191.119264 -292.574726)
			(xy 191.123224 -292.525672) (xy 191.135001 -292.477888) (xy 191.154292 -292.432612) (xy 191.180595 -292.391016)
			(xy 191.21323 -292.354179) (xy 191.251351 -292.323054) (xy 191.293972 -292.298447) (xy 191.339988 -292.280995)
			(xy 191.388207 -292.271151) (xy 191.437382 -292.26917) (xy 191.486237 -292.275102) (xy 191.533508 -292.288794)
			(xy 191.57797 -292.309892) (xy 191.618473 -292.337848) (xy 191.653966 -292.37194) (xy 191.683531 -292.411284)
			(xy 191.706402 -292.454861) (xy 191.721986 -292.501542) (xy 191.729881 -292.550119) (xy 191.730376 -292.574726)
			(xy 192.069224 -292.574726) (xy 192.073184 -292.525672) (xy 192.084961 -292.477888) (xy 192.104252 -292.432612)
			(xy 192.130555 -292.391016) (xy 192.16319 -292.354179) (xy 192.201311 -292.323054) (xy 192.243932 -292.298447)
			(xy 192.289948 -292.280995) (xy 192.338167 -292.271151) (xy 192.387342 -292.26917) (xy 192.436197 -292.275102)
			(xy 192.483468 -292.288794) (xy 192.52793 -292.309892) (xy 192.568433 -292.337848) (xy 192.603926 -292.37194)
			(xy 192.633491 -292.411284) (xy 192.656362 -292.454861) (xy 192.671946 -292.501542) (xy 192.679841 -292.550119)
			(xy 192.680336 -292.574726) (xy 192.679841 -292.599333) (xy 192.671946 -292.64791) (xy 192.656362 -292.694591)
			(xy 192.633491 -292.738168) (xy 192.603926 -292.777512) (xy 192.568433 -292.811604) (xy 192.52793 -292.83956)
			(xy 192.483468 -292.860658) (xy 192.436197 -292.87435) (xy 192.387342 -292.880282) (xy 192.338167 -292.878301)
			(xy 192.289948 -292.868457) (xy 192.243932 -292.851005) (xy 192.201311 -292.826398) (xy 192.16319 -292.795273)
			(xy 192.130555 -292.758436) (xy 192.104252 -292.71684) (xy 192.084961 -292.671564) (xy 192.073184 -292.62378)
			(xy 192.069224 -292.574726) (xy 191.730376 -292.574726) (xy 191.729881 -292.599333) (xy 191.721986 -292.64791)
			(xy 191.706402 -292.694591) (xy 191.683531 -292.738168) (xy 191.653966 -292.777512) (xy 191.618473 -292.811604)
			(xy 191.57797 -292.83956) (xy 191.533508 -292.860658) (xy 191.486237 -292.87435) (xy 191.437382 -292.880282)
			(xy 191.388207 -292.878301) (xy 191.339988 -292.868457) (xy 191.293972 -292.851005) (xy 191.251351 -292.826398)
			(xy 191.21323 -292.795273) (xy 191.180595 -292.758436) (xy 191.154292 -292.71684) (xy 191.135001 -292.671564)
			(xy 191.123224 -292.62378) (xy 191.119264 -292.574726) (xy 190.780162 -292.574726) (xy 190.779667 -292.599333)
			(xy 190.771772 -292.64791) (xy 190.756188 -292.694591) (xy 190.733317 -292.738168) (xy 190.703752 -292.777512)
			(xy 190.668259 -292.811604) (xy 190.627756 -292.83956) (xy 190.583294 -292.860658) (xy 190.536023 -292.87435)
			(xy 190.487168 -292.880282) (xy 190.437993 -292.878301) (xy 190.389774 -292.868457) (xy 190.343758 -292.851005)
			(xy 190.301137 -292.826398) (xy 190.263016 -292.795273) (xy 190.230381 -292.758436) (xy 190.204078 -292.71684)
			(xy 190.184787 -292.671564) (xy 190.17301 -292.62378) (xy 190.16905 -292.574726) (xy 189.830202 -292.574726)
			(xy 189.829707 -292.599333) (xy 189.821812 -292.64791) (xy 189.806228 -292.694591) (xy 189.783357 -292.738168)
			(xy 189.753792 -292.777512) (xy 189.718299 -292.811604) (xy 189.677796 -292.83956) (xy 189.633334 -292.860658)
			(xy 189.586063 -292.87435) (xy 189.537208 -292.880282) (xy 189.488033 -292.878301) (xy 189.439814 -292.868457)
			(xy 189.393798 -292.851005) (xy 189.351177 -292.826398) (xy 189.313056 -292.795273) (xy 189.280421 -292.758436)
			(xy 189.254118 -292.71684) (xy 189.234827 -292.671564) (xy 189.22305 -292.62378) (xy 189.21909 -292.574726)
			(xy 188.880242 -292.574726) (xy 188.879747 -292.599333) (xy 188.871852 -292.64791) (xy 188.856268 -292.694591)
			(xy 188.833397 -292.738168) (xy 188.803832 -292.777512) (xy 188.768339 -292.811604) (xy 188.727836 -292.83956)
			(xy 188.683374 -292.860658) (xy 188.636103 -292.87435) (xy 188.587248 -292.880282) (xy 188.538073 -292.878301)
			(xy 188.489854 -292.868457) (xy 188.443838 -292.851005) (xy 188.401217 -292.826398) (xy 188.363096 -292.795273)
			(xy 188.330461 -292.758436) (xy 188.304158 -292.71684) (xy 188.284867 -292.671564) (xy 188.27309 -292.62378)
			(xy 188.26913 -292.574726) (xy 187.930282 -292.574726) (xy 187.929787 -292.599333) (xy 187.921892 -292.64791)
			(xy 187.906308 -292.694591) (xy 187.883437 -292.738168) (xy 187.853872 -292.777512) (xy 187.818379 -292.811604)
			(xy 187.777876 -292.83956) (xy 187.733414 -292.860658) (xy 187.686143 -292.87435) (xy 187.637288 -292.880282)
			(xy 187.588113 -292.878301) (xy 187.539894 -292.868457) (xy 187.493878 -292.851005) (xy 187.451257 -292.826398)
			(xy 187.413136 -292.795273) (xy 187.380501 -292.758436) (xy 187.354198 -292.71684) (xy 187.334907 -292.671564)
			(xy 187.32313 -292.62378) (xy 187.31917 -292.574726) (xy 186.980656 -292.574726) (xy 186.980678 -292.574983)
			(xy 186.976193 -292.62719) (xy 186.962863 -292.677865) (xy 186.94108 -292.725521) (xy 186.926728 -292.747446)
			(xy 186.920836 -292.757102) (xy 186.917201 -292.779393) (xy 186.923493 -292.801084) (xy 186.930538 -292.80993)
			(xy 186.937396 -292.817296) (xy 186.943207 -292.82451) (xy 186.949734 -292.841824) (xy 186.950096 -292.851078)
			(xy 186.950096 -293.248842) (xy 186.949719 -293.258094) (xy 186.943205 -293.275413) (xy 186.937396 -293.282624)
			(xy 186.930538 -293.28999) (xy 186.923545 -293.298864) (xy 186.917287 -293.320543) (xy 186.920856 -293.342823)
			(xy 186.926728 -293.352474) (xy 186.941118 -293.374377) (xy 186.962901 -293.42204) (xy 186.976229 -293.472721)
			(xy 186.980712 -293.524933) (xy 186.980711 -293.52494) (xy 187.31917 -293.52494) (xy 187.32313 -293.475886)
			(xy 187.334907 -293.428102) (xy 187.354198 -293.382826) (xy 187.380501 -293.34123) (xy 187.413136 -293.304393)
			(xy 187.451257 -293.273268) (xy 187.493878 -293.248661) (xy 187.539894 -293.231209) (xy 187.588113 -293.221365)
			(xy 187.637288 -293.219384) (xy 187.686143 -293.225316) (xy 187.733414 -293.239008) (xy 187.777876 -293.260106)
			(xy 187.818379 -293.288062) (xy 187.853872 -293.322154) (xy 187.883437 -293.361498) (xy 187.906308 -293.405075)
			(xy 187.921892 -293.451756) (xy 187.929787 -293.500333) (xy 187.930282 -293.52494) (xy 188.26913 -293.52494)
			(xy 188.27309 -293.475886) (xy 188.284867 -293.428102) (xy 188.304158 -293.382826) (xy 188.330461 -293.34123)
			(xy 188.363096 -293.304393) (xy 188.401217 -293.273268) (xy 188.443838 -293.248661) (xy 188.489854 -293.231209)
			(xy 188.538073 -293.221365) (xy 188.587248 -293.219384) (xy 188.636103 -293.225316) (xy 188.683374 -293.239008)
			(xy 188.727836 -293.260106) (xy 188.768339 -293.288062) (xy 188.803832 -293.322154) (xy 188.833397 -293.361498)
			(xy 188.856268 -293.405075) (xy 188.871852 -293.451756) (xy 188.879747 -293.500333) (xy 188.880242 -293.52494)
			(xy 189.21909 -293.52494) (xy 189.22305 -293.475886) (xy 189.234827 -293.428102) (xy 189.254118 -293.382826)
			(xy 189.280421 -293.34123) (xy 189.313056 -293.304393) (xy 189.351177 -293.273268) (xy 189.393798 -293.248661)
			(xy 189.439814 -293.231209) (xy 189.488033 -293.221365) (xy 189.537208 -293.219384) (xy 189.586063 -293.225316)
			(xy 189.633334 -293.239008) (xy 189.677796 -293.260106) (xy 189.718299 -293.288062) (xy 189.753792 -293.322154)
			(xy 189.783357 -293.361498) (xy 189.806228 -293.405075) (xy 189.821812 -293.451756) (xy 189.829707 -293.500333)
			(xy 189.830202 -293.52494) (xy 190.169304 -293.52494) (xy 190.173264 -293.475886) (xy 190.185041 -293.428102)
			(xy 190.204332 -293.382826) (xy 190.230635 -293.34123) (xy 190.26327 -293.304393) (xy 190.301391 -293.273268)
			(xy 190.344012 -293.248661) (xy 190.390028 -293.231209) (xy 190.438247 -293.221365) (xy 190.487422 -293.219384)
			(xy 190.536277 -293.225316) (xy 190.583548 -293.239008) (xy 190.62801 -293.260106) (xy 190.668513 -293.288062)
			(xy 190.704006 -293.322154) (xy 190.733571 -293.361498) (xy 190.756442 -293.405075) (xy 190.772026 -293.451756)
			(xy 190.779921 -293.500333) (xy 190.780416 -293.52494) (xy 191.119264 -293.52494) (xy 191.123224 -293.475886)
			(xy 191.135001 -293.428102) (xy 191.154292 -293.382826) (xy 191.180595 -293.34123) (xy 191.21323 -293.304393)
			(xy 191.251351 -293.273268) (xy 191.293972 -293.248661) (xy 191.339988 -293.231209) (xy 191.388207 -293.221365)
			(xy 191.437382 -293.219384) (xy 191.486237 -293.225316) (xy 191.533508 -293.239008) (xy 191.57797 -293.260106)
			(xy 191.618473 -293.288062) (xy 191.653966 -293.322154) (xy 191.683531 -293.361498) (xy 191.706402 -293.405075)
			(xy 191.721986 -293.451756) (xy 191.729881 -293.500333) (xy 191.730376 -293.52494) (xy 192.069224 -293.52494)
			(xy 192.073184 -293.475886) (xy 192.084961 -293.428102) (xy 192.104252 -293.382826) (xy 192.130555 -293.34123)
			(xy 192.16319 -293.304393) (xy 192.201311 -293.273268) (xy 192.243932 -293.248661) (xy 192.289948 -293.231209)
			(xy 192.338167 -293.221365) (xy 192.387342 -293.219384) (xy 192.436197 -293.225316) (xy 192.483468 -293.239008)
			(xy 192.52793 -293.260106) (xy 192.568433 -293.288062) (xy 192.603926 -293.322154) (xy 192.633491 -293.361498)
			(xy 192.656362 -293.405075) (xy 192.671946 -293.451756) (xy 192.679841 -293.500333) (xy 192.680336 -293.52494)
			(xy 192.679841 -293.549547) (xy 192.671946 -293.598124) (xy 192.656362 -293.644805) (xy 192.633491 -293.688382)
			(xy 192.603926 -293.727726) (xy 192.568433 -293.761818) (xy 192.52793 -293.789774) (xy 192.483468 -293.810872)
			(xy 192.436197 -293.824564) (xy 192.387342 -293.830496) (xy 192.338167 -293.828515) (xy 192.289948 -293.818671)
			(xy 192.243932 -293.801219) (xy 192.201311 -293.776612) (xy 192.16319 -293.745487) (xy 192.130555 -293.70865)
			(xy 192.104252 -293.667054) (xy 192.084961 -293.621778) (xy 192.073184 -293.573994) (xy 192.069224 -293.52494)
			(xy 191.730376 -293.52494) (xy 191.729881 -293.549547) (xy 191.721986 -293.598124) (xy 191.706402 -293.644805)
			(xy 191.683531 -293.688382) (xy 191.653966 -293.727726) (xy 191.618473 -293.761818) (xy 191.57797 -293.789774)
			(xy 191.533508 -293.810872) (xy 191.486237 -293.824564) (xy 191.437382 -293.830496) (xy 191.388207 -293.828515)
			(xy 191.339988 -293.818671) (xy 191.293972 -293.801219) (xy 191.251351 -293.776612) (xy 191.21323 -293.745487)
			(xy 191.180595 -293.70865) (xy 191.154292 -293.667054) (xy 191.135001 -293.621778) (xy 191.123224 -293.573994)
			(xy 191.119264 -293.52494) (xy 190.780416 -293.52494) (xy 190.779921 -293.549547) (xy 190.772026 -293.598124)
			(xy 190.756442 -293.644805) (xy 190.733571 -293.688382) (xy 190.704006 -293.727726) (xy 190.668513 -293.761818)
			(xy 190.62801 -293.789774) (xy 190.583548 -293.810872) (xy 190.536277 -293.824564) (xy 190.487422 -293.830496)
			(xy 190.438247 -293.828515) (xy 190.390028 -293.818671) (xy 190.344012 -293.801219) (xy 190.301391 -293.776612)
			(xy 190.26327 -293.745487) (xy 190.230635 -293.70865) (xy 190.204332 -293.667054) (xy 190.185041 -293.621778)
			(xy 190.173264 -293.573994) (xy 190.169304 -293.52494) (xy 189.830202 -293.52494) (xy 189.829707 -293.549547)
			(xy 189.821812 -293.598124) (xy 189.806228 -293.644805) (xy 189.783357 -293.688382) (xy 189.753792 -293.727726)
			(xy 189.718299 -293.761818) (xy 189.677796 -293.789774) (xy 189.633334 -293.810872) (xy 189.586063 -293.824564)
			(xy 189.537208 -293.830496) (xy 189.488033 -293.828515) (xy 189.439814 -293.818671) (xy 189.393798 -293.801219)
			(xy 189.351177 -293.776612) (xy 189.313056 -293.745487) (xy 189.280421 -293.70865) (xy 189.254118 -293.667054)
			(xy 189.234827 -293.621778) (xy 189.22305 -293.573994) (xy 189.21909 -293.52494) (xy 188.880242 -293.52494)
			(xy 188.879747 -293.549547) (xy 188.871852 -293.598124) (xy 188.856268 -293.644805) (xy 188.833397 -293.688382)
			(xy 188.803832 -293.727726) (xy 188.768339 -293.761818) (xy 188.727836 -293.789774) (xy 188.683374 -293.810872)
			(xy 188.636103 -293.824564) (xy 188.587248 -293.830496) (xy 188.538073 -293.828515) (xy 188.489854 -293.818671)
			(xy 188.443838 -293.801219) (xy 188.401217 -293.776612) (xy 188.363096 -293.745487) (xy 188.330461 -293.70865)
			(xy 188.304158 -293.667054) (xy 188.284867 -293.621778) (xy 188.27309 -293.573994) (xy 188.26913 -293.52494)
			(xy 187.930282 -293.52494) (xy 187.929787 -293.549547) (xy 187.921892 -293.598124) (xy 187.906308 -293.644805)
			(xy 187.883437 -293.688382) (xy 187.853872 -293.727726) (xy 187.818379 -293.761818) (xy 187.777876 -293.789774)
			(xy 187.733414 -293.810872) (xy 187.686143 -293.824564) (xy 187.637288 -293.830496) (xy 187.588113 -293.828515)
			(xy 187.539894 -293.818671) (xy 187.493878 -293.801219) (xy 187.451257 -293.776612) (xy 187.413136 -293.745487)
			(xy 187.380501 -293.70865) (xy 187.354198 -293.667054) (xy 187.334907 -293.621778) (xy 187.32313 -293.573994)
			(xy 187.31917 -293.52494) (xy 186.980711 -293.52494) (xy 186.976218 -293.577144) (xy 186.962879 -293.627823)
			(xy 186.941085 -293.675481) (xy 186.926728 -293.697406) (xy 186.920781 -293.707032) (xy 186.917164 -293.729343)
			(xy 186.92348 -293.751044) (xy 186.930538 -293.75989) (xy 186.937396 -293.767256) (xy 186.943232 -293.774451)
			(xy 186.949745 -293.79178) (xy 186.950096 -293.801038) (xy 186.950096 -294.198802) (xy 186.9497 -294.208052)
			(xy 186.943199 -294.225371) (xy 186.937396 -294.232584) (xy 186.930538 -294.23995) (xy 186.923493 -294.248788)
			(xy 186.91725 -294.270488) (xy 186.920843 -294.292781) (xy 186.926728 -294.302434) (xy 186.941082 -294.324359)
			(xy 186.962868 -294.372016) (xy 186.976202 -294.422692) (xy 186.98069 -294.4749) (xy 187.31917 -294.4749)
			(xy 187.32313 -294.425846) (xy 187.334907 -294.378062) (xy 187.354198 -294.332786) (xy 187.380501 -294.29119)
			(xy 187.413136 -294.254353) (xy 187.451257 -294.223228) (xy 187.493878 -294.198621) (xy 187.539894 -294.181169)
			(xy 187.588113 -294.171325) (xy 187.637288 -294.169344) (xy 187.686143 -294.175276) (xy 187.733414 -294.188968)
			(xy 187.777876 -294.210066) (xy 187.818379 -294.238022) (xy 187.853872 -294.272114) (xy 187.883437 -294.311458)
			(xy 187.906308 -294.355035) (xy 187.921892 -294.401716) (xy 187.929787 -294.450293) (xy 187.930282 -294.4749)
			(xy 188.26913 -294.4749) (xy 188.27309 -294.425846) (xy 188.284867 -294.378062) (xy 188.304158 -294.332786)
			(xy 188.330461 -294.29119) (xy 188.363096 -294.254353) (xy 188.401217 -294.223228) (xy 188.443838 -294.198621)
			(xy 188.489854 -294.181169) (xy 188.538073 -294.171325) (xy 188.587248 -294.169344) (xy 188.636103 -294.175276)
			(xy 188.683374 -294.188968) (xy 188.727836 -294.210066) (xy 188.768339 -294.238022) (xy 188.803832 -294.272114)
			(xy 188.833397 -294.311458) (xy 188.856268 -294.355035) (xy 188.871852 -294.401716) (xy 188.879747 -294.450293)
			(xy 188.880242 -294.4749) (xy 189.21909 -294.4749) (xy 189.22305 -294.425846) (xy 189.234827 -294.378062)
			(xy 189.254118 -294.332786) (xy 189.280421 -294.29119) (xy 189.313056 -294.254353) (xy 189.351177 -294.223228)
			(xy 189.393798 -294.198621) (xy 189.439814 -294.181169) (xy 189.488033 -294.171325) (xy 189.537208 -294.169344)
			(xy 189.586063 -294.175276) (xy 189.633334 -294.188968) (xy 189.677796 -294.210066) (xy 189.718299 -294.238022)
			(xy 189.753792 -294.272114) (xy 189.783357 -294.311458) (xy 189.806228 -294.355035) (xy 189.821812 -294.401716)
			(xy 189.829707 -294.450293) (xy 189.830202 -294.4749) (xy 190.16905 -294.4749) (xy 190.17301 -294.425846)
			(xy 190.184787 -294.378062) (xy 190.204078 -294.332786) (xy 190.230381 -294.29119) (xy 190.263016 -294.254353)
			(xy 190.301137 -294.223228) (xy 190.343758 -294.198621) (xy 190.389774 -294.181169) (xy 190.437993 -294.171325)
			(xy 190.487168 -294.169344) (xy 190.536023 -294.175276) (xy 190.583294 -294.188968) (xy 190.627756 -294.210066)
			(xy 190.668259 -294.238022) (xy 190.703752 -294.272114) (xy 190.733317 -294.311458) (xy 190.756188 -294.355035)
			(xy 190.771772 -294.401716) (xy 190.779667 -294.450293) (xy 190.780162 -294.4749) (xy 191.119264 -294.4749)
			(xy 191.123224 -294.425846) (xy 191.135001 -294.378062) (xy 191.154292 -294.332786) (xy 191.180595 -294.29119)
			(xy 191.21323 -294.254353) (xy 191.251351 -294.223228) (xy 191.293972 -294.198621) (xy 191.339988 -294.181169)
			(xy 191.388207 -294.171325) (xy 191.437382 -294.169344) (xy 191.486237 -294.175276) (xy 191.533508 -294.188968)
			(xy 191.57797 -294.210066) (xy 191.618473 -294.238022) (xy 191.653966 -294.272114) (xy 191.683531 -294.311458)
			(xy 191.706402 -294.355035) (xy 191.721986 -294.401716) (xy 191.729881 -294.450293) (xy 191.730376 -294.4749)
			(xy 192.069224 -294.4749) (xy 192.073184 -294.425846) (xy 192.084961 -294.378062) (xy 192.104252 -294.332786)
			(xy 192.130555 -294.29119) (xy 192.16319 -294.254353) (xy 192.201311 -294.223228) (xy 192.243932 -294.198621)
			(xy 192.289948 -294.181169) (xy 192.338167 -294.171325) (xy 192.387342 -294.169344) (xy 192.436197 -294.175276)
			(xy 192.483468 -294.188968) (xy 192.52793 -294.210066) (xy 192.568433 -294.238022) (xy 192.603926 -294.272114)
			(xy 192.633491 -294.311458) (xy 192.656362 -294.355035) (xy 192.671946 -294.401716) (xy 192.679841 -294.450293)
			(xy 192.680336 -294.4749) (xy 192.679841 -294.499507) (xy 192.671946 -294.548084) (xy 192.656362 -294.594765)
			(xy 192.633491 -294.638342) (xy 192.603926 -294.677686) (xy 192.568433 -294.711778) (xy 192.52793 -294.739734)
			(xy 192.483468 -294.760832) (xy 192.436197 -294.774524) (xy 192.387342 -294.780456) (xy 192.338167 -294.778475)
			(xy 192.289948 -294.768631) (xy 192.243932 -294.751179) (xy 192.201311 -294.726572) (xy 192.16319 -294.695447)
			(xy 192.130555 -294.65861) (xy 192.104252 -294.617014) (xy 192.084961 -294.571738) (xy 192.073184 -294.523954)
			(xy 192.069224 -294.4749) (xy 191.730376 -294.4749) (xy 191.729881 -294.499507) (xy 191.721986 -294.548084)
			(xy 191.706402 -294.594765) (xy 191.683531 -294.638342) (xy 191.653966 -294.677686) (xy 191.618473 -294.711778)
			(xy 191.57797 -294.739734) (xy 191.533508 -294.760832) (xy 191.486237 -294.774524) (xy 191.437382 -294.780456)
			(xy 191.388207 -294.778475) (xy 191.339988 -294.768631) (xy 191.293972 -294.751179) (xy 191.251351 -294.726572)
			(xy 191.21323 -294.695447) (xy 191.180595 -294.65861) (xy 191.154292 -294.617014) (xy 191.135001 -294.571738)
			(xy 191.123224 -294.523954) (xy 191.119264 -294.4749) (xy 190.780162 -294.4749) (xy 190.779667 -294.499507)
			(xy 190.771772 -294.548084) (xy 190.756188 -294.594765) (xy 190.733317 -294.638342) (xy 190.703752 -294.677686)
			(xy 190.668259 -294.711778) (xy 190.627756 -294.739734) (xy 190.583294 -294.760832) (xy 190.536023 -294.774524)
			(xy 190.487168 -294.780456) (xy 190.437993 -294.778475) (xy 190.389774 -294.768631) (xy 190.343758 -294.751179)
			(xy 190.301137 -294.726572) (xy 190.263016 -294.695447) (xy 190.230381 -294.65861) (xy 190.204078 -294.617014)
			(xy 190.184787 -294.571738) (xy 190.17301 -294.523954) (xy 190.16905 -294.4749) (xy 189.830202 -294.4749)
			(xy 189.829707 -294.499507) (xy 189.821812 -294.548084) (xy 189.806228 -294.594765) (xy 189.783357 -294.638342)
			(xy 189.753792 -294.677686) (xy 189.718299 -294.711778) (xy 189.677796 -294.739734) (xy 189.633334 -294.760832)
			(xy 189.586063 -294.774524) (xy 189.537208 -294.780456) (xy 189.488033 -294.778475) (xy 189.439814 -294.768631)
			(xy 189.393798 -294.751179) (xy 189.351177 -294.726572) (xy 189.313056 -294.695447) (xy 189.280421 -294.65861)
			(xy 189.254118 -294.617014) (xy 189.234827 -294.571738) (xy 189.22305 -294.523954) (xy 189.21909 -294.4749)
			(xy 188.880242 -294.4749) (xy 188.879747 -294.499507) (xy 188.871852 -294.548084) (xy 188.856268 -294.594765)
			(xy 188.833397 -294.638342) (xy 188.803832 -294.677686) (xy 188.768339 -294.711778) (xy 188.727836 -294.739734)
			(xy 188.683374 -294.760832) (xy 188.636103 -294.774524) (xy 188.587248 -294.780456) (xy 188.538073 -294.778475)
			(xy 188.489854 -294.768631) (xy 188.443838 -294.751179) (xy 188.401217 -294.726572) (xy 188.363096 -294.695447)
			(xy 188.330461 -294.65861) (xy 188.304158 -294.617014) (xy 188.284867 -294.571738) (xy 188.27309 -294.523954)
			(xy 188.26913 -294.4749) (xy 187.930282 -294.4749) (xy 187.929787 -294.499507) (xy 187.921892 -294.548084)
			(xy 187.906308 -294.594765) (xy 187.883437 -294.638342) (xy 187.853872 -294.677686) (xy 187.818379 -294.711778)
			(xy 187.777876 -294.739734) (xy 187.733414 -294.760832) (xy 187.686143 -294.774524) (xy 187.637288 -294.780456)
			(xy 187.588113 -294.778475) (xy 187.539894 -294.768631) (xy 187.493878 -294.751179) (xy 187.451257 -294.726572)
			(xy 187.413136 -294.695447) (xy 187.380501 -294.65861) (xy 187.354198 -294.617014) (xy 187.334907 -294.571738)
			(xy 187.32313 -294.523954) (xy 187.31917 -294.4749) (xy 186.98069 -294.4749) (xy 186.976202 -294.527108)
			(xy 186.962868 -294.577784) (xy 186.941082 -294.625441) (xy 186.926728 -294.647366) (xy 186.920817 -294.657012)
			(xy 186.917189 -294.679309) (xy 186.923488 -294.701004) (xy 186.930538 -294.70985) (xy 186.937396 -294.717216)
			(xy 186.943215 -294.724424) (xy 186.949738 -294.741742) (xy 186.950096 -294.750998) (xy 186.950096 -296.098722)
			(xy 186.94971 -296.107973) (xy 186.943202 -296.125292) (xy 186.937396 -296.132504) (xy 186.930538 -296.13987)
			(xy 186.923562 -296.148756) (xy 186.917299 -296.170427) (xy 186.920861 -296.192703) (xy 186.926728 -296.202354)
			(xy 186.9411 -296.224268) (xy 186.962885 -296.271928) (xy 186.976215 -296.322606) (xy 186.980701 -296.374817)
			(xy 186.980701 -296.37482) (xy 187.31917 -296.37482) (xy 187.32313 -296.325766) (xy 187.334907 -296.277982)
			(xy 187.354198 -296.232706) (xy 187.380501 -296.19111) (xy 187.413136 -296.154273) (xy 187.451257 -296.123148)
			(xy 187.493878 -296.098541) (xy 187.539894 -296.081089) (xy 187.588113 -296.071245) (xy 187.637288 -296.069264)
			(xy 187.686143 -296.075196) (xy 187.733414 -296.088888) (xy 187.777876 -296.109986) (xy 187.818379 -296.137942)
			(xy 187.853872 -296.172034) (xy 187.883437 -296.211378) (xy 187.906308 -296.254955) (xy 187.921892 -296.301636)
			(xy 187.929787 -296.350213) (xy 187.930282 -296.37482) (xy 188.26913 -296.37482) (xy 188.27309 -296.325766)
			(xy 188.284867 -296.277982) (xy 188.304158 -296.232706) (xy 188.330461 -296.19111) (xy 188.363096 -296.154273)
			(xy 188.401217 -296.123148) (xy 188.443838 -296.098541) (xy 188.489854 -296.081089) (xy 188.538073 -296.071245)
			(xy 188.587248 -296.069264) (xy 188.636103 -296.075196) (xy 188.683374 -296.088888) (xy 188.727836 -296.109986)
			(xy 188.768339 -296.137942) (xy 188.803832 -296.172034) (xy 188.833397 -296.211378) (xy 188.856268 -296.254955)
			(xy 188.871852 -296.301636) (xy 188.879747 -296.350213) (xy 188.880242 -296.37482) (xy 189.21909 -296.37482)
			(xy 189.22305 -296.325766) (xy 189.234827 -296.277982) (xy 189.254118 -296.232706) (xy 189.280421 -296.19111)
			(xy 189.313056 -296.154273) (xy 189.351177 -296.123148) (xy 189.393798 -296.098541) (xy 189.439814 -296.081089)
			(xy 189.488033 -296.071245) (xy 189.537208 -296.069264) (xy 189.586063 -296.075196) (xy 189.633334 -296.088888)
			(xy 189.677796 -296.109986) (xy 189.718299 -296.137942) (xy 189.753792 -296.172034) (xy 189.783357 -296.211378)
			(xy 189.806228 -296.254955) (xy 189.821812 -296.301636) (xy 189.829707 -296.350213) (xy 189.830202 -296.37482)
			(xy 190.16905 -296.37482) (xy 190.17301 -296.325766) (xy 190.184787 -296.277982) (xy 190.204078 -296.232706)
			(xy 190.230381 -296.19111) (xy 190.263016 -296.154273) (xy 190.301137 -296.123148) (xy 190.343758 -296.098541)
			(xy 190.389774 -296.081089) (xy 190.437993 -296.071245) (xy 190.487168 -296.069264) (xy 190.536023 -296.075196)
			(xy 190.583294 -296.088888) (xy 190.627756 -296.109986) (xy 190.668259 -296.137942) (xy 190.703752 -296.172034)
			(xy 190.733317 -296.211378) (xy 190.756188 -296.254955) (xy 190.771772 -296.301636) (xy 190.779667 -296.350213)
			(xy 190.780162 -296.37482) (xy 191.119264 -296.37482) (xy 191.123224 -296.325766) (xy 191.135001 -296.277982)
			(xy 191.154292 -296.232706) (xy 191.180595 -296.19111) (xy 191.21323 -296.154273) (xy 191.251351 -296.123148)
			(xy 191.293972 -296.098541) (xy 191.339988 -296.081089) (xy 191.388207 -296.071245) (xy 191.437382 -296.069264)
			(xy 191.486237 -296.075196) (xy 191.533508 -296.088888) (xy 191.57797 -296.109986) (xy 191.618473 -296.137942)
			(xy 191.653966 -296.172034) (xy 191.683531 -296.211378) (xy 191.706402 -296.254955) (xy 191.721986 -296.301636)
			(xy 191.729881 -296.350213) (xy 191.730376 -296.37482) (xy 192.069224 -296.37482) (xy 192.073184 -296.325766)
			(xy 192.084961 -296.277982) (xy 192.104252 -296.232706) (xy 192.130555 -296.19111) (xy 192.16319 -296.154273)
			(xy 192.201311 -296.123148) (xy 192.243932 -296.098541) (xy 192.289948 -296.081089) (xy 192.338167 -296.071245)
			(xy 192.387342 -296.069264) (xy 192.436197 -296.075196) (xy 192.483468 -296.088888) (xy 192.52793 -296.109986)
			(xy 192.568433 -296.137942) (xy 192.603926 -296.172034) (xy 192.633491 -296.211378) (xy 192.656362 -296.254955)
			(xy 192.671946 -296.301636) (xy 192.679841 -296.350213) (xy 192.680336 -296.37482) (xy 192.679841 -296.399427)
			(xy 192.671946 -296.448004) (xy 192.656362 -296.494685) (xy 192.633491 -296.538262) (xy 192.603926 -296.577606)
			(xy 192.568433 -296.611698) (xy 192.52793 -296.639654) (xy 192.483468 -296.660752) (xy 192.436197 -296.674444)
			(xy 192.387342 -296.680376) (xy 192.338167 -296.678395) (xy 192.289948 -296.668551) (xy 192.243932 -296.651099)
			(xy 192.201311 -296.626492) (xy 192.16319 -296.595367) (xy 192.130555 -296.55853) (xy 192.104252 -296.516934)
			(xy 192.084961 -296.471658) (xy 192.073184 -296.423874) (xy 192.069224 -296.37482) (xy 191.730376 -296.37482)
			(xy 191.729881 -296.399427) (xy 191.721986 -296.448004) (xy 191.706402 -296.494685) (xy 191.683531 -296.538262)
			(xy 191.653966 -296.577606) (xy 191.618473 -296.611698) (xy 191.57797 -296.639654) (xy 191.533508 -296.660752)
			(xy 191.486237 -296.674444) (xy 191.437382 -296.680376) (xy 191.388207 -296.678395) (xy 191.339988 -296.668551)
			(xy 191.293972 -296.651099) (xy 191.251351 -296.626492) (xy 191.21323 -296.595367) (xy 191.180595 -296.55853)
			(xy 191.154292 -296.516934) (xy 191.135001 -296.471658) (xy 191.123224 -296.423874) (xy 191.119264 -296.37482)
			(xy 190.780162 -296.37482) (xy 190.779667 -296.399427) (xy 190.771772 -296.448004) (xy 190.756188 -296.494685)
			(xy 190.733317 -296.538262) (xy 190.703752 -296.577606) (xy 190.668259 -296.611698) (xy 190.627756 -296.639654)
			(xy 190.583294 -296.660752) (xy 190.536023 -296.674444) (xy 190.487168 -296.680376) (xy 190.437993 -296.678395)
			(xy 190.389774 -296.668551) (xy 190.343758 -296.651099) (xy 190.301137 -296.626492) (xy 190.263016 -296.595367)
			(xy 190.230381 -296.55853) (xy 190.204078 -296.516934) (xy 190.184787 -296.471658) (xy 190.17301 -296.423874)
			(xy 190.16905 -296.37482) (xy 189.830202 -296.37482) (xy 189.829707 -296.399427) (xy 189.821812 -296.448004)
			(xy 189.806228 -296.494685) (xy 189.783357 -296.538262) (xy 189.753792 -296.577606) (xy 189.718299 -296.611698)
			(xy 189.677796 -296.639654) (xy 189.633334 -296.660752) (xy 189.586063 -296.674444) (xy 189.537208 -296.680376)
			(xy 189.488033 -296.678395) (xy 189.439814 -296.668551) (xy 189.393798 -296.651099) (xy 189.351177 -296.626492)
			(xy 189.313056 -296.595367) (xy 189.280421 -296.55853) (xy 189.254118 -296.516934) (xy 189.234827 -296.471658)
			(xy 189.22305 -296.423874) (xy 189.21909 -296.37482) (xy 188.880242 -296.37482) (xy 188.879747 -296.399427)
			(xy 188.871852 -296.448004) (xy 188.856268 -296.494685) (xy 188.833397 -296.538262) (xy 188.803832 -296.577606)
			(xy 188.768339 -296.611698) (xy 188.727836 -296.639654) (xy 188.683374 -296.660752) (xy 188.636103 -296.674444)
			(xy 188.587248 -296.680376) (xy 188.538073 -296.678395) (xy 188.489854 -296.668551) (xy 188.443838 -296.651099)
			(xy 188.401217 -296.626492) (xy 188.363096 -296.595367) (xy 188.330461 -296.55853) (xy 188.304158 -296.516934)
			(xy 188.284867 -296.471658) (xy 188.27309 -296.423874) (xy 188.26913 -296.37482) (xy 187.930282 -296.37482)
			(xy 187.929787 -296.399427) (xy 187.921892 -296.448004) (xy 187.906308 -296.494685) (xy 187.883437 -296.538262)
			(xy 187.853872 -296.577606) (xy 187.818379 -296.611698) (xy 187.777876 -296.639654) (xy 187.733414 -296.660752)
			(xy 187.686143 -296.674444) (xy 187.637288 -296.680376) (xy 187.588113 -296.678395) (xy 187.539894 -296.668551)
			(xy 187.493878 -296.651099) (xy 187.451257 -296.626492) (xy 187.413136 -296.595367) (xy 187.380501 -296.55853)
			(xy 187.354198 -296.516934) (xy 187.334907 -296.471658) (xy 187.32313 -296.423874) (xy 187.31917 -296.37482)
			(xy 186.980701 -296.37482) (xy 186.97621 -296.427026) (xy 186.962874 -296.477703) (xy 186.941084 -296.525361)
			(xy 186.926728 -296.547286) (xy 186.920799 -296.556922) (xy 186.917176 -296.579226) (xy 186.923484 -296.600924)
			(xy 186.930538 -296.60977) (xy 186.937396 -296.617136) (xy 186.943224 -296.624337) (xy 186.949741 -296.641661)
			(xy 186.950096 -296.650918) (xy 186.950096 -297.048682) (xy 186.949739 -297.057936) (xy 186.943211 -297.075255)
			(xy 186.937396 -297.082464) (xy 186.930538 -297.08983) (xy 186.923511 -297.09868) (xy 186.917262 -297.120373)
			(xy 186.920847 -297.142661) (xy 186.926728 -297.152314) (xy 186.939381 -297.171444) (xy 186.959399 -297.212708)
			(xy 186.973008 -297.256506) (xy 186.979899 -297.301848) (xy 186.980322 -297.32478) (xy 187.31917 -297.32478)
			(xy 187.32313 -297.275726) (xy 187.334907 -297.227942) (xy 187.354198 -297.182666) (xy 187.380501 -297.14107)
			(xy 187.413136 -297.104233) (xy 187.451257 -297.073108) (xy 187.493878 -297.048501) (xy 187.539894 -297.031049)
			(xy 187.588113 -297.021205) (xy 187.637288 -297.019224) (xy 187.686143 -297.025156) (xy 187.733414 -297.038848)
			(xy 187.777876 -297.059946) (xy 187.818379 -297.087902) (xy 187.853872 -297.121994) (xy 187.883437 -297.161338)
			(xy 187.906308 -297.204915) (xy 187.921892 -297.251596) (xy 187.929787 -297.300173) (xy 187.930282 -297.32478)
			(xy 188.26913 -297.32478) (xy 188.27309 -297.275726) (xy 188.284867 -297.227942) (xy 188.304158 -297.182666)
			(xy 188.330461 -297.14107) (xy 188.363096 -297.104233) (xy 188.401217 -297.073108) (xy 188.443838 -297.048501)
			(xy 188.489854 -297.031049) (xy 188.538073 -297.021205) (xy 188.587248 -297.019224) (xy 188.636103 -297.025156)
			(xy 188.683374 -297.038848) (xy 188.727836 -297.059946) (xy 188.768339 -297.087902) (xy 188.803832 -297.121994)
			(xy 188.833397 -297.161338) (xy 188.856268 -297.204915) (xy 188.871852 -297.251596) (xy 188.879747 -297.300173)
			(xy 188.880242 -297.32478) (xy 189.21909 -297.32478) (xy 189.22305 -297.275726) (xy 189.234827 -297.227942)
			(xy 189.254118 -297.182666) (xy 189.280421 -297.14107) (xy 189.313056 -297.104233) (xy 189.351177 -297.073108)
			(xy 189.393798 -297.048501) (xy 189.439814 -297.031049) (xy 189.488033 -297.021205) (xy 189.537208 -297.019224)
			(xy 189.586063 -297.025156) (xy 189.633334 -297.038848) (xy 189.677796 -297.059946) (xy 189.718299 -297.087902)
			(xy 189.753792 -297.121994) (xy 189.783357 -297.161338) (xy 189.806228 -297.204915) (xy 189.821812 -297.251596)
			(xy 189.829707 -297.300173) (xy 189.830202 -297.32478) (xy 190.169304 -297.32478) (xy 190.173264 -297.275726)
			(xy 190.185041 -297.227942) (xy 190.204332 -297.182666) (xy 190.230635 -297.14107) (xy 190.26327 -297.104233)
			(xy 190.301391 -297.073108) (xy 190.344012 -297.048501) (xy 190.390028 -297.031049) (xy 190.438247 -297.021205)
			(xy 190.487422 -297.019224) (xy 190.536277 -297.025156) (xy 190.583548 -297.038848) (xy 190.62801 -297.059946)
			(xy 190.668513 -297.087902) (xy 190.704006 -297.121994) (xy 190.733571 -297.161338) (xy 190.756442 -297.204915)
			(xy 190.772026 -297.251596) (xy 190.779921 -297.300173) (xy 190.780416 -297.32478) (xy 191.119264 -297.32478)
			(xy 191.123224 -297.275726) (xy 191.135001 -297.227942) (xy 191.154292 -297.182666) (xy 191.180595 -297.14107)
			(xy 191.21323 -297.104233) (xy 191.251351 -297.073108) (xy 191.293972 -297.048501) (xy 191.339988 -297.031049)
			(xy 191.388207 -297.021205) (xy 191.437382 -297.019224) (xy 191.486237 -297.025156) (xy 191.533508 -297.038848)
			(xy 191.57797 -297.059946) (xy 191.618473 -297.087902) (xy 191.653966 -297.121994) (xy 191.683531 -297.161338)
			(xy 191.706402 -297.204915) (xy 191.721986 -297.251596) (xy 191.729881 -297.300173) (xy 191.730376 -297.32478)
			(xy 192.069224 -297.32478) (xy 192.073184 -297.275726) (xy 192.084961 -297.227942) (xy 192.104252 -297.182666)
			(xy 192.130555 -297.14107) (xy 192.16319 -297.104233) (xy 192.201311 -297.073108) (xy 192.243932 -297.048501)
			(xy 192.289948 -297.031049) (xy 192.338167 -297.021205) (xy 192.387342 -297.019224) (xy 192.436197 -297.025156)
			(xy 192.483468 -297.038848) (xy 192.52793 -297.059946) (xy 192.568433 -297.087902) (xy 192.603926 -297.121994)
			(xy 192.633491 -297.161338) (xy 192.656362 -297.204915) (xy 192.671946 -297.251596) (xy 192.679841 -297.300173)
			(xy 192.680336 -297.32478) (xy 192.679841 -297.349387) (xy 192.671946 -297.397964) (xy 192.656362 -297.444645)
			(xy 192.633491 -297.488222) (xy 192.603926 -297.527566) (xy 192.568433 -297.561658) (xy 192.52793 -297.589614)
			(xy 192.483468 -297.610712) (xy 192.436197 -297.624404) (xy 192.387342 -297.630336) (xy 192.338167 -297.628355)
			(xy 192.289948 -297.618511) (xy 192.243932 -297.601059) (xy 192.201311 -297.576452) (xy 192.16319 -297.545327)
			(xy 192.130555 -297.50849) (xy 192.104252 -297.466894) (xy 192.084961 -297.421618) (xy 192.073184 -297.373834)
			(xy 192.069224 -297.32478) (xy 191.730376 -297.32478) (xy 191.729881 -297.349387) (xy 191.721986 -297.397964)
			(xy 191.706402 -297.444645) (xy 191.683531 -297.488222) (xy 191.653966 -297.527566) (xy 191.618473 -297.561658)
			(xy 191.57797 -297.589614) (xy 191.533508 -297.610712) (xy 191.486237 -297.624404) (xy 191.437382 -297.630336)
			(xy 191.388207 -297.628355) (xy 191.339988 -297.618511) (xy 191.293972 -297.601059) (xy 191.251351 -297.576452)
			(xy 191.21323 -297.545327) (xy 191.180595 -297.50849) (xy 191.154292 -297.466894) (xy 191.135001 -297.421618)
			(xy 191.123224 -297.373834) (xy 191.119264 -297.32478) (xy 190.780416 -297.32478) (xy 190.779921 -297.349387)
			(xy 190.772026 -297.397964) (xy 190.756442 -297.444645) (xy 190.733571 -297.488222) (xy 190.704006 -297.527566)
			(xy 190.668513 -297.561658) (xy 190.62801 -297.589614) (xy 190.583548 -297.610712) (xy 190.536277 -297.624404)
			(xy 190.487422 -297.630336) (xy 190.438247 -297.628355) (xy 190.390028 -297.618511) (xy 190.344012 -297.601059)
			(xy 190.301391 -297.576452) (xy 190.26327 -297.545327) (xy 190.230635 -297.50849) (xy 190.204332 -297.466894)
			(xy 190.185041 -297.421618) (xy 190.173264 -297.373834) (xy 190.169304 -297.32478) (xy 189.830202 -297.32478)
			(xy 189.829707 -297.349387) (xy 189.821812 -297.397964) (xy 189.806228 -297.444645) (xy 189.783357 -297.488222)
			(xy 189.753792 -297.527566) (xy 189.718299 -297.561658) (xy 189.677796 -297.589614) (xy 189.633334 -297.610712)
			(xy 189.586063 -297.624404) (xy 189.537208 -297.630336) (xy 189.488033 -297.628355) (xy 189.439814 -297.618511)
			(xy 189.393798 -297.601059) (xy 189.351177 -297.576452) (xy 189.313056 -297.545327) (xy 189.280421 -297.50849)
			(xy 189.254118 -297.466894) (xy 189.234827 -297.421618) (xy 189.22305 -297.373834) (xy 189.21909 -297.32478)
			(xy 188.880242 -297.32478) (xy 188.879747 -297.349387) (xy 188.871852 -297.397964) (xy 188.856268 -297.444645)
			(xy 188.833397 -297.488222) (xy 188.803832 -297.527566) (xy 188.768339 -297.561658) (xy 188.727836 -297.589614)
			(xy 188.683374 -297.610712) (xy 188.636103 -297.624404) (xy 188.587248 -297.630336) (xy 188.538073 -297.628355)
			(xy 188.489854 -297.618511) (xy 188.443838 -297.601059) (xy 188.401217 -297.576452) (xy 188.363096 -297.545327)
			(xy 188.330461 -297.50849) (xy 188.304158 -297.466894) (xy 188.284867 -297.421618) (xy 188.27309 -297.373834)
			(xy 188.26913 -297.32478) (xy 187.930282 -297.32478) (xy 187.929787 -297.349387) (xy 187.921892 -297.397964)
			(xy 187.906308 -297.444645) (xy 187.883437 -297.488222) (xy 187.853872 -297.527566) (xy 187.818379 -297.561658)
			(xy 187.777876 -297.589614) (xy 187.733414 -297.610712) (xy 187.686143 -297.624404) (xy 187.637288 -297.630336)
			(xy 187.588113 -297.628355) (xy 187.539894 -297.618511) (xy 187.493878 -297.601059) (xy 187.451257 -297.576452)
			(xy 187.413136 -297.545327) (xy 187.380501 -297.50849) (xy 187.354198 -297.466894) (xy 187.334907 -297.421618)
			(xy 187.32313 -297.373834) (xy 187.31917 -297.32478) (xy 186.980322 -297.32478) (xy 186.979843 -297.348772)
			(xy 186.97234 -297.396165) (xy 186.957515 -297.441802) (xy 186.935734 -297.484557) (xy 186.907532 -297.523378)
			(xy 186.873604 -297.557309) (xy 186.834786 -297.585516) (xy 186.792033 -297.607302) (xy 186.746398 -297.622132)
			(xy 186.699006 -297.629641) (xy 186.675014 -297.630088) (xy 186.647485 -297.629445) (xy 186.593332 -297.619491)
			(xy 186.541833 -297.60001) (xy 186.49465 -297.571631) (xy 186.473592 -297.553888) (xy 186.454542 -297.537378)
			(xy 186.429396 -297.536362) (xy 186.422576 -297.541186) (xy 186.406757 -297.54652) (xy 186.398408 -297.546776)
			(xy 185.953908 -297.546776) (xy 185.944973 -297.547081) (xy 185.928188 -297.55321) (xy 185.921142 -297.558714)
			(xy 185.900384 -297.57542) (xy 185.854237 -297.602053) (xy 185.804167 -297.620268) (xy 185.751694 -297.629511)
			(xy 185.725054 -297.630088) (xy 185.697526 -297.629422) (xy 185.643374 -297.619476) (xy 185.591875 -297.600001)
			(xy 185.544691 -297.571628) (xy 185.523632 -297.553888) (xy 185.504582 -297.537378) (xy 185.479436 -297.536362)
			(xy 185.472631 -297.541211) (xy 185.4568 -297.54653) (xy 185.448448 -297.546776) (xy 185.003694 -297.546776)
			(xy 184.994758 -297.547074) (xy 184.977974 -297.553208) (xy 184.970928 -297.558714) (xy 184.95014 -297.575381)
			(xy 184.904004 -297.602021) (xy 184.853943 -297.620247) (xy 184.801478 -297.629504) (xy 184.77484 -297.630088)
			(xy 184.76001 -297.62989) (xy 184.730493 -297.626961) (xy 184.715912 -297.624246) (xy 184.715658 -297.624246)
			(xy 184.704468 -297.62266) (xy 184.682586 -297.6282) (xy 184.673494 -297.634914) (xy 184.629044 -297.671744)
			(xy 184.620809 -297.679357) (xy 184.611333 -297.699658) (xy 184.610756 -297.71086) (xy 184.610756 -297.88866)
			(xy 184.611324 -297.899865) (xy 184.620801 -297.920167) (xy 184.629044 -297.927776) (xy 184.673494 -297.964606)
			(xy 184.682556 -297.971375) (xy 184.704462 -297.9769) (xy 184.715658 -297.975274) (xy 184.716166 -297.975274)
			(xy 184.730684 -297.97257) (xy 184.760073 -297.969642) (xy 184.77484 -297.969432) (xy 184.800096 -297.969877)
			(xy 184.84992 -297.978197) (xy 184.897694 -297.994603) (xy 184.942117 -298.018649) (xy 184.981976 -298.049678)
			(xy 185.016186 -298.086843) (xy 185.043812 -298.129133) (xy 185.064101 -298.175392) (xy 185.0765 -298.224359)
			(xy 185.080671 -298.2747) (xy 185.080668 -298.27474) (xy 185.41925 -298.27474) (xy 185.42321 -298.225686)
			(xy 185.434987 -298.177902) (xy 185.454278 -298.132626) (xy 185.480581 -298.09103) (xy 185.513216 -298.054193)
			(xy 185.551337 -298.023068) (xy 185.593958 -297.998461) (xy 185.639974 -297.981009) (xy 185.688193 -297.971165)
			(xy 185.737368 -297.969184) (xy 185.786223 -297.975116) (xy 185.833494 -297.988808) (xy 185.877956 -298.009906)
			(xy 185.918459 -298.037862) (xy 185.953952 -298.071954) (xy 185.983517 -298.111298) (xy 186.006388 -298.154875)
			(xy 186.021972 -298.201556) (xy 186.029867 -298.250133) (xy 186.030362 -298.27474) (xy 186.36921 -298.27474)
			(xy 186.37317 -298.225686) (xy 186.384947 -298.177902) (xy 186.404238 -298.132626) (xy 186.430541 -298.09103)
			(xy 186.463176 -298.054193) (xy 186.501297 -298.023068) (xy 186.543918 -297.998461) (xy 186.589934 -297.981009)
			(xy 186.638153 -297.971165) (xy 186.687328 -297.969184) (xy 186.736183 -297.975116) (xy 186.783454 -297.988808)
			(xy 186.827916 -298.009906) (xy 186.868419 -298.037862) (xy 186.903912 -298.071954) (xy 186.933477 -298.111298)
			(xy 186.956348 -298.154875) (xy 186.971932 -298.201556) (xy 186.979827 -298.250133) (xy 186.980322 -298.27474)
			(xy 187.31917 -298.27474) (xy 187.32313 -298.225686) (xy 187.334907 -298.177902) (xy 187.354198 -298.132626)
			(xy 187.380501 -298.09103) (xy 187.413136 -298.054193) (xy 187.451257 -298.023068) (xy 187.493878 -297.998461)
			(xy 187.539894 -297.981009) (xy 187.588113 -297.971165) (xy 187.637288 -297.969184) (xy 187.686143 -297.975116)
			(xy 187.733414 -297.988808) (xy 187.777876 -298.009906) (xy 187.818379 -298.037862) (xy 187.853872 -298.071954)
			(xy 187.883437 -298.111298) (xy 187.906308 -298.154875) (xy 187.921892 -298.201556) (xy 187.929787 -298.250133)
			(xy 187.930282 -298.27474) (xy 188.26913 -298.27474) (xy 188.27309 -298.225686) (xy 188.284867 -298.177902)
			(xy 188.304158 -298.132626) (xy 188.330461 -298.09103) (xy 188.363096 -298.054193) (xy 188.401217 -298.023068)
			(xy 188.443838 -297.998461) (xy 188.489854 -297.981009) (xy 188.538073 -297.971165) (xy 188.587248 -297.969184)
			(xy 188.636103 -297.975116) (xy 188.683374 -297.988808) (xy 188.727836 -298.009906) (xy 188.768339 -298.037862)
			(xy 188.803832 -298.071954) (xy 188.833397 -298.111298) (xy 188.856268 -298.154875) (xy 188.871852 -298.201556)
			(xy 188.879747 -298.250133) (xy 188.880242 -298.27474) (xy 189.21909 -298.27474) (xy 189.22305 -298.225686)
			(xy 189.234827 -298.177902) (xy 189.254118 -298.132626) (xy 189.280421 -298.09103) (xy 189.313056 -298.054193)
			(xy 189.351177 -298.023068) (xy 189.393798 -297.998461) (xy 189.439814 -297.981009) (xy 189.488033 -297.971165)
			(xy 189.537208 -297.969184) (xy 189.586063 -297.975116) (xy 189.633334 -297.988808) (xy 189.677796 -298.009906)
			(xy 189.718299 -298.037862) (xy 189.753792 -298.071954) (xy 189.783357 -298.111298) (xy 189.806228 -298.154875)
			(xy 189.821812 -298.201556) (xy 189.829707 -298.250133) (xy 189.830202 -298.27474) (xy 190.16905 -298.27474)
			(xy 190.17301 -298.225686) (xy 190.184787 -298.177902) (xy 190.204078 -298.132626) (xy 190.230381 -298.09103)
			(xy 190.263016 -298.054193) (xy 190.301137 -298.023068) (xy 190.343758 -297.998461) (xy 190.389774 -297.981009)
			(xy 190.437993 -297.971165) (xy 190.487168 -297.969184) (xy 190.536023 -297.975116) (xy 190.583294 -297.988808)
			(xy 190.627756 -298.009906) (xy 190.668259 -298.037862) (xy 190.703752 -298.071954) (xy 190.733317 -298.111298)
			(xy 190.756188 -298.154875) (xy 190.771772 -298.201556) (xy 190.779667 -298.250133) (xy 190.780162 -298.27474)
			(xy 191.119264 -298.27474) (xy 191.123224 -298.225686) (xy 191.135001 -298.177902) (xy 191.154292 -298.132626)
			(xy 191.180595 -298.09103) (xy 191.21323 -298.054193) (xy 191.251351 -298.023068) (xy 191.293972 -297.998461)
			(xy 191.339988 -297.981009) (xy 191.388207 -297.971165) (xy 191.437382 -297.969184) (xy 191.486237 -297.975116)
			(xy 191.533508 -297.988808) (xy 191.57797 -298.009906) (xy 191.618473 -298.037862) (xy 191.653966 -298.071954)
			(xy 191.683531 -298.111298) (xy 191.706402 -298.154875) (xy 191.721986 -298.201556) (xy 191.729881 -298.250133)
			(xy 191.730376 -298.27474) (xy 192.069224 -298.27474) (xy 192.073184 -298.225686) (xy 192.084961 -298.177902)
			(xy 192.104252 -298.132626) (xy 192.130555 -298.09103) (xy 192.16319 -298.054193) (xy 192.201311 -298.023068)
			(xy 192.243932 -297.998461) (xy 192.289948 -297.981009) (xy 192.338167 -297.971165) (xy 192.387342 -297.969184)
			(xy 192.436197 -297.975116) (xy 192.483468 -297.988808) (xy 192.52793 -298.009906) (xy 192.568433 -298.037862)
			(xy 192.603926 -298.071954) (xy 192.633491 -298.111298) (xy 192.656362 -298.154875) (xy 192.671946 -298.201556)
			(xy 192.679841 -298.250133) (xy 192.680336 -298.27474) (xy 192.679841 -298.299347) (xy 192.671946 -298.347924)
			(xy 192.656362 -298.394605) (xy 192.633491 -298.438182) (xy 192.603926 -298.477526) (xy 192.568433 -298.511618)
			(xy 192.52793 -298.539574) (xy 192.483468 -298.560672) (xy 192.436197 -298.574364) (xy 192.387342 -298.580296)
			(xy 192.338167 -298.578315) (xy 192.289948 -298.568471) (xy 192.243932 -298.551019) (xy 192.201311 -298.526412)
			(xy 192.16319 -298.495287) (xy 192.130555 -298.45845) (xy 192.104252 -298.416854) (xy 192.084961 -298.371578)
			(xy 192.073184 -298.323794) (xy 192.069224 -298.27474) (xy 191.730376 -298.27474) (xy 191.729881 -298.299347)
			(xy 191.721986 -298.347924) (xy 191.706402 -298.394605) (xy 191.683531 -298.438182) (xy 191.653966 -298.477526)
			(xy 191.618473 -298.511618) (xy 191.57797 -298.539574) (xy 191.533508 -298.560672) (xy 191.486237 -298.574364)
			(xy 191.437382 -298.580296) (xy 191.388207 -298.578315) (xy 191.339988 -298.568471) (xy 191.293972 -298.551019)
			(xy 191.251351 -298.526412) (xy 191.21323 -298.495287) (xy 191.180595 -298.45845) (xy 191.154292 -298.416854)
			(xy 191.135001 -298.371578) (xy 191.123224 -298.323794) (xy 191.119264 -298.27474) (xy 190.780162 -298.27474)
			(xy 190.779667 -298.299347) (xy 190.771772 -298.347924) (xy 190.756188 -298.394605) (xy 190.733317 -298.438182)
			(xy 190.703752 -298.477526) (xy 190.668259 -298.511618) (xy 190.627756 -298.539574) (xy 190.583294 -298.560672)
			(xy 190.536023 -298.574364) (xy 190.487168 -298.580296) (xy 190.437993 -298.578315) (xy 190.389774 -298.568471)
			(xy 190.343758 -298.551019) (xy 190.301137 -298.526412) (xy 190.263016 -298.495287) (xy 190.230381 -298.45845)
			(xy 190.204078 -298.416854) (xy 190.184787 -298.371578) (xy 190.17301 -298.323794) (xy 190.16905 -298.27474)
			(xy 189.830202 -298.27474) (xy 189.829707 -298.299347) (xy 189.821812 -298.347924) (xy 189.806228 -298.394605)
			(xy 189.783357 -298.438182) (xy 189.753792 -298.477526) (xy 189.718299 -298.511618) (xy 189.677796 -298.539574)
			(xy 189.633334 -298.560672) (xy 189.586063 -298.574364) (xy 189.537208 -298.580296) (xy 189.488033 -298.578315)
			(xy 189.439814 -298.568471) (xy 189.393798 -298.551019) (xy 189.351177 -298.526412) (xy 189.313056 -298.495287)
			(xy 189.280421 -298.45845) (xy 189.254118 -298.416854) (xy 189.234827 -298.371578) (xy 189.22305 -298.323794)
			(xy 189.21909 -298.27474) (xy 188.880242 -298.27474) (xy 188.879747 -298.299347) (xy 188.871852 -298.347924)
			(xy 188.856268 -298.394605) (xy 188.833397 -298.438182) (xy 188.803832 -298.477526) (xy 188.768339 -298.511618)
			(xy 188.727836 -298.539574) (xy 188.683374 -298.560672) (xy 188.636103 -298.574364) (xy 188.587248 -298.580296)
			(xy 188.538073 -298.578315) (xy 188.489854 -298.568471) (xy 188.443838 -298.551019) (xy 188.401217 -298.526412)
			(xy 188.363096 -298.495287) (xy 188.330461 -298.45845) (xy 188.304158 -298.416854) (xy 188.284867 -298.371578)
			(xy 188.27309 -298.323794) (xy 188.26913 -298.27474) (xy 187.930282 -298.27474) (xy 187.929787 -298.299347)
			(xy 187.921892 -298.347924) (xy 187.906308 -298.394605) (xy 187.883437 -298.438182) (xy 187.853872 -298.477526)
			(xy 187.818379 -298.511618) (xy 187.777876 -298.539574) (xy 187.733414 -298.560672) (xy 187.686143 -298.574364)
			(xy 187.637288 -298.580296) (xy 187.588113 -298.578315) (xy 187.539894 -298.568471) (xy 187.493878 -298.551019)
			(xy 187.451257 -298.526412) (xy 187.413136 -298.495287) (xy 187.380501 -298.45845) (xy 187.354198 -298.416854)
			(xy 187.334907 -298.371578) (xy 187.32313 -298.323794) (xy 187.31917 -298.27474) (xy 186.980322 -298.27474)
			(xy 186.979827 -298.299347) (xy 186.971932 -298.347924) (xy 186.956348 -298.394605) (xy 186.933477 -298.438182)
			(xy 186.903912 -298.477526) (xy 186.868419 -298.511618) (xy 186.827916 -298.539574) (xy 186.783454 -298.560672)
			(xy 186.736183 -298.574364) (xy 186.687328 -298.580296) (xy 186.638153 -298.578315) (xy 186.589934 -298.568471)
			(xy 186.543918 -298.551019) (xy 186.501297 -298.526412) (xy 186.463176 -298.495287) (xy 186.430541 -298.45845)
			(xy 186.404238 -298.416854) (xy 186.384947 -298.371578) (xy 186.37317 -298.323794) (xy 186.36921 -298.27474)
			(xy 186.030362 -298.27474) (xy 186.029867 -298.299347) (xy 186.021972 -298.347924) (xy 186.006388 -298.394605)
			(xy 185.983517 -298.438182) (xy 185.953952 -298.477526) (xy 185.918459 -298.511618) (xy 185.877956 -298.539574)
			(xy 185.833494 -298.560672) (xy 185.786223 -298.574364) (xy 185.737368 -298.580296) (xy 185.688193 -298.578315)
			(xy 185.639974 -298.568471) (xy 185.593958 -298.551019) (xy 185.551337 -298.526412) (xy 185.513216 -298.495287)
			(xy 185.480581 -298.45845) (xy 185.454278 -298.416854) (xy 185.434987 -298.371578) (xy 185.42321 -298.323794)
			(xy 185.41925 -298.27474) (xy 185.080668 -298.27474) (xy 185.0765 -298.325041) (xy 185.064101 -298.374008)
			(xy 185.043812 -298.420267) (xy 185.016186 -298.462557) (xy 184.981976 -298.499722) (xy 184.942117 -298.530751)
			(xy 184.897694 -298.554797) (xy 184.84992 -298.571203) (xy 184.800096 -298.579523) (xy 184.77484 -298.580048)
			(xy 184.76001 -298.579849) (xy 184.730493 -298.576921) (xy 184.715912 -298.574206) (xy 184.715658 -298.574206)
			(xy 184.704468 -298.572629) (xy 184.682587 -298.578165) (xy 184.673494 -298.584874) (xy 184.629044 -298.621704)
			(xy 184.620827 -298.629334) (xy 184.611341 -298.649622) (xy 184.610756 -298.66082) (xy 184.610756 -298.838874)
			(xy 184.611316 -298.85008) (xy 184.620798 -298.870382) (xy 184.629044 -298.87799) (xy 184.673494 -298.91482)
			(xy 184.682555 -298.92159) (xy 184.704462 -298.927114) (xy 184.715658 -298.925488) (xy 184.716166 -298.925488)
			(xy 184.730684 -298.922784) (xy 184.760073 -298.919856) (xy 184.77484 -298.919646) (xy 184.800089 -298.920263)
			(xy 184.849898 -298.92858) (xy 184.897659 -298.944982) (xy 184.94207 -298.969021) (xy 184.981918 -299.000041)
			(xy 185.016118 -299.037196) (xy 185.043736 -299.079474) (xy 185.064019 -299.12572) (xy 185.076415 -299.174674)
			(xy 185.080581 -299.224954) (xy 185.41925 -299.224954) (xy 185.42321 -299.1759) (xy 185.434987 -299.128116)
			(xy 185.454278 -299.08284) (xy 185.480581 -299.041244) (xy 185.513216 -299.004407) (xy 185.551337 -298.973282)
			(xy 185.593958 -298.948675) (xy 185.639974 -298.931223) (xy 185.688193 -298.921379) (xy 185.737368 -298.919398)
			(xy 185.786223 -298.92533) (xy 185.833494 -298.939022) (xy 185.877956 -298.96012) (xy 185.918459 -298.988076)
			(xy 185.953952 -299.022168) (xy 185.983517 -299.061512) (xy 186.006388 -299.105089) (xy 186.021972 -299.15177)
			(xy 186.029867 -299.200347) (xy 186.030362 -299.224954) (xy 186.36921 -299.224954) (xy 186.37317 -299.1759)
			(xy 186.384947 -299.128116) (xy 186.404238 -299.08284) (xy 186.430541 -299.041244) (xy 186.463176 -299.004407)
			(xy 186.501297 -298.973282) (xy 186.543918 -298.948675) (xy 186.589934 -298.931223) (xy 186.638153 -298.921379)
			(xy 186.687328 -298.919398) (xy 186.736183 -298.92533) (xy 186.783454 -298.939022) (xy 186.827916 -298.96012)
			(xy 186.868419 -298.988076) (xy 186.903912 -299.022168) (xy 186.933477 -299.061512) (xy 186.956348 -299.105089)
			(xy 186.971932 -299.15177) (xy 186.979827 -299.200347) (xy 186.980322 -299.224954) (xy 187.31917 -299.224954)
			(xy 187.32313 -299.1759) (xy 187.334907 -299.128116) (xy 187.354198 -299.08284) (xy 187.380501 -299.041244)
			(xy 187.413136 -299.004407) (xy 187.451257 -298.973282) (xy 187.493878 -298.948675) (xy 187.539894 -298.931223)
			(xy 187.588113 -298.921379) (xy 187.637288 -298.919398) (xy 187.686143 -298.92533) (xy 187.733414 -298.939022)
			(xy 187.777876 -298.96012) (xy 187.818379 -298.988076) (xy 187.853872 -299.022168) (xy 187.883437 -299.061512)
			(xy 187.906308 -299.105089) (xy 187.921892 -299.15177) (xy 187.929787 -299.200347) (xy 187.930282 -299.224954)
			(xy 188.26913 -299.224954) (xy 188.27309 -299.1759) (xy 188.284867 -299.128116) (xy 188.304158 -299.08284)
			(xy 188.330461 -299.041244) (xy 188.363096 -299.004407) (xy 188.401217 -298.973282) (xy 188.443838 -298.948675)
			(xy 188.489854 -298.931223) (xy 188.538073 -298.921379) (xy 188.587248 -298.919398) (xy 188.636103 -298.92533)
			(xy 188.683374 -298.939022) (xy 188.727836 -298.96012) (xy 188.768339 -298.988076) (xy 188.803832 -299.022168)
			(xy 188.833397 -299.061512) (xy 188.856268 -299.105089) (xy 188.871852 -299.15177) (xy 188.879747 -299.200347)
			(xy 188.880242 -299.224954) (xy 189.21909 -299.224954) (xy 189.22305 -299.1759) (xy 189.234827 -299.128116)
			(xy 189.254118 -299.08284) (xy 189.280421 -299.041244) (xy 189.313056 -299.004407) (xy 189.351177 -298.973282)
			(xy 189.393798 -298.948675) (xy 189.439814 -298.931223) (xy 189.488033 -298.921379) (xy 189.537208 -298.919398)
			(xy 189.586063 -298.92533) (xy 189.633334 -298.939022) (xy 189.677796 -298.96012) (xy 189.718299 -298.988076)
			(xy 189.753792 -299.022168) (xy 189.783357 -299.061512) (xy 189.806228 -299.105089) (xy 189.821812 -299.15177)
			(xy 189.829707 -299.200347) (xy 189.830202 -299.224954) (xy 192.069224 -299.224954) (xy 192.073184 -299.1759)
			(xy 192.084961 -299.128116) (xy 192.104252 -299.08284) (xy 192.130555 -299.041244) (xy 192.16319 -299.004407)
			(xy 192.201311 -298.973282) (xy 192.243932 -298.948675) (xy 192.289948 -298.931223) (xy 192.338167 -298.921379)
			(xy 192.387342 -298.919398) (xy 192.436197 -298.92533) (xy 192.483468 -298.939022) (xy 192.52793 -298.96012)
			(xy 192.568433 -298.988076) (xy 192.603926 -299.022168) (xy 192.633491 -299.061512) (xy 192.656362 -299.105089)
			(xy 192.671946 -299.15177) (xy 192.679841 -299.200347) (xy 192.680336 -299.224954) (xy 192.679841 -299.249561)
			(xy 192.671946 -299.298138) (xy 192.656362 -299.344819) (xy 192.633491 -299.388396) (xy 192.603926 -299.42774)
			(xy 192.568433 -299.461832) (xy 192.52793 -299.489788) (xy 192.483468 -299.510886) (xy 192.436197 -299.524578)
			(xy 192.387342 -299.53051) (xy 192.338167 -299.528529) (xy 192.289948 -299.518685) (xy 192.243932 -299.501233)
			(xy 192.201311 -299.476626) (xy 192.16319 -299.445501) (xy 192.130555 -299.408664) (xy 192.104252 -299.367068)
			(xy 192.084961 -299.321792) (xy 192.073184 -299.274008) (xy 192.069224 -299.224954) (xy 189.830202 -299.224954)
			(xy 189.829707 -299.249561) (xy 189.821812 -299.298138) (xy 189.806228 -299.344819) (xy 189.783357 -299.388396)
			(xy 189.753792 -299.42774) (xy 189.718299 -299.461832) (xy 189.677796 -299.489788) (xy 189.633334 -299.510886)
			(xy 189.586063 -299.524578) (xy 189.537208 -299.53051) (xy 189.488033 -299.528529) (xy 189.439814 -299.518685)
			(xy 189.393798 -299.501233) (xy 189.351177 -299.476626) (xy 189.313056 -299.445501) (xy 189.280421 -299.408664)
			(xy 189.254118 -299.367068) (xy 189.234827 -299.321792) (xy 189.22305 -299.274008) (xy 189.21909 -299.224954)
			(xy 188.880242 -299.224954) (xy 188.879747 -299.249561) (xy 188.871852 -299.298138) (xy 188.856268 -299.344819)
			(xy 188.833397 -299.388396) (xy 188.803832 -299.42774) (xy 188.768339 -299.461832) (xy 188.727836 -299.489788)
			(xy 188.683374 -299.510886) (xy 188.636103 -299.524578) (xy 188.587248 -299.53051) (xy 188.538073 -299.528529)
			(xy 188.489854 -299.518685) (xy 188.443838 -299.501233) (xy 188.401217 -299.476626) (xy 188.363096 -299.445501)
			(xy 188.330461 -299.408664) (xy 188.304158 -299.367068) (xy 188.284867 -299.321792) (xy 188.27309 -299.274008)
			(xy 188.26913 -299.224954) (xy 187.930282 -299.224954) (xy 187.929787 -299.249561) (xy 187.921892 -299.298138)
			(xy 187.906308 -299.344819) (xy 187.883437 -299.388396) (xy 187.853872 -299.42774) (xy 187.818379 -299.461832)
			(xy 187.777876 -299.489788) (xy 187.733414 -299.510886) (xy 187.686143 -299.524578) (xy 187.637288 -299.53051)
			(xy 187.588113 -299.528529) (xy 187.539894 -299.518685) (xy 187.493878 -299.501233) (xy 187.451257 -299.476626)
			(xy 187.413136 -299.445501) (xy 187.380501 -299.408664) (xy 187.354198 -299.367068) (xy 187.334907 -299.321792)
			(xy 187.32313 -299.274008) (xy 187.31917 -299.224954) (xy 186.980322 -299.224954) (xy 186.979827 -299.249561)
			(xy 186.971932 -299.298138) (xy 186.956348 -299.344819) (xy 186.933477 -299.388396) (xy 186.903912 -299.42774)
			(xy 186.868419 -299.461832) (xy 186.827916 -299.489788) (xy 186.783454 -299.510886) (xy 186.736183 -299.524578)
			(xy 186.687328 -299.53051) (xy 186.638153 -299.528529) (xy 186.589934 -299.518685) (xy 186.543918 -299.501233)
			(xy 186.501297 -299.476626) (xy 186.463176 -299.445501) (xy 186.430541 -299.408664) (xy 186.404238 -299.367068)
			(xy 186.384947 -299.321792) (xy 186.37317 -299.274008) (xy 186.36921 -299.224954) (xy 186.030362 -299.224954)
			(xy 186.029867 -299.249561) (xy 186.021972 -299.298138) (xy 186.006388 -299.344819) (xy 185.983517 -299.388396)
			(xy 185.953952 -299.42774) (xy 185.918459 -299.461832) (xy 185.877956 -299.489788) (xy 185.833494 -299.510886)
			(xy 185.786223 -299.524578) (xy 185.737368 -299.53051) (xy 185.688193 -299.528529) (xy 185.639974 -299.518685)
			(xy 185.593958 -299.501233) (xy 185.551337 -299.476626) (xy 185.513216 -299.445501) (xy 185.480581 -299.408664)
			(xy 185.454278 -299.367068) (xy 185.434987 -299.321792) (xy 185.42321 -299.274008) (xy 185.41925 -299.224954)
			(xy 185.080581 -299.224954) (xy 185.080585 -299.225) (xy 185.076415 -299.275326) (xy 185.064019 -299.32428)
			(xy 185.043736 -299.370526) (xy 185.016118 -299.412804) (xy 184.981918 -299.449959) (xy 184.94207 -299.480979)
			(xy 184.897659 -299.505018) (xy 184.849898 -299.52142) (xy 184.800089 -299.529737) (xy 184.77484 -299.530262)
			(xy 184.76001 -299.530063) (xy 184.730493 -299.527135) (xy 184.715912 -299.52442) (xy 184.715658 -299.52442)
			(xy 184.704468 -299.52284) (xy 184.682587 -299.528377) (xy 184.673494 -299.535088) (xy 184.629044 -299.571918)
			(xy 184.620821 -299.579542) (xy 184.611338 -299.599835) (xy 184.610756 -299.611034) (xy 184.610756 -300.281848)
			(xy 184.611248 -300.291853) (xy 184.618915 -300.310338) (xy 184.633066 -300.324487) (xy 184.651551 -300.332153)
			(xy 184.661556 -300.332648) (xy 185.337958 -300.332648) (xy 185.349069 -300.332089) (xy 185.369229 -300.322746)
			(xy 185.37682 -300.314614) (xy 185.420762 -300.262036) (xy 185.426604 -300.240446) (xy 185.424572 -300.22927)
			(xy 185.422328 -300.215921) (xy 185.419909 -300.188958) (xy 185.419746 -300.175422) (xy 185.419746 -300.174914)
			(xy 185.420268 -300.149659) (xy 185.428581 -300.099837) (xy 185.444982 -300.052063) (xy 185.469023 -300.00764)
			(xy 185.500047 -299.96778) (xy 185.537209 -299.93357) (xy 185.579495 -299.905944) (xy 185.625751 -299.885654)
			(xy 185.674716 -299.873254) (xy 185.725054 -299.869083) (xy 185.775392 -299.873254) (xy 185.824357 -299.885654)
			(xy 185.870613 -299.905944) (xy 185.912899 -299.93357) (xy 185.950061 -299.96778) (xy 185.981085 -300.00764)
			(xy 186.005126 -300.052063) (xy 186.021527 -300.099837) (xy 186.02984 -300.149659) (xy 186.030362 -300.174914)
			(xy 186.36921 -300.174914) (xy 186.37317 -300.12586) (xy 186.384947 -300.078076) (xy 186.404238 -300.0328)
			(xy 186.430541 -299.991204) (xy 186.463176 -299.954367) (xy 186.501297 -299.923242) (xy 186.543918 -299.898635)
			(xy 186.589934 -299.881183) (xy 186.638153 -299.871339) (xy 186.687328 -299.869358) (xy 186.736183 -299.87529)
			(xy 186.783454 -299.888982) (xy 186.827916 -299.91008) (xy 186.868419 -299.938036) (xy 186.903912 -299.972128)
			(xy 186.933477 -300.011472) (xy 186.956348 -300.055049) (xy 186.971932 -300.10173) (xy 186.979827 -300.150307)
			(xy 186.980322 -300.174914) (xy 188.26913 -300.174914) (xy 188.27309 -300.12586) (xy 188.284867 -300.078076)
			(xy 188.304158 -300.0328) (xy 188.330461 -299.991204) (xy 188.363096 -299.954367) (xy 188.401217 -299.923242)
			(xy 188.443838 -299.898635) (xy 188.489854 -299.881183) (xy 188.538073 -299.871339) (xy 188.587248 -299.869358)
			(xy 188.636103 -299.87529) (xy 188.683374 -299.888982) (xy 188.727836 -299.91008) (xy 188.768339 -299.938036)
			(xy 188.803832 -299.972128) (xy 188.833397 -300.011472) (xy 188.856268 -300.055049) (xy 188.871852 -300.10173)
			(xy 188.879747 -300.150307) (xy 188.880242 -300.174914) (xy 189.21909 -300.174914) (xy 189.22305 -300.12586)
			(xy 189.234827 -300.078076) (xy 189.254118 -300.0328) (xy 189.280421 -299.991204) (xy 189.313056 -299.954367)
			(xy 189.351177 -299.923242) (xy 189.393798 -299.898635) (xy 189.439814 -299.881183) (xy 189.488033 -299.871339)
			(xy 189.537208 -299.869358) (xy 189.586063 -299.87529) (xy 189.633334 -299.888982) (xy 189.677796 -299.91008)
			(xy 189.718299 -299.938036) (xy 189.753792 -299.972128) (xy 189.783357 -300.011472) (xy 189.806228 -300.055049)
			(xy 189.821812 -300.10173) (xy 189.829707 -300.150307) (xy 189.830202 -300.174914) (xy 190.16905 -300.174914)
			(xy 190.17301 -300.12586) (xy 190.184787 -300.078076) (xy 190.204078 -300.0328) (xy 190.230381 -299.991204)
			(xy 190.263016 -299.954367) (xy 190.301137 -299.923242) (xy 190.343758 -299.898635) (xy 190.389774 -299.881183)
			(xy 190.437993 -299.871339) (xy 190.487168 -299.869358) (xy 190.536023 -299.87529) (xy 190.583294 -299.888982)
			(xy 190.627756 -299.91008) (xy 190.668259 -299.938036) (xy 190.703752 -299.972128) (xy 190.733317 -300.011472)
			(xy 190.756188 -300.055049) (xy 190.771772 -300.10173) (xy 190.779667 -300.150307) (xy 190.780162 -300.174914)
			(xy 191.119264 -300.174914) (xy 191.123224 -300.12586) (xy 191.135001 -300.078076) (xy 191.154292 -300.0328)
			(xy 191.180595 -299.991204) (xy 191.21323 -299.954367) (xy 191.251351 -299.923242) (xy 191.293972 -299.898635)
			(xy 191.339988 -299.881183) (xy 191.388207 -299.871339) (xy 191.437382 -299.869358) (xy 191.486237 -299.87529)
			(xy 191.533508 -299.888982) (xy 191.57797 -299.91008) (xy 191.618473 -299.938036) (xy 191.653966 -299.972128)
			(xy 191.683531 -300.011472) (xy 191.706402 -300.055049) (xy 191.721986 -300.10173) (xy 191.729881 -300.150307)
			(xy 191.730376 -300.174914) (xy 192.069224 -300.174914) (xy 192.073184 -300.12586) (xy 192.084961 -300.078076)
			(xy 192.104252 -300.0328) (xy 192.130555 -299.991204) (xy 192.16319 -299.954367) (xy 192.201311 -299.923242)
			(xy 192.243932 -299.898635) (xy 192.289948 -299.881183) (xy 192.338167 -299.871339) (xy 192.387342 -299.869358)
			(xy 192.436197 -299.87529) (xy 192.483468 -299.888982) (xy 192.52793 -299.91008) (xy 192.568433 -299.938036)
			(xy 192.603926 -299.972128) (xy 192.633491 -300.011472) (xy 192.656362 -300.055049) (xy 192.671946 -300.10173)
			(xy 192.679841 -300.150307) (xy 192.680336 -300.174914) (xy 192.679841 -300.199521) (xy 192.671946 -300.248098)
			(xy 192.656362 -300.294779) (xy 192.633491 -300.338356) (xy 192.603926 -300.3777) (xy 192.568433 -300.411792)
			(xy 192.52793 -300.439748) (xy 192.483468 -300.460846) (xy 192.436197 -300.474538) (xy 192.387342 -300.48047)
			(xy 192.338167 -300.478489) (xy 192.289948 -300.468645) (xy 192.243932 -300.451193) (xy 192.201311 -300.426586)
			(xy 192.16319 -300.395461) (xy 192.130555 -300.358624) (xy 192.104252 -300.317028) (xy 192.084961 -300.271752)
			(xy 192.073184 -300.223968) (xy 192.069224 -300.174914) (xy 191.730376 -300.174914) (xy 191.729881 -300.199521)
			(xy 191.721986 -300.248098) (xy 191.706402 -300.294779) (xy 191.683531 -300.338356) (xy 191.653966 -300.3777)
			(xy 191.618473 -300.411792) (xy 191.57797 -300.439748) (xy 191.533508 -300.460846) (xy 191.486237 -300.474538)
			(xy 191.437382 -300.48047) (xy 191.388207 -300.478489) (xy 191.339988 -300.468645) (xy 191.293972 -300.451193)
			(xy 191.251351 -300.426586) (xy 191.21323 -300.395461) (xy 191.180595 -300.358624) (xy 191.154292 -300.317028)
			(xy 191.135001 -300.271752) (xy 191.123224 -300.223968) (xy 191.119264 -300.174914) (xy 190.780162 -300.174914)
			(xy 190.779667 -300.199521) (xy 190.771772 -300.248098) (xy 190.756188 -300.294779) (xy 190.733317 -300.338356)
			(xy 190.703752 -300.3777) (xy 190.668259 -300.411792) (xy 190.627756 -300.439748) (xy 190.583294 -300.460846)
			(xy 190.536023 -300.474538) (xy 190.487168 -300.48047) (xy 190.437993 -300.478489) (xy 190.389774 -300.468645)
			(xy 190.343758 -300.451193) (xy 190.301137 -300.426586) (xy 190.263016 -300.395461) (xy 190.230381 -300.358624)
			(xy 190.204078 -300.317028) (xy 190.184787 -300.271752) (xy 190.17301 -300.223968) (xy 190.16905 -300.174914)
			(xy 189.830202 -300.174914) (xy 189.829707 -300.199521) (xy 189.821812 -300.248098) (xy 189.806228 -300.294779)
			(xy 189.783357 -300.338356) (xy 189.753792 -300.3777) (xy 189.718299 -300.411792) (xy 189.677796 -300.439748)
			(xy 189.633334 -300.460846) (xy 189.586063 -300.474538) (xy 189.537208 -300.48047) (xy 189.488033 -300.478489)
			(xy 189.439814 -300.468645) (xy 189.393798 -300.451193) (xy 189.351177 -300.426586) (xy 189.313056 -300.395461)
			(xy 189.280421 -300.358624) (xy 189.254118 -300.317028) (xy 189.234827 -300.271752) (xy 189.22305 -300.223968)
			(xy 189.21909 -300.174914) (xy 188.880242 -300.174914) (xy 188.879747 -300.199521) (xy 188.871852 -300.248098)
			(xy 188.856268 -300.294779) (xy 188.833397 -300.338356) (xy 188.803832 -300.3777) (xy 188.768339 -300.411792)
			(xy 188.727836 -300.439748) (xy 188.683374 -300.460846) (xy 188.636103 -300.474538) (xy 188.587248 -300.48047)
			(xy 188.538073 -300.478489) (xy 188.489854 -300.468645) (xy 188.443838 -300.451193) (xy 188.401217 -300.426586)
			(xy 188.363096 -300.395461) (xy 188.330461 -300.358624) (xy 188.304158 -300.317028) (xy 188.284867 -300.271752)
			(xy 188.27309 -300.223968) (xy 188.26913 -300.174914) (xy 186.980322 -300.174914) (xy 186.979827 -300.199521)
			(xy 186.971932 -300.248098) (xy 186.956348 -300.294779) (xy 186.933477 -300.338356) (xy 186.903912 -300.3777)
			(xy 186.868419 -300.411792) (xy 186.827916 -300.439748) (xy 186.783454 -300.460846) (xy 186.736183 -300.474538)
			(xy 186.687328 -300.48047) (xy 186.638153 -300.478489) (xy 186.589934 -300.468645) (xy 186.543918 -300.451193)
			(xy 186.501297 -300.426586) (xy 186.463176 -300.395461) (xy 186.430541 -300.358624) (xy 186.404238 -300.317028)
			(xy 186.384947 -300.271752) (xy 186.37317 -300.223968) (xy 186.36921 -300.174914) (xy 186.030362 -300.174914)
			(xy 186.02984 -300.200329) (xy 186.021396 -300.250452) (xy 186.004762 -300.298483) (xy 185.980396 -300.343092)
			(xy 185.965084 -300.363382) (xy 185.959496 -300.370494) (xy 185.953908 -300.387258) (xy 185.954416 -300.403006)
			(xy 185.955148 -300.412605) (xy 185.962862 -300.43023) (xy 185.969402 -300.437296) (xy 186.282584 -300.750478)
			(xy 186.303756 -300.772665) (xy 186.338148 -300.82343) (xy 186.35091 -300.851316) (xy 186.356213 -300.862036)
			(xy 186.374487 -300.877413) (xy 186.385962 -300.88078) (xy 186.44362 -300.894242) (xy 186.454809 -300.896211)
			(xy 186.476965 -300.89133) (xy 186.486292 -300.884844) (xy 186.486546 -300.884844) (xy 186.506841 -300.86954)
			(xy 186.551454 -300.845187) (xy 186.599482 -300.828552) (xy 186.649601 -300.820094) (xy 186.675014 -300.819566)
			(xy 186.700266 -300.820141) (xy 186.750082 -300.828455) (xy 186.79785 -300.844856) (xy 186.842267 -300.868895)
			(xy 186.882122 -300.899917) (xy 186.916327 -300.937075) (xy 186.94395 -300.979357) (xy 186.964237 -301.025608)
			(xy 186.976634 -301.074568) (xy 186.980803 -301.124874) (xy 187.31917 -301.124874) (xy 187.32313 -301.07582)
			(xy 187.334907 -301.028036) (xy 187.354198 -300.98276) (xy 187.380501 -300.941164) (xy 187.413136 -300.904327)
			(xy 187.451257 -300.873202) (xy 187.493878 -300.848595) (xy 187.539894 -300.831143) (xy 187.588113 -300.821299)
			(xy 187.637288 -300.819318) (xy 187.686143 -300.82525) (xy 187.733414 -300.838942) (xy 187.777876 -300.86004)
			(xy 187.818379 -300.887996) (xy 187.853872 -300.922088) (xy 187.883437 -300.961432) (xy 187.906308 -301.005009)
			(xy 187.921892 -301.05169) (xy 187.929787 -301.100267) (xy 187.930282 -301.124874) (xy 188.26913 -301.124874)
			(xy 188.27309 -301.07582) (xy 188.284867 -301.028036) (xy 188.304158 -300.98276) (xy 188.330461 -300.941164)
			(xy 188.363096 -300.904327) (xy 188.401217 -300.873202) (xy 188.443838 -300.848595) (xy 188.489854 -300.831143)
			(xy 188.538073 -300.821299) (xy 188.587248 -300.819318) (xy 188.636103 -300.82525) (xy 188.683374 -300.838942)
			(xy 188.727836 -300.86004) (xy 188.768339 -300.887996) (xy 188.803832 -300.922088) (xy 188.833397 -300.961432)
			(xy 188.856268 -301.005009) (xy 188.871852 -301.05169) (xy 188.879747 -301.100267) (xy 188.880242 -301.124874)
			(xy 189.21909 -301.124874) (xy 189.22305 -301.07582) (xy 189.234827 -301.028036) (xy 189.254118 -300.98276)
			(xy 189.280421 -300.941164) (xy 189.313056 -300.904327) (xy 189.351177 -300.873202) (xy 189.393798 -300.848595)
			(xy 189.439814 -300.831143) (xy 189.488033 -300.821299) (xy 189.537208 -300.819318) (xy 189.586063 -300.82525)
			(xy 189.633334 -300.838942) (xy 189.677796 -300.86004) (xy 189.718299 -300.887996) (xy 189.753792 -300.922088)
			(xy 189.783357 -300.961432) (xy 189.806228 -301.005009) (xy 189.821812 -301.05169) (xy 189.829707 -301.100267)
			(xy 189.830202 -301.124874) (xy 189.829707 -301.149481) (xy 189.821812 -301.198058) (xy 189.806228 -301.244739)
			(xy 189.783357 -301.288316) (xy 189.753792 -301.32766) (xy 189.718299 -301.361752) (xy 189.677796 -301.389708)
			(xy 189.633334 -301.410806) (xy 189.586063 -301.424498) (xy 189.537208 -301.43043) (xy 189.488033 -301.428449)
			(xy 189.439814 -301.418605) (xy 189.393798 -301.401153) (xy 189.351177 -301.376546) (xy 189.313056 -301.345421)
			(xy 189.280421 -301.308584) (xy 189.254118 -301.266988) (xy 189.234827 -301.221712) (xy 189.22305 -301.173928)
			(xy 189.21909 -301.124874) (xy 188.880242 -301.124874) (xy 188.879747 -301.149481) (xy 188.871852 -301.198058)
			(xy 188.856268 -301.244739) (xy 188.833397 -301.288316) (xy 188.803832 -301.32766) (xy 188.768339 -301.361752)
			(xy 188.727836 -301.389708) (xy 188.683374 -301.410806) (xy 188.636103 -301.424498) (xy 188.587248 -301.43043)
			(xy 188.538073 -301.428449) (xy 188.489854 -301.418605) (xy 188.443838 -301.401153) (xy 188.401217 -301.376546)
			(xy 188.363096 -301.345421) (xy 188.330461 -301.308584) (xy 188.304158 -301.266988) (xy 188.284867 -301.221712)
			(xy 188.27309 -301.173928) (xy 188.26913 -301.124874) (xy 187.930282 -301.124874) (xy 187.929787 -301.149481)
			(xy 187.921892 -301.198058) (xy 187.906308 -301.244739) (xy 187.883437 -301.288316) (xy 187.853872 -301.32766)
			(xy 187.818379 -301.361752) (xy 187.777876 -301.389708) (xy 187.733414 -301.410806) (xy 187.686143 -301.424498)
			(xy 187.637288 -301.43043) (xy 187.588113 -301.428449) (xy 187.539894 -301.418605) (xy 187.493878 -301.401153)
			(xy 187.451257 -301.376546) (xy 187.413136 -301.345421) (xy 187.380501 -301.308584) (xy 187.354198 -301.266988)
			(xy 187.334907 -301.221712) (xy 187.32313 -301.173928) (xy 187.31917 -301.124874) (xy 186.980803 -301.124874)
			(xy 186.980805 -301.1249) (xy 186.976634 -301.175232) (xy 186.964237 -301.224192) (xy 186.94395 -301.270443)
			(xy 186.916327 -301.312725) (xy 186.882122 -301.349883) (xy 186.842267 -301.380905) (xy 186.79785 -301.404944)
			(xy 186.750082 -301.421345) (xy 186.700266 -301.429659) (xy 186.675014 -301.430182) (xy 186.647023 -301.429545)
			(xy 186.591977 -301.419344) (xy 186.539705 -301.3993) (xy 186.515502 -301.385224) (xy 186.507624 -301.380759)
			(xy 186.489874 -301.377228) (xy 186.472002 -301.380083) (xy 186.46394 -301.384208) (xy 186.40298 -301.418498)
			(xy 186.3953 -301.423177) (xy 186.383624 -301.43684) (xy 186.377416 -301.453707) (xy 186.377072 -301.462694)
			(xy 186.377072 -301.737014) (xy 186.377463 -301.745988) (xy 186.383699 -301.762822) (xy 186.395338 -301.776489)
			(xy 186.40298 -301.78121) (xy 186.46394 -301.8155) (xy 186.472012 -301.819601) (xy 186.489873 -301.822464)
			(xy 186.507612 -301.818922) (xy 186.515502 -301.814484) (xy 186.539704 -301.800404) (xy 186.591973 -301.78035)
			(xy 186.647022 -301.770154) (xy 186.675014 -301.769526) (xy 186.700271 -301.769981) (xy 186.750097 -301.778297)
			(xy 186.797874 -301.794701) (xy 186.8423 -301.818745) (xy 186.882162 -301.849773) (xy 186.916374 -301.886938)
			(xy 186.944002 -301.929228) (xy 186.964293 -301.975489) (xy 186.976694 -302.024458) (xy 186.980865 -302.0748)
			(xy 186.980862 -302.074834) (xy 187.31917 -302.074834) (xy 187.32313 -302.02578) (xy 187.334907 -301.977996)
			(xy 187.354198 -301.93272) (xy 187.380501 -301.891124) (xy 187.413136 -301.854287) (xy 187.451257 -301.823162)
			(xy 187.493878 -301.798555) (xy 187.539894 -301.781103) (xy 187.588113 -301.771259) (xy 187.637288 -301.769278)
			(xy 187.686143 -301.77521) (xy 187.733414 -301.788902) (xy 187.777876 -301.81) (xy 187.818379 -301.837956)
			(xy 187.853872 -301.872048) (xy 187.883437 -301.911392) (xy 187.906308 -301.954969) (xy 187.921892 -302.00165)
			(xy 187.929787 -302.050227) (xy 187.930282 -302.074834) (xy 188.26913 -302.074834) (xy 188.27309 -302.02578)
			(xy 188.284867 -301.977996) (xy 188.304158 -301.93272) (xy 188.330461 -301.891124) (xy 188.363096 -301.854287)
			(xy 188.401217 -301.823162) (xy 188.443838 -301.798555) (xy 188.489854 -301.781103) (xy 188.538073 -301.771259)
			(xy 188.587248 -301.769278) (xy 188.636103 -301.77521) (xy 188.683374 -301.788902) (xy 188.727836 -301.81)
			(xy 188.768339 -301.837956) (xy 188.803832 -301.872048) (xy 188.833397 -301.911392) (xy 188.856268 -301.954969)
			(xy 188.871852 -302.00165) (xy 188.879747 -302.050227) (xy 188.880242 -302.074834) (xy 188.880076 -302.083066)
			(xy 189.219187 -302.083066) (xy 189.221877 -302.033498) (xy 189.232551 -301.985017) (xy 189.250928 -301.938902)
			(xy 189.276523 -301.896368) (xy 189.308663 -301.858535) (xy 189.3465 -301.8264) (xy 189.389038 -301.80081)
			(xy 189.435155 -301.782439) (xy 189.483637 -301.771771) (xy 189.533206 -301.769088) (xy 189.582557 -301.774459)
			(xy 189.630388 -301.787744) (xy 189.67544 -301.808592) (xy 189.716525 -301.836454) (xy 189.752561 -301.870596)
			(xy 189.782599 -301.910118) (xy 189.805847 -301.95398) (xy 189.821693 -302.001024) (xy 189.829719 -302.050013)
			(xy 189.83004 -302.06653) (xy 191.119415 -302.06653) (xy 191.124779 -302.017186) (xy 191.138056 -301.969361)
			(xy 191.158894 -301.924313) (xy 191.186745 -301.88323) (xy 191.220876 -301.847194) (xy 191.260387 -301.817154)
			(xy 191.304237 -301.793901) (xy 191.351272 -301.778049) (xy 191.400251 -301.770014) (xy 191.425068 -301.769526)
			(xy 191.439251 -301.769707) (xy 191.467491 -301.772376) (xy 191.481456 -301.77486) (xy 191.493902 -301.777146)
			(xy 191.517524 -301.76978) (xy 191.594994 -301.69231) (xy 191.60236 -301.668688) (xy 191.600074 -301.656242)
			(xy 191.597593 -301.642277) (xy 191.594924 -301.614037) (xy 191.59474 -301.599854) (xy 191.595096 -301.575857)
			(xy 191.602611 -301.528456) (xy 191.617449 -301.482813) (xy 191.639244 -301.440054) (xy 191.66746 -301.40123)
			(xy 191.701402 -301.367299) (xy 191.740234 -301.339095) (xy 191.783 -301.317313) (xy 191.828647 -301.302489)
			(xy 191.876051 -301.294989) (xy 191.900048 -301.294546) (xy 191.914231 -301.294731) (xy 191.942471 -301.297397)
			(xy 191.956436 -301.29988) (xy 191.968882 -301.302166) (xy 191.992504 -301.2948) (xy 192.069974 -301.21733)
			(xy 192.07734 -301.193708) (xy 192.075054 -301.181262) (xy 192.072577 -301.167296) (xy 192.069905 -301.139057)
			(xy 192.06972 -301.124874) (xy 192.070206 -301.100056) (xy 192.07824 -301.051075) (xy 192.094092 -301.004039)
			(xy 192.117345 -300.960187) (xy 192.147385 -300.920674) (xy 192.183422 -300.886542) (xy 192.224507 -300.858689)
			(xy 192.269556 -300.837849) (xy 192.317382 -300.824572) (xy 192.366727 -300.819207) (xy 192.41629 -300.821895)
			(xy 192.464765 -300.832566) (xy 192.510875 -300.850939) (xy 192.553406 -300.876529) (xy 192.591236 -300.908663)
			(xy 192.62337 -300.946493) (xy 192.64896 -300.989023) (xy 192.667333 -301.035133) (xy 192.678004 -301.083608)
			(xy 192.680693 -301.133171) (xy 192.675328 -301.182516) (xy 192.662052 -301.230343) (xy 192.641212 -301.275392)
			(xy 192.61336 -301.316476) (xy 192.579227 -301.352513) (xy 192.539715 -301.382554) (xy 192.495863 -301.405807)
			(xy 192.448827 -301.42166) (xy 192.399846 -301.429694) (xy 192.375028 -301.430182) (xy 192.360845 -301.430002)
			(xy 192.332605 -301.427332) (xy 192.31864 -301.424848) (xy 192.306194 -301.422562) (xy 192.282572 -301.429928)
			(xy 192.205102 -301.507398) (xy 192.197736 -301.53102) (xy 192.200022 -301.543466) (xy 192.202504 -301.557431)
			(xy 192.205172 -301.585671) (xy 192.205356 -301.599854) (xy 192.204795 -301.623842) (xy 192.197297 -301.671227)
			(xy 192.182479 -301.716856) (xy 192.160706 -301.759606) (xy 192.132512 -301.798423) (xy 192.098594 -301.832351)
			(xy 192.059786 -301.860556) (xy 192.017043 -301.882343) (xy 191.971419 -301.897175) (xy 191.924035 -301.904688)
			(xy 191.900048 -301.905162) (xy 191.885865 -301.904979) (xy 191.857625 -301.902311) (xy 191.84366 -301.899828)
			(xy 191.831214 -301.897542) (xy 191.807592 -301.904908) (xy 191.730122 -301.982378) (xy 191.722756 -302.006)
			(xy 191.725042 -302.018446) (xy 191.72752 -302.032412) (xy 191.730191 -302.060651) (xy 191.730376 -302.074834)
			(xy 191.729886 -302.099651) (xy 191.721851 -302.14863) (xy 191.705998 -302.195664) (xy 191.682745 -302.239514)
			(xy 191.652705 -302.279025) (xy 191.616668 -302.313156) (xy 191.575585 -302.341007) (xy 191.530537 -302.361845)
			(xy 191.482712 -302.375121) (xy 191.433368 -302.380485) (xy 191.383807 -302.377796) (xy 191.335334 -302.367125)
			(xy 191.289226 -302.348753) (xy 191.246697 -302.323163) (xy 191.208868 -302.29103) (xy 191.176736 -302.253201)
			(xy 191.151147 -302.210672) (xy 191.132774 -302.164564) (xy 191.122103 -302.116091) (xy 191.119415 -302.06653)
			(xy 189.83004 -302.06653) (xy 189.830202 -302.074834) (xy 189.83003 -302.089017) (xy 189.827355 -302.117257)
			(xy 189.824868 -302.131222) (xy 189.822699 -302.145186) (xy 189.825283 -302.173317) (xy 189.835476 -302.199663)
			(xy 189.852496 -302.222208) (xy 189.875043 -302.239227) (xy 189.90139 -302.249418) (xy 189.92952 -302.252001)
			(xy 189.943486 -302.24984) (xy 189.957453 -302.24737) (xy 189.985692 -302.244694) (xy 189.999874 -302.244506)
			(xy 190.024697 -302.24495) (xy 190.07369 -302.252978) (xy 190.120739 -302.268826) (xy 190.164604 -302.292077)
			(xy 190.20413 -302.322119) (xy 190.238274 -302.358159) (xy 190.266138 -302.399249) (xy 190.286988 -302.444305)
			(xy 190.300273 -302.492141) (xy 190.305644 -302.541495) (xy 190.30296 -302.591069) (xy 190.292291 -302.639556)
			(xy 190.273918 -302.685677) (xy 190.248326 -302.728219) (xy 190.216188 -302.766059) (xy 190.178351 -302.798202)
			(xy 190.135813 -302.8238) (xy 190.089694 -302.842179) (xy 190.041209 -302.852855) (xy 189.991636 -302.855545)
			(xy 189.94228 -302.85018) (xy 189.894442 -302.836901) (xy 189.849383 -302.816058) (xy 189.80829 -302.788199)
			(xy 189.772245 -302.754059) (xy 189.742199 -302.714538) (xy 189.718942 -302.670676) (xy 189.703087 -302.623629)
			(xy 189.695053 -302.574637) (xy 189.694566 -302.549814) (xy 189.694745 -302.535631) (xy 189.697416 -302.507391)
			(xy 189.6999 -302.493426) (xy 189.702057 -302.479458) (xy 189.699484 -302.451325) (xy 189.689298 -302.424975)
			(xy 189.672279 -302.402426) (xy 189.649731 -302.385406) (xy 189.623381 -302.375218) (xy 189.595248 -302.372643)
			(xy 189.581282 -302.374808) (xy 189.567316 -302.377283) (xy 189.539076 -302.379956) (xy 189.524894 -302.380142)
			(xy 189.500073 -302.379616) (xy 189.451086 -302.371583) (xy 189.404043 -302.355731) (xy 189.360185 -302.332478)
			(xy 189.320666 -302.302434) (xy 189.286529 -302.266394) (xy 189.258672 -302.225305) (xy 189.23783 -302.18025)
			(xy 189.224552 -302.132417) (xy 189.219187 -302.083066) (xy 188.880076 -302.083066) (xy 188.879747 -302.099441)
			(xy 188.871852 -302.148018) (xy 188.856268 -302.194699) (xy 188.833397 -302.238276) (xy 188.803832 -302.27762)
			(xy 188.768339 -302.311712) (xy 188.727836 -302.339668) (xy 188.683374 -302.360766) (xy 188.636103 -302.374458)
			(xy 188.587248 -302.38039) (xy 188.538073 -302.378409) (xy 188.489854 -302.368565) (xy 188.443838 -302.351113)
			(xy 188.401217 -302.326506) (xy 188.363096 -302.295381) (xy 188.330461 -302.258544) (xy 188.304158 -302.216948)
			(xy 188.284867 -302.171672) (xy 188.27309 -302.123888) (xy 188.26913 -302.074834) (xy 187.930282 -302.074834)
			(xy 187.929787 -302.099441) (xy 187.921892 -302.148018) (xy 187.906308 -302.194699) (xy 187.883437 -302.238276)
			(xy 187.853872 -302.27762) (xy 187.818379 -302.311712) (xy 187.777876 -302.339668) (xy 187.733414 -302.360766)
			(xy 187.686143 -302.374458) (xy 187.637288 -302.38039) (xy 187.588113 -302.378409) (xy 187.539894 -302.368565)
			(xy 187.493878 -302.351113) (xy 187.451257 -302.326506) (xy 187.413136 -302.295381) (xy 187.380501 -302.258544)
			(xy 187.354198 -302.216948) (xy 187.334907 -302.171672) (xy 187.32313 -302.123888) (xy 187.31917 -302.074834)
			(xy 186.980862 -302.074834) (xy 186.976694 -302.125142) (xy 186.964293 -302.174111) (xy 186.944002 -302.220372)
			(xy 186.916374 -302.262662) (xy 186.882162 -302.299827) (xy 186.8423 -302.330855) (xy 186.797874 -302.354899)
			(xy 186.750097 -302.371303) (xy 186.700271 -302.379619) (xy 186.675014 -302.380142) (xy 186.647022 -302.37951)
			(xy 186.591976 -302.369309) (xy 186.539705 -302.349261) (xy 186.515502 -302.335184) (xy 186.507624 -302.330722)
			(xy 186.489874 -302.327193) (xy 186.472003 -302.330046) (xy 186.46394 -302.334168) (xy 186.40298 -302.368458)
			(xy 186.395318 -302.373162) (xy 186.383639 -302.386814) (xy 186.377423 -302.403671) (xy 186.377072 -302.412654)
			(xy 186.377072 -302.686974) (xy 186.377491 -302.695946) (xy 186.383714 -302.712778) (xy 186.395343 -302.726447)
			(xy 186.40298 -302.73117) (xy 186.46394 -302.76546) (xy 186.472011 -302.769564) (xy 186.489873 -302.77243)
			(xy 186.507613 -302.768885) (xy 186.515502 -302.764444) (xy 186.539707 -302.750369) (xy 186.591975 -302.730312)
			(xy 186.647022 -302.720114) (xy 186.675014 -302.719486) (xy 186.700268 -302.720021) (xy 186.750087 -302.728336)
			(xy 186.797858 -302.744738) (xy 186.842278 -302.768778) (xy 186.882135 -302.799802) (xy 186.916343 -302.836963)
			(xy 186.943967 -302.879247) (xy 186.964256 -302.925502) (xy 186.976654 -302.974464) (xy 186.980825 -303.024794)
			(xy 187.31917 -303.024794) (xy 187.32313 -302.97574) (xy 187.334907 -302.927956) (xy 187.354198 -302.88268)
			(xy 187.380501 -302.841084) (xy 187.413136 -302.804247) (xy 187.451257 -302.773122) (xy 187.493878 -302.748515)
			(xy 187.539894 -302.731063) (xy 187.588113 -302.721219) (xy 187.637288 -302.719238) (xy 187.686143 -302.72517)
			(xy 187.733414 -302.738862) (xy 187.777876 -302.75996) (xy 187.818379 -302.787916) (xy 187.853872 -302.822008)
			(xy 187.883437 -302.861352) (xy 187.906308 -302.904929) (xy 187.921892 -302.95161) (xy 187.929787 -303.000187)
			(xy 187.930282 -303.024794) (xy 188.26913 -303.024794) (xy 188.27309 -302.97574) (xy 188.284867 -302.927956)
			(xy 188.304158 -302.88268) (xy 188.330461 -302.841084) (xy 188.363096 -302.804247) (xy 188.401217 -302.773122)
			(xy 188.443838 -302.748515) (xy 188.489854 -302.731063) (xy 188.538073 -302.721219) (xy 188.587248 -302.719238)
			(xy 188.636103 -302.72517) (xy 188.683374 -302.738862) (xy 188.727836 -302.75996) (xy 188.768339 -302.787916)
			(xy 188.803832 -302.822008) (xy 188.833397 -302.861352) (xy 188.856268 -302.904929) (xy 188.871852 -302.95161)
			(xy 188.879747 -303.000187) (xy 188.880242 -303.024794) (xy 188.879747 -303.049401) (xy 188.871852 -303.097978)
			(xy 188.856268 -303.144659) (xy 188.833397 -303.188236) (xy 188.803832 -303.22758) (xy 188.768339 -303.261672)
			(xy 188.727836 -303.289628) (xy 188.683374 -303.310726) (xy 188.636103 -303.324418) (xy 188.587248 -303.33035)
			(xy 188.538073 -303.328369) (xy 188.489854 -303.318525) (xy 188.443838 -303.301073) (xy 188.401217 -303.276466)
			(xy 188.363096 -303.245341) (xy 188.330461 -303.208504) (xy 188.304158 -303.166908) (xy 188.284867 -303.121632)
			(xy 188.27309 -303.073848) (xy 188.26913 -303.024794) (xy 187.930282 -303.024794) (xy 187.929787 -303.049401)
			(xy 187.921892 -303.097978) (xy 187.906308 -303.144659) (xy 187.883437 -303.188236) (xy 187.853872 -303.22758)
			(xy 187.818379 -303.261672) (xy 187.777876 -303.289628) (xy 187.733414 -303.310726) (xy 187.686143 -303.324418)
			(xy 187.637288 -303.33035) (xy 187.588113 -303.328369) (xy 187.539894 -303.318525) (xy 187.493878 -303.301073)
			(xy 187.451257 -303.276466) (xy 187.413136 -303.245341) (xy 187.380501 -303.208504) (xy 187.354198 -303.166908)
			(xy 187.334907 -303.121632) (xy 187.32313 -303.073848) (xy 187.31917 -303.024794) (xy 186.980825 -303.024794)
			(xy 186.980825 -303.0248) (xy 186.976654 -303.075136) (xy 186.964256 -303.124098) (xy 186.943967 -303.170353)
			(xy 186.916343 -303.212637) (xy 186.882135 -303.249798) (xy 186.842278 -303.280822) (xy 186.797858 -303.304862)
			(xy 186.750087 -303.321264) (xy 186.700268 -303.329579) (xy 186.675014 -303.330102) (xy 186.647023 -303.329462)
			(xy 186.591977 -303.319262) (xy 186.539705 -303.299219) (xy 186.515502 -303.285144) (xy 186.507624 -303.280679)
			(xy 186.489874 -303.277146) (xy 186.472002 -303.280002) (xy 186.46394 -303.284128) (xy 186.40298 -303.318418)
			(xy 186.395291 -303.323084) (xy 186.383616 -303.336753) (xy 186.377413 -303.353625) (xy 186.377072 -303.362614)
			(xy 186.377072 -303.499774) (xy 189.69407 -303.499774) (xy 189.69803 -303.45072) (xy 189.709807 -303.402936)
			(xy 189.729098 -303.35766) (xy 189.755401 -303.316064) (xy 189.788036 -303.279227) (xy 189.826157 -303.248102)
			(xy 189.868778 -303.223495) (xy 189.914794 -303.206043) (xy 189.963013 -303.196199) (xy 190.012188 -303.194218)
			(xy 190.061043 -303.20015) (xy 190.108314 -303.213842) (xy 190.152776 -303.23494) (xy 190.193279 -303.262896)
			(xy 190.228772 -303.296988) (xy 190.258337 -303.336332) (xy 190.281208 -303.379909) (xy 190.296792 -303.42659)
			(xy 190.304687 -303.475167) (xy 190.305182 -303.499774) (xy 190.644284 -303.499774) (xy 190.648244 -303.45072)
			(xy 190.660021 -303.402936) (xy 190.679312 -303.35766) (xy 190.705615 -303.316064) (xy 190.73825 -303.279227)
			(xy 190.776371 -303.248102) (xy 190.818992 -303.223495) (xy 190.865008 -303.206043) (xy 190.913227 -303.196199)
			(xy 190.962402 -303.194218) (xy 191.011257 -303.20015) (xy 191.058528 -303.213842) (xy 191.10299 -303.23494)
			(xy 191.143493 -303.262896) (xy 191.178986 -303.296988) (xy 191.208551 -303.336332) (xy 191.231422 -303.379909)
			(xy 191.247006 -303.42659) (xy 191.254901 -303.475167) (xy 191.255396 -303.499774) (xy 191.594244 -303.499774)
			(xy 191.598204 -303.45072) (xy 191.609981 -303.402936) (xy 191.629272 -303.35766) (xy 191.655575 -303.316064)
			(xy 191.68821 -303.279227) (xy 191.726331 -303.248102) (xy 191.768952 -303.223495) (xy 191.814968 -303.206043)
			(xy 191.863187 -303.196199) (xy 191.912362 -303.194218) (xy 191.961217 -303.20015) (xy 192.008488 -303.213842)
			(xy 192.05295 -303.23494) (xy 192.093453 -303.262896) (xy 192.128946 -303.296988) (xy 192.158511 -303.336332)
			(xy 192.181382 -303.379909) (xy 192.196966 -303.42659) (xy 192.204861 -303.475167) (xy 192.205356 -303.499774)
			(xy 192.204861 -303.524381) (xy 192.196966 -303.572958) (xy 192.181382 -303.619639) (xy 192.158511 -303.663216)
			(xy 192.128946 -303.70256) (xy 192.093453 -303.736652) (xy 192.05295 -303.764608) (xy 192.008488 -303.785706)
			(xy 191.961217 -303.799398) (xy 191.912362 -303.80533) (xy 191.863187 -303.803349) (xy 191.814968 -303.793505)
			(xy 191.768952 -303.776053) (xy 191.726331 -303.751446) (xy 191.68821 -303.720321) (xy 191.655575 -303.683484)
			(xy 191.629272 -303.641888) (xy 191.609981 -303.596612) (xy 191.598204 -303.548828) (xy 191.594244 -303.499774)
			(xy 191.255396 -303.499774) (xy 191.254901 -303.524381) (xy 191.247006 -303.572958) (xy 191.231422 -303.619639)
			(xy 191.208551 -303.663216) (xy 191.178986 -303.70256) (xy 191.143493 -303.736652) (xy 191.10299 -303.764608)
			(xy 191.058528 -303.785706) (xy 191.011257 -303.799398) (xy 190.962402 -303.80533) (xy 190.913227 -303.803349)
			(xy 190.865008 -303.793505) (xy 190.818992 -303.776053) (xy 190.776371 -303.751446) (xy 190.73825 -303.720321)
			(xy 190.705615 -303.683484) (xy 190.679312 -303.641888) (xy 190.660021 -303.596612) (xy 190.648244 -303.548828)
			(xy 190.644284 -303.499774) (xy 190.305182 -303.499774) (xy 190.304687 -303.524381) (xy 190.296792 -303.572958)
			(xy 190.281208 -303.619639) (xy 190.258337 -303.663216) (xy 190.228772 -303.70256) (xy 190.193279 -303.736652)
			(xy 190.152776 -303.764608) (xy 190.108314 -303.785706) (xy 190.061043 -303.799398) (xy 190.012188 -303.80533)
			(xy 189.963013 -303.803349) (xy 189.914794 -303.793505) (xy 189.868778 -303.776053) (xy 189.826157 -303.751446)
			(xy 189.788036 -303.720321) (xy 189.755401 -303.683484) (xy 189.729098 -303.641888) (xy 189.709807 -303.596612)
			(xy 189.69803 -303.548828) (xy 189.69407 -303.499774) (xy 186.377072 -303.499774) (xy 186.377072 -303.645316)
			(xy 186.376777 -303.66319) (xy 186.372703 -303.698706) (xy 186.368944 -303.716182) (xy 186.367674 -303.72939)
			(xy 186.368528 -303.739303) (xy 186.376721 -303.75741) (xy 186.391178 -303.771047) (xy 186.409732 -303.778169)
			(xy 186.4296 -303.777709) (xy 186.447805 -303.769735) (xy 186.45505 -303.762918) (xy 186.47245 -303.745565)
			(xy 186.511779 -303.716106) (xy 186.555316 -303.693321) (xy 186.601939 -303.677798) (xy 186.650445 -303.669936)
			(xy 186.675014 -303.669446) (xy 186.700265 -303.670061) (xy 186.750077 -303.678375) (xy 186.797842 -303.694774)
			(xy 186.842256 -303.718812) (xy 186.882108 -303.749832) (xy 186.916311 -303.786988) (xy 186.943932 -303.829266)
			(xy 186.964218 -303.875515) (xy 186.976615 -303.924471) (xy 186.980781 -303.974754) (xy 187.31917 -303.974754)
			(xy 187.32313 -303.9257) (xy 187.334907 -303.877916) (xy 187.354198 -303.83264) (xy 187.380501 -303.791044)
			(xy 187.413136 -303.754207) (xy 187.451257 -303.723082) (xy 187.493878 -303.698475) (xy 187.539894 -303.681023)
			(xy 187.588113 -303.671179) (xy 187.637288 -303.669198) (xy 187.686143 -303.67513) (xy 187.733414 -303.688822)
			(xy 187.777876 -303.70992) (xy 187.818379 -303.737876) (xy 187.853872 -303.771968) (xy 187.883437 -303.811312)
			(xy 187.906308 -303.854889) (xy 187.921892 -303.90157) (xy 187.929787 -303.950147) (xy 187.930282 -303.974754)
			(xy 188.26913 -303.974754) (xy 188.27309 -303.9257) (xy 188.284867 -303.877916) (xy 188.304158 -303.83264)
			(xy 188.330461 -303.791044) (xy 188.363096 -303.754207) (xy 188.401217 -303.723082) (xy 188.443838 -303.698475)
			(xy 188.489854 -303.681023) (xy 188.538073 -303.671179) (xy 188.587248 -303.669198) (xy 188.636103 -303.67513)
			(xy 188.683374 -303.688822) (xy 188.727836 -303.70992) (xy 188.768339 -303.737876) (xy 188.803832 -303.771968)
			(xy 188.833397 -303.811312) (xy 188.856268 -303.854889) (xy 188.871852 -303.90157) (xy 188.879747 -303.950147)
			(xy 188.880242 -303.974754) (xy 188.879747 -303.999361) (xy 188.871852 -304.047938) (xy 188.856268 -304.094619)
			(xy 188.833397 -304.138196) (xy 188.803832 -304.17754) (xy 188.768339 -304.211632) (xy 188.727836 -304.239588)
			(xy 188.683374 -304.260686) (xy 188.636103 -304.274378) (xy 188.587248 -304.28031) (xy 188.538073 -304.278329)
			(xy 188.489854 -304.268485) (xy 188.443838 -304.251033) (xy 188.401217 -304.226426) (xy 188.363096 -304.195301)
			(xy 188.330461 -304.158464) (xy 188.304158 -304.116868) (xy 188.284867 -304.071592) (xy 188.27309 -304.023808)
			(xy 188.26913 -303.974754) (xy 187.930282 -303.974754) (xy 187.929787 -303.999361) (xy 187.921892 -304.047938)
			(xy 187.906308 -304.094619) (xy 187.883437 -304.138196) (xy 187.853872 -304.17754) (xy 187.818379 -304.211632)
			(xy 187.777876 -304.239588) (xy 187.733414 -304.260686) (xy 187.686143 -304.274378) (xy 187.637288 -304.28031)
			(xy 187.588113 -304.278329) (xy 187.539894 -304.268485) (xy 187.493878 -304.251033) (xy 187.451257 -304.226426)
			(xy 187.413136 -304.195301) (xy 187.380501 -304.158464) (xy 187.354198 -304.116868) (xy 187.334907 -304.071592)
			(xy 187.32313 -304.023808) (xy 187.31917 -303.974754) (xy 186.980781 -303.974754) (xy 186.980785 -303.9748)
			(xy 186.976615 -304.025129) (xy 186.964218 -304.074085) (xy 186.943932 -304.120334) (xy 186.916311 -304.162612)
			(xy 186.882108 -304.199768) (xy 186.842256 -304.230788) (xy 186.797842 -304.254826) (xy 186.750077 -304.271225)
			(xy 186.700265 -304.279539) (xy 186.675014 -304.280062) (xy 186.649069 -304.279595) (xy 186.597924 -304.270826)
			(xy 186.548998 -304.25354) (xy 186.503697 -304.228232) (xy 186.463326 -304.195631) (xy 186.429046 -304.156676)
			(xy 186.401843 -304.112487) (xy 186.382501 -304.064336) (xy 186.371576 -304.013608) (xy 186.36996 -303.987708)
			(xy 186.36996 -303.987454) (xy 186.36922 -303.978651) (xy 186.362517 -303.962322) (xy 186.350659 -303.949246)
			(xy 186.343036 -303.944782) (xy 186.269884 -303.906174) (xy 186.242198 -303.90719) (xy 186.230768 -303.91481)
			(xy 186.221028 -303.920962) (xy 186.200814 -303.932019) (xy 186.190382 -303.936908) (xy 186.041538 -304.005742)
			(xy 186.026806 -304.024538) (xy 186.024266 -304.036476) (xy 186.018489 -304.061952) (xy 185.999351 -304.110557)
			(xy 185.972229 -304.1552) (xy 185.937912 -304.194583) (xy 185.897399 -304.227558) (xy 185.85187 -304.253166)
			(xy 185.80265 -304.270661) (xy 185.751172 -304.279533) (xy 185.725054 -304.280062) (xy 185.721244 -304.280062)
			(xy 185.712365 -304.280339) (xy 185.695625 -304.286249) (xy 185.681904 -304.297514) (xy 185.677048 -304.304954)
			(xy 185.622184 -304.397156) (xy 185.609653 -304.417366) (xy 185.583293 -304.449734) (xy 189.69407 -304.449734)
			(xy 189.69803 -304.40068) (xy 189.709807 -304.352896) (xy 189.729098 -304.30762) (xy 189.755401 -304.266024)
			(xy 189.788036 -304.229187) (xy 189.826157 -304.198062) (xy 189.868778 -304.173455) (xy 189.914794 -304.156003)
			(xy 189.963013 -304.146159) (xy 190.012188 -304.144178) (xy 190.061043 -304.15011) (xy 190.108314 -304.163802)
			(xy 190.152776 -304.1849) (xy 190.193279 -304.212856) (xy 190.228772 -304.246948) (xy 190.258337 -304.286292)
			(xy 190.281208 -304.329869) (xy 190.296792 -304.37655) (xy 190.304687 -304.425127) (xy 190.305182 -304.449734)
			(xy 190.304687 -304.474341) (xy 190.304508 -304.475442) (xy 190.62344 -304.475442) (xy 190.62344 -304.424026)
			(xy 190.631483 -304.373244) (xy 190.647371 -304.324345) (xy 190.670714 -304.278533) (xy 190.700935 -304.236937)
			(xy 190.737291 -304.200581) (xy 190.778887 -304.17036) (xy 190.824699 -304.147017) (xy 190.873598 -304.131129)
			(xy 190.92438 -304.123086) (xy 190.975796 -304.123086) (xy 191.026578 -304.131129) (xy 191.075477 -304.147017)
			(xy 191.121289 -304.17036) (xy 191.162885 -304.200581) (xy 191.199241 -304.236937) (xy 191.229462 -304.278533)
			(xy 191.252805 -304.324345) (xy 191.268693 -304.373244) (xy 191.276736 -304.424026) (xy 191.27724 -304.449734)
			(xy 191.276736 -304.475442) (xy 191.5734 -304.475442) (xy 191.5734 -304.424026) (xy 191.581443 -304.373244)
			(xy 191.597331 -304.324345) (xy 191.620674 -304.278533) (xy 191.650895 -304.236937) (xy 191.687251 -304.200581)
			(xy 191.728847 -304.17036) (xy 191.774659 -304.147017) (xy 191.823558 -304.131129) (xy 191.87434 -304.123086)
			(xy 191.925756 -304.123086) (xy 191.976538 -304.131129) (xy 192.025437 -304.147017) (xy 192.071249 -304.17036)
			(xy 192.112845 -304.200581) (xy 192.149201 -304.236937) (xy 192.179422 -304.278533) (xy 192.202765 -304.324345)
			(xy 192.218653 -304.373244) (xy 192.226696 -304.424026) (xy 192.2272 -304.449734) (xy 192.226696 -304.475442)
			(xy 192.218653 -304.526224) (xy 192.202765 -304.575123) (xy 192.179422 -304.620935) (xy 192.149201 -304.662531)
			(xy 192.112845 -304.698887) (xy 192.071249 -304.729108) (xy 192.025437 -304.752451) (xy 191.976538 -304.768339)
			(xy 191.925756 -304.776382) (xy 191.87434 -304.776382) (xy 191.823558 -304.768339) (xy 191.774659 -304.752451)
			(xy 191.728847 -304.729108) (xy 191.687251 -304.698887) (xy 191.650895 -304.662531) (xy 191.620674 -304.620935)
			(xy 191.597331 -304.575123) (xy 191.581443 -304.526224) (xy 191.5734 -304.475442) (xy 191.276736 -304.475442)
			(xy 191.268693 -304.526224) (xy 191.252805 -304.575123) (xy 191.229462 -304.620935) (xy 191.199241 -304.662531)
			(xy 191.162885 -304.698887) (xy 191.121289 -304.729108) (xy 191.075477 -304.752451) (xy 191.026578 -304.768339)
			(xy 190.975796 -304.776382) (xy 190.92438 -304.776382) (xy 190.873598 -304.768339) (xy 190.824699 -304.752451)
			(xy 190.778887 -304.729108) (xy 190.737291 -304.698887) (xy 190.700935 -304.662531) (xy 190.670714 -304.620935)
			(xy 190.647371 -304.575123) (xy 190.631483 -304.526224) (xy 190.62344 -304.475442) (xy 190.304508 -304.475442)
			(xy 190.296792 -304.522918) (xy 190.281208 -304.569599) (xy 190.258337 -304.613176) (xy 190.228772 -304.65252)
			(xy 190.193279 -304.686612) (xy 190.152776 -304.714568) (xy 190.108314 -304.735666) (xy 190.061043 -304.749358)
			(xy 190.012188 -304.75529) (xy 189.963013 -304.753309) (xy 189.914794 -304.743465) (xy 189.868778 -304.726013)
			(xy 189.826157 -304.701406) (xy 189.788036 -304.670281) (xy 189.755401 -304.633444) (xy 189.729098 -304.591848)
			(xy 189.709807 -304.546572) (xy 189.69803 -304.498788) (xy 189.69407 -304.449734) (xy 185.583293 -304.449734)
			(xy 185.579627 -304.454235) (xy 185.544501 -304.486283) (xy 185.505041 -304.512813) (xy 185.462105 -304.533246)
			(xy 185.41663 -304.547137) (xy 185.369606 -304.554184) (xy 185.345832 -304.554636) (xy 185.156094 -304.554636)
			(xy 185.132192 -304.554115) (xy 185.084923 -304.546976) (xy 185.039233 -304.532916) (xy 184.996128 -304.512245)
			(xy 184.956559 -304.485419) (xy 184.921399 -304.45303) (xy 184.891424 -304.415791) (xy 184.87898 -304.395378)
			(xy 184.81675 -304.289206) (xy 184.793382 -304.275744) (xy 184.780174 -304.275744) (xy 184.771306 -304.276069)
			(xy 184.754615 -304.282055) (xy 184.740985 -304.293398) (xy 184.736232 -304.30089) (xy 184.68086 -304.395378)
			(xy 184.6684 -304.415782) (xy 184.638425 -304.453022) (xy 184.603267 -304.485415) (xy 184.563703 -304.512248)
			(xy 184.520602 -304.532929) (xy 184.474915 -304.547002) (xy 184.427648 -304.554158) (xy 184.403746 -304.554636)
			(xy 184.204102 -304.554636) (xy 184.180325 -304.554177) (xy 184.133291 -304.547155) (xy 184.087806 -304.533281)
			(xy 184.044861 -304.512855) (xy 184.005395 -304.486325) (xy 183.970268 -304.45427) (xy 183.940248 -304.417388)
			(xy 183.92775 -304.397156) (xy 183.872886 -304.304954) (xy 183.868021 -304.297522) (xy 183.854306 -304.286256)
			(xy 183.837567 -304.280357) (xy 183.82869 -304.280062) (xy 183.82107 -304.280062) (xy 183.812192 -304.280358)
			(xy 183.795453 -304.286259) (xy 183.781732 -304.297517) (xy 183.776874 -304.304954) (xy 183.72201 -304.397156)
			(xy 183.70953 -304.417399) (xy 183.679496 -304.454268) (xy 183.644361 -304.486315) (xy 183.604892 -304.512841)
			(xy 183.561948 -304.533268) (xy 183.516466 -304.547152) (xy 183.469435 -304.554189) (xy 183.445658 -304.554636)
			(xy 183.254142 -304.554636) (xy 183.230363 -304.554224) (xy 183.183328 -304.547194) (xy 183.137841 -304.533311)
			(xy 183.094896 -304.512878) (xy 183.05543 -304.48634) (xy 183.020305 -304.454278) (xy 182.990287 -304.417391)
			(xy 182.97779 -304.397156) (xy 182.922926 -304.304954) (xy 182.918036 -304.29754) (xy 182.904333 -304.286271)
			(xy 182.887604 -304.280364) (xy 182.87873 -304.280062) (xy 182.87111 -304.280062) (xy 182.862235 -304.280386)
			(xy 182.845497 -304.286274) (xy 182.831773 -304.297521) (xy 182.826914 -304.304954) (xy 182.77205 -304.397156)
			(xy 182.759543 -304.417381) (xy 182.729512 -304.45425) (xy 182.694383 -304.486298) (xy 182.654918 -304.512826)
			(xy 182.611979 -304.533256) (xy 182.566501 -304.547144) (xy 182.519473 -304.554187) (xy 182.495698 -304.554636)
			(xy 182.304182 -304.554636) (xy 182.280404 -304.554192) (xy 182.23337 -304.547168) (xy 182.187884 -304.533291)
			(xy 182.144939 -304.512863) (xy 182.105473 -304.48633) (xy 182.070347 -304.454273) (xy 182.040328 -304.417389)
			(xy 182.02783 -304.397156) (xy 181.972966 -304.304954) (xy 181.968113 -304.297513) (xy 181.954393 -304.286249)
			(xy 181.937649 -304.280354) (xy 181.92877 -304.280062) (xy 181.92115 -304.280062) (xy 181.912271 -304.280344)
			(xy 181.895531 -304.286251) (xy 181.88181 -304.297515) (xy 181.876954 -304.304954) (xy 181.82209 -304.397156)
			(xy 181.809555 -304.417363) (xy 181.779529 -304.454232) (xy 181.744404 -304.486281) (xy 181.704945 -304.512811)
			(xy 181.66201 -304.533244) (xy 181.616536 -304.547136) (xy 181.569512 -304.554184) (xy 181.545738 -304.554636)
			(xy 181.354222 -304.554636) (xy 181.330445 -304.554161) (xy 181.283413 -304.547142) (xy 181.237927 -304.533271)
			(xy 181.194983 -304.512848) (xy 181.155516 -304.48632) (xy 181.120389 -304.454267) (xy 181.090368 -304.417387)
			(xy 181.07787 -304.397156) (xy 181.023006 -304.304954) (xy 181.018128 -304.297531) (xy 181.00442 -304.286264)
			(xy 180.987686 -304.28036) (xy 180.97881 -304.280062) (xy 180.97119 -304.280062) (xy 180.962313 -304.280372)
			(xy 180.945575 -304.286267) (xy 180.931852 -304.297519) (xy 180.926994 -304.304954) (xy 180.87213 -304.397156)
			(xy 180.859636 -304.41739) (xy 180.829604 -304.454259) (xy 180.794472 -304.486306) (xy 180.755005 -304.512833)
			(xy 180.712064 -304.533262) (xy 180.666583 -304.547148) (xy 180.619554 -304.554188) (xy 180.595778 -304.554636)
			(xy 180.404262 -304.554636) (xy 180.380484 -304.554208) (xy 180.333449 -304.547181) (xy 180.287963 -304.533301)
			(xy 180.245018 -304.51287) (xy 180.205552 -304.486335) (xy 180.170426 -304.454275) (xy 180.140407 -304.41739)
			(xy 180.12791 -304.397156) (xy 180.073046 -304.304954) (xy 180.068205 -304.297503) (xy 180.05448 -304.286241)
			(xy 180.037731 -304.280351) (xy 180.02885 -304.280062) (xy 180.02123 -304.280062) (xy 180.012356 -304.2804)
			(xy 179.995618 -304.286282) (xy 179.981894 -304.297524) (xy 179.977034 -304.304954) (xy 179.92217 -304.397156)
			(xy 179.909649 -304.417372) (xy 179.879621 -304.454241) (xy 179.844493 -304.486289) (xy 179.805031 -304.512818)
			(xy 179.762095 -304.53325) (xy 179.716618 -304.54714) (xy 179.669593 -304.554185) (xy 179.645818 -304.554636)
			(xy 179.454302 -304.554636) (xy 179.430525 -304.554177) (xy 179.383491 -304.547155) (xy 179.338006 -304.533281)
			(xy 179.295061 -304.512855) (xy 179.255595 -304.486325) (xy 179.220468 -304.45427) (xy 179.190448 -304.417388)
			(xy 179.17795 -304.397156) (xy 179.123086 -304.304954) (xy 179.118221 -304.297522) (xy 179.104506 -304.286256)
			(xy 179.087767 -304.280357) (xy 179.07889 -304.280062) (xy 179.07127 -304.280062) (xy 179.062392 -304.280358)
			(xy 179.045653 -304.286259) (xy 179.031932 -304.297517) (xy 179.027074 -304.304954) (xy 178.97221 -304.397156)
			(xy 178.95973 -304.417399) (xy 178.929696 -304.454268) (xy 178.894561 -304.486315) (xy 178.855092 -304.512841)
			(xy 178.812148 -304.533268) (xy 178.766666 -304.547152) (xy 178.719635 -304.554189) (xy 178.695858 -304.554636)
			(xy 178.504088 -304.554636) (xy 178.48031 -304.554188) (xy 178.433276 -304.547164) (xy 178.387791 -304.533288)
			(xy 178.344846 -304.512861) (xy 178.30538 -304.486329) (xy 178.270253 -304.454272) (xy 178.240234 -304.417389)
			(xy 178.227736 -304.397156) (xy 178.172872 -304.304954) (xy 178.168015 -304.297515) (xy 178.154297 -304.286251)
			(xy 178.137555 -304.280355) (xy 178.128676 -304.280062) (xy 178.121056 -304.280062) (xy 178.112178 -304.280348)
			(xy 178.095438 -304.286253) (xy 178.081717 -304.297515) (xy 178.07686 -304.304954) (xy 178.021996 -304.397156)
			(xy 178.009457 -304.41736) (xy 177.979432 -304.45423) (xy 177.944307 -304.486278) (xy 177.904849 -304.512809)
			(xy 177.861915 -304.533242) (xy 177.816441 -304.547135) (xy 177.769418 -304.554183) (xy 177.745644 -304.554636)
			(xy 177.554128 -304.554636) (xy 177.530352 -304.554156) (xy 177.483319 -304.547139) (xy 177.437834 -304.533268)
			(xy 177.394889 -304.512846) (xy 177.355423 -304.486319) (xy 177.320295 -304.454266) (xy 177.290274 -304.417387)
			(xy 177.277776 -304.397156) (xy 177.222912 -304.304954) (xy 177.218031 -304.297534) (xy 177.204324 -304.286266)
			(xy 177.187591 -304.280361) (xy 177.178716 -304.280062) (xy 177.171096 -304.280062) (xy 177.16222 -304.280376)
			(xy 177.145481 -304.286269) (xy 177.131759 -304.29752) (xy 177.1269 -304.304954) (xy 177.072036 -304.397156)
			(xy 177.059538 -304.417387) (xy 177.029507 -304.454256) (xy 176.994375 -304.486304) (xy 176.954909 -304.512831)
			(xy 176.911968 -304.53326) (xy 176.866488 -304.547147) (xy 176.81946 -304.554188) (xy 176.795684 -304.554636)
			(xy 176.604168 -304.554636) (xy 176.58039 -304.554203) (xy 176.533355 -304.547177) (xy 176.487869 -304.533298)
			(xy 176.444924 -304.512868) (xy 176.405458 -304.486334) (xy 176.370332 -304.454275) (xy 176.340313 -304.41739)
			(xy 176.327816 -304.397156) (xy 176.272952 -304.304954) (xy 176.268108 -304.297506) (xy 176.254384 -304.286243)
			(xy 176.237636 -304.280352) (xy 176.228756 -304.280062) (xy 176.221136 -304.280062) (xy 176.212256 -304.280334)
			(xy 176.195516 -304.286246) (xy 176.181796 -304.297513) (xy 176.17694 -304.304954) (xy 176.122076 -304.397156)
			(xy 176.109551 -304.417369) (xy 176.079524 -304.454239) (xy 176.044397 -304.486287) (xy 176.004935 -304.512816)
			(xy 175.961999 -304.533248) (xy 175.916523 -304.547139) (xy 175.869498 -304.554185) (xy 175.845724 -304.554636)
			(xy 174.704248 -304.554636) (xy 174.680469 -304.554219) (xy 174.633434 -304.54719) (xy 174.587947 -304.533308)
			(xy 174.545003 -304.512875) (xy 174.505537 -304.486339) (xy 174.470411 -304.454277) (xy 174.440393 -304.417391)
			(xy 174.427896 -304.397156) (xy 174.373032 -304.304954) (xy 174.3682 -304.297497) (xy 174.354471 -304.286236)
			(xy 174.337718 -304.280349) (xy 174.328836 -304.280062) (xy 174.321216 -304.280062) (xy 174.312341 -304.28039)
			(xy 174.295603 -304.286276) (xy 174.281879 -304.297522) (xy 174.27702 -304.304954) (xy 174.222156 -304.397156)
			(xy 174.209645 -304.417378) (xy 174.179615 -304.454247) (xy 174.144486 -304.486295) (xy 174.105022 -304.512824)
			(xy 174.062084 -304.533254) (xy 174.016606 -304.547143) (xy 173.969579 -304.554186) (xy 173.945804 -304.554636)
			(xy 173.754288 -304.554636) (xy 173.73051 -304.554188) (xy 173.683476 -304.547164) (xy 173.637991 -304.533288)
			(xy 173.595046 -304.512861) (xy 173.55558 -304.486329) (xy 173.520453 -304.454272) (xy 173.490434 -304.417389)
			(xy 173.477936 -304.397156) (xy 173.423072 -304.304954) (xy 173.418215 -304.297515) (xy 173.404497 -304.286251)
			(xy 173.387755 -304.280355) (xy 173.378876 -304.280062) (xy 173.371256 -304.280062) (xy 173.362378 -304.280348)
			(xy 173.345638 -304.286253) (xy 173.331917 -304.297515) (xy 173.32706 -304.304954) (xy 173.272196 -304.397156)
			(xy 173.259657 -304.41736) (xy 173.229632 -304.45423) (xy 173.194507 -304.486278) (xy 173.155049 -304.512809)
			(xy 173.112115 -304.533242) (xy 173.066641 -304.547135) (xy 173.019618 -304.554183) (xy 172.995844 -304.554636)
			(xy 172.804074 -304.554636) (xy 172.780296 -304.554199) (xy 172.733262 -304.547173) (xy 172.687776 -304.533295)
			(xy 172.644831 -304.512866) (xy 172.605365 -304.486332) (xy 172.570239 -304.454274) (xy 172.54022 -304.41739)
			(xy 172.527722 -304.397156) (xy 172.472858 -304.304954) (xy 172.46801 -304.297509) (xy 172.454288 -304.286245)
			(xy 172.437542 -304.280353) (xy 172.428662 -304.280062) (xy 172.421042 -304.280062) (xy 172.412163 -304.280338)
			(xy 172.395423 -304.286248) (xy 172.381702 -304.297514) (xy 172.376846 -304.304954) (xy 172.321982 -304.397156)
			(xy 172.309453 -304.417367) (xy 172.279426 -304.454236) (xy 172.2443 -304.486284) (xy 172.204839 -304.512814)
			(xy 172.161904 -304.533247) (xy 172.116429 -304.547138) (xy 172.069404 -304.554184) (xy 172.04563 -304.554636)
			(xy 171.854114 -304.554636) (xy 171.830337 -304.554167) (xy 171.783304 -304.547148) (xy 171.737819 -304.533275)
			(xy 171.694874 -304.512851) (xy 171.655408 -304.486322) (xy 171.620281 -304.454268) (xy 171.59026 -304.417388)
			(xy 171.577762 -304.397156) (xy 171.522898 -304.304954) (xy 171.518025 -304.297527) (xy 171.504314 -304.286261)
			(xy 171.487578 -304.280359) (xy 171.478702 -304.280062) (xy 171.471082 -304.280062) (xy 171.462205 -304.280366)
			(xy 171.445466 -304.286264) (xy 171.431744 -304.297518) (xy 171.426886 -304.304954) (xy 171.372022 -304.397156)
			(xy 171.359534 -304.417393) (xy 171.329501 -304.454263) (xy 171.294367 -304.48631) (xy 171.2549 -304.512836)
			(xy 171.211958 -304.533265) (xy 171.166476 -304.547149) (xy 171.119446 -304.554189) (xy 171.09567 -304.554636)
			(xy 170.904154 -304.554636) (xy 170.880376 -304.554214) (xy 170.83334 -304.547186) (xy 170.787854 -304.533305)
			(xy 170.744909 -304.512873) (xy 170.705443 -304.486337) (xy 170.670318 -304.454277) (xy 170.640299 -304.41739)
			(xy 170.627802 -304.397156) (xy 170.572938 -304.304954) (xy 170.568102 -304.2975) (xy 170.554375 -304.286238)
			(xy 170.537624 -304.280349) (xy 170.528742 -304.280062) (xy 170.521122 -304.280062) (xy 170.512247 -304.280394)
			(xy 170.49551 -304.286279) (xy 170.481786 -304.297523) (xy 170.476926 -304.304954) (xy 170.422062 -304.397156)
			(xy 170.409546 -304.417375) (xy 170.379518 -304.454245) (xy 170.344389 -304.486293) (xy 170.304926 -304.512821)
			(xy 170.261988 -304.533253) (xy 170.216511 -304.547142) (xy 170.169485 -304.554186) (xy 170.14571 -304.554636)
			(xy 169.954194 -304.554636) (xy 169.930417 -304.554183) (xy 169.883383 -304.54716) (xy 169.837897 -304.533285)
			(xy 169.794952 -304.512858) (xy 169.755486 -304.486327) (xy 169.72036 -304.454271) (xy 169.69034 -304.417389)
			(xy 169.677842 -304.397156) (xy 169.622978 -304.304954) (xy 169.618118 -304.297518) (xy 169.604401 -304.286253)
			(xy 169.58766 -304.280356) (xy 169.578782 -304.280062) (xy 169.571162 -304.280062) (xy 169.562284 -304.280353)
			(xy 169.545544 -304.286256) (xy 169.531823 -304.297516) (xy 169.526966 -304.304954) (xy 169.472102 -304.397156)
			(xy 169.459559 -304.417358) (xy 169.429535 -304.454227) (xy 169.394411 -304.486276) (xy 169.354952 -304.512806)
			(xy 169.312019 -304.533241) (xy 169.266546 -304.547134) (xy 169.219524 -304.554183) (xy 169.19575 -304.554636)
			(xy 169.004234 -304.554636) (xy 168.980455 -304.55423) (xy 168.933419 -304.547199) (xy 168.887932 -304.533315)
			(xy 168.844987 -304.512881) (xy 168.805522 -304.486342) (xy 168.770397 -304.454279) (xy 168.740379 -304.417391)
			(xy 168.727882 -304.397156) (xy 168.673018 -304.304954) (xy 168.668133 -304.297536) (xy 168.654427 -304.286268)
			(xy 168.637697 -304.280362) (xy 168.628822 -304.280062) (xy 168.621202 -304.280062) (xy 168.612326 -304.28038)
			(xy 168.595588 -304.286271) (xy 168.581865 -304.297521) (xy 168.577006 -304.304954) (xy 168.522142 -304.397156)
			(xy 168.50964 -304.417384) (xy 168.479609 -304.454254) (xy 168.444478 -304.486301) (xy 168.405013 -304.512829)
			(xy 168.362073 -304.533259) (xy 168.316594 -304.547145) (xy 168.269566 -304.554187) (xy 168.24579 -304.554636)
			(xy 168.054274 -304.554636) (xy 168.030496 -304.554199) (xy 167.983462 -304.547173) (xy 167.937976 -304.533295)
			(xy 167.895031 -304.512866) (xy 167.855565 -304.486332) (xy 167.820439 -304.454274) (xy 167.79042 -304.41739)
			(xy 167.777922 -304.397156) (xy 167.723058 -304.304954) (xy 167.71821 -304.297509) (xy 167.704488 -304.286245)
			(xy 167.687742 -304.280353) (xy 167.678862 -304.280062) (xy 167.671242 -304.280062) (xy 167.662363 -304.280338)
			(xy 167.645623 -304.286248) (xy 167.631902 -304.297514) (xy 167.627046 -304.304954) (xy 167.572182 -304.397156)
			(xy 167.559653 -304.417367) (xy 167.529626 -304.454236) (xy 167.4945 -304.486284) (xy 167.455039 -304.512814)
			(xy 167.412104 -304.533247) (xy 167.366629 -304.547138) (xy 167.319604 -304.554184) (xy 167.29583 -304.554636)
			(xy 167.104314 -304.554636) (xy 167.080537 -304.554167) (xy 167.033504 -304.547148) (xy 166.988019 -304.533275)
			(xy 166.945074 -304.512851) (xy 166.905608 -304.486322) (xy 166.870481 -304.454268) (xy 166.84046 -304.417388)
			(xy 166.827962 -304.397156) (xy 166.773098 -304.304954) (xy 166.768225 -304.297527) (xy 166.754514 -304.286261)
			(xy 166.737778 -304.280359) (xy 166.728902 -304.280062) (xy 166.721282 -304.280062) (xy 166.712405 -304.280366)
			(xy 166.695666 -304.286264) (xy 166.681944 -304.297518) (xy 166.677086 -304.304954) (xy 166.622222 -304.397156)
			(xy 166.609734 -304.417393) (xy 166.579701 -304.454263) (xy 166.544567 -304.48631) (xy 166.5051 -304.512836)
			(xy 166.462158 -304.533265) (xy 166.416676 -304.547149) (xy 166.369646 -304.554189) (xy 166.34587 -304.554636)
			(xy 166.1541 -304.554636) (xy 166.130323 -304.554178) (xy 166.083289 -304.547157) (xy 166.037804 -304.533282)
			(xy 165.994859 -304.512856) (xy 165.955393 -304.486326) (xy 165.920266 -304.45427) (xy 165.890246 -304.417388)
			(xy 165.877748 -304.397156) (xy 165.822884 -304.304954) (xy 165.81802 -304.297521) (xy 165.804305 -304.286255)
			(xy 165.787566 -304.280357) (xy 165.778688 -304.280062) (xy 165.774878 -304.280062) (xy 165.750882 -304.279682)
			(xy 165.703481 -304.272171) (xy 165.657839 -304.257336) (xy 165.61508 -304.235544) (xy 165.576257 -304.207331)
			(xy 165.542325 -304.173392) (xy 165.51412 -304.134562) (xy 165.492338 -304.091798) (xy 165.477514 -304.046152)
			(xy 165.470013 -303.99875) (xy 165.46957 -303.974754) (xy 165.46957 -303.973992) (xy 165.469691 -303.965142)
			(xy 165.470836 -303.947478) (xy 165.471856 -303.938686) (xy 165.471856 -303.938432) (xy 165.472535 -303.92909)
			(xy 165.467901 -303.910958) (xy 165.457066 -303.895699) (xy 165.449504 -303.890172) (xy 165.378892 -303.843436)
			(xy 165.357248 -303.828398) (xy 165.318723 -303.792439) (xy 165.286588 -303.750671) (xy 165.261705 -303.704215)
			(xy 165.244743 -303.65432) (xy 165.236157 -303.602324) (xy 165.235636 -303.575974) (xy 165.235636 -303.423574)
			(xy 165.236211 -303.397232) (xy 165.244842 -303.345258) (xy 165.26182 -303.295383) (xy 165.286693 -303.248938)
			(xy 165.318796 -303.207163) (xy 165.357272 -303.171172) (xy 165.378892 -303.156112) (xy 165.449504 -303.109376)
			(xy 165.45704 -303.103824) (xy 165.467851 -303.088565) (xy 165.472504 -303.070453) (xy 165.471856 -303.061116)
			(xy 165.471856 -303.060608) (xy 165.46957 -303.027588) (xy 165.469069 -303.018258) (xy 165.462184 -303.000904)
			(xy 165.449549 -302.98716) (xy 165.441376 -302.98263) (xy 165.43528 -302.979582) (xy 165.342062 -302.931322)
			(xy 165.335951 -302.927947) (xy 165.325776 -302.918396) (xy 165.321996 -302.912526) (xy 165.253416 -302.79975)
			(xy 165.245796 -302.790098) (xy 165.096698 -302.641) (xy 165.089215 -302.63431) (xy 165.070657 -302.626719)
			(xy 165.06063 -302.626268) (xy 164.153088 -302.626268) (xy 164.142922 -302.626763) (xy 164.124192 -302.634679)
			(xy 164.109988 -302.649231) (xy 164.105844 -302.658526) (xy 164.0713 -302.74641) (xy 164.067973 -302.755996)
			(xy 164.06839 -302.776267) (xy 164.07665 -302.794782) (xy 164.083746 -302.802036) (xy 164.101621 -302.819495)
			(xy 164.132028 -302.859139) (xy 164.155574 -302.903205) (xy 164.171629 -302.950518) (xy 164.179766 -302.999813)
			(xy 164.180266 -303.024794) (xy 164.179744 -303.050049) (xy 164.171431 -303.099871) (xy 164.15503 -303.147645)
			(xy 164.130989 -303.192068) (xy 164.099965 -303.231928) (xy 164.062803 -303.266138) (xy 164.020517 -303.293764)
			(xy 163.974261 -303.314054) (xy 163.925296 -303.326454) (xy 163.874958 -303.330625) (xy 163.82462 -303.326454)
			(xy 163.775655 -303.314054) (xy 163.729399 -303.293764) (xy 163.687113 -303.266138) (xy 163.649951 -303.231928)
			(xy 163.618927 -303.192068) (xy 163.594886 -303.147645) (xy 163.578485 -303.099871) (xy 163.570172 -303.050049)
			(xy 163.56965 -303.024794) (xy 163.570157 -302.999813) (xy 163.578292 -302.950517) (xy 163.594344 -302.903203)
			(xy 163.617885 -302.859134) (xy 163.648286 -302.819485) (xy 163.66617 -302.802036) (xy 163.673238 -302.79477)
			(xy 163.681451 -302.776252) (xy 163.681902 -302.756) (xy 163.678616 -302.74641) (xy 163.644072 -302.658526)
			(xy 163.63996 -302.649205) (xy 163.625765 -302.634615) (xy 163.607007 -302.62671) (xy 163.596828 -302.626268)
			(xy 163.203128 -302.626268) (xy 163.192965 -302.626793) (xy 163.174236 -302.634695) (xy 163.16003 -302.649236)
			(xy 163.155884 -302.658526) (xy 163.12134 -302.74641) (xy 163.118001 -302.755994) (xy 163.118419 -302.776268)
			(xy 163.126686 -302.794784) (xy 163.133786 -302.802036) (xy 163.151668 -302.819488) (xy 163.182073 -302.859135)
			(xy 163.205616 -302.903203) (xy 163.22167 -302.950516) (xy 163.229806 -302.999812) (xy 163.230306 -303.024794)
			(xy 163.229784 -303.050049) (xy 163.221471 -303.099871) (xy 163.20507 -303.147645) (xy 163.181029 -303.192068)
			(xy 163.150005 -303.231928) (xy 163.112843 -303.266138) (xy 163.070557 -303.293764) (xy 163.024301 -303.314054)
			(xy 162.975336 -303.326454) (xy 162.924998 -303.330625) (xy 162.87466 -303.326454) (xy 162.825695 -303.314054)
			(xy 162.779439 -303.293764) (xy 162.737153 -303.266138) (xy 162.699991 -303.231928) (xy 162.668967 -303.192068)
			(xy 162.644926 -303.147645) (xy 162.628525 -303.099871) (xy 162.620212 -303.050049) (xy 162.61969 -303.024794)
			(xy 162.620185 -302.999812) (xy 162.628321 -302.950515) (xy 162.644375 -302.903201) (xy 162.667919 -302.859132)
			(xy 162.698324 -302.819484) (xy 162.71621 -302.802036) (xy 162.723282 -302.794773) (xy 162.73149 -302.776253)
			(xy 162.731941 -302.756001) (xy 162.728656 -302.74641) (xy 162.694112 -302.658526) (xy 162.68997 -302.649221)
			(xy 162.675788 -302.634631) (xy 162.657042 -302.626717) (xy 162.646868 -302.626268) (xy 162.59302 -302.626268)
			(xy 162.568201 -302.625743) (xy 162.519167 -302.618018) (xy 162.471899 -302.602856) (xy 162.42752 -302.580617)
			(xy 162.387082 -302.551827) (xy 162.368992 -302.534828) (xy 162.367468 -302.533304) (xy 162.365436 -302.531526)
			(xy 162.171888 -302.337978) (xy 162.13836 -302.333406) (xy 162.123628 -302.341788) (xy 162.100779 -302.353837)
			(xy 162.052036 -302.370925) (xy 162.001118 -302.3796) (xy 161.975292 -302.380142) (xy 161.975038 -302.380142)
			(xy 161.960919 -302.379957) (xy 161.932806 -302.377284) (xy 161.918904 -302.374808) (xy 161.91865 -302.374808)
			(xy 161.90642 -302.373331) (xy 161.882932 -302.380631) (xy 161.873692 -302.388778) (xy 161.814002 -302.448468)
			(xy 161.805849 -302.457708) (xy 161.798539 -302.481196) (xy 161.800032 -302.493426) (xy 161.800032 -302.493934)
			(xy 161.802477 -302.507712) (xy 161.805149 -302.535569) (xy 161.805366 -302.54956) (xy 161.805366 -302.550068)
			(xy 161.805155 -302.56406) (xy 161.802485 -302.591917) (xy 161.800032 -302.605694) (xy 161.800032 -302.606202)
			(xy 161.798579 -302.618433) (xy 161.805861 -302.641919) (xy 161.814002 -302.65116) (xy 161.873692 -302.71085)
			(xy 161.882927 -302.719011) (xy 161.906418 -302.726319) (xy 161.91865 -302.72482) (xy 161.919158 -302.72482)
			(xy 161.932998 -302.722362) (xy 161.960983 -302.719693) (xy 161.975038 -302.719486) (xy 162.000291 -302.720023)
			(xy 162.050107 -302.728341) (xy 162.097874 -302.744745) (xy 162.142291 -302.768787) (xy 162.182144 -302.799811)
			(xy 162.216349 -302.836971) (xy 162.243971 -302.879254) (xy 162.264257 -302.925506) (xy 162.276655 -302.974467)
			(xy 162.280825 -303.0248) (xy 162.276655 -303.075133) (xy 162.264257 -303.124094) (xy 162.243971 -303.170346)
			(xy 162.216349 -303.212629) (xy 162.182144 -303.249789) (xy 162.142291 -303.280813) (xy 162.097874 -303.304855)
			(xy 162.050107 -303.321259) (xy 162.000291 -303.329577) (xy 161.975038 -303.330102) (xy 161.960919 -303.329917)
			(xy 161.932806 -303.327245) (xy 161.918904 -303.324768) (xy 161.91865 -303.324768) (xy 161.90642 -303.323302)
			(xy 161.882934 -303.330596) (xy 161.873692 -303.338738) (xy 161.814002 -303.398428) (xy 161.805815 -303.407643)
			(xy 161.798524 -303.431151) (xy 161.800032 -303.443386) (xy 161.800032 -303.443894) (xy 161.802482 -303.457735)
			(xy 161.805156 -303.485719) (xy 161.805366 -303.499774) (xy 161.80495 -303.524597) (xy 161.796923 -303.573589)
			(xy 161.781075 -303.620637) (xy 161.757825 -303.664501) (xy 161.727784 -303.704026) (xy 161.691745 -303.738171)
			(xy 161.650657 -303.766035) (xy 161.605602 -303.786885) (xy 161.557768 -303.800171) (xy 161.508414 -303.805544)
			(xy 161.458841 -303.802861) (xy 161.410355 -303.792194) (xy 161.364234 -303.773823) (xy 161.321692 -303.748233)
			(xy 161.283851 -303.716098) (xy 161.251707 -303.678263) (xy 161.226107 -303.635727) (xy 161.207726 -303.58961)
			(xy 161.197048 -303.541127) (xy 161.194354 -303.491554) (xy 161.199716 -303.442199) (xy 161.212991 -303.394362)
			(xy 161.233831 -303.349302) (xy 161.261687 -303.308208) (xy 161.295823 -303.272161) (xy 161.335341 -303.242112)
			(xy 161.379201 -303.218852) (xy 161.426245 -303.202994) (xy 161.475235 -303.194955) (xy 161.500058 -303.194466)
			(xy 161.514177 -303.194652) (xy 161.54229 -303.197324) (xy 161.556192 -303.1998) (xy 161.556446 -303.1998)
			(xy 161.568676 -303.201272) (xy 161.592163 -303.193976) (xy 161.601404 -303.18583) (xy 161.661094 -303.12614)
			(xy 161.669242 -303.116896) (xy 161.676555 -303.093412) (xy 161.675064 -303.081182) (xy 161.675064 -303.080674)
			(xy 161.67262 -303.066896) (xy 161.669947 -303.039039) (xy 161.66973 -303.025048) (xy 161.66973 -303.02454)
			(xy 161.669942 -303.010548) (xy 161.672611 -302.982691) (xy 161.675064 -302.968914) (xy 161.675064 -302.968406)
			(xy 161.676578 -302.956177) (xy 161.669254 -302.932684) (xy 161.661094 -302.923448) (xy 161.601404 -302.863758)
			(xy 161.59218 -302.855585) (xy 161.56868 -302.848288) (xy 161.556446 -302.849788) (xy 161.555938 -302.849788)
			(xy 161.542098 -302.852247) (xy 161.514113 -302.854915) (xy 161.500058 -302.855122) (xy 161.474806 -302.854569)
			(xy 161.424992 -302.84625) (xy 161.377226 -302.829847) (xy 161.332812 -302.805805) (xy 161.292959 -302.774782)
			(xy 161.258757 -302.737623) (xy 161.231136 -302.695341) (xy 161.21085 -302.64909) (xy 161.198453 -302.600131)
			(xy 161.194283 -302.5498) (xy 161.198453 -302.499469) (xy 161.21085 -302.45051) (xy 161.231136 -302.404259)
			(xy 161.258757 -302.361977) (xy 161.292959 -302.324818) (xy 161.332812 -302.293795) (xy 161.377226 -302.269753)
			(xy 161.424992 -302.25335) (xy 161.474806 -302.245031) (xy 161.500058 -302.244506) (xy 161.514177 -302.244691)
			(xy 161.54229 -302.247363) (xy 161.556192 -302.24984) (xy 161.556446 -302.24984) (xy 161.568676 -302.251329)
			(xy 161.592166 -302.244023) (xy 161.601404 -302.23587) (xy 161.661094 -302.17618) (xy 161.669275 -302.166961)
			(xy 161.676569 -302.143457) (xy 161.675064 -302.131222) (xy 161.675064 -302.130714) (xy 161.672612 -302.116937)
			(xy 161.669945 -302.08908) (xy 161.66973 -302.075088) (xy 161.66973 -302.07458) (xy 161.669934 -302.060588)
			(xy 161.672609 -302.032731) (xy 161.675064 -302.018954) (xy 161.675064 -302.018446) (xy 161.676552 -302.006216)
			(xy 161.669246 -301.982726) (xy 161.661094 -301.973488) (xy 161.601404 -301.913798) (xy 161.592176 -301.905629)
			(xy 161.568679 -301.898329) (xy 161.556446 -301.899828) (xy 161.555938 -301.899828) (xy 161.542098 -301.902287)
			(xy 161.514113 -301.904956) (xy 161.500058 -301.905162) (xy 161.476061 -301.9048) (xy 161.42866 -301.897286)
			(xy 161.383018 -301.882449) (xy 161.340259 -301.860654) (xy 161.301435 -301.832439) (xy 161.267504 -301.798498)
			(xy 161.2393 -301.759666) (xy 161.217517 -301.716901) (xy 161.202693 -301.671254) (xy 161.195193 -301.623851)
			(xy 161.19475 -301.599854) (xy 161.194942 -301.585798) (xy 161.197616 -301.557813) (xy 161.200084 -301.543974)
			(xy 161.200084 -301.543466) (xy 161.201553 -301.531236) (xy 161.194259 -301.507748) (xy 161.186114 -301.498508)
			(xy 161.126424 -301.438818) (xy 161.117186 -301.430662) (xy 161.093697 -301.423353) (xy 161.081466 -301.424848)
			(xy 161.080958 -301.424848) (xy 161.067118 -301.427304) (xy 161.039133 -301.429975) (xy 161.025078 -301.430182)
			(xy 161.010895 -301.430009) (xy 160.982655 -301.427334) (xy 160.96869 -301.424848) (xy 160.968436 -301.424848)
			(xy 160.956206 -301.42335) (xy 160.932715 -301.430662) (xy 160.923478 -301.438818) (xy 160.863788 -301.498254)
			(xy 160.855641 -301.507499) (xy 160.848328 -301.530983) (xy 160.849818 -301.543212) (xy 160.849818 -301.54372)
			(xy 160.85228 -301.557624) (xy 160.854952 -301.585735) (xy 160.855152 -301.599854) (xy 160.854672 -301.62468)
			(xy 160.846646 -301.67368) (xy 160.830798 -301.720735) (xy 160.807546 -301.764606) (xy 160.777502 -301.804137)
			(xy 160.741458 -301.838287) (xy 160.700364 -301.866155) (xy 160.655302 -301.887007) (xy 160.60746 -301.900294)
			(xy 160.5581 -301.905665) (xy 160.50852 -301.902979) (xy 160.460028 -301.892307) (xy 160.413902 -301.87393)
			(xy 160.371356 -301.848333) (xy 160.333513 -301.816189) (xy 160.301368 -301.778346) (xy 160.275771 -301.7358)
			(xy 160.257393 -301.689674) (xy 160.246721 -301.641182) (xy 160.244035 -301.591602) (xy 160.249406 -301.542241)
			(xy 160.262692 -301.4944) (xy 160.283544 -301.449338) (xy 160.311412 -301.408244) (xy 160.345561 -301.372199)
			(xy 160.385092 -301.342155) (xy 160.428963 -301.318903) (xy 160.476018 -301.303054) (xy 160.525018 -301.295028)
			(xy 160.549844 -301.294546) (xy 160.564027 -301.294731) (xy 160.592267 -301.297398) (xy 160.606232 -301.29988)
			(xy 160.606486 -301.29988) (xy 160.618715 -301.301385) (xy 160.642206 -301.294067) (xy 160.651444 -301.28591)
			(xy 160.711134 -301.226474) (xy 160.719324 -301.217262) (xy 160.726611 -301.193752) (xy 160.725104 -301.181516)
			(xy 160.725104 -301.181008) (xy 160.722645 -301.167104) (xy 160.719971 -301.138993) (xy 160.71977 -301.124874)
			(xy 160.720292 -301.099619) (xy 160.728605 -301.049797) (xy 160.745006 -301.002023) (xy 160.769047 -300.9576)
			(xy 160.800071 -300.91774) (xy 160.837233 -300.88353) (xy 160.879519 -300.855904) (xy 160.925775 -300.835614)
			(xy 160.97474 -300.823214) (xy 161.025078 -300.819043) (xy 161.075416 -300.823214) (xy 161.124381 -300.835614)
			(xy 161.170637 -300.855904) (xy 161.212923 -300.88353) (xy 161.250085 -300.91774) (xy 161.281109 -300.9576)
			(xy 161.30515 -301.002023) (xy 161.321551 -301.049797) (xy 161.329864 -301.099619) (xy 161.330386 -301.124874)
			(xy 161.330185 -301.13893) (xy 161.327517 -301.166915) (xy 161.325052 -301.180754) (xy 161.325052 -301.181262)
			(xy 161.323554 -301.193492) (xy 161.330866 -301.216983) (xy 161.339022 -301.22622) (xy 161.398712 -301.28591)
			(xy 161.407933 -301.294089) (xy 161.431436 -301.301384) (xy 161.44367 -301.29988) (xy 161.444178 -301.29988)
			(xy 161.457955 -301.297429) (xy 161.485812 -301.294761) (xy 161.499804 -301.294546) (xy 161.500312 -301.294546)
			(xy 161.514368 -301.294741) (xy 161.542353 -301.297413) (xy 161.556192 -301.29988) (xy 161.556446 -301.29988)
			(xy 161.568676 -301.301358) (xy 161.592164 -301.294058) (xy 161.601404 -301.28591) (xy 161.661094 -301.22622)
			(xy 161.669253 -301.216984) (xy 161.67656 -301.193493) (xy 161.675064 -301.181262) (xy 161.675064 -301.180754)
			(xy 161.672607 -301.166914) (xy 161.669937 -301.138929) (xy 161.66973 -301.124874) (xy 161.66973 -301.12462)
			(xy 161.670241 -301.098532) (xy 161.679075 -301.04711) (xy 161.696506 -300.997932) (xy 161.722029 -300.952425)
			(xy 161.738056 -300.931834) (xy 161.749232 -300.918118) (xy 161.749486 -300.88205) (xy 161.7472 -300.879256)
			(xy 161.74209 -300.872328) (xy 161.736366 -300.856107) (xy 161.736024 -300.847506) (xy 161.736024 -300.452536)
			(xy 161.736412 -300.443853) (xy 161.742252 -300.427495) (xy 161.747454 -300.420532) (xy 161.74974 -300.417738)
			(xy 161.749486 -300.381924) (xy 161.738056 -300.3677) (xy 161.722051 -300.347132) (xy 161.696544 -300.301689)
			(xy 161.679113 -300.252579) (xy 161.670263 -300.201224) (xy 161.66973 -300.175168) (xy 161.66973 -300.17466)
			(xy 161.670263 -300.148573) (xy 161.67909 -300.097151) (xy 161.696514 -300.047974) (xy 161.722032 -300.002466)
			(xy 161.738056 -299.981874) (xy 161.749232 -299.968158) (xy 161.749486 -299.93209) (xy 161.7472 -299.929296)
			(xy 161.742066 -299.922384) (xy 161.736356 -299.90615) (xy 161.736024 -299.897546) (xy 161.736024 -299.502576)
			(xy 161.736384 -299.49389) (xy 161.742244 -299.477532) (xy 161.747454 -299.470572) (xy 161.74974 -299.467778)
			(xy 161.749486 -299.431964) (xy 161.738056 -299.41774) (xy 161.722024 -299.397192) (xy 161.696522 -299.351742)
			(xy 161.679099 -299.302626) (xy 161.670258 -299.251266) (xy 161.66973 -299.225208) (xy 161.66973 -299.2247)
			(xy 161.67023 -299.198611) (xy 161.679067 -299.147189) (xy 161.696501 -299.098011) (xy 161.722028 -299.052505)
			(xy 161.738056 -299.031914) (xy 161.749232 -299.018198) (xy 161.749486 -298.98213) (xy 161.7472 -298.979336)
			(xy 161.742082 -298.972413) (xy 161.736363 -298.956188) (xy 161.736024 -298.947586) (xy 161.736024 -298.552362)
			(xy 161.736424 -298.54368) (xy 161.742256 -298.527322) (xy 161.747454 -298.520358) (xy 161.74974 -298.517564)
			(xy 161.749486 -298.48175) (xy 161.738056 -298.467526) (xy 161.722018 -298.446983) (xy 161.696517 -298.401531)
			(xy 161.679095 -298.352413) (xy 161.670257 -298.301052) (xy 161.66973 -298.274994) (xy 161.66973 -298.274486)
			(xy 161.670223 -298.248397) (xy 161.679062 -298.196974) (xy 161.696498 -298.147796) (xy 161.722027 -298.10229)
			(xy 161.738056 -298.0817) (xy 161.749232 -298.067984) (xy 161.749486 -298.031916) (xy 161.7472 -298.029122)
			(xy 161.742076 -298.022203) (xy 161.736361 -298.005975) (xy 161.736024 -297.997372) (xy 161.736024 -297.664124)
			(xy 161.724594 -297.64228) (xy 161.71418 -297.635168) (xy 161.70347 -297.628626) (xy 161.678567 -297.62581)
			(xy 161.666682 -297.629834) (xy 161.614358 -297.650408) (xy 161.609892 -297.652028) (xy 161.600564 -297.653821)
			(xy 161.595816 -297.653964) (xy 161.454846 -297.653964) (xy 161.427562 -297.653291) (xy 161.373795 -297.643957)
			(xy 161.322369 -297.625699) (xy 161.274753 -297.59904) (xy 161.25317 -297.582336) (xy 161.244455 -297.57605)
			(xy 161.223684 -297.570633) (xy 161.202502 -297.574115) (xy 161.193226 -297.579542) (xy 161.174437 -297.591512)
			(xy 161.134095 -297.610414) (xy 161.091431 -297.623238) (xy 161.047353 -297.629709) (xy 161.025078 -297.630088)
			(xy 161.024824 -297.630088) (xy 161.002625 -297.629667) (xy 160.9587 -297.623208) (xy 160.916174 -297.610452)
			(xy 160.875945 -297.591669) (xy 160.857184 -297.579796) (xy 160.847587 -297.574188) (xy 160.825621 -297.570985)
			(xy 160.804366 -297.577389) (xy 160.795716 -297.584368) (xy 160.772856 -297.604434) (xy 160.769446 -297.607378)
			(xy 160.761777 -297.612104) (xy 160.757616 -297.613832) (xy 160.664398 -297.650408) (xy 160.659948 -297.652082)
			(xy 160.65061 -297.653869) (xy 160.645856 -297.653964) (xy 160.504632 -297.653964) (xy 160.477348 -297.653299)
			(xy 160.423581 -297.643962) (xy 160.372154 -297.625702) (xy 160.324538 -297.599041) (xy 160.302956 -297.582336)
			(xy 160.294248 -297.576038) (xy 160.273473 -297.570625) (xy 160.252288 -297.574112) (xy 160.243012 -297.579542)
			(xy 160.224226 -297.591518) (xy 160.183884 -297.610418) (xy 160.141218 -297.62324) (xy 160.09714 -297.62971)
			(xy 160.074864 -297.630088) (xy 160.052633 -297.62969) (xy 160.00864 -297.623247) (xy 159.966048 -297.610489)
			(xy 159.925758 -297.591686) (xy 159.90697 -297.579796) (xy 159.897303 -297.574109) (xy 159.875147 -297.570832)
			(xy 159.853706 -297.577307) (xy 159.844994 -297.584368) (xy 159.809434 -297.616372) (xy 159.804714 -297.620362)
			(xy 159.793798 -297.626148) (xy 159.787844 -297.627802) (xy 159.65932 -297.660314) (xy 159.653363 -297.661625)
			(xy 159.641171 -297.661759) (xy 159.63519 -297.660568) (xy 159.568896 -297.64482) (xy 159.540445 -297.637269)
			(xy 159.486711 -297.613252) (xy 159.438253 -297.579846) (xy 159.417004 -297.559476) (xy 159.034226 -297.176698)
			(xy 159.016879 -297.158552) (xy 158.987489 -297.117856) (xy 158.964791 -297.073082) (xy 158.949337 -297.025321)
			(xy 158.941503 -296.975737) (xy 158.941008 -296.950638) (xy 158.941008 -294.830754) (xy 158.941248 -294.813275)
			(xy 158.945069 -294.778526) (xy 158.948628 -294.761412) (xy 158.950264 -294.752193) (xy 158.947503 -294.733689)
			(xy 158.938302 -294.7174) (xy 158.931356 -294.71112) (xy 158.912666 -294.695171) (xy 158.880137 -294.65835)
			(xy 158.853924 -294.616796) (xy 158.834701 -294.571581) (xy 158.822966 -294.523872) (xy 158.81902 -294.4749)
			(xy 158.822966 -294.425928) (xy 158.834701 -294.378219) (xy 158.853924 -294.333004) (xy 158.880137 -294.29145)
			(xy 158.912666 -294.254629) (xy 158.931356 -294.23868) (xy 158.938379 -294.232463) (xy 158.947621 -294.216155)
			(xy 158.950344 -294.197609) (xy 158.948628 -294.188388) (xy 158.945069 -294.171274) (xy 158.941252 -294.136525)
			(xy 158.941008 -294.119046) (xy 158.941008 -293.85768) (xy 158.940296 -293.845481) (xy 158.929011 -293.823849)
			(xy 158.919418 -293.816278) (xy 158.898278 -293.80072) (xy 158.860285 -293.76451) (xy 158.828012 -293.723121)
			(xy 158.802156 -293.677447) (xy 158.783277 -293.628476) (xy 158.771782 -293.577265) (xy 158.767921 -293.524923)
			(xy 158.480252 -293.524923) (xy 158.480252 -293.52494) (xy 158.479757 -293.549547) (xy 158.471862 -293.598124)
			(xy 158.456278 -293.644805) (xy 158.433407 -293.688382) (xy 158.403842 -293.727726) (xy 158.368349 -293.761818)
			(xy 158.327846 -293.789774) (xy 158.283384 -293.810872) (xy 158.236113 -293.824564) (xy 158.187258 -293.830496)
			(xy 158.138083 -293.828515) (xy 158.089864 -293.818671) (xy 158.043848 -293.801219) (xy 158.001227 -293.776612)
			(xy 157.963106 -293.745487) (xy 157.930471 -293.70865) (xy 157.904168 -293.667054) (xy 157.884877 -293.621778)
			(xy 157.8731 -293.573994) (xy 157.86914 -293.52494) (xy 157.530292 -293.52494) (xy 157.529797 -293.549547)
			(xy 157.521902 -293.598124) (xy 157.506318 -293.644805) (xy 157.483447 -293.688382) (xy 157.453882 -293.727726)
			(xy 157.418389 -293.761818) (xy 157.377886 -293.789774) (xy 157.333424 -293.810872) (xy 157.286153 -293.824564)
			(xy 157.237298 -293.830496) (xy 157.188123 -293.828515) (xy 157.139904 -293.818671) (xy 157.093888 -293.801219)
			(xy 157.051267 -293.776612) (xy 157.013146 -293.745487) (xy 156.980511 -293.70865) (xy 156.954208 -293.667054)
			(xy 156.934917 -293.621778) (xy 156.92314 -293.573994) (xy 156.91918 -293.52494) (xy 156.580332 -293.52494)
			(xy 156.579837 -293.549547) (xy 156.571942 -293.598124) (xy 156.556358 -293.644805) (xy 156.533487 -293.688382)
			(xy 156.503922 -293.727726) (xy 156.468429 -293.761818) (xy 156.427926 -293.789774) (xy 156.383464 -293.810872)
			(xy 156.336193 -293.824564) (xy 156.287338 -293.830496) (xy 156.238163 -293.828515) (xy 156.189944 -293.818671)
			(xy 156.143928 -293.801219) (xy 156.101307 -293.776612) (xy 156.063186 -293.745487) (xy 156.030551 -293.70865)
			(xy 156.004248 -293.667054) (xy 155.984957 -293.621778) (xy 155.97318 -293.573994) (xy 155.96922 -293.52494)
			(xy 155.630372 -293.52494) (xy 155.629877 -293.549547) (xy 155.621982 -293.598124) (xy 155.606398 -293.644805)
			(xy 155.583527 -293.688382) (xy 155.553962 -293.727726) (xy 155.518469 -293.761818) (xy 155.477966 -293.789774)
			(xy 155.433504 -293.810872) (xy 155.386233 -293.824564) (xy 155.337378 -293.830496) (xy 155.288203 -293.828515)
			(xy 155.239984 -293.818671) (xy 155.193968 -293.801219) (xy 155.151347 -293.776612) (xy 155.113226 -293.745487)
			(xy 155.080591 -293.70865) (xy 155.054288 -293.667054) (xy 155.034997 -293.621778) (xy 155.02322 -293.573994)
			(xy 155.01926 -293.52494) (xy 154.680412 -293.52494) (xy 154.679917 -293.549547) (xy 154.672022 -293.598124)
			(xy 154.656438 -293.644805) (xy 154.633567 -293.688382) (xy 154.604002 -293.727726) (xy 154.568509 -293.761818)
			(xy 154.528006 -293.789774) (xy 154.483544 -293.810872) (xy 154.436273 -293.824564) (xy 154.387418 -293.830496)
			(xy 154.338243 -293.828515) (xy 154.290024 -293.818671) (xy 154.244008 -293.801219) (xy 154.201387 -293.776612)
			(xy 154.163266 -293.745487) (xy 154.130631 -293.70865) (xy 154.104328 -293.667054) (xy 154.085037 -293.621778)
			(xy 154.07326 -293.573994) (xy 154.0693 -293.52494) (xy 152.178004 -293.52494) (xy 152.178004 -294.087296)
			(xy 152.178068 -294.091103) (xy 152.179211 -294.098631) (xy 152.18029 -294.102282) (xy 152.182576 -294.109648)
			(xy 152.189688 -294.125396) (xy 152.195784 -294.13073) (xy 152.199086 -294.13327) (xy 152.276048 -294.180514)
			(xy 152.290526 -294.180768) (xy 152.30602 -294.180768) (xy 152.312624 -294.18026) (xy 152.332944 -294.175942)
			(xy 152.338024 -294.173656) (xy 152.359549 -294.16436) (xy 152.404564 -294.151243) (xy 152.450979 -294.144606)
			(xy 152.474422 -294.144192) (xy 152.47493 -294.144192) (xy 152.500916 -294.144704) (xy 152.552246 -294.152838)
			(xy 152.601673 -294.168902) (xy 152.647978 -294.192499) (xy 152.690022 -294.223049) (xy 152.72677 -294.2598)
			(xy 152.757317 -294.301847) (xy 152.78091 -294.348155) (xy 152.796969 -294.397583) (xy 152.805099 -294.448914)
			(xy 152.805099 -294.4749) (xy 153.119086 -294.4749) (xy 153.123046 -294.425846) (xy 153.134823 -294.378062)
			(xy 153.154114 -294.332786) (xy 153.180417 -294.29119) (xy 153.213052 -294.254353) (xy 153.251173 -294.223228)
			(xy 153.293794 -294.198621) (xy 153.33981 -294.181169) (xy 153.388029 -294.171325) (xy 153.437204 -294.169344)
			(xy 153.486059 -294.175276) (xy 153.53333 -294.188968) (xy 153.577792 -294.210066) (xy 153.618295 -294.238022)
			(xy 153.653788 -294.272114) (xy 153.683353 -294.311458) (xy 153.706224 -294.355035) (xy 153.721808 -294.401716)
			(xy 153.729703 -294.450293) (xy 153.730198 -294.4749) (xy 154.0693 -294.4749) (xy 154.07326 -294.425846)
			(xy 154.085037 -294.378062) (xy 154.104328 -294.332786) (xy 154.130631 -294.29119) (xy 154.163266 -294.254353)
			(xy 154.201387 -294.223228) (xy 154.244008 -294.198621) (xy 154.290024 -294.181169) (xy 154.338243 -294.171325)
			(xy 154.387418 -294.169344) (xy 154.436273 -294.175276) (xy 154.483544 -294.188968) (xy 154.528006 -294.210066)
			(xy 154.568509 -294.238022) (xy 154.604002 -294.272114) (xy 154.633567 -294.311458) (xy 154.656438 -294.355035)
			(xy 154.672022 -294.401716) (xy 154.679917 -294.450293) (xy 154.680412 -294.4749) (xy 156.91918 -294.4749)
			(xy 156.92314 -294.425846) (xy 156.934917 -294.378062) (xy 156.954208 -294.332786) (xy 156.980511 -294.29119)
			(xy 157.013146 -294.254353) (xy 157.051267 -294.223228) (xy 157.093888 -294.198621) (xy 157.139904 -294.181169)
			(xy 157.188123 -294.171325) (xy 157.237298 -294.169344) (xy 157.286153 -294.175276) (xy 157.333424 -294.188968)
			(xy 157.377886 -294.210066) (xy 157.418389 -294.238022) (xy 157.453882 -294.272114) (xy 157.483447 -294.311458)
			(xy 157.506318 -294.355035) (xy 157.521902 -294.401716) (xy 157.529797 -294.450293) (xy 157.530292 -294.4749)
			(xy 157.529797 -294.499507) (xy 157.529465 -294.501549) (xy 157.819334 -294.501549) (xy 157.819334 -294.448251)
			(xy 157.827277 -294.395547) (xy 157.842987 -294.344617) (xy 157.866113 -294.296596) (xy 157.896137 -294.252559)
			(xy 157.932389 -294.213488) (xy 157.97406 -294.180257) (xy 158.020218 -294.153608) (xy 158.069832 -294.134136)
			(xy 158.121794 -294.122276) (xy 158.174944 -294.118293) (xy 158.228094 -294.122276) (xy 158.280056 -294.134136)
			(xy 158.32967 -294.153608) (xy 158.375828 -294.180257) (xy 158.417499 -294.213488) (xy 158.453751 -294.252559)
			(xy 158.483775 -294.296596) (xy 158.506901 -294.344617) (xy 158.522611 -294.395547) (xy 158.530554 -294.448251)
			(xy 158.531052 -294.4749) (xy 158.530554 -294.501549) (xy 158.522611 -294.554253) (xy 158.506901 -294.605183)
			(xy 158.483775 -294.653204) (xy 158.453751 -294.697241) (xy 158.417499 -294.736312) (xy 158.375828 -294.769543)
			(xy 158.32967 -294.796192) (xy 158.280056 -294.815664) (xy 158.228094 -294.827524) (xy 158.174944 -294.831508)
			(xy 158.121794 -294.827524) (xy 158.069832 -294.815664) (xy 158.020218 -294.796192) (xy 157.97406 -294.769543)
			(xy 157.932389 -294.736312) (xy 157.896137 -294.697241) (xy 157.866113 -294.653204) (xy 157.842987 -294.605183)
			(xy 157.827277 -294.554253) (xy 157.819334 -294.501549) (xy 157.529465 -294.501549) (xy 157.521902 -294.548084)
			(xy 157.506318 -294.594765) (xy 157.483447 -294.638342) (xy 157.453882 -294.677686) (xy 157.418389 -294.711778)
			(xy 157.377886 -294.739734) (xy 157.333424 -294.760832) (xy 157.286153 -294.774524) (xy 157.237298 -294.780456)
			(xy 157.188123 -294.778475) (xy 157.139904 -294.768631) (xy 157.093888 -294.751179) (xy 157.051267 -294.726572)
			(xy 157.013146 -294.695447) (xy 156.980511 -294.65861) (xy 156.954208 -294.617014) (xy 156.934917 -294.571738)
			(xy 156.92314 -294.523954) (xy 156.91918 -294.4749) (xy 154.680412 -294.4749) (xy 154.679917 -294.499507)
			(xy 154.672022 -294.548084) (xy 154.656438 -294.594765) (xy 154.633567 -294.638342) (xy 154.604002 -294.677686)
			(xy 154.568509 -294.711778) (xy 154.528006 -294.739734) (xy 154.483544 -294.760832) (xy 154.436273 -294.774524)
			(xy 154.387418 -294.780456) (xy 154.338243 -294.778475) (xy 154.290024 -294.768631) (xy 154.244008 -294.751179)
			(xy 154.201387 -294.726572) (xy 154.163266 -294.695447) (xy 154.130631 -294.65861) (xy 154.104328 -294.617014)
			(xy 154.085037 -294.571738) (xy 154.07326 -294.523954) (xy 154.0693 -294.4749) (xy 153.730198 -294.4749)
			(xy 153.729703 -294.499507) (xy 153.721808 -294.548084) (xy 153.706224 -294.594765) (xy 153.683353 -294.638342)
			(xy 153.653788 -294.677686) (xy 153.618295 -294.711778) (xy 153.577792 -294.739734) (xy 153.53333 -294.760832)
			(xy 153.486059 -294.774524) (xy 153.437204 -294.780456) (xy 153.388029 -294.778475) (xy 153.33981 -294.768631)
			(xy 153.293794 -294.751179) (xy 153.251173 -294.726572) (xy 153.213052 -294.695447) (xy 153.180417 -294.65861)
			(xy 153.154114 -294.617014) (xy 153.134823 -294.571738) (xy 153.123046 -294.523954) (xy 153.119086 -294.4749)
			(xy 152.805099 -294.4749) (xy 152.805099 -294.500886) (xy 152.796969 -294.552217) (xy 152.78091 -294.601645)
			(xy 152.757317 -294.647953) (xy 152.72677 -294.69) (xy 152.690022 -294.726751) (xy 152.647978 -294.757301)
			(xy 152.601673 -294.780898) (xy 152.552246 -294.796962) (xy 152.500916 -294.805096) (xy 152.47493 -294.805608)
			(xy 152.474422 -294.805608) (xy 152.448246 -294.80511) (xy 152.39655 -294.796856) (xy 152.346803 -294.78055)
			(xy 152.323292 -294.769032) (xy 152.323038 -294.769032) (xy 152.317197 -294.766277) (xy 152.304603 -294.763439)
			(xy 152.298146 -294.763444) (xy 152.284938 -294.763952) (xy 152.204928 -294.812974) (xy 152.19553 -294.82034)
			(xy 152.18664 -294.82923) (xy 152.18283 -294.838374) (xy 152.178004 -294.84828) (xy 152.178004 -296.37482)
			(xy 153.11934 -296.37482) (xy 153.1233 -296.325766) (xy 153.135077 -296.277982) (xy 153.154368 -296.232706)
			(xy 153.180671 -296.19111) (xy 153.213306 -296.154273) (xy 153.251427 -296.123148) (xy 153.294048 -296.098541)
			(xy 153.340064 -296.081089) (xy 153.388283 -296.071245) (xy 153.437458 -296.069264) (xy 153.486313 -296.075196)
			(xy 153.533584 -296.088888) (xy 153.578046 -296.109986) (xy 153.618549 -296.137942) (xy 153.654042 -296.172034)
			(xy 153.683607 -296.211378) (xy 153.706478 -296.254955) (xy 153.722062 -296.301636) (xy 153.729957 -296.350213)
			(xy 153.730452 -296.37482) (xy 154.069046 -296.37482) (xy 154.073006 -296.325766) (xy 154.084783 -296.277982)
			(xy 154.104074 -296.232706) (xy 154.130377 -296.19111) (xy 154.163012 -296.154273) (xy 154.201133 -296.123148)
			(xy 154.243754 -296.098541) (xy 154.28977 -296.081089) (xy 154.337989 -296.071245) (xy 154.387164 -296.069264)
			(xy 154.436019 -296.075196) (xy 154.48329 -296.088888) (xy 154.527752 -296.109986) (xy 154.568255 -296.137942)
			(xy 154.603748 -296.172034) (xy 154.633313 -296.211378) (xy 154.656184 -296.254955) (xy 154.671768 -296.301636)
			(xy 154.679663 -296.350213) (xy 154.680158 -296.37482) (xy 155.01926 -296.37482) (xy 155.02322 -296.325766)
			(xy 155.034997 -296.277982) (xy 155.054288 -296.232706) (xy 155.080591 -296.19111) (xy 155.113226 -296.154273)
			(xy 155.151347 -296.123148) (xy 155.193968 -296.098541) (xy 155.239984 -296.081089) (xy 155.288203 -296.071245)
			(xy 155.337378 -296.069264) (xy 155.386233 -296.075196) (xy 155.433504 -296.088888) (xy 155.477966 -296.109986)
			(xy 155.518469 -296.137942) (xy 155.553962 -296.172034) (xy 155.583527 -296.211378) (xy 155.606398 -296.254955)
			(xy 155.621982 -296.301636) (xy 155.629877 -296.350213) (xy 155.630372 -296.37482) (xy 155.96922 -296.37482)
			(xy 155.97318 -296.325766) (xy 155.984957 -296.277982) (xy 156.004248 -296.232706) (xy 156.030551 -296.19111)
			(xy 156.063186 -296.154273) (xy 156.101307 -296.123148) (xy 156.143928 -296.098541) (xy 156.189944 -296.081089)
			(xy 156.238163 -296.071245) (xy 156.287338 -296.069264) (xy 156.336193 -296.075196) (xy 156.383464 -296.088888)
			(xy 156.427926 -296.109986) (xy 156.468429 -296.137942) (xy 156.503922 -296.172034) (xy 156.533487 -296.211378)
			(xy 156.556358 -296.254955) (xy 156.571942 -296.301636) (xy 156.579837 -296.350213) (xy 156.580332 -296.37482)
			(xy 157.86914 -296.37482) (xy 157.8731 -296.325766) (xy 157.884877 -296.277982) (xy 157.904168 -296.232706)
			(xy 157.930471 -296.19111) (xy 157.963106 -296.154273) (xy 158.001227 -296.123148) (xy 158.043848 -296.098541)
			(xy 158.089864 -296.081089) (xy 158.138083 -296.071245) (xy 158.187258 -296.069264) (xy 158.236113 -296.075196)
			(xy 158.283384 -296.088888) (xy 158.327846 -296.109986) (xy 158.368349 -296.137942) (xy 158.403842 -296.172034)
			(xy 158.433407 -296.211378) (xy 158.456278 -296.254955) (xy 158.471862 -296.301636) (xy 158.479757 -296.350213)
			(xy 158.480252 -296.37482) (xy 158.479757 -296.399427) (xy 158.471862 -296.448004) (xy 158.456278 -296.494685)
			(xy 158.433407 -296.538262) (xy 158.403842 -296.577606) (xy 158.368349 -296.611698) (xy 158.327846 -296.639654)
			(xy 158.283384 -296.660752) (xy 158.236113 -296.674444) (xy 158.187258 -296.680376) (xy 158.138083 -296.678395)
			(xy 158.089864 -296.668551) (xy 158.043848 -296.651099) (xy 158.001227 -296.626492) (xy 157.963106 -296.595367)
			(xy 157.930471 -296.55853) (xy 157.904168 -296.516934) (xy 157.884877 -296.471658) (xy 157.8731 -296.423874)
			(xy 157.86914 -296.37482) (xy 156.580332 -296.37482) (xy 156.579837 -296.399427) (xy 156.571942 -296.448004)
			(xy 156.556358 -296.494685) (xy 156.533487 -296.538262) (xy 156.503922 -296.577606) (xy 156.468429 -296.611698)
			(xy 156.427926 -296.639654) (xy 156.383464 -296.660752) (xy 156.336193 -296.674444) (xy 156.287338 -296.680376)
			(xy 156.238163 -296.678395) (xy 156.189944 -296.668551) (xy 156.143928 -296.651099) (xy 156.101307 -296.626492)
			(xy 156.063186 -296.595367) (xy 156.030551 -296.55853) (xy 156.004248 -296.516934) (xy 155.984957 -296.471658)
			(xy 155.97318 -296.423874) (xy 155.96922 -296.37482) (xy 155.630372 -296.37482) (xy 155.629877 -296.399427)
			(xy 155.621982 -296.448004) (xy 155.606398 -296.494685) (xy 155.583527 -296.538262) (xy 155.553962 -296.577606)
			(xy 155.518469 -296.611698) (xy 155.477966 -296.639654) (xy 155.433504 -296.660752) (xy 155.386233 -296.674444)
			(xy 155.337378 -296.680376) (xy 155.288203 -296.678395) (xy 155.239984 -296.668551) (xy 155.193968 -296.651099)
			(xy 155.151347 -296.626492) (xy 155.113226 -296.595367) (xy 155.080591 -296.55853) (xy 155.054288 -296.516934)
			(xy 155.034997 -296.471658) (xy 155.02322 -296.423874) (xy 155.01926 -296.37482) (xy 154.680158 -296.37482)
			(xy 154.679663 -296.399427) (xy 154.671768 -296.448004) (xy 154.656184 -296.494685) (xy 154.633313 -296.538262)
			(xy 154.603748 -296.577606) (xy 154.568255 -296.611698) (xy 154.527752 -296.639654) (xy 154.48329 -296.660752)
			(xy 154.436019 -296.674444) (xy 154.387164 -296.680376) (xy 154.337989 -296.678395) (xy 154.28977 -296.668551)
			(xy 154.243754 -296.651099) (xy 154.201133 -296.626492) (xy 154.163012 -296.595367) (xy 154.130377 -296.55853)
			(xy 154.104074 -296.516934) (xy 154.084783 -296.471658) (xy 154.073006 -296.423874) (xy 154.069046 -296.37482)
			(xy 153.730452 -296.37482) (xy 153.729957 -296.399427) (xy 153.722062 -296.448004) (xy 153.706478 -296.494685)
			(xy 153.683607 -296.538262) (xy 153.654042 -296.577606) (xy 153.618549 -296.611698) (xy 153.578046 -296.639654)
			(xy 153.533584 -296.660752) (xy 153.486313 -296.674444) (xy 153.437458 -296.680376) (xy 153.388283 -296.678395)
			(xy 153.340064 -296.668551) (xy 153.294048 -296.651099) (xy 153.251427 -296.626492) (xy 153.213306 -296.595367)
			(xy 153.180671 -296.55853) (xy 153.154368 -296.516934) (xy 153.135077 -296.471658) (xy 153.1233 -296.423874)
			(xy 153.11934 -296.37482) (xy 152.178004 -296.37482) (xy 152.178004 -296.938446) (xy 152.178126 -296.942994)
			(xy 152.179782 -296.951939) (xy 152.181306 -296.956226) (xy 152.192482 -296.985944) (xy 152.194514 -296.99331)
			(xy 152.196292 -297.001438) (xy 152.198307 -297.009619) (xy 152.206922 -297.024088) (xy 152.21979 -297.03495)
			(xy 152.227534 -297.038268) (xy 152.26538 -297.053) (xy 152.288748 -297.050714) (xy 152.299162 -297.044364)
			(xy 152.318965 -297.032463) (xy 152.361167 -297.013665) (xy 152.405574 -297.000918) (xy 152.451322 -296.994469)
			(xy 152.474422 -296.994072) (xy 153.424636 -296.994072) (xy 153.450623 -296.994584) (xy 153.501956 -297.00272)
			(xy 153.551385 -297.018785) (xy 153.597692 -297.042384) (xy 153.639738 -297.072936) (xy 153.676487 -297.109689)
			(xy 153.707035 -297.151739) (xy 153.730629 -297.198048) (xy 153.746689 -297.247479) (xy 153.754819 -297.298813)
			(xy 153.754819 -297.32478) (xy 154.069046 -297.32478) (xy 154.073006 -297.275726) (xy 154.084783 -297.227942)
			(xy 154.104074 -297.182666) (xy 154.130377 -297.14107) (xy 154.163012 -297.104233) (xy 154.201133 -297.073108)
			(xy 154.243754 -297.048501) (xy 154.28977 -297.031049) (xy 154.337989 -297.021205) (xy 154.387164 -297.019224)
			(xy 154.436019 -297.025156) (xy 154.48329 -297.038848) (xy 154.527752 -297.059946) (xy 154.568255 -297.087902)
			(xy 154.603748 -297.121994) (xy 154.633313 -297.161338) (xy 154.656184 -297.204915) (xy 154.671768 -297.251596)
			(xy 154.679663 -297.300173) (xy 154.680158 -297.32478) (xy 155.01926 -297.32478) (xy 155.02322 -297.275726)
			(xy 155.034997 -297.227942) (xy 155.054288 -297.182666) (xy 155.080591 -297.14107) (xy 155.113226 -297.104233)
			(xy 155.151347 -297.073108) (xy 155.193968 -297.048501) (xy 155.239984 -297.031049) (xy 155.288203 -297.021205)
			(xy 155.337378 -297.019224) (xy 155.386233 -297.025156) (xy 155.433504 -297.038848) (xy 155.477966 -297.059946)
			(xy 155.518469 -297.087902) (xy 155.553962 -297.121994) (xy 155.583527 -297.161338) (xy 155.606398 -297.204915)
			(xy 155.621982 -297.251596) (xy 155.629877 -297.300173) (xy 155.630372 -297.32478) (xy 157.86914 -297.32478)
			(xy 157.8731 -297.275726) (xy 157.884877 -297.227942) (xy 157.904168 -297.182666) (xy 157.930471 -297.14107)
			(xy 157.963106 -297.104233) (xy 158.001227 -297.073108) (xy 158.043848 -297.048501) (xy 158.089864 -297.031049)
			(xy 158.138083 -297.021205) (xy 158.187258 -297.019224) (xy 158.236113 -297.025156) (xy 158.283384 -297.038848)
			(xy 158.327846 -297.059946) (xy 158.368349 -297.087902) (xy 158.403842 -297.121994) (xy 158.433407 -297.161338)
			(xy 158.456278 -297.204915) (xy 158.471862 -297.251596) (xy 158.479757 -297.300173) (xy 158.480252 -297.32478)
			(xy 158.479757 -297.349387) (xy 158.471862 -297.397964) (xy 158.456278 -297.444645) (xy 158.433407 -297.488222)
			(xy 158.403842 -297.527566) (xy 158.368349 -297.561658) (xy 158.327846 -297.589614) (xy 158.283384 -297.610712)
			(xy 158.236113 -297.624404) (xy 158.187258 -297.630336) (xy 158.138083 -297.628355) (xy 158.089864 -297.618511)
			(xy 158.043848 -297.601059) (xy 158.001227 -297.576452) (xy 157.963106 -297.545327) (xy 157.930471 -297.50849)
			(xy 157.904168 -297.466894) (xy 157.884877 -297.421618) (xy 157.8731 -297.373834) (xy 157.86914 -297.32478)
			(xy 155.630372 -297.32478) (xy 155.629877 -297.349387) (xy 155.621982 -297.397964) (xy 155.606398 -297.444645)
			(xy 155.583527 -297.488222) (xy 155.553962 -297.527566) (xy 155.518469 -297.561658) (xy 155.477966 -297.589614)
			(xy 155.433504 -297.610712) (xy 155.386233 -297.624404) (xy 155.337378 -297.630336) (xy 155.288203 -297.628355)
			(xy 155.239984 -297.618511) (xy 155.193968 -297.601059) (xy 155.151347 -297.576452) (xy 155.113226 -297.545327)
			(xy 155.080591 -297.50849) (xy 155.054288 -297.466894) (xy 155.034997 -297.421618) (xy 155.02322 -297.373834)
			(xy 155.01926 -297.32478) (xy 154.680158 -297.32478) (xy 154.679663 -297.349387) (xy 154.671768 -297.397964)
			(xy 154.656184 -297.444645) (xy 154.633313 -297.488222) (xy 154.603748 -297.527566) (xy 154.568255 -297.561658)
			(xy 154.527752 -297.589614) (xy 154.48329 -297.610712) (xy 154.436019 -297.624404) (xy 154.387164 -297.630336)
			(xy 154.337989 -297.628355) (xy 154.28977 -297.618511) (xy 154.243754 -297.601059) (xy 154.201133 -297.576452)
			(xy 154.163012 -297.545327) (xy 154.130377 -297.50849) (xy 154.104074 -297.466894) (xy 154.084783 -297.421618)
			(xy 154.073006 -297.373834) (xy 154.069046 -297.32478) (xy 153.754819 -297.32478) (xy 153.754819 -297.350787)
			(xy 153.746689 -297.402121) (xy 153.730629 -297.451552) (xy 153.707035 -297.497861) (xy 153.676487 -297.539911)
			(xy 153.639738 -297.576664) (xy 153.597692 -297.607216) (xy 153.551385 -297.630815) (xy 153.501956 -297.64688)
			(xy 153.450623 -297.655016) (xy 153.424636 -297.655488) (xy 152.474422 -297.655488) (xy 152.452367 -297.655101)
			(xy 152.408652 -297.649207) (xy 152.366104 -297.637571) (xy 152.345644 -297.629326) (xy 152.333754 -297.624945)
			(xy 152.308548 -297.6272) (xy 152.297638 -297.633644) (xy 152.22982 -297.678856) (xy 152.219679 -297.686327)
			(xy 152.207689 -297.708445) (xy 152.20696 -297.72102) (xy 152.20696 -298.058078) (xy 152.207399 -298.068141)
			(xy 152.21514 -298.086719) (xy 152.221946 -298.094146) (xy 152.402598 -298.27474) (xy 153.118832 -298.27474)
			(xy 153.122792 -298.225686) (xy 153.134569 -298.177902) (xy 153.15386 -298.132626) (xy 153.180163 -298.09103)
			(xy 153.212798 -298.054193) (xy 153.250919 -298.023068) (xy 153.29354 -297.998461) (xy 153.339556 -297.981009)
			(xy 153.387775 -297.971165) (xy 153.43695 -297.969184) (xy 153.485805 -297.975116) (xy 153.533076 -297.988808)
			(xy 153.577538 -298.009906) (xy 153.618041 -298.037862) (xy 153.653534 -298.071954) (xy 153.683099 -298.111298)
			(xy 153.70597 -298.154875) (xy 153.721554 -298.201556) (xy 153.729449 -298.250133) (xy 153.729944 -298.27474)
			(xy 154.069046 -298.27474) (xy 154.073006 -298.225686) (xy 154.084783 -298.177902) (xy 154.104074 -298.132626)
			(xy 154.130377 -298.09103) (xy 154.163012 -298.054193) (xy 154.201133 -298.023068) (xy 154.243754 -297.998461)
			(xy 154.28977 -297.981009) (xy 154.337989 -297.971165) (xy 154.387164 -297.969184) (xy 154.436019 -297.975116)
			(xy 154.48329 -297.988808) (xy 154.527752 -298.009906) (xy 154.568255 -298.037862) (xy 154.603748 -298.071954)
			(xy 154.633313 -298.111298) (xy 154.656184 -298.154875) (xy 154.671768 -298.201556) (xy 154.679663 -298.250133)
			(xy 154.680158 -298.27474) (xy 155.01926 -298.27474) (xy 155.02322 -298.225686) (xy 155.034997 -298.177902)
			(xy 155.054288 -298.132626) (xy 155.080591 -298.09103) (xy 155.113226 -298.054193) (xy 155.151347 -298.023068)
			(xy 155.193968 -297.998461) (xy 155.239984 -297.981009) (xy 155.288203 -297.971165) (xy 155.337378 -297.969184)
			(xy 155.386233 -297.975116) (xy 155.433504 -297.988808) (xy 155.477966 -298.009906) (xy 155.518469 -298.037862)
			(xy 155.553962 -298.071954) (xy 155.583527 -298.111298) (xy 155.606398 -298.154875) (xy 155.621982 -298.201556)
			(xy 155.629877 -298.250133) (xy 155.630372 -298.27474) (xy 155.96922 -298.27474) (xy 155.97318 -298.225686)
			(xy 155.984957 -298.177902) (xy 156.004248 -298.132626) (xy 156.030551 -298.09103) (xy 156.063186 -298.054193)
			(xy 156.101307 -298.023068) (xy 156.143928 -297.998461) (xy 156.189944 -297.981009) (xy 156.238163 -297.971165)
			(xy 156.287338 -297.969184) (xy 156.336193 -297.975116) (xy 156.383464 -297.988808) (xy 156.427926 -298.009906)
			(xy 156.468429 -298.037862) (xy 156.503922 -298.071954) (xy 156.533487 -298.111298) (xy 156.556358 -298.154875)
			(xy 156.571942 -298.201556) (xy 156.579837 -298.250133) (xy 156.580332 -298.27474) (xy 156.91918 -298.27474)
			(xy 156.92314 -298.225686) (xy 156.934917 -298.177902) (xy 156.954208 -298.132626) (xy 156.980511 -298.09103)
			(xy 157.013146 -298.054193) (xy 157.051267 -298.023068) (xy 157.093888 -297.998461) (xy 157.139904 -297.981009)
			(xy 157.188123 -297.971165) (xy 157.237298 -297.969184) (xy 157.286153 -297.975116) (xy 157.333424 -297.988808)
			(xy 157.377886 -298.009906) (xy 157.418389 -298.037862) (xy 157.453882 -298.071954) (xy 157.483447 -298.111298)
			(xy 157.506318 -298.154875) (xy 157.521902 -298.201556) (xy 157.529797 -298.250133) (xy 157.530292 -298.27474)
			(xy 157.86914 -298.27474) (xy 157.8731 -298.225686) (xy 157.884877 -298.177902) (xy 157.904168 -298.132626)
			(xy 157.930471 -298.09103) (xy 157.963106 -298.054193) (xy 158.001227 -298.023068) (xy 158.043848 -297.998461)
			(xy 158.089864 -297.981009) (xy 158.138083 -297.971165) (xy 158.187258 -297.969184) (xy 158.236113 -297.975116)
			(xy 158.283384 -297.988808) (xy 158.327846 -298.009906) (xy 158.368349 -298.037862) (xy 158.403842 -298.071954)
			(xy 158.433407 -298.111298) (xy 158.456278 -298.154875) (xy 158.471862 -298.201556) (xy 158.479757 -298.250133)
			(xy 158.480252 -298.27474) (xy 159.76906 -298.27474) (xy 159.77302 -298.225686) (xy 159.784797 -298.177902)
			(xy 159.804088 -298.132626) (xy 159.830391 -298.09103) (xy 159.863026 -298.054193) (xy 159.901147 -298.023068)
			(xy 159.943768 -297.998461) (xy 159.989784 -297.981009) (xy 160.038003 -297.971165) (xy 160.087178 -297.969184)
			(xy 160.136033 -297.975116) (xy 160.183304 -297.988808) (xy 160.227766 -298.009906) (xy 160.268269 -298.037862)
			(xy 160.303762 -298.071954) (xy 160.333327 -298.111298) (xy 160.356198 -298.154875) (xy 160.371782 -298.201556)
			(xy 160.379677 -298.250133) (xy 160.380172 -298.27474) (xy 160.379677 -298.299347) (xy 160.371782 -298.347924)
			(xy 160.356198 -298.394605) (xy 160.333327 -298.438182) (xy 160.303762 -298.477526) (xy 160.268269 -298.511618)
			(xy 160.227766 -298.539574) (xy 160.183304 -298.560672) (xy 160.136033 -298.574364) (xy 160.087178 -298.580296)
			(xy 160.038003 -298.578315) (xy 159.989784 -298.568471) (xy 159.943768 -298.551019) (xy 159.901147 -298.526412)
			(xy 159.863026 -298.495287) (xy 159.830391 -298.45845) (xy 159.804088 -298.416854) (xy 159.784797 -298.371578)
			(xy 159.77302 -298.323794) (xy 159.76906 -298.27474) (xy 158.480252 -298.27474) (xy 158.479757 -298.299347)
			(xy 158.471862 -298.347924) (xy 158.456278 -298.394605) (xy 158.433407 -298.438182) (xy 158.403842 -298.477526)
			(xy 158.368349 -298.511618) (xy 158.327846 -298.539574) (xy 158.283384 -298.560672) (xy 158.236113 -298.574364)
			(xy 158.187258 -298.580296) (xy 158.138083 -298.578315) (xy 158.089864 -298.568471) (xy 158.043848 -298.551019)
			(xy 158.001227 -298.526412) (xy 157.963106 -298.495287) (xy 157.930471 -298.45845) (xy 157.904168 -298.416854)
			(xy 157.884877 -298.371578) (xy 157.8731 -298.323794) (xy 157.86914 -298.27474) (xy 157.530292 -298.27474)
			(xy 157.529797 -298.299347) (xy 157.521902 -298.347924) (xy 157.506318 -298.394605) (xy 157.483447 -298.438182)
			(xy 157.453882 -298.477526) (xy 157.418389 -298.511618) (xy 157.377886 -298.539574) (xy 157.333424 -298.560672)
			(xy 157.286153 -298.574364) (xy 157.237298 -298.580296) (xy 157.188123 -298.578315) (xy 157.139904 -298.568471)
			(xy 157.093888 -298.551019) (xy 157.051267 -298.526412) (xy 157.013146 -298.495287) (xy 156.980511 -298.45845)
			(xy 156.954208 -298.416854) (xy 156.934917 -298.371578) (xy 156.92314 -298.323794) (xy 156.91918 -298.27474)
			(xy 156.580332 -298.27474) (xy 156.579837 -298.299347) (xy 156.571942 -298.347924) (xy 156.556358 -298.394605)
			(xy 156.533487 -298.438182) (xy 156.503922 -298.477526) (xy 156.468429 -298.511618) (xy 156.427926 -298.539574)
			(xy 156.383464 -298.560672) (xy 156.336193 -298.574364) (xy 156.287338 -298.580296) (xy 156.238163 -298.578315)
			(xy 156.189944 -298.568471) (xy 156.143928 -298.551019) (xy 156.101307 -298.526412) (xy 156.063186 -298.495287)
			(xy 156.030551 -298.45845) (xy 156.004248 -298.416854) (xy 155.984957 -298.371578) (xy 155.97318 -298.323794)
			(xy 155.96922 -298.27474) (xy 155.630372 -298.27474) (xy 155.629877 -298.299347) (xy 155.621982 -298.347924)
			(xy 155.606398 -298.394605) (xy 155.583527 -298.438182) (xy 155.553962 -298.477526) (xy 155.518469 -298.511618)
			(xy 155.477966 -298.539574) (xy 155.433504 -298.560672) (xy 155.386233 -298.574364) (xy 155.337378 -298.580296)
			(xy 155.288203 -298.578315) (xy 155.239984 -298.568471) (xy 155.193968 -298.551019) (xy 155.151347 -298.526412)
			(xy 155.113226 -298.495287) (xy 155.080591 -298.45845) (xy 155.054288 -298.416854) (xy 155.034997 -298.371578)
			(xy 155.02322 -298.323794) (xy 155.01926 -298.27474) (xy 154.680158 -298.27474) (xy 154.679663 -298.299347)
			(xy 154.671768 -298.347924) (xy 154.656184 -298.394605) (xy 154.633313 -298.438182) (xy 154.603748 -298.477526)
			(xy 154.568255 -298.511618) (xy 154.527752 -298.539574) (xy 154.48329 -298.560672) (xy 154.436019 -298.574364)
			(xy 154.387164 -298.580296) (xy 154.337989 -298.578315) (xy 154.28977 -298.568471) (xy 154.243754 -298.551019)
			(xy 154.201133 -298.526412) (xy 154.163012 -298.495287) (xy 154.130377 -298.45845) (xy 154.104074 -298.416854)
			(xy 154.084783 -298.371578) (xy 154.073006 -298.323794) (xy 154.069046 -298.27474) (xy 153.729944 -298.27474)
			(xy 153.729449 -298.299347) (xy 153.721554 -298.347924) (xy 153.70597 -298.394605) (xy 153.683099 -298.438182)
			(xy 153.653534 -298.477526) (xy 153.618041 -298.511618) (xy 153.577538 -298.539574) (xy 153.533076 -298.560672)
			(xy 153.485805 -298.574364) (xy 153.43695 -298.580296) (xy 153.387775 -298.578315) (xy 153.339556 -298.568471)
			(xy 153.29354 -298.551019) (xy 153.250919 -298.526412) (xy 153.212798 -298.495287) (xy 153.180163 -298.45845)
			(xy 153.15386 -298.416854) (xy 153.134569 -298.371578) (xy 153.122792 -298.323794) (xy 153.118832 -298.27474)
			(xy 152.402598 -298.27474) (xy 153.00706 -298.879006) (xy 153.014462 -298.885842) (xy 153.03306 -298.893554)
			(xy 153.043128 -298.893992) (xy 153.424636 -298.893992) (xy 153.450621 -298.894504) (xy 153.501951 -298.902639)
			(xy 153.551377 -298.918703) (xy 153.597682 -298.942301) (xy 153.639725 -298.972852) (xy 153.676472 -299.009602)
			(xy 153.707018 -299.051649) (xy 153.73061 -299.097956) (xy 153.746669 -299.147384) (xy 153.754799 -299.198715)
			(xy 153.755344 -299.2247) (xy 153.755344 -299.224954) (xy 154.069046 -299.224954) (xy 154.073006 -299.1759)
			(xy 154.084783 -299.128116) (xy 154.104074 -299.08284) (xy 154.130377 -299.041244) (xy 154.163012 -299.004407)
			(xy 154.201133 -298.973282) (xy 154.243754 -298.948675) (xy 154.28977 -298.931223) (xy 154.337989 -298.921379)
			(xy 154.387164 -298.919398) (xy 154.436019 -298.92533) (xy 154.48329 -298.939022) (xy 154.527752 -298.96012)
			(xy 154.568255 -298.988076) (xy 154.603748 -299.022168) (xy 154.633313 -299.061512) (xy 154.656184 -299.105089)
			(xy 154.671768 -299.15177) (xy 154.679663 -299.200347) (xy 154.680158 -299.224954) (xy 154.679663 -299.249561)
			(xy 154.679428 -299.251009) (xy 154.994602 -299.251009) (xy 154.994602 -299.198991) (xy 155.002739 -299.147613)
			(xy 155.018812 -299.098141) (xy 155.042426 -299.051792) (xy 155.073 -299.009707) (xy 155.10978 -298.972923)
			(xy 155.151861 -298.942345) (xy 155.198208 -298.918726) (xy 155.247678 -298.902647) (xy 155.299055 -298.894505)
			(xy 155.325064 -298.893992) (xy 156.275024 -298.893992) (xy 156.301026 -298.894596) (xy 156.35239 -298.902735)
			(xy 156.401848 -298.918808) (xy 156.448184 -298.94242) (xy 156.490255 -298.972989) (xy 156.527026 -299.009763)
			(xy 156.557593 -299.051837) (xy 156.581201 -299.098174) (xy 156.597271 -299.147633) (xy 156.605406 -299.198998)
			(xy 156.605406 -299.224954) (xy 156.91918 -299.224954) (xy 156.92314 -299.1759) (xy 156.934917 -299.128116)
			(xy 156.954208 -299.08284) (xy 156.980511 -299.041244) (xy 157.013146 -299.004407) (xy 157.051267 -298.973282)
			(xy 157.093888 -298.948675) (xy 157.139904 -298.931223) (xy 157.188123 -298.921379) (xy 157.237298 -298.919398)
			(xy 157.286153 -298.92533) (xy 157.333424 -298.939022) (xy 157.377886 -298.96012) (xy 157.418389 -298.988076)
			(xy 157.453882 -299.022168) (xy 157.483447 -299.061512) (xy 157.506318 -299.105089) (xy 157.521902 -299.15177)
			(xy 157.529797 -299.200347) (xy 157.530287 -299.2247) (xy 157.86914 -299.2247) (xy 157.8731 -299.175646)
			(xy 157.884877 -299.127862) (xy 157.904168 -299.082586) (xy 157.930471 -299.04099) (xy 157.963106 -299.004153)
			(xy 158.001227 -298.973028) (xy 158.043848 -298.948421) (xy 158.089864 -298.930969) (xy 158.138083 -298.921125)
			(xy 158.187258 -298.919144) (xy 158.236113 -298.925076) (xy 158.283384 -298.938768) (xy 158.327846 -298.959866)
			(xy 158.368349 -298.987822) (xy 158.403842 -299.021914) (xy 158.433407 -299.061258) (xy 158.456278 -299.104835)
			(xy 158.471862 -299.151516) (xy 158.479757 -299.200093) (xy 158.480252 -299.2247) (xy 158.480247 -299.224954)
			(xy 159.76906 -299.224954) (xy 159.77302 -299.1759) (xy 159.784797 -299.128116) (xy 159.804088 -299.08284)
			(xy 159.830391 -299.041244) (xy 159.863026 -299.004407) (xy 159.901147 -298.973282) (xy 159.943768 -298.948675)
			(xy 159.989784 -298.931223) (xy 160.038003 -298.921379) (xy 160.087178 -298.919398) (xy 160.136033 -298.92533)
			(xy 160.183304 -298.939022) (xy 160.227766 -298.96012) (xy 160.268269 -298.988076) (xy 160.303762 -299.022168)
			(xy 160.333327 -299.061512) (xy 160.356198 -299.105089) (xy 160.371782 -299.15177) (xy 160.379677 -299.200347)
			(xy 160.380172 -299.224954) (xy 160.379677 -299.249561) (xy 160.371782 -299.298138) (xy 160.356198 -299.344819)
			(xy 160.333327 -299.388396) (xy 160.303762 -299.42774) (xy 160.268269 -299.461832) (xy 160.227766 -299.489788)
			(xy 160.183304 -299.510886) (xy 160.136033 -299.524578) (xy 160.087178 -299.53051) (xy 160.038003 -299.528529)
			(xy 159.989784 -299.518685) (xy 159.943768 -299.501233) (xy 159.901147 -299.476626) (xy 159.863026 -299.445501)
			(xy 159.830391 -299.408664) (xy 159.804088 -299.367068) (xy 159.784797 -299.321792) (xy 159.77302 -299.274008)
			(xy 159.76906 -299.224954) (xy 158.480247 -299.224954) (xy 158.479757 -299.249307) (xy 158.471862 -299.297884)
			(xy 158.456278 -299.344565) (xy 158.433407 -299.388142) (xy 158.403842 -299.427486) (xy 158.368349 -299.461578)
			(xy 158.327846 -299.489534) (xy 158.283384 -299.510632) (xy 158.236113 -299.524324) (xy 158.187258 -299.530256)
			(xy 158.138083 -299.528275) (xy 158.089864 -299.518431) (xy 158.043848 -299.500979) (xy 158.001227 -299.476372)
			(xy 157.963106 -299.445247) (xy 157.930471 -299.40841) (xy 157.904168 -299.366814) (xy 157.884877 -299.321538)
			(xy 157.8731 -299.273754) (xy 157.86914 -299.2247) (xy 157.530287 -299.2247) (xy 157.530292 -299.224954)
			(xy 157.529797 -299.249561) (xy 157.521902 -299.298138) (xy 157.506318 -299.344819) (xy 157.483447 -299.388396)
			(xy 157.453882 -299.42774) (xy 157.418389 -299.461832) (xy 157.377886 -299.489788) (xy 157.333424 -299.510886)
			(xy 157.286153 -299.524578) (xy 157.237298 -299.53051) (xy 157.188123 -299.528529) (xy 157.139904 -299.518685)
			(xy 157.093888 -299.501233) (xy 157.051267 -299.476626) (xy 157.013146 -299.445501) (xy 156.980511 -299.408664)
			(xy 156.954208 -299.367068) (xy 156.934917 -299.321792) (xy 156.92314 -299.274008) (xy 156.91918 -299.224954)
			(xy 156.605406 -299.224954) (xy 156.605406 -299.251002) (xy 156.597271 -299.302367) (xy 156.581201 -299.351826)
			(xy 156.557593 -299.398163) (xy 156.527026 -299.440237) (xy 156.490255 -299.477011) (xy 156.448184 -299.50758)
			(xy 156.401848 -299.531192) (xy 156.35239 -299.547265) (xy 156.301026 -299.555404) (xy 156.275024 -299.555916)
			(xy 156.204666 -299.555916) (xy 156.193941 -299.556335) (xy 156.174336 -299.565018) (xy 156.16682 -299.57268)
			(xy 156.109162 -299.636942) (xy 156.102558 -299.657262) (xy 156.103574 -299.667676) (xy 156.103574 -299.668184)
			(xy 156.105352 -299.699934) (xy 156.10483 -299.725189) (xy 156.096517 -299.775011) (xy 156.080116 -299.822785)
			(xy 156.056075 -299.867208) (xy 156.025051 -299.907068) (xy 155.987889 -299.941278) (xy 155.945603 -299.968904)
			(xy 155.899347 -299.989194) (xy 155.850382 -300.001594) (xy 155.800044 -300.005765) (xy 155.749706 -300.001594)
			(xy 155.700741 -299.989194) (xy 155.654485 -299.968904) (xy 155.612199 -299.941278) (xy 155.575037 -299.907068)
			(xy 155.544013 -299.867208) (xy 155.519972 -299.822785) (xy 155.503571 -299.775011) (xy 155.495258 -299.725189)
			(xy 155.494736 -299.699934) (xy 155.496514 -299.66793) (xy 155.49753 -299.657262) (xy 155.490926 -299.636942)
			(xy 155.433268 -299.57268) (xy 155.425667 -299.56514) (xy 155.406114 -299.55648) (xy 155.395422 -299.555916)
			(xy 155.325064 -299.555916) (xy 155.299055 -299.555495) (xy 155.247678 -299.547353) (xy 155.198208 -299.531274)
			(xy 155.151861 -299.507655) (xy 155.10978 -299.477077) (xy 155.073 -299.440293) (xy 155.042426 -299.398208)
			(xy 155.018812 -299.351859) (xy 155.002739 -299.302387) (xy 154.994602 -299.251009) (xy 154.679428 -299.251009)
			(xy 154.671768 -299.298138) (xy 154.656184 -299.344819) (xy 154.633313 -299.388396) (xy 154.603748 -299.42774)
			(xy 154.568255 -299.461832) (xy 154.527752 -299.489788) (xy 154.48329 -299.510886) (xy 154.436019 -299.524578)
			(xy 154.387164 -299.53051) (xy 154.337989 -299.528529) (xy 154.28977 -299.518685) (xy 154.243754 -299.501233)
			(xy 154.201133 -299.476626) (xy 154.163012 -299.445501) (xy 154.130377 -299.408664) (xy 154.104074 -299.367068)
			(xy 154.084783 -299.321792) (xy 154.073006 -299.274008) (xy 154.069046 -299.224954) (xy 153.755344 -299.224954)
			(xy 153.755344 -299.225208) (xy 153.754868 -299.251179) (xy 153.746753 -299.302484) (xy 153.73071 -299.351886)
			(xy 153.707133 -299.398169) (xy 153.676603 -299.440192) (xy 153.65857 -299.458888) (xy 153.658316 -299.459142)
			(xy 153.651684 -299.466586) (xy 153.644191 -299.48504) (xy 153.64427 -299.504957) (xy 153.651907 -299.523351)
			(xy 153.65857 -299.53077) (xy 154.170634 -300.042834) (xy 154.178031 -300.049682) (xy 154.19663 -300.057415)
			(xy 154.206702 -300.05782) (xy 155.196794 -300.05782) (xy 155.23918 -300.058294) (xy 155.323628 -300.065702)
			(xy 155.40711 -300.080435) (xy 155.488992 -300.102383) (xy 155.568652 -300.131377) (xy 155.645484 -300.167199)
			(xy 155.718905 -300.209575) (xy 155.788356 -300.258184) (xy 155.853311 -300.312656) (xy 155.88361 -300.3423)
			(xy 155.903676 -300.36262) (xy 155.913328 -300.36643) (xy 155.936134 -300.376065) (xy 155.978534 -300.401619)
			(xy 156.016256 -300.433679) (xy 156.04831 -300.471406) (xy 156.073857 -300.513811) (xy 156.083508 -300.53661)
			(xy 156.087318 -300.546262) (xy 156.107638 -300.566328) (xy 156.142899 -300.60253) (xy 156.206527 -300.68105)
			(xy 156.234638 -300.723046) (xy 156.23832 -300.728306) (xy 156.247831 -300.736929) (xy 156.253434 -300.740064)
			(xy 156.292296 -300.761908) (xy 156.300421 -300.766207) (xy 156.318528 -300.769303) (xy 156.336567 -300.765836)
			(xy 156.34462 -300.7614) (xy 156.421074 -300.714664) (xy 156.428649 -300.709519) (xy 156.439856 -300.695054)
			(xy 156.445327 -300.677591) (xy 156.445204 -300.668436) (xy 156.445204 -300.668182) (xy 156.444696 -300.649894)
			(xy 156.445182 -300.625074) (xy 156.453214 -300.576087) (xy 156.469065 -300.529045) (xy 156.492318 -300.485187)
			(xy 156.52236 -300.445669) (xy 156.5584 -300.411532) (xy 156.599487 -300.383675) (xy 156.64454 -300.362832)
			(xy 156.692371 -300.349552) (xy 156.741721 -300.344185) (xy 156.791289 -300.346873) (xy 156.839769 -300.357545)
			(xy 156.885884 -300.375919) (xy 156.928419 -300.401511) (xy 156.966253 -300.433648) (xy 156.99839 -300.471483)
			(xy 157.023982 -300.514018) (xy 157.042356 -300.560133) (xy 157.053027 -300.608613) (xy 157.055266 -300.649894)
			(xy 157.39416 -300.649894) (xy 157.39812 -300.60084) (xy 157.409897 -300.553056) (xy 157.429188 -300.50778)
			(xy 157.455491 -300.466184) (xy 157.488126 -300.429347) (xy 157.526247 -300.398222) (xy 157.568868 -300.373615)
			(xy 157.614884 -300.356163) (xy 157.663103 -300.346319) (xy 157.712278 -300.344338) (xy 157.761133 -300.35027)
			(xy 157.808404 -300.363962) (xy 157.852866 -300.38506) (xy 157.893369 -300.413016) (xy 157.928862 -300.447108)
			(xy 157.958427 -300.486452) (xy 157.981298 -300.530029) (xy 157.996882 -300.57671) (xy 158.004777 -300.625287)
			(xy 158.005272 -300.649894) (xy 158.34412 -300.649894) (xy 158.34808 -300.60084) (xy 158.359857 -300.553056)
			(xy 158.379148 -300.50778) (xy 158.405451 -300.466184) (xy 158.438086 -300.429347) (xy 158.476207 -300.398222)
			(xy 158.518828 -300.373615) (xy 158.564844 -300.356163) (xy 158.613063 -300.346319) (xy 158.662238 -300.344338)
			(xy 158.711093 -300.35027) (xy 158.758364 -300.363962) (xy 158.802826 -300.38506) (xy 158.843329 -300.413016)
			(xy 158.878822 -300.447108) (xy 158.908387 -300.486452) (xy 158.931258 -300.530029) (xy 158.946842 -300.57671)
			(xy 158.954737 -300.625287) (xy 158.955066 -300.641631) (xy 159.294175 -300.641631) (xy 159.29954 -300.592279)
			(xy 159.312819 -300.544446) (xy 159.333661 -300.499391) (xy 159.361518 -300.458301) (xy 159.395655 -300.422259)
			(xy 159.435174 -300.392215) (xy 159.479032 -300.36896) (xy 159.526075 -300.353107) (xy 159.575063 -300.345073)
			(xy 159.599884 -300.344586) (xy 159.614067 -300.344765) (xy 159.642307 -300.347436) (xy 159.656272 -300.34992)
			(xy 159.670242 -300.352051) (xy 159.698371 -300.349479) (xy 159.724717 -300.339295) (xy 159.747264 -300.322281)
			(xy 159.764284 -300.299738) (xy 159.774473 -300.273394) (xy 159.777053 -300.245266) (xy 159.77489 -300.231302)
			(xy 159.772418 -300.217335) (xy 159.769743 -300.189096) (xy 159.769556 -300.174914) (xy 159.770063 -300.150091)
			(xy 159.778093 -300.101099) (xy 159.793943 -300.054052) (xy 159.817196 -300.010188) (xy 159.84724 -299.970665)
			(xy 159.883282 -299.936523) (xy 159.924372 -299.908662) (xy 159.969429 -299.887816) (xy 160.017266 -299.874534)
			(xy 160.06662 -299.869167) (xy 160.116193 -299.871855) (xy 160.164678 -299.882529) (xy 160.210797 -299.900905)
			(xy 160.253336 -299.926502) (xy 160.291173 -299.958643) (xy 160.323311 -299.996482) (xy 160.348904 -300.039022)
			(xy 160.367278 -300.085143) (xy 160.377948 -300.133629) (xy 160.380632 -300.183202) (xy 160.375261 -300.232556)
			(xy 160.361976 -300.280391) (xy 160.341127 -300.325447) (xy 160.313263 -300.366536) (xy 160.279118 -300.402575)
			(xy 160.239593 -300.432616) (xy 160.195728 -300.455866) (xy 160.14868 -300.471713) (xy 160.099687 -300.479739)
			(xy 160.074864 -300.480222) (xy 160.060681 -300.48005) (xy 160.032441 -300.477375) (xy 160.018476 -300.474888)
			(xy 160.004514 -300.472693) (xy 159.976379 -300.475278) (xy 159.950029 -300.485473) (xy 159.927482 -300.502499)
			(xy 159.910462 -300.52505) (xy 159.900273 -300.551403) (xy 159.897694 -300.579538) (xy 159.899858 -300.593506)
			(xy 159.902331 -300.607472) (xy 159.905005 -300.635712) (xy 159.905192 -300.649894) (xy 159.904729 -300.674715)
			(xy 159.896698 -300.723704) (xy 159.880849 -300.770748) (xy 159.857597 -300.814608) (xy 159.827555 -300.854129)
			(xy 159.791516 -300.888268) (xy 159.750428 -300.916128) (xy 159.705375 -300.936974) (xy 159.657542 -300.950256)
			(xy 159.608191 -300.955625) (xy 159.558622 -300.952939) (xy 159.510139 -300.942268) (xy 159.464022 -300.923895)
			(xy 159.421485 -300.898304) (xy 159.383648 -300.866167) (xy 159.351509 -300.828333) (xy 159.325914 -300.785797)
			(xy 159.307538 -300.739682) (xy 159.296864 -300.6912) (xy 159.294175 -300.641631) (xy 158.955066 -300.641631)
			(xy 158.955232 -300.649894) (xy 158.954737 -300.674501) (xy 158.946842 -300.723078) (xy 158.931258 -300.769759)
			(xy 158.908387 -300.813336) (xy 158.878822 -300.85268) (xy 158.843329 -300.886772) (xy 158.802826 -300.914728)
			(xy 158.758364 -300.935826) (xy 158.711093 -300.949518) (xy 158.662238 -300.95545) (xy 158.613063 -300.953469)
			(xy 158.564844 -300.943625) (xy 158.518828 -300.926173) (xy 158.476207 -300.901566) (xy 158.438086 -300.870441)
			(xy 158.405451 -300.833604) (xy 158.379148 -300.792008) (xy 158.359857 -300.746732) (xy 158.34808 -300.698948)
			(xy 158.34412 -300.649894) (xy 158.005272 -300.649894) (xy 158.004777 -300.674501) (xy 157.996882 -300.723078)
			(xy 157.981298 -300.769759) (xy 157.958427 -300.813336) (xy 157.928862 -300.85268) (xy 157.893369 -300.886772)
			(xy 157.852866 -300.914728) (xy 157.808404 -300.935826) (xy 157.761133 -300.949518) (xy 157.712278 -300.95545)
			(xy 157.663103 -300.953469) (xy 157.614884 -300.943625) (xy 157.568868 -300.926173) (xy 157.526247 -300.901566)
			(xy 157.488126 -300.870441) (xy 157.455491 -300.833604) (xy 157.429188 -300.792008) (xy 157.409897 -300.746732)
			(xy 157.39812 -300.698948) (xy 157.39416 -300.649894) (xy 157.055266 -300.649894) (xy 157.055715 -300.658181)
			(xy 157.050348 -300.707531) (xy 157.037068 -300.755362) (xy 157.016224 -300.800415) (xy 156.988367 -300.841502)
			(xy 156.954229 -300.877541) (xy 156.914711 -300.907583) (xy 156.870853 -300.930835) (xy 156.823811 -300.946686)
			(xy 156.774824 -300.954718) (xy 156.750004 -300.955202) (xy 156.731716 -300.954694) (xy 156.731462 -300.954694)
			(xy 156.722291 -300.954515) (xy 156.70478 -300.959926) (xy 156.690325 -300.971195) (xy 156.685234 -300.978824)
			(xy 156.638498 -301.055278) (xy 156.633987 -301.063307) (xy 156.630475 -301.08137) (xy 156.633611 -301.099502)
			(xy 156.63799 -301.107602) (xy 156.66363 -301.152559) (xy 156.706267 -301.246869) (xy 156.72308 -301.295816)
			(xy 156.750004 -301.294546) (xy 156.775263 -301.295068) (xy 156.825092 -301.303383) (xy 156.872872 -301.319787)
			(xy 156.917301 -301.343831) (xy 156.957167 -301.37486) (xy 156.991381 -301.412027) (xy 157.019012 -301.45432)
			(xy 157.039304 -301.500583) (xy 157.051706 -301.549555) (xy 157.055874 -301.599854) (xy 157.39416 -301.599854)
			(xy 157.39812 -301.5508) (xy 157.409897 -301.503016) (xy 157.429188 -301.45774) (xy 157.455491 -301.416144)
			(xy 157.488126 -301.379307) (xy 157.526247 -301.348182) (xy 157.568868 -301.323575) (xy 157.614884 -301.306123)
			(xy 157.663103 -301.296279) (xy 157.712278 -301.294298) (xy 157.761133 -301.30023) (xy 157.808404 -301.313922)
			(xy 157.852866 -301.33502) (xy 157.893369 -301.362976) (xy 157.928862 -301.397068) (xy 157.958427 -301.436412)
			(xy 157.981298 -301.479989) (xy 157.996882 -301.52667) (xy 158.004777 -301.575247) (xy 158.005272 -301.599854)
			(xy 158.34412 -301.599854) (xy 158.34808 -301.5508) (xy 158.359857 -301.503016) (xy 158.379148 -301.45774)
			(xy 158.405451 -301.416144) (xy 158.438086 -301.379307) (xy 158.476207 -301.348182) (xy 158.518828 -301.323575)
			(xy 158.564844 -301.306123) (xy 158.613063 -301.296279) (xy 158.662238 -301.294298) (xy 158.711093 -301.30023)
			(xy 158.758364 -301.313922) (xy 158.802826 -301.33502) (xy 158.843329 -301.362976) (xy 158.878822 -301.397068)
			(xy 158.908387 -301.436412) (xy 158.931258 -301.479989) (xy 158.946842 -301.52667) (xy 158.954737 -301.575247)
			(xy 158.955232 -301.599854) (xy 159.29408 -301.599854) (xy 159.29804 -301.5508) (xy 159.309817 -301.503016)
			(xy 159.329108 -301.45774) (xy 159.355411 -301.416144) (xy 159.388046 -301.379307) (xy 159.426167 -301.348182)
			(xy 159.468788 -301.323575) (xy 159.514804 -301.306123) (xy 159.563023 -301.296279) (xy 159.612198 -301.294298)
			(xy 159.661053 -301.30023) (xy 159.708324 -301.313922) (xy 159.752786 -301.33502) (xy 159.793289 -301.362976)
			(xy 159.828782 -301.397068) (xy 159.858347 -301.436412) (xy 159.881218 -301.479989) (xy 159.896802 -301.52667)
			(xy 159.904697 -301.575247) (xy 159.905192 -301.599854) (xy 159.904697 -301.624461) (xy 159.896802 -301.673038)
			(xy 159.881218 -301.719719) (xy 159.858347 -301.763296) (xy 159.828782 -301.80264) (xy 159.793289 -301.836732)
			(xy 159.752786 -301.864688) (xy 159.708324 -301.885786) (xy 159.661053 -301.899478) (xy 159.612198 -301.90541)
			(xy 159.563023 -301.903429) (xy 159.514804 -301.893585) (xy 159.468788 -301.876133) (xy 159.426167 -301.851526)
			(xy 159.388046 -301.820401) (xy 159.355411 -301.783564) (xy 159.329108 -301.741968) (xy 159.309817 -301.696692)
			(xy 159.29804 -301.648908) (xy 159.29408 -301.599854) (xy 158.955232 -301.599854) (xy 158.954737 -301.624461)
			(xy 158.946842 -301.673038) (xy 158.931258 -301.719719) (xy 158.908387 -301.763296) (xy 158.878822 -301.80264)
			(xy 158.843329 -301.836732) (xy 158.802826 -301.864688) (xy 158.758364 -301.885786) (xy 158.711093 -301.899478)
			(xy 158.662238 -301.90541) (xy 158.613063 -301.903429) (xy 158.564844 -301.893585) (xy 158.518828 -301.876133)
			(xy 158.476207 -301.851526) (xy 158.438086 -301.820401) (xy 158.405451 -301.783564) (xy 158.379148 -301.741968)
			(xy 158.359857 -301.696692) (xy 158.34808 -301.648908) (xy 158.34412 -301.599854) (xy 158.005272 -301.599854)
			(xy 158.004777 -301.624461) (xy 157.996882 -301.673038) (xy 157.981298 -301.719719) (xy 157.958427 -301.763296)
			(xy 157.928862 -301.80264) (xy 157.893369 -301.836732) (xy 157.852866 -301.864688) (xy 157.808404 -301.885786)
			(xy 157.761133 -301.899478) (xy 157.712278 -301.90541) (xy 157.663103 -301.903429) (xy 157.614884 -301.893585)
			(xy 157.568868 -301.876133) (xy 157.526247 -301.851526) (xy 157.488126 -301.820401) (xy 157.455491 -301.783564)
			(xy 157.429188 -301.741968) (xy 157.409897 -301.696692) (xy 157.39812 -301.648908) (xy 157.39416 -301.599854)
			(xy 157.055874 -301.599854) (xy 157.055878 -301.5999) (xy 157.051706 -301.650245) (xy 157.039304 -301.699217)
			(xy 157.019012 -301.74548) (xy 156.991381 -301.787773) (xy 156.957167 -301.82494) (xy 156.917301 -301.855969)
			(xy 156.872872 -301.880013) (xy 156.825092 -301.896417) (xy 156.775263 -301.904732) (xy 156.750004 -301.905162)
			(xy 156.72308 -301.903892) (xy 156.706237 -301.952828) (xy 156.663604 -302.047136) (xy 156.63799 -302.092106)
			(xy 156.633693 -302.100231) (xy 156.6306 -302.118336) (xy 156.63407 -302.136373) (xy 156.638498 -302.14443)
			(xy 156.685234 -302.220884) (xy 156.690379 -302.228458) (xy 156.704845 -302.239664) (xy 156.722307 -302.245134)
			(xy 156.731462 -302.245014) (xy 156.731716 -302.245014) (xy 156.750004 -302.244506) (xy 156.773997 -302.244953)
			(xy 156.821391 -302.25246) (xy 156.867027 -302.267289) (xy 156.909782 -302.289075) (xy 156.948602 -302.317281)
			(xy 156.982531 -302.351212) (xy 157.010735 -302.390034) (xy 157.032518 -302.43279) (xy 157.047344 -302.478427)
			(xy 157.054849 -302.525821) (xy 157.055312 -302.549814) (xy 157.39416 -302.549814) (xy 157.39812 -302.50076)
			(xy 157.409897 -302.452976) (xy 157.429188 -302.4077) (xy 157.455491 -302.366104) (xy 157.488126 -302.329267)
			(xy 157.526247 -302.298142) (xy 157.568868 -302.273535) (xy 157.614884 -302.256083) (xy 157.663103 -302.246239)
			(xy 157.712278 -302.244258) (xy 157.761133 -302.25019) (xy 157.808404 -302.263882) (xy 157.852866 -302.28498)
			(xy 157.893369 -302.312936) (xy 157.928862 -302.347028) (xy 157.958427 -302.386372) (xy 157.981298 -302.429949)
			(xy 157.996882 -302.47663) (xy 158.004777 -302.525207) (xy 158.005272 -302.549814) (xy 158.34412 -302.549814)
			(xy 158.34808 -302.50076) (xy 158.359857 -302.452976) (xy 158.379148 -302.4077) (xy 158.405451 -302.366104)
			(xy 158.438086 -302.329267) (xy 158.476207 -302.298142) (xy 158.518828 -302.273535) (xy 158.564844 -302.256083)
			(xy 158.613063 -302.246239) (xy 158.662238 -302.244258) (xy 158.711093 -302.25019) (xy 158.758364 -302.263882)
			(xy 158.802826 -302.28498) (xy 158.843329 -302.312936) (xy 158.878822 -302.347028) (xy 158.908387 -302.386372)
			(xy 158.931258 -302.429949) (xy 158.946842 -302.47663) (xy 158.954737 -302.525207) (xy 158.955232 -302.549814)
			(xy 159.29408 -302.549814) (xy 159.29804 -302.50076) (xy 159.309817 -302.452976) (xy 159.329108 -302.4077)
			(xy 159.355411 -302.366104) (xy 159.388046 -302.329267) (xy 159.426167 -302.298142) (xy 159.468788 -302.273535)
			(xy 159.514804 -302.256083) (xy 159.563023 -302.246239) (xy 159.612198 -302.244258) (xy 159.661053 -302.25019)
			(xy 159.708324 -302.263882) (xy 159.752786 -302.28498) (xy 159.793289 -302.312936) (xy 159.828782 -302.347028)
			(xy 159.858347 -302.386372) (xy 159.881218 -302.429949) (xy 159.896802 -302.47663) (xy 159.904697 -302.525207)
			(xy 159.905192 -302.549814) (xy 160.24404 -302.549814) (xy 160.248 -302.50076) (xy 160.259777 -302.452976)
			(xy 160.279068 -302.4077) (xy 160.305371 -302.366104) (xy 160.338006 -302.329267) (xy 160.376127 -302.298142)
			(xy 160.418748 -302.273535) (xy 160.464764 -302.256083) (xy 160.512983 -302.246239) (xy 160.562158 -302.244258)
			(xy 160.611013 -302.25019) (xy 160.658284 -302.263882) (xy 160.702746 -302.28498) (xy 160.743249 -302.312936)
			(xy 160.778742 -302.347028) (xy 160.808307 -302.386372) (xy 160.831178 -302.429949) (xy 160.846762 -302.47663)
			(xy 160.854657 -302.525207) (xy 160.855152 -302.549814) (xy 160.854657 -302.574421) (xy 160.846762 -302.622998)
			(xy 160.831178 -302.669679) (xy 160.808307 -302.713256) (xy 160.778742 -302.7526) (xy 160.743249 -302.786692)
			(xy 160.702746 -302.814648) (xy 160.658284 -302.835746) (xy 160.611013 -302.849438) (xy 160.562158 -302.85537)
			(xy 160.512983 -302.853389) (xy 160.464764 -302.843545) (xy 160.418748 -302.826093) (xy 160.376127 -302.801486)
			(xy 160.338006 -302.770361) (xy 160.305371 -302.733524) (xy 160.279068 -302.691928) (xy 160.259777 -302.646652)
			(xy 160.248 -302.598868) (xy 160.24404 -302.549814) (xy 159.905192 -302.549814) (xy 159.904697 -302.574421)
			(xy 159.896802 -302.622998) (xy 159.881218 -302.669679) (xy 159.858347 -302.713256) (xy 159.828782 -302.7526)
			(xy 159.793289 -302.786692) (xy 159.752786 -302.814648) (xy 159.708324 -302.835746) (xy 159.661053 -302.849438)
			(xy 159.612198 -302.85537) (xy 159.563023 -302.853389) (xy 159.514804 -302.843545) (xy 159.468788 -302.826093)
			(xy 159.426167 -302.801486) (xy 159.388046 -302.770361) (xy 159.355411 -302.733524) (xy 159.329108 -302.691928)
			(xy 159.309817 -302.646652) (xy 159.29804 -302.598868) (xy 159.29408 -302.549814) (xy 158.955232 -302.549814)
			(xy 158.954737 -302.574421) (xy 158.946842 -302.622998) (xy 158.931258 -302.669679) (xy 158.908387 -302.713256)
			(xy 158.878822 -302.7526) (xy 158.843329 -302.786692) (xy 158.802826 -302.814648) (xy 158.758364 -302.835746)
			(xy 158.711093 -302.849438) (xy 158.662238 -302.85537) (xy 158.613063 -302.853389) (xy 158.564844 -302.843545)
			(xy 158.518828 -302.826093) (xy 158.476207 -302.801486) (xy 158.438086 -302.770361) (xy 158.405451 -302.733524)
			(xy 158.379148 -302.691928) (xy 158.359857 -302.646652) (xy 158.34808 -302.598868) (xy 158.34412 -302.549814)
			(xy 158.005272 -302.549814) (xy 158.004777 -302.574421) (xy 157.996882 -302.622998) (xy 157.981298 -302.669679)
			(xy 157.958427 -302.713256) (xy 157.928862 -302.7526) (xy 157.893369 -302.786692) (xy 157.852866 -302.814648)
			(xy 157.808404 -302.835746) (xy 157.761133 -302.849438) (xy 157.712278 -302.85537) (xy 157.663103 -302.853389)
			(xy 157.614884 -302.843545) (xy 157.568868 -302.826093) (xy 157.526247 -302.801486) (xy 157.488126 -302.770361)
			(xy 157.455491 -302.733524) (xy 157.429188 -302.691928) (xy 157.409897 -302.646652) (xy 157.39812 -302.598868)
			(xy 157.39416 -302.549814) (xy 157.055312 -302.549814) (xy 157.054707 -302.577541) (xy 157.044702 -302.632086)
			(xy 157.025021 -302.683931) (xy 156.996312 -302.731375) (xy 156.97835 -302.752506) (xy 156.972254 -302.759364)
			(xy 156.96565 -302.776636) (xy 156.96565 -302.816768) (xy 156.966087 -302.826832) (xy 156.973824 -302.845413)
			(xy 156.980636 -302.852836) (xy 157.084014 -302.956214) (xy 157.090868 -302.963609) (xy 157.09861 -302.982208)
			(xy 157.099 -302.992282) (xy 157.099 -303.499774) (xy 157.39416 -303.499774) (xy 157.39812 -303.45072)
			(xy 157.409897 -303.402936) (xy 157.429188 -303.35766) (xy 157.455491 -303.316064) (xy 157.488126 -303.279227)
			(xy 157.526247 -303.248102) (xy 157.568868 -303.223495) (xy 157.614884 -303.206043) (xy 157.663103 -303.196199)
			(xy 157.712278 -303.194218) (xy 157.761133 -303.20015) (xy 157.808404 -303.213842) (xy 157.852866 -303.23494)
			(xy 157.893369 -303.262896) (xy 157.928862 -303.296988) (xy 157.958427 -303.336332) (xy 157.981298 -303.379909)
			(xy 157.996882 -303.42659) (xy 158.004777 -303.475167) (xy 158.005272 -303.499774) (xy 158.34412 -303.499774)
			(xy 158.34808 -303.45072) (xy 158.359857 -303.402936) (xy 158.379148 -303.35766) (xy 158.405451 -303.316064)
			(xy 158.438086 -303.279227) (xy 158.476207 -303.248102) (xy 158.518828 -303.223495) (xy 158.564844 -303.206043)
			(xy 158.613063 -303.196199) (xy 158.662238 -303.194218) (xy 158.711093 -303.20015) (xy 158.758364 -303.213842)
			(xy 158.802826 -303.23494) (xy 158.843329 -303.262896) (xy 158.878822 -303.296988) (xy 158.908387 -303.336332)
			(xy 158.931258 -303.379909) (xy 158.946842 -303.42659) (xy 158.954737 -303.475167) (xy 158.955232 -303.499774)
			(xy 159.29408 -303.499774) (xy 159.29804 -303.45072) (xy 159.309817 -303.402936) (xy 159.329108 -303.35766)
			(xy 159.355411 -303.316064) (xy 159.388046 -303.279227) (xy 159.426167 -303.248102) (xy 159.468788 -303.223495)
			(xy 159.514804 -303.206043) (xy 159.563023 -303.196199) (xy 159.612198 -303.194218) (xy 159.661053 -303.20015)
			(xy 159.708324 -303.213842) (xy 159.752786 -303.23494) (xy 159.793289 -303.262896) (xy 159.828782 -303.296988)
			(xy 159.858347 -303.336332) (xy 159.881218 -303.379909) (xy 159.896802 -303.42659) (xy 159.904697 -303.475167)
			(xy 159.905192 -303.499774) (xy 160.24404 -303.499774) (xy 160.248 -303.45072) (xy 160.259777 -303.402936)
			(xy 160.279068 -303.35766) (xy 160.305371 -303.316064) (xy 160.338006 -303.279227) (xy 160.376127 -303.248102)
			(xy 160.418748 -303.223495) (xy 160.464764 -303.206043) (xy 160.512983 -303.196199) (xy 160.562158 -303.194218)
			(xy 160.611013 -303.20015) (xy 160.658284 -303.213842) (xy 160.702746 -303.23494) (xy 160.743249 -303.262896)
			(xy 160.778742 -303.296988) (xy 160.808307 -303.336332) (xy 160.831178 -303.379909) (xy 160.846762 -303.42659)
			(xy 160.854657 -303.475167) (xy 160.855152 -303.499774) (xy 160.854657 -303.524381) (xy 160.846762 -303.572958)
			(xy 160.831178 -303.619639) (xy 160.808307 -303.663216) (xy 160.778742 -303.70256) (xy 160.743249 -303.736652)
			(xy 160.702746 -303.764608) (xy 160.658284 -303.785706) (xy 160.611013 -303.799398) (xy 160.562158 -303.80533)
			(xy 160.512983 -303.803349) (xy 160.464764 -303.793505) (xy 160.418748 -303.776053) (xy 160.376127 -303.751446)
			(xy 160.338006 -303.720321) (xy 160.305371 -303.683484) (xy 160.279068 -303.641888) (xy 160.259777 -303.596612)
			(xy 160.248 -303.548828) (xy 160.24404 -303.499774) (xy 159.905192 -303.499774) (xy 159.904697 -303.524381)
			(xy 159.896802 -303.572958) (xy 159.881218 -303.619639) (xy 159.858347 -303.663216) (xy 159.828782 -303.70256)
			(xy 159.793289 -303.736652) (xy 159.752786 -303.764608) (xy 159.708324 -303.785706) (xy 159.661053 -303.799398)
			(xy 159.612198 -303.80533) (xy 159.563023 -303.803349) (xy 159.514804 -303.793505) (xy 159.468788 -303.776053)
			(xy 159.426167 -303.751446) (xy 159.388046 -303.720321) (xy 159.355411 -303.683484) (xy 159.329108 -303.641888)
			(xy 159.309817 -303.596612) (xy 159.29804 -303.548828) (xy 159.29408 -303.499774) (xy 158.955232 -303.499774)
			(xy 158.954737 -303.524381) (xy 158.946842 -303.572958) (xy 158.931258 -303.619639) (xy 158.908387 -303.663216)
			(xy 158.878822 -303.70256) (xy 158.843329 -303.736652) (xy 158.802826 -303.764608) (xy 158.758364 -303.785706)
			(xy 158.711093 -303.799398) (xy 158.662238 -303.80533) (xy 158.613063 -303.803349) (xy 158.564844 -303.793505)
			(xy 158.518828 -303.776053) (xy 158.476207 -303.751446) (xy 158.438086 -303.720321) (xy 158.405451 -303.683484)
			(xy 158.379148 -303.641888) (xy 158.359857 -303.596612) (xy 158.34808 -303.548828) (xy 158.34412 -303.499774)
			(xy 158.005272 -303.499774) (xy 158.004777 -303.524381) (xy 157.996882 -303.572958) (xy 157.981298 -303.619639)
			(xy 157.958427 -303.663216) (xy 157.928862 -303.70256) (xy 157.893369 -303.736652) (xy 157.852866 -303.764608)
			(xy 157.808404 -303.785706) (xy 157.761133 -303.799398) (xy 157.712278 -303.80533) (xy 157.663103 -303.803349)
			(xy 157.614884 -303.793505) (xy 157.568868 -303.776053) (xy 157.526247 -303.751446) (xy 157.488126 -303.720321)
			(xy 157.455491 -303.683484) (xy 157.429188 -303.641888) (xy 157.409897 -303.596612) (xy 157.39812 -303.548828)
			(xy 157.39416 -303.499774) (xy 157.099 -303.499774) (xy 157.099 -303.974754) (xy 162.619194 -303.974754)
			(xy 162.623154 -303.9257) (xy 162.634931 -303.877916) (xy 162.654222 -303.83264) (xy 162.680525 -303.791044)
			(xy 162.71316 -303.754207) (xy 162.751281 -303.723082) (xy 162.793902 -303.698475) (xy 162.839918 -303.681023)
			(xy 162.888137 -303.671179) (xy 162.937312 -303.669198) (xy 162.986167 -303.67513) (xy 163.033438 -303.688822)
			(xy 163.0779 -303.70992) (xy 163.118403 -303.737876) (xy 163.153896 -303.771968) (xy 163.183461 -303.811312)
			(xy 163.206332 -303.854889) (xy 163.221916 -303.90157) (xy 163.229811 -303.950147) (xy 163.230306 -303.974754)
			(xy 163.569154 -303.974754) (xy 163.573114 -303.9257) (xy 163.584891 -303.877916) (xy 163.604182 -303.83264)
			(xy 163.630485 -303.791044) (xy 163.66312 -303.754207) (xy 163.701241 -303.723082) (xy 163.743862 -303.698475)
			(xy 163.789878 -303.681023) (xy 163.838097 -303.671179) (xy 163.887272 -303.669198) (xy 163.936127 -303.67513)
			(xy 163.983398 -303.688822) (xy 164.02786 -303.70992) (xy 164.068363 -303.737876) (xy 164.103856 -303.771968)
			(xy 164.133421 -303.811312) (xy 164.156292 -303.854889) (xy 164.171876 -303.90157) (xy 164.179771 -303.950147)
			(xy 164.180266 -303.974754) (xy 164.519114 -303.974754) (xy 164.523074 -303.9257) (xy 164.534851 -303.877916)
			(xy 164.554142 -303.83264) (xy 164.580445 -303.791044) (xy 164.61308 -303.754207) (xy 164.651201 -303.723082)
			(xy 164.693822 -303.698475) (xy 164.739838 -303.681023) (xy 164.788057 -303.671179) (xy 164.837232 -303.669198)
			(xy 164.886087 -303.67513) (xy 164.933358 -303.688822) (xy 164.97782 -303.70992) (xy 165.018323 -303.737876)
			(xy 165.053816 -303.771968) (xy 165.083381 -303.811312) (xy 165.106252 -303.854889) (xy 165.121836 -303.90157)
			(xy 165.129731 -303.950147) (xy 165.130226 -303.974754) (xy 165.129731 -303.999361) (xy 165.121836 -304.047938)
			(xy 165.106252 -304.094619) (xy 165.083381 -304.138196) (xy 165.053816 -304.17754) (xy 165.018323 -304.211632)
			(xy 164.97782 -304.239588) (xy 164.933358 -304.260686) (xy 164.886087 -304.274378) (xy 164.837232 -304.28031)
			(xy 164.788057 -304.278329) (xy 164.739838 -304.268485) (xy 164.693822 -304.251033) (xy 164.651201 -304.226426)
			(xy 164.61308 -304.195301) (xy 164.580445 -304.158464) (xy 164.554142 -304.116868) (xy 164.534851 -304.071592)
			(xy 164.523074 -304.023808) (xy 164.519114 -303.974754) (xy 164.180266 -303.974754) (xy 164.179771 -303.999361)
			(xy 164.171876 -304.047938) (xy 164.156292 -304.094619) (xy 164.133421 -304.138196) (xy 164.103856 -304.17754)
			(xy 164.068363 -304.211632) (xy 164.02786 -304.239588) (xy 163.983398 -304.260686) (xy 163.936127 -304.274378)
			(xy 163.887272 -304.28031) (xy 163.838097 -304.278329) (xy 163.789878 -304.268485) (xy 163.743862 -304.251033)
			(xy 163.701241 -304.226426) (xy 163.66312 -304.195301) (xy 163.630485 -304.158464) (xy 163.604182 -304.116868)
			(xy 163.584891 -304.071592) (xy 163.573114 -304.023808) (xy 163.569154 -303.974754) (xy 163.230306 -303.974754)
			(xy 163.229811 -303.999361) (xy 163.221916 -304.047938) (xy 163.206332 -304.094619) (xy 163.183461 -304.138196)
			(xy 163.153896 -304.17754) (xy 163.118403 -304.211632) (xy 163.0779 -304.239588) (xy 163.033438 -304.260686)
			(xy 162.986167 -304.274378) (xy 162.937312 -304.28031) (xy 162.888137 -304.278329) (xy 162.839918 -304.268485)
			(xy 162.793902 -304.251033) (xy 162.751281 -304.226426) (xy 162.71316 -304.195301) (xy 162.680525 -304.158464)
			(xy 162.654222 -304.116868) (xy 162.634931 -304.071592) (xy 162.623154 -304.023808) (xy 162.619194 -303.974754)
			(xy 157.099 -303.974754) (xy 157.099 -304.449734) (xy 157.39416 -304.449734) (xy 157.39812 -304.40068)
			(xy 157.409897 -304.352896) (xy 157.429188 -304.30762) (xy 157.455491 -304.266024) (xy 157.488126 -304.229187)
			(xy 157.526247 -304.198062) (xy 157.568868 -304.173455) (xy 157.614884 -304.156003) (xy 157.663103 -304.146159)
			(xy 157.712278 -304.144178) (xy 157.761133 -304.15011) (xy 157.808404 -304.163802) (xy 157.852866 -304.1849)
			(xy 157.893369 -304.212856) (xy 157.928862 -304.246948) (xy 157.958427 -304.286292) (xy 157.981298 -304.329869)
			(xy 157.996882 -304.37655) (xy 158.004777 -304.425127) (xy 158.005272 -304.449734) (xy 158.34412 -304.449734)
			(xy 158.34808 -304.40068) (xy 158.359857 -304.352896) (xy 158.379148 -304.30762) (xy 158.405451 -304.266024)
			(xy 158.438086 -304.229187) (xy 158.476207 -304.198062) (xy 158.518828 -304.173455) (xy 158.564844 -304.156003)
			(xy 158.613063 -304.146159) (xy 158.662238 -304.144178) (xy 158.711093 -304.15011) (xy 158.758364 -304.163802)
			(xy 158.802826 -304.1849) (xy 158.843329 -304.212856) (xy 158.878822 -304.246948) (xy 158.908387 -304.286292)
			(xy 158.931258 -304.329869) (xy 158.946842 -304.37655) (xy 158.954737 -304.425127) (xy 158.955232 -304.449734)
			(xy 159.29408 -304.449734) (xy 159.29804 -304.40068) (xy 159.309817 -304.352896) (xy 159.329108 -304.30762)
			(xy 159.355411 -304.266024) (xy 159.388046 -304.229187) (xy 159.426167 -304.198062) (xy 159.468788 -304.173455)
			(xy 159.514804 -304.156003) (xy 159.563023 -304.146159) (xy 159.612198 -304.144178) (xy 159.661053 -304.15011)
			(xy 159.708324 -304.163802) (xy 159.752786 -304.1849) (xy 159.793289 -304.212856) (xy 159.828782 -304.246948)
			(xy 159.858347 -304.286292) (xy 159.881218 -304.329869) (xy 159.896802 -304.37655) (xy 159.904697 -304.425127)
			(xy 159.905192 -304.449734) (xy 160.24404 -304.449734) (xy 160.248 -304.40068) (xy 160.259777 -304.352896)
			(xy 160.279068 -304.30762) (xy 160.305371 -304.266024) (xy 160.338006 -304.229187) (xy 160.376127 -304.198062)
			(xy 160.418748 -304.173455) (xy 160.464764 -304.156003) (xy 160.512983 -304.146159) (xy 160.562158 -304.144178)
			(xy 160.611013 -304.15011) (xy 160.658284 -304.163802) (xy 160.702746 -304.1849) (xy 160.743249 -304.212856)
			(xy 160.778742 -304.246948) (xy 160.808307 -304.286292) (xy 160.831178 -304.329869) (xy 160.846762 -304.37655)
			(xy 160.854657 -304.425127) (xy 160.855152 -304.449734) (xy 161.194254 -304.449734) (xy 161.198214 -304.40068)
			(xy 161.209991 -304.352896) (xy 161.229282 -304.30762) (xy 161.255585 -304.266024) (xy 161.28822 -304.229187)
			(xy 161.326341 -304.198062) (xy 161.368962 -304.173455) (xy 161.414978 -304.156003) (xy 161.463197 -304.146159)
			(xy 161.512372 -304.144178) (xy 161.561227 -304.15011) (xy 161.608498 -304.163802) (xy 161.65296 -304.1849)
			(xy 161.693463 -304.212856) (xy 161.728956 -304.246948) (xy 161.758521 -304.286292) (xy 161.781392 -304.329869)
			(xy 161.796976 -304.37655) (xy 161.804871 -304.425127) (xy 161.805366 -304.449734) (xy 161.804871 -304.474341)
			(xy 161.796976 -304.522918) (xy 161.781392 -304.569599) (xy 161.758521 -304.613176) (xy 161.728956 -304.65252)
			(xy 161.693463 -304.686612) (xy 161.65296 -304.714568) (xy 161.608498 -304.735666) (xy 161.561227 -304.749358)
			(xy 161.512372 -304.75529) (xy 161.463197 -304.753309) (xy 161.414978 -304.743465) (xy 161.368962 -304.726013)
			(xy 161.326341 -304.701406) (xy 161.28822 -304.670281) (xy 161.255585 -304.633444) (xy 161.229282 -304.591848)
			(xy 161.209991 -304.546572) (xy 161.198214 -304.498788) (xy 161.194254 -304.449734) (xy 160.855152 -304.449734)
			(xy 160.854657 -304.474341) (xy 160.846762 -304.522918) (xy 160.831178 -304.569599) (xy 160.808307 -304.613176)
			(xy 160.778742 -304.65252) (xy 160.743249 -304.686612) (xy 160.702746 -304.714568) (xy 160.658284 -304.735666)
			(xy 160.611013 -304.749358) (xy 160.562158 -304.75529) (xy 160.512983 -304.753309) (xy 160.464764 -304.743465)
			(xy 160.418748 -304.726013) (xy 160.376127 -304.701406) (xy 160.338006 -304.670281) (xy 160.305371 -304.633444)
			(xy 160.279068 -304.591848) (xy 160.259777 -304.546572) (xy 160.248 -304.498788) (xy 160.24404 -304.449734)
			(xy 159.905192 -304.449734) (xy 159.904697 -304.474341) (xy 159.896802 -304.522918) (xy 159.881218 -304.569599)
			(xy 159.858347 -304.613176) (xy 159.828782 -304.65252) (xy 159.793289 -304.686612) (xy 159.752786 -304.714568)
			(xy 159.708324 -304.735666) (xy 159.661053 -304.749358) (xy 159.612198 -304.75529) (xy 159.563023 -304.753309)
			(xy 159.514804 -304.743465) (xy 159.468788 -304.726013) (xy 159.426167 -304.701406) (xy 159.388046 -304.670281)
			(xy 159.355411 -304.633444) (xy 159.329108 -304.591848) (xy 159.309817 -304.546572) (xy 159.29804 -304.498788)
			(xy 159.29408 -304.449734) (xy 158.955232 -304.449734) (xy 158.954737 -304.474341) (xy 158.946842 -304.522918)
			(xy 158.931258 -304.569599) (xy 158.908387 -304.613176) (xy 158.878822 -304.65252) (xy 158.843329 -304.686612)
			(xy 158.802826 -304.714568) (xy 158.758364 -304.735666) (xy 158.711093 -304.749358) (xy 158.662238 -304.75529)
			(xy 158.613063 -304.753309) (xy 158.564844 -304.743465) (xy 158.518828 -304.726013) (xy 158.476207 -304.701406)
			(xy 158.438086 -304.670281) (xy 158.405451 -304.633444) (xy 158.379148 -304.591848) (xy 158.359857 -304.546572)
			(xy 158.34808 -304.498788) (xy 158.34412 -304.449734) (xy 158.005272 -304.449734) (xy 158.004777 -304.474341)
			(xy 157.996882 -304.522918) (xy 157.981298 -304.569599) (xy 157.958427 -304.613176) (xy 157.928862 -304.65252)
			(xy 157.893369 -304.686612) (xy 157.852866 -304.714568) (xy 157.808404 -304.735666) (xy 157.761133 -304.749358)
			(xy 157.712278 -304.75529) (xy 157.663103 -304.753309) (xy 157.614884 -304.743465) (xy 157.568868 -304.726013)
			(xy 157.526247 -304.701406) (xy 157.488126 -304.670281) (xy 157.455491 -304.633444) (xy 157.429188 -304.591848)
			(xy 157.409897 -304.546572) (xy 157.39812 -304.498788) (xy 157.39416 -304.449734) (xy 157.099 -304.449734)
			(xy 157.099 -304.924714) (xy 162.619194 -304.924714) (xy 162.623154 -304.87566) (xy 162.634931 -304.827876)
			(xy 162.654222 -304.7826) (xy 162.680525 -304.741004) (xy 162.71316 -304.704167) (xy 162.751281 -304.673042)
			(xy 162.793902 -304.648435) (xy 162.839918 -304.630983) (xy 162.888137 -304.621139) (xy 162.937312 -304.619158)
			(xy 162.986167 -304.62509) (xy 163.033438 -304.638782) (xy 163.0779 -304.65988) (xy 163.118403 -304.687836)
			(xy 163.153896 -304.721928) (xy 163.183461 -304.761272) (xy 163.206332 -304.804849) (xy 163.221916 -304.85153)
			(xy 163.229811 -304.900107) (xy 163.230306 -304.924714) (xy 163.569154 -304.924714) (xy 163.573114 -304.87566)
			(xy 163.584891 -304.827876) (xy 163.604182 -304.7826) (xy 163.630485 -304.741004) (xy 163.66312 -304.704167)
			(xy 163.701241 -304.673042) (xy 163.743862 -304.648435) (xy 163.789878 -304.630983) (xy 163.838097 -304.621139)
			(xy 163.887272 -304.619158) (xy 163.936127 -304.62509) (xy 163.983398 -304.638782) (xy 164.02786 -304.65988)
			(xy 164.068363 -304.687836) (xy 164.103856 -304.721928) (xy 164.133421 -304.761272) (xy 164.156292 -304.804849)
			(xy 164.171876 -304.85153) (xy 164.179771 -304.900107) (xy 164.180266 -304.924714) (xy 164.519114 -304.924714)
			(xy 164.523074 -304.87566) (xy 164.534851 -304.827876) (xy 164.554142 -304.7826) (xy 164.580445 -304.741004)
			(xy 164.61308 -304.704167) (xy 164.651201 -304.673042) (xy 164.693822 -304.648435) (xy 164.739838 -304.630983)
			(xy 164.788057 -304.621139) (xy 164.837232 -304.619158) (xy 164.886087 -304.62509) (xy 164.933358 -304.638782)
			(xy 164.97782 -304.65988) (xy 165.018323 -304.687836) (xy 165.053816 -304.721928) (xy 165.083381 -304.761272)
			(xy 165.106252 -304.804849) (xy 165.121836 -304.85153) (xy 165.129731 -304.900107) (xy 165.130226 -304.924714)
			(xy 165.469074 -304.924714) (xy 165.473034 -304.87566) (xy 165.484811 -304.827876) (xy 165.504102 -304.7826)
			(xy 165.530405 -304.741004) (xy 165.56304 -304.704167) (xy 165.601161 -304.673042) (xy 165.643782 -304.648435)
			(xy 165.689798 -304.630983) (xy 165.738017 -304.621139) (xy 165.787192 -304.619158) (xy 165.836047 -304.62509)
			(xy 165.883318 -304.638782) (xy 165.92778 -304.65988) (xy 165.968283 -304.687836) (xy 166.003776 -304.721928)
			(xy 166.033341 -304.761272) (xy 166.056212 -304.804849) (xy 166.071796 -304.85153) (xy 166.079691 -304.900107)
			(xy 166.080186 -304.924714) (xy 166.419288 -304.924714) (xy 166.423248 -304.87566) (xy 166.435025 -304.827876)
			(xy 166.454316 -304.7826) (xy 166.480619 -304.741004) (xy 166.513254 -304.704167) (xy 166.551375 -304.673042)
			(xy 166.593996 -304.648435) (xy 166.640012 -304.630983) (xy 166.688231 -304.621139) (xy 166.737406 -304.619158)
			(xy 166.786261 -304.62509) (xy 166.833532 -304.638782) (xy 166.877994 -304.65988) (xy 166.918497 -304.687836)
			(xy 166.95399 -304.721928) (xy 166.983555 -304.761272) (xy 167.006426 -304.804849) (xy 167.02201 -304.85153)
			(xy 167.029905 -304.900107) (xy 167.0304 -304.924714) (xy 167.369248 -304.924714) (xy 167.373208 -304.87566)
			(xy 167.384985 -304.827876) (xy 167.404276 -304.7826) (xy 167.430579 -304.741004) (xy 167.463214 -304.704167)
			(xy 167.501335 -304.673042) (xy 167.543956 -304.648435) (xy 167.589972 -304.630983) (xy 167.638191 -304.621139)
			(xy 167.687366 -304.619158) (xy 167.736221 -304.62509) (xy 167.783492 -304.638782) (xy 167.827954 -304.65988)
			(xy 167.868457 -304.687836) (xy 167.90395 -304.721928) (xy 167.933515 -304.761272) (xy 167.956386 -304.804849)
			(xy 167.97197 -304.85153) (xy 167.979865 -304.900107) (xy 167.98036 -304.924714) (xy 168.319208 -304.924714)
			(xy 168.323168 -304.87566) (xy 168.334945 -304.827876) (xy 168.354236 -304.7826) (xy 168.380539 -304.741004)
			(xy 168.413174 -304.704167) (xy 168.451295 -304.673042) (xy 168.493916 -304.648435) (xy 168.539932 -304.630983)
			(xy 168.588151 -304.621139) (xy 168.637326 -304.619158) (xy 168.686181 -304.62509) (xy 168.733452 -304.638782)
			(xy 168.777914 -304.65988) (xy 168.818417 -304.687836) (xy 168.85391 -304.721928) (xy 168.883475 -304.761272)
			(xy 168.906346 -304.804849) (xy 168.92193 -304.85153) (xy 168.929825 -304.900107) (xy 168.93032 -304.924714)
			(xy 169.269168 -304.924714) (xy 169.273128 -304.87566) (xy 169.284905 -304.827876) (xy 169.304196 -304.7826)
			(xy 169.330499 -304.741004) (xy 169.363134 -304.704167) (xy 169.401255 -304.673042) (xy 169.443876 -304.648435)
			(xy 169.489892 -304.630983) (xy 169.538111 -304.621139) (xy 169.587286 -304.619158) (xy 169.636141 -304.62509)
			(xy 169.683412 -304.638782) (xy 169.727874 -304.65988) (xy 169.768377 -304.687836) (xy 169.80387 -304.721928)
			(xy 169.833435 -304.761272) (xy 169.856306 -304.804849) (xy 169.87189 -304.85153) (xy 169.879785 -304.900107)
			(xy 169.88028 -304.924714) (xy 170.219128 -304.924714) (xy 170.223088 -304.87566) (xy 170.234865 -304.827876)
			(xy 170.254156 -304.7826) (xy 170.280459 -304.741004) (xy 170.313094 -304.704167) (xy 170.351215 -304.673042)
			(xy 170.393836 -304.648435) (xy 170.439852 -304.630983) (xy 170.488071 -304.621139) (xy 170.537246 -304.619158)
			(xy 170.586101 -304.62509) (xy 170.633372 -304.638782) (xy 170.677834 -304.65988) (xy 170.718337 -304.687836)
			(xy 170.75383 -304.721928) (xy 170.783395 -304.761272) (xy 170.806266 -304.804849) (xy 170.82185 -304.85153)
			(xy 170.829745 -304.900107) (xy 170.83024 -304.924714) (xy 171.169088 -304.924714) (xy 171.173048 -304.87566)
			(xy 171.184825 -304.827876) (xy 171.204116 -304.7826) (xy 171.230419 -304.741004) (xy 171.263054 -304.704167)
			(xy 171.301175 -304.673042) (xy 171.343796 -304.648435) (xy 171.389812 -304.630983) (xy 171.438031 -304.621139)
			(xy 171.487206 -304.619158) (xy 171.536061 -304.62509) (xy 171.583332 -304.638782) (xy 171.627794 -304.65988)
			(xy 171.668297 -304.687836) (xy 171.70379 -304.721928) (xy 171.733355 -304.761272) (xy 171.756226 -304.804849)
			(xy 171.77181 -304.85153) (xy 171.779705 -304.900107) (xy 171.7802 -304.924714) (xy 172.119048 -304.924714)
			(xy 172.123008 -304.87566) (xy 172.134785 -304.827876) (xy 172.154076 -304.7826) (xy 172.180379 -304.741004)
			(xy 172.213014 -304.704167) (xy 172.251135 -304.673042) (xy 172.293756 -304.648435) (xy 172.339772 -304.630983)
			(xy 172.387991 -304.621139) (xy 172.437166 -304.619158) (xy 172.486021 -304.62509) (xy 172.533292 -304.638782)
			(xy 172.577754 -304.65988) (xy 172.618257 -304.687836) (xy 172.65375 -304.721928) (xy 172.683315 -304.761272)
			(xy 172.706186 -304.804849) (xy 172.72177 -304.85153) (xy 172.729665 -304.900107) (xy 172.73016 -304.924714)
			(xy 173.069262 -304.924714) (xy 173.073222 -304.87566) (xy 173.084999 -304.827876) (xy 173.10429 -304.7826)
			(xy 173.130593 -304.741004) (xy 173.163228 -304.704167) (xy 173.201349 -304.673042) (xy 173.24397 -304.648435)
			(xy 173.289986 -304.630983) (xy 173.338205 -304.621139) (xy 173.38738 -304.619158) (xy 173.436235 -304.62509)
			(xy 173.483506 -304.638782) (xy 173.527968 -304.65988) (xy 173.568471 -304.687836) (xy 173.603964 -304.721928)
			(xy 173.633529 -304.761272) (xy 173.6564 -304.804849) (xy 173.671984 -304.85153) (xy 173.679879 -304.900107)
			(xy 173.680374 -304.924714) (xy 174.019222 -304.924714) (xy 174.023182 -304.87566) (xy 174.034959 -304.827876)
			(xy 174.05425 -304.7826) (xy 174.080553 -304.741004) (xy 174.113188 -304.704167) (xy 174.151309 -304.673042)
			(xy 174.19393 -304.648435) (xy 174.239946 -304.630983) (xy 174.288165 -304.621139) (xy 174.33734 -304.619158)
			(xy 174.386195 -304.62509) (xy 174.433466 -304.638782) (xy 174.477928 -304.65988) (xy 174.518431 -304.687836)
			(xy 174.553924 -304.721928) (xy 174.583489 -304.761272) (xy 174.60636 -304.804849) (xy 174.621944 -304.85153)
			(xy 174.629839 -304.900107) (xy 174.630334 -304.924714) (xy 175.919142 -304.924714) (xy 175.923102 -304.87566)
			(xy 175.934879 -304.827876) (xy 175.95417 -304.7826) (xy 175.980473 -304.741004) (xy 176.013108 -304.704167)
			(xy 176.051229 -304.673042) (xy 176.09385 -304.648435) (xy 176.139866 -304.630983) (xy 176.188085 -304.621139)
			(xy 176.23726 -304.619158) (xy 176.286115 -304.62509) (xy 176.333386 -304.638782) (xy 176.377848 -304.65988)
			(xy 176.418351 -304.687836) (xy 176.453844 -304.721928) (xy 176.483409 -304.761272) (xy 176.50628 -304.804849)
			(xy 176.521864 -304.85153) (xy 176.529759 -304.900107) (xy 176.530254 -304.924714) (xy 176.869102 -304.924714)
			(xy 176.873062 -304.87566) (xy 176.884839 -304.827876) (xy 176.90413 -304.7826) (xy 176.930433 -304.741004)
			(xy 176.963068 -304.704167) (xy 177.001189 -304.673042) (xy 177.04381 -304.648435) (xy 177.089826 -304.630983)
			(xy 177.138045 -304.621139) (xy 177.18722 -304.619158) (xy 177.236075 -304.62509) (xy 177.283346 -304.638782)
			(xy 177.327808 -304.65988) (xy 177.368311 -304.687836) (xy 177.403804 -304.721928) (xy 177.433369 -304.761272)
			(xy 177.45624 -304.804849) (xy 177.471824 -304.85153) (xy 177.479719 -304.900107) (xy 177.480214 -304.924714)
			(xy 177.819062 -304.924714) (xy 177.823022 -304.87566) (xy 177.834799 -304.827876) (xy 177.85409 -304.7826)
			(xy 177.880393 -304.741004) (xy 177.913028 -304.704167) (xy 177.951149 -304.673042) (xy 177.99377 -304.648435)
			(xy 178.039786 -304.630983) (xy 178.088005 -304.621139) (xy 178.13718 -304.619158) (xy 178.186035 -304.62509)
			(xy 178.233306 -304.638782) (xy 178.277768 -304.65988) (xy 178.318271 -304.687836) (xy 178.353764 -304.721928)
			(xy 178.383329 -304.761272) (xy 178.4062 -304.804849) (xy 178.421784 -304.85153) (xy 178.429679 -304.900107)
			(xy 178.430174 -304.924714) (xy 178.769276 -304.924714) (xy 178.773236 -304.87566) (xy 178.785013 -304.827876)
			(xy 178.804304 -304.7826) (xy 178.830607 -304.741004) (xy 178.863242 -304.704167) (xy 178.901363 -304.673042)
			(xy 178.943984 -304.648435) (xy 178.99 -304.630983) (xy 179.038219 -304.621139) (xy 179.087394 -304.619158)
			(xy 179.136249 -304.62509) (xy 179.18352 -304.638782) (xy 179.227982 -304.65988) (xy 179.268485 -304.687836)
			(xy 179.303978 -304.721928) (xy 179.333543 -304.761272) (xy 179.356414 -304.804849) (xy 179.371998 -304.85153)
			(xy 179.379893 -304.900107) (xy 179.380388 -304.924714) (xy 179.719236 -304.924714) (xy 179.723196 -304.87566)
			(xy 179.734973 -304.827876) (xy 179.754264 -304.7826) (xy 179.780567 -304.741004) (xy 179.813202 -304.704167)
			(xy 179.851323 -304.673042) (xy 179.893944 -304.648435) (xy 179.93996 -304.630983) (xy 179.988179 -304.621139)
			(xy 180.037354 -304.619158) (xy 180.086209 -304.62509) (xy 180.13348 -304.638782) (xy 180.177942 -304.65988)
			(xy 180.218445 -304.687836) (xy 180.253938 -304.721928) (xy 180.283503 -304.761272) (xy 180.306374 -304.804849)
			(xy 180.321958 -304.85153) (xy 180.329853 -304.900107) (xy 180.330348 -304.924714) (xy 180.669196 -304.924714)
			(xy 180.673156 -304.87566) (xy 180.684933 -304.827876) (xy 180.704224 -304.7826) (xy 180.730527 -304.741004)
			(xy 180.763162 -304.704167) (xy 180.801283 -304.673042) (xy 180.843904 -304.648435) (xy 180.88992 -304.630983)
			(xy 180.938139 -304.621139) (xy 180.987314 -304.619158) (xy 181.036169 -304.62509) (xy 181.08344 -304.638782)
			(xy 181.127902 -304.65988) (xy 181.168405 -304.687836) (xy 181.203898 -304.721928) (xy 181.233463 -304.761272)
			(xy 181.256334 -304.804849) (xy 181.271918 -304.85153) (xy 181.279813 -304.900107) (xy 181.280308 -304.924714)
			(xy 181.619156 -304.924714) (xy 181.623116 -304.87566) (xy 181.634893 -304.827876) (xy 181.654184 -304.7826)
			(xy 181.680487 -304.741004) (xy 181.713122 -304.704167) (xy 181.751243 -304.673042) (xy 181.793864 -304.648435)
			(xy 181.83988 -304.630983) (xy 181.888099 -304.621139) (xy 181.937274 -304.619158) (xy 181.986129 -304.62509)
			(xy 182.0334 -304.638782) (xy 182.077862 -304.65988) (xy 182.118365 -304.687836) (xy 182.153858 -304.721928)
			(xy 182.183423 -304.761272) (xy 182.206294 -304.804849) (xy 182.221878 -304.85153) (xy 182.229773 -304.900107)
			(xy 182.230268 -304.924714) (xy 182.569116 -304.924714) (xy 182.573076 -304.87566) (xy 182.584853 -304.827876)
			(xy 182.604144 -304.7826) (xy 182.630447 -304.741004) (xy 182.663082 -304.704167) (xy 182.701203 -304.673042)
			(xy 182.743824 -304.648435) (xy 182.78984 -304.630983) (xy 182.838059 -304.621139) (xy 182.887234 -304.619158)
			(xy 182.936089 -304.62509) (xy 182.98336 -304.638782) (xy 183.027822 -304.65988) (xy 183.068325 -304.687836)
			(xy 183.103818 -304.721928) (xy 183.133383 -304.761272) (xy 183.156254 -304.804849) (xy 183.171838 -304.85153)
			(xy 183.179733 -304.900107) (xy 183.180228 -304.924714) (xy 183.519076 -304.924714) (xy 183.523036 -304.87566)
			(xy 183.534813 -304.827876) (xy 183.554104 -304.7826) (xy 183.580407 -304.741004) (xy 183.613042 -304.704167)
			(xy 183.651163 -304.673042) (xy 183.693784 -304.648435) (xy 183.7398 -304.630983) (xy 183.788019 -304.621139)
			(xy 183.837194 -304.619158) (xy 183.886049 -304.62509) (xy 183.93332 -304.638782) (xy 183.977782 -304.65988)
			(xy 184.018285 -304.687836) (xy 184.053778 -304.721928) (xy 184.083343 -304.761272) (xy 184.106214 -304.804849)
			(xy 184.121798 -304.85153) (xy 184.129693 -304.900107) (xy 184.130188 -304.924714) (xy 184.469036 -304.924714)
			(xy 184.472996 -304.87566) (xy 184.484773 -304.827876) (xy 184.504064 -304.7826) (xy 184.530367 -304.741004)
			(xy 184.563002 -304.704167) (xy 184.601123 -304.673042) (xy 184.643744 -304.648435) (xy 184.68976 -304.630983)
			(xy 184.737979 -304.621139) (xy 184.787154 -304.619158) (xy 184.836009 -304.62509) (xy 184.88328 -304.638782)
			(xy 184.927742 -304.65988) (xy 184.968245 -304.687836) (xy 185.003738 -304.721928) (xy 185.033303 -304.761272)
			(xy 185.056174 -304.804849) (xy 185.071758 -304.85153) (xy 185.079653 -304.900107) (xy 185.080148 -304.924714)
			(xy 186.36921 -304.924714) (xy 186.37317 -304.87566) (xy 186.384947 -304.827876) (xy 186.404238 -304.7826)
			(xy 186.430541 -304.741004) (xy 186.463176 -304.704167) (xy 186.501297 -304.673042) (xy 186.543918 -304.648435)
			(xy 186.589934 -304.630983) (xy 186.638153 -304.621139) (xy 186.687328 -304.619158) (xy 186.736183 -304.62509)
			(xy 186.783454 -304.638782) (xy 186.827916 -304.65988) (xy 186.868419 -304.687836) (xy 186.903912 -304.721928)
			(xy 186.933477 -304.761272) (xy 186.956348 -304.804849) (xy 186.971932 -304.85153) (xy 186.979827 -304.900107)
			(xy 186.980322 -304.924714) (xy 187.31917 -304.924714) (xy 187.32313 -304.87566) (xy 187.334907 -304.827876)
			(xy 187.354198 -304.7826) (xy 187.380501 -304.741004) (xy 187.413136 -304.704167) (xy 187.451257 -304.673042)
			(xy 187.493878 -304.648435) (xy 187.539894 -304.630983) (xy 187.588113 -304.621139) (xy 187.637288 -304.619158)
			(xy 187.686143 -304.62509) (xy 187.733414 -304.638782) (xy 187.777876 -304.65988) (xy 187.818379 -304.687836)
			(xy 187.853872 -304.721928) (xy 187.883437 -304.761272) (xy 187.906308 -304.804849) (xy 187.921892 -304.85153)
			(xy 187.929787 -304.900107) (xy 187.930282 -304.924714) (xy 188.26913 -304.924714) (xy 188.27309 -304.87566)
			(xy 188.284867 -304.827876) (xy 188.304158 -304.7826) (xy 188.330461 -304.741004) (xy 188.363096 -304.704167)
			(xy 188.401217 -304.673042) (xy 188.443838 -304.648435) (xy 188.489854 -304.630983) (xy 188.538073 -304.621139)
			(xy 188.587248 -304.619158) (xy 188.636103 -304.62509) (xy 188.683374 -304.638782) (xy 188.727836 -304.65988)
			(xy 188.768339 -304.687836) (xy 188.803832 -304.721928) (xy 188.833397 -304.761272) (xy 188.856268 -304.804849)
			(xy 188.871852 -304.85153) (xy 188.879747 -304.900107) (xy 188.880242 -304.924714) (xy 188.879747 -304.949321)
			(xy 188.871852 -304.997898) (xy 188.856268 -305.044579) (xy 188.833397 -305.088156) (xy 188.803832 -305.1275)
			(xy 188.768339 -305.161592) (xy 188.727836 -305.189548) (xy 188.683374 -305.210646) (xy 188.636103 -305.224338)
			(xy 188.587248 -305.23027) (xy 188.538073 -305.228289) (xy 188.489854 -305.218445) (xy 188.443838 -305.200993)
			(xy 188.401217 -305.176386) (xy 188.363096 -305.145261) (xy 188.330461 -305.108424) (xy 188.304158 -305.066828)
			(xy 188.284867 -305.021552) (xy 188.27309 -304.973768) (xy 188.26913 -304.924714) (xy 187.930282 -304.924714)
			(xy 187.929787 -304.949321) (xy 187.921892 -304.997898) (xy 187.906308 -305.044579) (xy 187.883437 -305.088156)
			(xy 187.853872 -305.1275) (xy 187.818379 -305.161592) (xy 187.777876 -305.189548) (xy 187.733414 -305.210646)
			(xy 187.686143 -305.224338) (xy 187.637288 -305.23027) (xy 187.588113 -305.228289) (xy 187.539894 -305.218445)
			(xy 187.493878 -305.200993) (xy 187.451257 -305.176386) (xy 187.413136 -305.145261) (xy 187.380501 -305.108424)
			(xy 187.354198 -305.066828) (xy 187.334907 -305.021552) (xy 187.32313 -304.973768) (xy 187.31917 -304.924714)
			(xy 186.980322 -304.924714) (xy 186.979827 -304.949321) (xy 186.971932 -304.997898) (xy 186.956348 -305.044579)
			(xy 186.933477 -305.088156) (xy 186.903912 -305.1275) (xy 186.868419 -305.161592) (xy 186.827916 -305.189548)
			(xy 186.783454 -305.210646) (xy 186.736183 -305.224338) (xy 186.687328 -305.23027) (xy 186.638153 -305.228289)
			(xy 186.589934 -305.218445) (xy 186.543918 -305.200993) (xy 186.501297 -305.176386) (xy 186.463176 -305.145261)
			(xy 186.430541 -305.108424) (xy 186.404238 -305.066828) (xy 186.384947 -305.021552) (xy 186.37317 -304.973768)
			(xy 186.36921 -304.924714) (xy 185.080148 -304.924714) (xy 185.079653 -304.949321) (xy 185.071758 -304.997898)
			(xy 185.056174 -305.044579) (xy 185.033303 -305.088156) (xy 185.003738 -305.1275) (xy 184.968245 -305.161592)
			(xy 184.927742 -305.189548) (xy 184.88328 -305.210646) (xy 184.836009 -305.224338) (xy 184.787154 -305.23027)
			(xy 184.737979 -305.228289) (xy 184.68976 -305.218445) (xy 184.643744 -305.200993) (xy 184.601123 -305.176386)
			(xy 184.563002 -305.145261) (xy 184.530367 -305.108424) (xy 184.504064 -305.066828) (xy 184.484773 -305.021552)
			(xy 184.472996 -304.973768) (xy 184.469036 -304.924714) (xy 184.130188 -304.924714) (xy 184.129693 -304.949321)
			(xy 184.121798 -304.997898) (xy 184.106214 -305.044579) (xy 184.083343 -305.088156) (xy 184.053778 -305.1275)
			(xy 184.018285 -305.161592) (xy 183.977782 -305.189548) (xy 183.93332 -305.210646) (xy 183.886049 -305.224338)
			(xy 183.837194 -305.23027) (xy 183.788019 -305.228289) (xy 183.7398 -305.218445) (xy 183.693784 -305.200993)
			(xy 183.651163 -305.176386) (xy 183.613042 -305.145261) (xy 183.580407 -305.108424) (xy 183.554104 -305.066828)
			(xy 183.534813 -305.021552) (xy 183.523036 -304.973768) (xy 183.519076 -304.924714) (xy 183.180228 -304.924714)
			(xy 183.179733 -304.949321) (xy 183.171838 -304.997898) (xy 183.156254 -305.044579) (xy 183.133383 -305.088156)
			(xy 183.103818 -305.1275) (xy 183.068325 -305.161592) (xy 183.027822 -305.189548) (xy 182.98336 -305.210646)
			(xy 182.936089 -305.224338) (xy 182.887234 -305.23027) (xy 182.838059 -305.228289) (xy 182.78984 -305.218445)
			(xy 182.743824 -305.200993) (xy 182.701203 -305.176386) (xy 182.663082 -305.145261) (xy 182.630447 -305.108424)
			(xy 182.604144 -305.066828) (xy 182.584853 -305.021552) (xy 182.573076 -304.973768) (xy 182.569116 -304.924714)
			(xy 182.230268 -304.924714) (xy 182.229773 -304.949321) (xy 182.221878 -304.997898) (xy 182.206294 -305.044579)
			(xy 182.183423 -305.088156) (xy 182.153858 -305.1275) (xy 182.118365 -305.161592) (xy 182.077862 -305.189548)
			(xy 182.0334 -305.210646) (xy 181.986129 -305.224338) (xy 181.937274 -305.23027) (xy 181.888099 -305.228289)
			(xy 181.83988 -305.218445) (xy 181.793864 -305.200993) (xy 181.751243 -305.176386) (xy 181.713122 -305.145261)
			(xy 181.680487 -305.108424) (xy 181.654184 -305.066828) (xy 181.634893 -305.021552) (xy 181.623116 -304.973768)
			(xy 181.619156 -304.924714) (xy 181.280308 -304.924714) (xy 181.279813 -304.949321) (xy 181.271918 -304.997898)
			(xy 181.256334 -305.044579) (xy 181.233463 -305.088156) (xy 181.203898 -305.1275) (xy 181.168405 -305.161592)
			(xy 181.127902 -305.189548) (xy 181.08344 -305.210646) (xy 181.036169 -305.224338) (xy 180.987314 -305.23027)
			(xy 180.938139 -305.228289) (xy 180.88992 -305.218445) (xy 180.843904 -305.200993) (xy 180.801283 -305.176386)
			(xy 180.763162 -305.145261) (xy 180.730527 -305.108424) (xy 180.704224 -305.066828) (xy 180.684933 -305.021552)
			(xy 180.673156 -304.973768) (xy 180.669196 -304.924714) (xy 180.330348 -304.924714) (xy 180.329853 -304.949321)
			(xy 180.321958 -304.997898) (xy 180.306374 -305.044579) (xy 180.283503 -305.088156) (xy 180.253938 -305.1275)
			(xy 180.218445 -305.161592) (xy 180.177942 -305.189548) (xy 180.13348 -305.210646) (xy 180.086209 -305.224338)
			(xy 180.037354 -305.23027) (xy 179.988179 -305.228289) (xy 179.93996 -305.218445) (xy 179.893944 -305.200993)
			(xy 179.851323 -305.176386) (xy 179.813202 -305.145261) (xy 179.780567 -305.108424) (xy 179.754264 -305.066828)
			(xy 179.734973 -305.021552) (xy 179.723196 -304.973768) (xy 179.719236 -304.924714) (xy 179.380388 -304.924714)
			(xy 179.379893 -304.949321) (xy 179.371998 -304.997898) (xy 179.356414 -305.044579) (xy 179.333543 -305.088156)
			(xy 179.303978 -305.1275) (xy 179.268485 -305.161592) (xy 179.227982 -305.189548) (xy 179.18352 -305.210646)
			(xy 179.136249 -305.224338) (xy 179.087394 -305.23027) (xy 179.038219 -305.228289) (xy 178.99 -305.218445)
			(xy 178.943984 -305.200993) (xy 178.901363 -305.176386) (xy 178.863242 -305.145261) (xy 178.830607 -305.108424)
			(xy 178.804304 -305.066828) (xy 178.785013 -305.021552) (xy 178.773236 -304.973768) (xy 178.769276 -304.924714)
			(xy 178.430174 -304.924714) (xy 178.429679 -304.949321) (xy 178.421784 -304.997898) (xy 178.4062 -305.044579)
			(xy 178.383329 -305.088156) (xy 178.353764 -305.1275) (xy 178.318271 -305.161592) (xy 178.277768 -305.189548)
			(xy 178.233306 -305.210646) (xy 178.186035 -305.224338) (xy 178.13718 -305.23027) (xy 178.088005 -305.228289)
			(xy 178.039786 -305.218445) (xy 177.99377 -305.200993) (xy 177.951149 -305.176386) (xy 177.913028 -305.145261)
			(xy 177.880393 -305.108424) (xy 177.85409 -305.066828) (xy 177.834799 -305.021552) (xy 177.823022 -304.973768)
			(xy 177.819062 -304.924714) (xy 177.480214 -304.924714) (xy 177.479719 -304.949321) (xy 177.471824 -304.997898)
			(xy 177.45624 -305.044579) (xy 177.433369 -305.088156) (xy 177.403804 -305.1275) (xy 177.368311 -305.161592)
			(xy 177.327808 -305.189548) (xy 177.283346 -305.210646) (xy 177.236075 -305.224338) (xy 177.18722 -305.23027)
			(xy 177.138045 -305.228289) (xy 177.089826 -305.218445) (xy 177.04381 -305.200993) (xy 177.001189 -305.176386)
			(xy 176.963068 -305.145261) (xy 176.930433 -305.108424) (xy 176.90413 -305.066828) (xy 176.884839 -305.021552)
			(xy 176.873062 -304.973768) (xy 176.869102 -304.924714) (xy 176.530254 -304.924714) (xy 176.529759 -304.949321)
			(xy 176.521864 -304.997898) (xy 176.50628 -305.044579) (xy 176.483409 -305.088156) (xy 176.453844 -305.1275)
			(xy 176.418351 -305.161592) (xy 176.377848 -305.189548) (xy 176.333386 -305.210646) (xy 176.286115 -305.224338)
			(xy 176.23726 -305.23027) (xy 176.188085 -305.228289) (xy 176.139866 -305.218445) (xy 176.09385 -305.200993)
			(xy 176.051229 -305.176386) (xy 176.013108 -305.145261) (xy 175.980473 -305.108424) (xy 175.95417 -305.066828)
			(xy 175.934879 -305.021552) (xy 175.923102 -304.973768) (xy 175.919142 -304.924714) (xy 174.630334 -304.924714)
			(xy 174.629839 -304.949321) (xy 174.621944 -304.997898) (xy 174.60636 -305.044579) (xy 174.583489 -305.088156)
			(xy 174.553924 -305.1275) (xy 174.518431 -305.161592) (xy 174.477928 -305.189548) (xy 174.433466 -305.210646)
			(xy 174.386195 -305.224338) (xy 174.33734 -305.23027) (xy 174.288165 -305.228289) (xy 174.239946 -305.218445)
			(xy 174.19393 -305.200993) (xy 174.151309 -305.176386) (xy 174.113188 -305.145261) (xy 174.080553 -305.108424)
			(xy 174.05425 -305.066828) (xy 174.034959 -305.021552) (xy 174.023182 -304.973768) (xy 174.019222 -304.924714)
			(xy 173.680374 -304.924714) (xy 173.679879 -304.949321) (xy 173.671984 -304.997898) (xy 173.6564 -305.044579)
			(xy 173.633529 -305.088156) (xy 173.603964 -305.1275) (xy 173.568471 -305.161592) (xy 173.527968 -305.189548)
			(xy 173.483506 -305.210646) (xy 173.436235 -305.224338) (xy 173.38738 -305.23027) (xy 173.338205 -305.228289)
			(xy 173.289986 -305.218445) (xy 173.24397 -305.200993) (xy 173.201349 -305.176386) (xy 173.163228 -305.145261)
			(xy 173.130593 -305.108424) (xy 173.10429 -305.066828) (xy 173.084999 -305.021552) (xy 173.073222 -304.973768)
			(xy 173.069262 -304.924714) (xy 172.73016 -304.924714) (xy 172.729665 -304.949321) (xy 172.72177 -304.997898)
			(xy 172.706186 -305.044579) (xy 172.683315 -305.088156) (xy 172.65375 -305.1275) (xy 172.618257 -305.161592)
			(xy 172.577754 -305.189548) (xy 172.533292 -305.210646) (xy 172.486021 -305.224338) (xy 172.437166 -305.23027)
			(xy 172.387991 -305.228289) (xy 172.339772 -305.218445) (xy 172.293756 -305.200993) (xy 172.251135 -305.176386)
			(xy 172.213014 -305.145261) (xy 172.180379 -305.108424) (xy 172.154076 -305.066828) (xy 172.134785 -305.021552)
			(xy 172.123008 -304.973768) (xy 172.119048 -304.924714) (xy 171.7802 -304.924714) (xy 171.779705 -304.949321)
			(xy 171.77181 -304.997898) (xy 171.756226 -305.044579) (xy 171.733355 -305.088156) (xy 171.70379 -305.1275)
			(xy 171.668297 -305.161592) (xy 171.627794 -305.189548) (xy 171.583332 -305.210646) (xy 171.536061 -305.224338)
			(xy 171.487206 -305.23027) (xy 171.438031 -305.228289) (xy 171.389812 -305.218445) (xy 171.343796 -305.200993)
			(xy 171.301175 -305.176386) (xy 171.263054 -305.145261) (xy 171.230419 -305.108424) (xy 171.204116 -305.066828)
			(xy 171.184825 -305.021552) (xy 171.173048 -304.973768) (xy 171.169088 -304.924714) (xy 170.83024 -304.924714)
			(xy 170.829745 -304.949321) (xy 170.82185 -304.997898) (xy 170.806266 -305.044579) (xy 170.783395 -305.088156)
			(xy 170.75383 -305.1275) (xy 170.718337 -305.161592) (xy 170.677834 -305.189548) (xy 170.633372 -305.210646)
			(xy 170.586101 -305.224338) (xy 170.537246 -305.23027) (xy 170.488071 -305.228289) (xy 170.439852 -305.218445)
			(xy 170.393836 -305.200993) (xy 170.351215 -305.176386) (xy 170.313094 -305.145261) (xy 170.280459 -305.108424)
			(xy 170.254156 -305.066828) (xy 170.234865 -305.021552) (xy 170.223088 -304.973768) (xy 170.219128 -304.924714)
			(xy 169.88028 -304.924714) (xy 169.879785 -304.949321) (xy 169.87189 -304.997898) (xy 169.856306 -305.044579)
			(xy 169.833435 -305.088156) (xy 169.80387 -305.1275) (xy 169.768377 -305.161592) (xy 169.727874 -305.189548)
			(xy 169.683412 -305.210646) (xy 169.636141 -305.224338) (xy 169.587286 -305.23027) (xy 169.538111 -305.228289)
			(xy 169.489892 -305.218445) (xy 169.443876 -305.200993) (xy 169.401255 -305.176386) (xy 169.363134 -305.145261)
			(xy 169.330499 -305.108424) (xy 169.304196 -305.066828) (xy 169.284905 -305.021552) (xy 169.273128 -304.973768)
			(xy 169.269168 -304.924714) (xy 168.93032 -304.924714) (xy 168.929825 -304.949321) (xy 168.92193 -304.997898)
			(xy 168.906346 -305.044579) (xy 168.883475 -305.088156) (xy 168.85391 -305.1275) (xy 168.818417 -305.161592)
			(xy 168.777914 -305.189548) (xy 168.733452 -305.210646) (xy 168.686181 -305.224338) (xy 168.637326 -305.23027)
			(xy 168.588151 -305.228289) (xy 168.539932 -305.218445) (xy 168.493916 -305.200993) (xy 168.451295 -305.176386)
			(xy 168.413174 -305.145261) (xy 168.380539 -305.108424) (xy 168.354236 -305.066828) (xy 168.334945 -305.021552)
			(xy 168.323168 -304.973768) (xy 168.319208 -304.924714) (xy 167.98036 -304.924714) (xy 167.979865 -304.949321)
			(xy 167.97197 -304.997898) (xy 167.956386 -305.044579) (xy 167.933515 -305.088156) (xy 167.90395 -305.1275)
			(xy 167.868457 -305.161592) (xy 167.827954 -305.189548) (xy 167.783492 -305.210646) (xy 167.736221 -305.224338)
			(xy 167.687366 -305.23027) (xy 167.638191 -305.228289) (xy 167.589972 -305.218445) (xy 167.543956 -305.200993)
			(xy 167.501335 -305.176386) (xy 167.463214 -305.145261) (xy 167.430579 -305.108424) (xy 167.404276 -305.066828)
			(xy 167.384985 -305.021552) (xy 167.373208 -304.973768) (xy 167.369248 -304.924714) (xy 167.0304 -304.924714)
			(xy 167.029905 -304.949321) (xy 167.02201 -304.997898) (xy 167.006426 -305.044579) (xy 166.983555 -305.088156)
			(xy 166.95399 -305.1275) (xy 166.918497 -305.161592) (xy 166.877994 -305.189548) (xy 166.833532 -305.210646)
			(xy 166.786261 -305.224338) (xy 166.737406 -305.23027) (xy 166.688231 -305.228289) (xy 166.640012 -305.218445)
			(xy 166.593996 -305.200993) (xy 166.551375 -305.176386) (xy 166.513254 -305.145261) (xy 166.480619 -305.108424)
			(xy 166.454316 -305.066828) (xy 166.435025 -305.021552) (xy 166.423248 -304.973768) (xy 166.419288 -304.924714)
			(xy 166.080186 -304.924714) (xy 166.079691 -304.949321) (xy 166.071796 -304.997898) (xy 166.056212 -305.044579)
			(xy 166.033341 -305.088156) (xy 166.003776 -305.1275) (xy 165.968283 -305.161592) (xy 165.92778 -305.189548)
			(xy 165.883318 -305.210646) (xy 165.836047 -305.224338) (xy 165.787192 -305.23027) (xy 165.738017 -305.228289)
			(xy 165.689798 -305.218445) (xy 165.643782 -305.200993) (xy 165.601161 -305.176386) (xy 165.56304 -305.145261)
			(xy 165.530405 -305.108424) (xy 165.504102 -305.066828) (xy 165.484811 -305.021552) (xy 165.473034 -304.973768)
			(xy 165.469074 -304.924714) (xy 165.130226 -304.924714) (xy 165.129731 -304.949321) (xy 165.121836 -304.997898)
			(xy 165.106252 -305.044579) (xy 165.083381 -305.088156) (xy 165.053816 -305.1275) (xy 165.018323 -305.161592)
			(xy 164.97782 -305.189548) (xy 164.933358 -305.210646) (xy 164.886087 -305.224338) (xy 164.837232 -305.23027)
			(xy 164.788057 -305.228289) (xy 164.739838 -305.218445) (xy 164.693822 -305.200993) (xy 164.651201 -305.176386)
			(xy 164.61308 -305.145261) (xy 164.580445 -305.108424) (xy 164.554142 -305.066828) (xy 164.534851 -305.021552)
			(xy 164.523074 -304.973768) (xy 164.519114 -304.924714) (xy 164.180266 -304.924714) (xy 164.179771 -304.949321)
			(xy 164.171876 -304.997898) (xy 164.156292 -305.044579) (xy 164.133421 -305.088156) (xy 164.103856 -305.1275)
			(xy 164.068363 -305.161592) (xy 164.02786 -305.189548) (xy 163.983398 -305.210646) (xy 163.936127 -305.224338)
			(xy 163.887272 -305.23027) (xy 163.838097 -305.228289) (xy 163.789878 -305.218445) (xy 163.743862 -305.200993)
			(xy 163.701241 -305.176386) (xy 163.66312 -305.145261) (xy 163.630485 -305.108424) (xy 163.604182 -305.066828)
			(xy 163.584891 -305.021552) (xy 163.573114 -304.973768) (xy 163.569154 -304.924714) (xy 163.230306 -304.924714)
			(xy 163.229811 -304.949321) (xy 163.221916 -304.997898) (xy 163.206332 -305.044579) (xy 163.183461 -305.088156)
			(xy 163.153896 -305.1275) (xy 163.118403 -305.161592) (xy 163.0779 -305.189548) (xy 163.033438 -305.210646)
			(xy 162.986167 -305.224338) (xy 162.937312 -305.23027) (xy 162.888137 -305.228289) (xy 162.839918 -305.218445)
			(xy 162.793902 -305.200993) (xy 162.751281 -305.176386) (xy 162.71316 -305.145261) (xy 162.680525 -305.108424)
			(xy 162.654222 -305.066828) (xy 162.634931 -305.021552) (xy 162.623154 -304.973768) (xy 162.619194 -304.924714)
			(xy 157.099 -304.924714) (xy 157.099 -305.399948) (xy 157.39416 -305.399948) (xy 157.39812 -305.350894)
			(xy 157.409897 -305.30311) (xy 157.429188 -305.257834) (xy 157.455491 -305.216238) (xy 157.488126 -305.179401)
			(xy 157.526247 -305.148276) (xy 157.568868 -305.123669) (xy 157.614884 -305.106217) (xy 157.663103 -305.096373)
			(xy 157.712278 -305.094392) (xy 157.761133 -305.100324) (xy 157.808404 -305.114016) (xy 157.852866 -305.135114)
			(xy 157.893369 -305.16307) (xy 157.928862 -305.197162) (xy 157.958427 -305.236506) (xy 157.981298 -305.280083)
			(xy 157.996882 -305.326764) (xy 158.004777 -305.375341) (xy 158.005272 -305.399948) (xy 158.34412 -305.399948)
			(xy 158.34808 -305.350894) (xy 158.359857 -305.30311) (xy 158.379148 -305.257834) (xy 158.405451 -305.216238)
			(xy 158.438086 -305.179401) (xy 158.476207 -305.148276) (xy 158.518828 -305.123669) (xy 158.564844 -305.106217)
			(xy 158.613063 -305.096373) (xy 158.662238 -305.094392) (xy 158.711093 -305.100324) (xy 158.758364 -305.114016)
			(xy 158.802826 -305.135114) (xy 158.843329 -305.16307) (xy 158.878822 -305.197162) (xy 158.908387 -305.236506)
			(xy 158.931258 -305.280083) (xy 158.946842 -305.326764) (xy 158.954737 -305.375341) (xy 158.955232 -305.399948)
			(xy 159.29408 -305.399948) (xy 159.29804 -305.350894) (xy 159.309817 -305.30311) (xy 159.329108 -305.257834)
			(xy 159.355411 -305.216238) (xy 159.388046 -305.179401) (xy 159.426167 -305.148276) (xy 159.468788 -305.123669)
			(xy 159.514804 -305.106217) (xy 159.563023 -305.096373) (xy 159.612198 -305.094392) (xy 159.661053 -305.100324)
			(xy 159.708324 -305.114016) (xy 159.752786 -305.135114) (xy 159.793289 -305.16307) (xy 159.828782 -305.197162)
			(xy 159.858347 -305.236506) (xy 159.881218 -305.280083) (xy 159.896802 -305.326764) (xy 159.904697 -305.375341)
			(xy 159.905192 -305.399948) (xy 160.24404 -305.399948) (xy 160.248 -305.350894) (xy 160.259777 -305.30311)
			(xy 160.279068 -305.257834) (xy 160.305371 -305.216238) (xy 160.338006 -305.179401) (xy 160.376127 -305.148276)
			(xy 160.418748 -305.123669) (xy 160.464764 -305.106217) (xy 160.512983 -305.096373) (xy 160.562158 -305.094392)
			(xy 160.611013 -305.100324) (xy 160.658284 -305.114016) (xy 160.702746 -305.135114) (xy 160.743249 -305.16307)
			(xy 160.778742 -305.197162) (xy 160.808307 -305.236506) (xy 160.831178 -305.280083) (xy 160.846762 -305.326764)
			(xy 160.854657 -305.375341) (xy 160.855152 -305.399948) (xy 161.194254 -305.399948) (xy 161.198214 -305.350894)
			(xy 161.209991 -305.30311) (xy 161.229282 -305.257834) (xy 161.255585 -305.216238) (xy 161.28822 -305.179401)
			(xy 161.326341 -305.148276) (xy 161.368962 -305.123669) (xy 161.414978 -305.106217) (xy 161.463197 -305.096373)
			(xy 161.512372 -305.094392) (xy 161.561227 -305.100324) (xy 161.608498 -305.114016) (xy 161.65296 -305.135114)
			(xy 161.693463 -305.16307) (xy 161.728956 -305.197162) (xy 161.758521 -305.236506) (xy 161.781392 -305.280083)
			(xy 161.796976 -305.326764) (xy 161.804871 -305.375341) (xy 161.805366 -305.399948) (xy 189.69407 -305.399948)
			(xy 189.69803 -305.350894) (xy 189.709807 -305.30311) (xy 189.729098 -305.257834) (xy 189.755401 -305.216238)
			(xy 189.788036 -305.179401) (xy 189.826157 -305.148276) (xy 189.868778 -305.123669) (xy 189.914794 -305.106217)
			(xy 189.963013 -305.096373) (xy 190.012188 -305.094392) (xy 190.061043 -305.100324) (xy 190.108314 -305.114016)
			(xy 190.152776 -305.135114) (xy 190.193279 -305.16307) (xy 190.228772 -305.197162) (xy 190.258337 -305.236506)
			(xy 190.281208 -305.280083) (xy 190.296792 -305.326764) (xy 190.304687 -305.375341) (xy 190.305182 -305.399948)
			(xy 190.644284 -305.399948) (xy 190.648244 -305.350894) (xy 190.660021 -305.30311) (xy 190.679312 -305.257834)
			(xy 190.705615 -305.216238) (xy 190.73825 -305.179401) (xy 190.776371 -305.148276) (xy 190.818992 -305.123669)
			(xy 190.865008 -305.106217) (xy 190.913227 -305.096373) (xy 190.962402 -305.094392) (xy 191.011257 -305.100324)
			(xy 191.058528 -305.114016) (xy 191.10299 -305.135114) (xy 191.143493 -305.16307) (xy 191.178986 -305.197162)
			(xy 191.208551 -305.236506) (xy 191.231422 -305.280083) (xy 191.247006 -305.326764) (xy 191.254901 -305.375341)
			(xy 191.255396 -305.399948) (xy 191.594244 -305.399948) (xy 191.598204 -305.350894) (xy 191.609981 -305.30311)
			(xy 191.629272 -305.257834) (xy 191.655575 -305.216238) (xy 191.68821 -305.179401) (xy 191.726331 -305.148276)
			(xy 191.768952 -305.123669) (xy 191.814968 -305.106217) (xy 191.863187 -305.096373) (xy 191.912362 -305.094392)
			(xy 191.961217 -305.100324) (xy 192.008488 -305.114016) (xy 192.05295 -305.135114) (xy 192.093453 -305.16307)
			(xy 192.128946 -305.197162) (xy 192.158511 -305.236506) (xy 192.181382 -305.280083) (xy 192.196966 -305.326764)
			(xy 192.204861 -305.375341) (xy 192.205356 -305.399948) (xy 192.204861 -305.424555) (xy 192.196966 -305.473132)
			(xy 192.181382 -305.519813) (xy 192.158511 -305.56339) (xy 192.128946 -305.602734) (xy 192.093453 -305.636826)
			(xy 192.05295 -305.664782) (xy 192.008488 -305.68588) (xy 191.961217 -305.699572) (xy 191.912362 -305.705504)
			(xy 191.863187 -305.703523) (xy 191.814968 -305.693679) (xy 191.768952 -305.676227) (xy 191.726331 -305.65162)
			(xy 191.68821 -305.620495) (xy 191.655575 -305.583658) (xy 191.629272 -305.542062) (xy 191.609981 -305.496786)
			(xy 191.598204 -305.449002) (xy 191.594244 -305.399948) (xy 191.255396 -305.399948) (xy 191.254901 -305.424555)
			(xy 191.247006 -305.473132) (xy 191.231422 -305.519813) (xy 191.208551 -305.56339) (xy 191.178986 -305.602734)
			(xy 191.143493 -305.636826) (xy 191.10299 -305.664782) (xy 191.058528 -305.68588) (xy 191.011257 -305.699572)
			(xy 190.962402 -305.705504) (xy 190.913227 -305.703523) (xy 190.865008 -305.693679) (xy 190.818992 -305.676227)
			(xy 190.776371 -305.65162) (xy 190.73825 -305.620495) (xy 190.705615 -305.583658) (xy 190.679312 -305.542062)
			(xy 190.660021 -305.496786) (xy 190.648244 -305.449002) (xy 190.644284 -305.399948) (xy 190.305182 -305.399948)
			(xy 190.304687 -305.424555) (xy 190.296792 -305.473132) (xy 190.281208 -305.519813) (xy 190.258337 -305.56339)
			(xy 190.228772 -305.602734) (xy 190.193279 -305.636826) (xy 190.152776 -305.664782) (xy 190.108314 -305.68588)
			(xy 190.061043 -305.699572) (xy 190.012188 -305.705504) (xy 189.963013 -305.703523) (xy 189.914794 -305.693679)
			(xy 189.868778 -305.676227) (xy 189.826157 -305.65162) (xy 189.788036 -305.620495) (xy 189.755401 -305.583658)
			(xy 189.729098 -305.542062) (xy 189.709807 -305.496786) (xy 189.69803 -305.449002) (xy 189.69407 -305.399948)
			(xy 161.805366 -305.399948) (xy 161.804871 -305.424555) (xy 161.796976 -305.473132) (xy 161.781392 -305.519813)
			(xy 161.758521 -305.56339) (xy 161.728956 -305.602734) (xy 161.693463 -305.636826) (xy 161.65296 -305.664782)
			(xy 161.608498 -305.68588) (xy 161.561227 -305.699572) (xy 161.512372 -305.705504) (xy 161.463197 -305.703523)
			(xy 161.414978 -305.693679) (xy 161.368962 -305.676227) (xy 161.326341 -305.65162) (xy 161.28822 -305.620495)
			(xy 161.255585 -305.583658) (xy 161.229282 -305.542062) (xy 161.209991 -305.496786) (xy 161.198214 -305.449002)
			(xy 161.194254 -305.399948) (xy 160.855152 -305.399948) (xy 160.854657 -305.424555) (xy 160.846762 -305.473132)
			(xy 160.831178 -305.519813) (xy 160.808307 -305.56339) (xy 160.778742 -305.602734) (xy 160.743249 -305.636826)
			(xy 160.702746 -305.664782) (xy 160.658284 -305.68588) (xy 160.611013 -305.699572) (xy 160.562158 -305.705504)
			(xy 160.512983 -305.703523) (xy 160.464764 -305.693679) (xy 160.418748 -305.676227) (xy 160.376127 -305.65162)
			(xy 160.338006 -305.620495) (xy 160.305371 -305.583658) (xy 160.279068 -305.542062) (xy 160.259777 -305.496786)
			(xy 160.248 -305.449002) (xy 160.24404 -305.399948) (xy 159.905192 -305.399948) (xy 159.904697 -305.424555)
			(xy 159.896802 -305.473132) (xy 159.881218 -305.519813) (xy 159.858347 -305.56339) (xy 159.828782 -305.602734)
			(xy 159.793289 -305.636826) (xy 159.752786 -305.664782) (xy 159.708324 -305.68588) (xy 159.661053 -305.699572)
			(xy 159.612198 -305.705504) (xy 159.563023 -305.703523) (xy 159.514804 -305.693679) (xy 159.468788 -305.676227)
			(xy 159.426167 -305.65162) (xy 159.388046 -305.620495) (xy 159.355411 -305.583658) (xy 159.329108 -305.542062)
			(xy 159.309817 -305.496786) (xy 159.29804 -305.449002) (xy 159.29408 -305.399948) (xy 158.955232 -305.399948)
			(xy 158.954737 -305.424555) (xy 158.946842 -305.473132) (xy 158.931258 -305.519813) (xy 158.908387 -305.56339)
			(xy 158.878822 -305.602734) (xy 158.843329 -305.636826) (xy 158.802826 -305.664782) (xy 158.758364 -305.68588)
			(xy 158.711093 -305.699572) (xy 158.662238 -305.705504) (xy 158.613063 -305.703523) (xy 158.564844 -305.693679)
			(xy 158.518828 -305.676227) (xy 158.476207 -305.65162) (xy 158.438086 -305.620495) (xy 158.405451 -305.583658)
			(xy 158.379148 -305.542062) (xy 158.359857 -305.496786) (xy 158.34808 -305.449002) (xy 158.34412 -305.399948)
			(xy 158.005272 -305.399948) (xy 158.004777 -305.424555) (xy 157.996882 -305.473132) (xy 157.981298 -305.519813)
			(xy 157.958427 -305.56339) (xy 157.928862 -305.602734) (xy 157.893369 -305.636826) (xy 157.852866 -305.664782)
			(xy 157.808404 -305.68588) (xy 157.761133 -305.699572) (xy 157.712278 -305.705504) (xy 157.663103 -305.703523)
			(xy 157.614884 -305.693679) (xy 157.568868 -305.676227) (xy 157.526247 -305.65162) (xy 157.488126 -305.620495)
			(xy 157.455491 -305.583658) (xy 157.429188 -305.542062) (xy 157.409897 -305.496786) (xy 157.39812 -305.449002)
			(xy 157.39416 -305.399948) (xy 157.099 -305.399948) (xy 157.099 -305.874928) (xy 162.619194 -305.874928)
			(xy 162.623154 -305.825874) (xy 162.634931 -305.77809) (xy 162.654222 -305.732814) (xy 162.680525 -305.691218)
			(xy 162.71316 -305.654381) (xy 162.751281 -305.623256) (xy 162.793902 -305.598649) (xy 162.839918 -305.581197)
			(xy 162.888137 -305.571353) (xy 162.937312 -305.569372) (xy 162.986167 -305.575304) (xy 163.033438 -305.588996)
			(xy 163.0779 -305.610094) (xy 163.118403 -305.63805) (xy 163.153896 -305.672142) (xy 163.183461 -305.711486)
			(xy 163.206332 -305.755063) (xy 163.221916 -305.801744) (xy 163.229811 -305.850321) (xy 163.230306 -305.874928)
			(xy 163.569154 -305.874928) (xy 163.573114 -305.825874) (xy 163.584891 -305.77809) (xy 163.604182 -305.732814)
			(xy 163.630485 -305.691218) (xy 163.66312 -305.654381) (xy 163.701241 -305.623256) (xy 163.743862 -305.598649)
			(xy 163.789878 -305.581197) (xy 163.838097 -305.571353) (xy 163.887272 -305.569372) (xy 163.936127 -305.575304)
			(xy 163.983398 -305.588996) (xy 164.02786 -305.610094) (xy 164.068363 -305.63805) (xy 164.103856 -305.672142)
			(xy 164.133421 -305.711486) (xy 164.156292 -305.755063) (xy 164.171876 -305.801744) (xy 164.179771 -305.850321)
			(xy 164.180266 -305.874928) (xy 164.519114 -305.874928) (xy 164.523074 -305.825874) (xy 164.534851 -305.77809)
			(xy 164.554142 -305.732814) (xy 164.580445 -305.691218) (xy 164.61308 -305.654381) (xy 164.651201 -305.623256)
			(xy 164.693822 -305.598649) (xy 164.739838 -305.581197) (xy 164.788057 -305.571353) (xy 164.837232 -305.569372)
			(xy 164.886087 -305.575304) (xy 164.933358 -305.588996) (xy 164.97782 -305.610094) (xy 165.018323 -305.63805)
			(xy 165.053816 -305.672142) (xy 165.083381 -305.711486) (xy 165.106252 -305.755063) (xy 165.121836 -305.801744)
			(xy 165.129731 -305.850321) (xy 165.130226 -305.874928) (xy 165.469074 -305.874928) (xy 165.473034 -305.825874)
			(xy 165.484811 -305.77809) (xy 165.504102 -305.732814) (xy 165.530405 -305.691218) (xy 165.56304 -305.654381)
			(xy 165.601161 -305.623256) (xy 165.643782 -305.598649) (xy 165.689798 -305.581197) (xy 165.738017 -305.571353)
			(xy 165.787192 -305.569372) (xy 165.836047 -305.575304) (xy 165.883318 -305.588996) (xy 165.92778 -305.610094)
			(xy 165.968283 -305.63805) (xy 166.003776 -305.672142) (xy 166.033341 -305.711486) (xy 166.056212 -305.755063)
			(xy 166.071796 -305.801744) (xy 166.079691 -305.850321) (xy 166.080186 -305.874928) (xy 166.419288 -305.874928)
			(xy 166.423248 -305.825874) (xy 166.435025 -305.77809) (xy 166.454316 -305.732814) (xy 166.480619 -305.691218)
			(xy 166.513254 -305.654381) (xy 166.551375 -305.623256) (xy 166.593996 -305.598649) (xy 166.640012 -305.581197)
			(xy 166.688231 -305.571353) (xy 166.737406 -305.569372) (xy 166.786261 -305.575304) (xy 166.833532 -305.588996)
			(xy 166.877994 -305.610094) (xy 166.918497 -305.63805) (xy 166.95399 -305.672142) (xy 166.983555 -305.711486)
			(xy 167.006426 -305.755063) (xy 167.02201 -305.801744) (xy 167.029905 -305.850321) (xy 167.0304 -305.874928)
			(xy 167.369248 -305.874928) (xy 167.373208 -305.825874) (xy 167.384985 -305.77809) (xy 167.404276 -305.732814)
			(xy 167.430579 -305.691218) (xy 167.463214 -305.654381) (xy 167.501335 -305.623256) (xy 167.543956 -305.598649)
			(xy 167.589972 -305.581197) (xy 167.638191 -305.571353) (xy 167.687366 -305.569372) (xy 167.736221 -305.575304)
			(xy 167.783492 -305.588996) (xy 167.827954 -305.610094) (xy 167.868457 -305.63805) (xy 167.90395 -305.672142)
			(xy 167.933515 -305.711486) (xy 167.956386 -305.755063) (xy 167.97197 -305.801744) (xy 167.979865 -305.850321)
			(xy 167.98036 -305.874928) (xy 168.319208 -305.874928) (xy 168.323168 -305.825874) (xy 168.334945 -305.77809)
			(xy 168.354236 -305.732814) (xy 168.380539 -305.691218) (xy 168.413174 -305.654381) (xy 168.451295 -305.623256)
			(xy 168.493916 -305.598649) (xy 168.539932 -305.581197) (xy 168.588151 -305.571353) (xy 168.637326 -305.569372)
			(xy 168.686181 -305.575304) (xy 168.733452 -305.588996) (xy 168.777914 -305.610094) (xy 168.818417 -305.63805)
			(xy 168.85391 -305.672142) (xy 168.883475 -305.711486) (xy 168.906346 -305.755063) (xy 168.92193 -305.801744)
			(xy 168.929825 -305.850321) (xy 168.93032 -305.874928) (xy 169.269168 -305.874928) (xy 169.273128 -305.825874)
			(xy 169.284905 -305.77809) (xy 169.304196 -305.732814) (xy 169.330499 -305.691218) (xy 169.363134 -305.654381)
			(xy 169.401255 -305.623256) (xy 169.443876 -305.598649) (xy 169.489892 -305.581197) (xy 169.538111 -305.571353)
			(xy 169.587286 -305.569372) (xy 169.636141 -305.575304) (xy 169.683412 -305.588996) (xy 169.727874 -305.610094)
			(xy 169.768377 -305.63805) (xy 169.80387 -305.672142) (xy 169.833435 -305.711486) (xy 169.856306 -305.755063)
			(xy 169.87189 -305.801744) (xy 169.879785 -305.850321) (xy 169.88028 -305.874928) (xy 170.219128 -305.874928)
			(xy 170.223088 -305.825874) (xy 170.234865 -305.77809) (xy 170.254156 -305.732814) (xy 170.280459 -305.691218)
			(xy 170.313094 -305.654381) (xy 170.351215 -305.623256) (xy 170.393836 -305.598649) (xy 170.439852 -305.581197)
			(xy 170.488071 -305.571353) (xy 170.537246 -305.569372) (xy 170.586101 -305.575304) (xy 170.633372 -305.588996)
			(xy 170.677834 -305.610094) (xy 170.718337 -305.63805) (xy 170.75383 -305.672142) (xy 170.783395 -305.711486)
			(xy 170.806266 -305.755063) (xy 170.82185 -305.801744) (xy 170.829745 -305.850321) (xy 170.83024 -305.874928)
			(xy 171.169088 -305.874928) (xy 171.173048 -305.825874) (xy 171.184825 -305.77809) (xy 171.204116 -305.732814)
			(xy 171.230419 -305.691218) (xy 171.263054 -305.654381) (xy 171.301175 -305.623256) (xy 171.343796 -305.598649)
			(xy 171.389812 -305.581197) (xy 171.438031 -305.571353) (xy 171.487206 -305.569372) (xy 171.536061 -305.575304)
			(xy 171.583332 -305.588996) (xy 171.627794 -305.610094) (xy 171.668297 -305.63805) (xy 171.70379 -305.672142)
			(xy 171.733355 -305.711486) (xy 171.756226 -305.755063) (xy 171.77181 -305.801744) (xy 171.779705 -305.850321)
			(xy 171.7802 -305.874928) (xy 172.119048 -305.874928) (xy 172.123008 -305.825874) (xy 172.134785 -305.77809)
			(xy 172.154076 -305.732814) (xy 172.180379 -305.691218) (xy 172.213014 -305.654381) (xy 172.251135 -305.623256)
			(xy 172.293756 -305.598649) (xy 172.339772 -305.581197) (xy 172.387991 -305.571353) (xy 172.437166 -305.569372)
			(xy 172.486021 -305.575304) (xy 172.533292 -305.588996) (xy 172.577754 -305.610094) (xy 172.618257 -305.63805)
			(xy 172.65375 -305.672142) (xy 172.683315 -305.711486) (xy 172.706186 -305.755063) (xy 172.72177 -305.801744)
			(xy 172.729665 -305.850321) (xy 172.73016 -305.874928) (xy 173.069262 -305.874928) (xy 173.073222 -305.825874)
			(xy 173.084999 -305.77809) (xy 173.10429 -305.732814) (xy 173.130593 -305.691218) (xy 173.163228 -305.654381)
			(xy 173.201349 -305.623256) (xy 173.24397 -305.598649) (xy 173.289986 -305.581197) (xy 173.338205 -305.571353)
			(xy 173.38738 -305.569372) (xy 173.436235 -305.575304) (xy 173.483506 -305.588996) (xy 173.527968 -305.610094)
			(xy 173.568471 -305.63805) (xy 173.603964 -305.672142) (xy 173.633529 -305.711486) (xy 173.6564 -305.755063)
			(xy 173.671984 -305.801744) (xy 173.679879 -305.850321) (xy 173.680374 -305.874928) (xy 174.019222 -305.874928)
			(xy 174.023182 -305.825874) (xy 174.034959 -305.77809) (xy 174.05425 -305.732814) (xy 174.080553 -305.691218)
			(xy 174.113188 -305.654381) (xy 174.151309 -305.623256) (xy 174.19393 -305.598649) (xy 174.239946 -305.581197)
			(xy 174.288165 -305.571353) (xy 174.33734 -305.569372) (xy 174.386195 -305.575304) (xy 174.433466 -305.588996)
			(xy 174.477928 -305.610094) (xy 174.518431 -305.63805) (xy 174.553924 -305.672142) (xy 174.583489 -305.711486)
			(xy 174.60636 -305.755063) (xy 174.621944 -305.801744) (xy 174.629839 -305.850321) (xy 174.630334 -305.874928)
			(xy 175.919142 -305.874928) (xy 175.923102 -305.825874) (xy 175.934879 -305.77809) (xy 175.95417 -305.732814)
			(xy 175.980473 -305.691218) (xy 176.013108 -305.654381) (xy 176.051229 -305.623256) (xy 176.09385 -305.598649)
			(xy 176.139866 -305.581197) (xy 176.188085 -305.571353) (xy 176.23726 -305.569372) (xy 176.286115 -305.575304)
			(xy 176.333386 -305.588996) (xy 176.377848 -305.610094) (xy 176.418351 -305.63805) (xy 176.453844 -305.672142)
			(xy 176.483409 -305.711486) (xy 176.50628 -305.755063) (xy 176.521864 -305.801744) (xy 176.529759 -305.850321)
			(xy 176.530254 -305.874928) (xy 176.869102 -305.874928) (xy 176.873062 -305.825874) (xy 176.884839 -305.77809)
			(xy 176.90413 -305.732814) (xy 176.930433 -305.691218) (xy 176.963068 -305.654381) (xy 177.001189 -305.623256)
			(xy 177.04381 -305.598649) (xy 177.089826 -305.581197) (xy 177.138045 -305.571353) (xy 177.18722 -305.569372)
			(xy 177.236075 -305.575304) (xy 177.283346 -305.588996) (xy 177.327808 -305.610094) (xy 177.368311 -305.63805)
			(xy 177.403804 -305.672142) (xy 177.433369 -305.711486) (xy 177.45624 -305.755063) (xy 177.471824 -305.801744)
			(xy 177.479719 -305.850321) (xy 177.480214 -305.874928) (xy 177.819062 -305.874928) (xy 177.823022 -305.825874)
			(xy 177.834799 -305.77809) (xy 177.85409 -305.732814) (xy 177.880393 -305.691218) (xy 177.913028 -305.654381)
			(xy 177.951149 -305.623256) (xy 177.99377 -305.598649) (xy 178.039786 -305.581197) (xy 178.088005 -305.571353)
			(xy 178.13718 -305.569372) (xy 178.186035 -305.575304) (xy 178.233306 -305.588996) (xy 178.277768 -305.610094)
			(xy 178.318271 -305.63805) (xy 178.353764 -305.672142) (xy 178.383329 -305.711486) (xy 178.4062 -305.755063)
			(xy 178.421784 -305.801744) (xy 178.429679 -305.850321) (xy 178.430174 -305.874928) (xy 178.769276 -305.874928)
			(xy 178.773236 -305.825874) (xy 178.785013 -305.77809) (xy 178.804304 -305.732814) (xy 178.830607 -305.691218)
			(xy 178.863242 -305.654381) (xy 178.901363 -305.623256) (xy 178.943984 -305.598649) (xy 178.99 -305.581197)
			(xy 179.038219 -305.571353) (xy 179.087394 -305.569372) (xy 179.136249 -305.575304) (xy 179.18352 -305.588996)
			(xy 179.227982 -305.610094) (xy 179.268485 -305.63805) (xy 179.303978 -305.672142) (xy 179.333543 -305.711486)
			(xy 179.356414 -305.755063) (xy 179.371998 -305.801744) (xy 179.379893 -305.850321) (xy 179.380388 -305.874928)
			(xy 179.719236 -305.874928) (xy 179.723196 -305.825874) (xy 179.734973 -305.77809) (xy 179.754264 -305.732814)
			(xy 179.780567 -305.691218) (xy 179.813202 -305.654381) (xy 179.851323 -305.623256) (xy 179.893944 -305.598649)
			(xy 179.93996 -305.581197) (xy 179.988179 -305.571353) (xy 180.037354 -305.569372) (xy 180.086209 -305.575304)
			(xy 180.13348 -305.588996) (xy 180.177942 -305.610094) (xy 180.218445 -305.63805) (xy 180.253938 -305.672142)
			(xy 180.283503 -305.711486) (xy 180.306374 -305.755063) (xy 180.321958 -305.801744) (xy 180.329853 -305.850321)
			(xy 180.330348 -305.874928) (xy 180.669196 -305.874928) (xy 180.673156 -305.825874) (xy 180.684933 -305.77809)
			(xy 180.704224 -305.732814) (xy 180.730527 -305.691218) (xy 180.763162 -305.654381) (xy 180.801283 -305.623256)
			(xy 180.843904 -305.598649) (xy 180.88992 -305.581197) (xy 180.938139 -305.571353) (xy 180.987314 -305.569372)
			(xy 181.036169 -305.575304) (xy 181.08344 -305.588996) (xy 181.127902 -305.610094) (xy 181.168405 -305.63805)
			(xy 181.203898 -305.672142) (xy 181.233463 -305.711486) (xy 181.256334 -305.755063) (xy 181.271918 -305.801744)
			(xy 181.279813 -305.850321) (xy 181.280308 -305.874928) (xy 181.619156 -305.874928) (xy 181.623116 -305.825874)
			(xy 181.634893 -305.77809) (xy 181.654184 -305.732814) (xy 181.680487 -305.691218) (xy 181.713122 -305.654381)
			(xy 181.751243 -305.623256) (xy 181.793864 -305.598649) (xy 181.83988 -305.581197) (xy 181.888099 -305.571353)
			(xy 181.937274 -305.569372) (xy 181.986129 -305.575304) (xy 182.0334 -305.588996) (xy 182.077862 -305.610094)
			(xy 182.118365 -305.63805) (xy 182.153858 -305.672142) (xy 182.183423 -305.711486) (xy 182.206294 -305.755063)
			(xy 182.221878 -305.801744) (xy 182.229773 -305.850321) (xy 182.230268 -305.874928) (xy 182.569116 -305.874928)
			(xy 182.573076 -305.825874) (xy 182.584853 -305.77809) (xy 182.604144 -305.732814) (xy 182.630447 -305.691218)
			(xy 182.663082 -305.654381) (xy 182.701203 -305.623256) (xy 182.743824 -305.598649) (xy 182.78984 -305.581197)
			(xy 182.838059 -305.571353) (xy 182.887234 -305.569372) (xy 182.936089 -305.575304) (xy 182.98336 -305.588996)
			(xy 183.027822 -305.610094) (xy 183.068325 -305.63805) (xy 183.103818 -305.672142) (xy 183.133383 -305.711486)
			(xy 183.156254 -305.755063) (xy 183.171838 -305.801744) (xy 183.179733 -305.850321) (xy 183.180228 -305.874928)
			(xy 183.519076 -305.874928) (xy 183.523036 -305.825874) (xy 183.534813 -305.77809) (xy 183.554104 -305.732814)
			(xy 183.580407 -305.691218) (xy 183.613042 -305.654381) (xy 183.651163 -305.623256) (xy 183.693784 -305.598649)
			(xy 183.7398 -305.581197) (xy 183.788019 -305.571353) (xy 183.837194 -305.569372) (xy 183.886049 -305.575304)
			(xy 183.93332 -305.588996) (xy 183.977782 -305.610094) (xy 184.018285 -305.63805) (xy 184.053778 -305.672142)
			(xy 184.083343 -305.711486) (xy 184.106214 -305.755063) (xy 184.121798 -305.801744) (xy 184.129693 -305.850321)
			(xy 184.130188 -305.874928) (xy 184.469036 -305.874928) (xy 184.472996 -305.825874) (xy 184.484773 -305.77809)
			(xy 184.504064 -305.732814) (xy 184.530367 -305.691218) (xy 184.563002 -305.654381) (xy 184.601123 -305.623256)
			(xy 184.643744 -305.598649) (xy 184.68976 -305.581197) (xy 184.737979 -305.571353) (xy 184.787154 -305.569372)
			(xy 184.836009 -305.575304) (xy 184.88328 -305.588996) (xy 184.927742 -305.610094) (xy 184.968245 -305.63805)
			(xy 185.003738 -305.672142) (xy 185.033303 -305.711486) (xy 185.056174 -305.755063) (xy 185.071758 -305.801744)
			(xy 185.079653 -305.850321) (xy 185.080148 -305.874928) (xy 185.41925 -305.874928) (xy 185.42321 -305.825874)
			(xy 185.434987 -305.77809) (xy 185.454278 -305.732814) (xy 185.480581 -305.691218) (xy 185.513216 -305.654381)
			(xy 185.551337 -305.623256) (xy 185.593958 -305.598649) (xy 185.639974 -305.581197) (xy 185.688193 -305.571353)
			(xy 185.737368 -305.569372) (xy 185.786223 -305.575304) (xy 185.833494 -305.588996) (xy 185.877956 -305.610094)
			(xy 185.918459 -305.63805) (xy 185.953952 -305.672142) (xy 185.983517 -305.711486) (xy 186.006388 -305.755063)
			(xy 186.021972 -305.801744) (xy 186.029867 -305.850321) (xy 186.030362 -305.874928) (xy 186.36921 -305.874928)
			(xy 186.37317 -305.825874) (xy 186.384947 -305.77809) (xy 186.404238 -305.732814) (xy 186.430541 -305.691218)
			(xy 186.463176 -305.654381) (xy 186.501297 -305.623256) (xy 186.543918 -305.598649) (xy 186.589934 -305.581197)
			(xy 186.638153 -305.571353) (xy 186.687328 -305.569372) (xy 186.736183 -305.575304) (xy 186.783454 -305.588996)
			(xy 186.827916 -305.610094) (xy 186.868419 -305.63805) (xy 186.903912 -305.672142) (xy 186.933477 -305.711486)
			(xy 186.956348 -305.755063) (xy 186.971932 -305.801744) (xy 186.979827 -305.850321) (xy 186.980322 -305.874928)
			(xy 187.31917 -305.874928) (xy 187.32313 -305.825874) (xy 187.334907 -305.77809) (xy 187.354198 -305.732814)
			(xy 187.380501 -305.691218) (xy 187.413136 -305.654381) (xy 187.451257 -305.623256) (xy 187.493878 -305.598649)
			(xy 187.539894 -305.581197) (xy 187.588113 -305.571353) (xy 187.637288 -305.569372) (xy 187.686143 -305.575304)
			(xy 187.733414 -305.588996) (xy 187.777876 -305.610094) (xy 187.818379 -305.63805) (xy 187.853872 -305.672142)
			(xy 187.883437 -305.711486) (xy 187.906308 -305.755063) (xy 187.921892 -305.801744) (xy 187.929787 -305.850321)
			(xy 187.930282 -305.874928) (xy 188.26913 -305.874928) (xy 188.27309 -305.825874) (xy 188.284867 -305.77809)
			(xy 188.304158 -305.732814) (xy 188.330461 -305.691218) (xy 188.363096 -305.654381) (xy 188.401217 -305.623256)
			(xy 188.443838 -305.598649) (xy 188.489854 -305.581197) (xy 188.538073 -305.571353) (xy 188.587248 -305.569372)
			(xy 188.636103 -305.575304) (xy 188.683374 -305.588996) (xy 188.727836 -305.610094) (xy 188.768339 -305.63805)
			(xy 188.803832 -305.672142) (xy 188.833397 -305.711486) (xy 188.856268 -305.755063) (xy 188.871852 -305.801744)
			(xy 188.879747 -305.850321) (xy 188.880242 -305.874928) (xy 188.879747 -305.899535) (xy 188.871852 -305.948112)
			(xy 188.856268 -305.994793) (xy 188.833397 -306.03837) (xy 188.803832 -306.077714) (xy 188.768339 -306.111806)
			(xy 188.727836 -306.139762) (xy 188.683374 -306.16086) (xy 188.636103 -306.174552) (xy 188.587248 -306.180484)
			(xy 188.538073 -306.178503) (xy 188.489854 -306.168659) (xy 188.443838 -306.151207) (xy 188.401217 -306.1266)
			(xy 188.363096 -306.095475) (xy 188.330461 -306.058638) (xy 188.304158 -306.017042) (xy 188.284867 -305.971766)
			(xy 188.27309 -305.923982) (xy 188.26913 -305.874928) (xy 187.930282 -305.874928) (xy 187.929787 -305.899535)
			(xy 187.921892 -305.948112) (xy 187.906308 -305.994793) (xy 187.883437 -306.03837) (xy 187.853872 -306.077714)
			(xy 187.818379 -306.111806) (xy 187.777876 -306.139762) (xy 187.733414 -306.16086) (xy 187.686143 -306.174552)
			(xy 187.637288 -306.180484) (xy 187.588113 -306.178503) (xy 187.539894 -306.168659) (xy 187.493878 -306.151207)
			(xy 187.451257 -306.1266) (xy 187.413136 -306.095475) (xy 187.380501 -306.058638) (xy 187.354198 -306.017042)
			(xy 187.334907 -305.971766) (xy 187.32313 -305.923982) (xy 187.31917 -305.874928) (xy 186.980322 -305.874928)
			(xy 186.979827 -305.899535) (xy 186.971932 -305.948112) (xy 186.956348 -305.994793) (xy 186.933477 -306.03837)
			(xy 186.903912 -306.077714) (xy 186.868419 -306.111806) (xy 186.827916 -306.139762) (xy 186.783454 -306.16086)
			(xy 186.736183 -306.174552) (xy 186.687328 -306.180484) (xy 186.638153 -306.178503) (xy 186.589934 -306.168659)
			(xy 186.543918 -306.151207) (xy 186.501297 -306.1266) (xy 186.463176 -306.095475) (xy 186.430541 -306.058638)
			(xy 186.404238 -306.017042) (xy 186.384947 -305.971766) (xy 186.37317 -305.923982) (xy 186.36921 -305.874928)
			(xy 186.030362 -305.874928) (xy 186.029867 -305.899535) (xy 186.021972 -305.948112) (xy 186.006388 -305.994793)
			(xy 185.983517 -306.03837) (xy 185.953952 -306.077714) (xy 185.918459 -306.111806) (xy 185.877956 -306.139762)
			(xy 185.833494 -306.16086) (xy 185.786223 -306.174552) (xy 185.737368 -306.180484) (xy 185.688193 -306.178503)
			(xy 185.639974 -306.168659) (xy 185.593958 -306.151207) (xy 185.551337 -306.1266) (xy 185.513216 -306.095475)
			(xy 185.480581 -306.058638) (xy 185.454278 -306.017042) (xy 185.434987 -305.971766) (xy 185.42321 -305.923982)
			(xy 185.41925 -305.874928) (xy 185.080148 -305.874928) (xy 185.079653 -305.899535) (xy 185.071758 -305.948112)
			(xy 185.056174 -305.994793) (xy 185.033303 -306.03837) (xy 185.003738 -306.077714) (xy 184.968245 -306.111806)
			(xy 184.927742 -306.139762) (xy 184.88328 -306.16086) (xy 184.836009 -306.174552) (xy 184.787154 -306.180484)
			(xy 184.737979 -306.178503) (xy 184.68976 -306.168659) (xy 184.643744 -306.151207) (xy 184.601123 -306.1266)
			(xy 184.563002 -306.095475) (xy 184.530367 -306.058638) (xy 184.504064 -306.017042) (xy 184.484773 -305.971766)
			(xy 184.472996 -305.923982) (xy 184.469036 -305.874928) (xy 184.130188 -305.874928) (xy 184.129693 -305.899535)
			(xy 184.121798 -305.948112) (xy 184.106214 -305.994793) (xy 184.083343 -306.03837) (xy 184.053778 -306.077714)
			(xy 184.018285 -306.111806) (xy 183.977782 -306.139762) (xy 183.93332 -306.16086) (xy 183.886049 -306.174552)
			(xy 183.837194 -306.180484) (xy 183.788019 -306.178503) (xy 183.7398 -306.168659) (xy 183.693784 -306.151207)
			(xy 183.651163 -306.1266) (xy 183.613042 -306.095475) (xy 183.580407 -306.058638) (xy 183.554104 -306.017042)
			(xy 183.534813 -305.971766) (xy 183.523036 -305.923982) (xy 183.519076 -305.874928) (xy 183.180228 -305.874928)
			(xy 183.179733 -305.899535) (xy 183.171838 -305.948112) (xy 183.156254 -305.994793) (xy 183.133383 -306.03837)
			(xy 183.103818 -306.077714) (xy 183.068325 -306.111806) (xy 183.027822 -306.139762) (xy 182.98336 -306.16086)
			(xy 182.936089 -306.174552) (xy 182.887234 -306.180484) (xy 182.838059 -306.178503) (xy 182.78984 -306.168659)
			(xy 182.743824 -306.151207) (xy 182.701203 -306.1266) (xy 182.663082 -306.095475) (xy 182.630447 -306.058638)
			(xy 182.604144 -306.017042) (xy 182.584853 -305.971766) (xy 182.573076 -305.923982) (xy 182.569116 -305.874928)
			(xy 182.230268 -305.874928) (xy 182.229773 -305.899535) (xy 182.221878 -305.948112) (xy 182.206294 -305.994793)
			(xy 182.183423 -306.03837) (xy 182.153858 -306.077714) (xy 182.118365 -306.111806) (xy 182.077862 -306.139762)
			(xy 182.0334 -306.16086) (xy 181.986129 -306.174552) (xy 181.937274 -306.180484) (xy 181.888099 -306.178503)
			(xy 181.83988 -306.168659) (xy 181.793864 -306.151207) (xy 181.751243 -306.1266) (xy 181.713122 -306.095475)
			(xy 181.680487 -306.058638) (xy 181.654184 -306.017042) (xy 181.634893 -305.971766) (xy 181.623116 -305.923982)
			(xy 181.619156 -305.874928) (xy 181.280308 -305.874928) (xy 181.279813 -305.899535) (xy 181.271918 -305.948112)
			(xy 181.256334 -305.994793) (xy 181.233463 -306.03837) (xy 181.203898 -306.077714) (xy 181.168405 -306.111806)
			(xy 181.127902 -306.139762) (xy 181.08344 -306.16086) (xy 181.036169 -306.174552) (xy 180.987314 -306.180484)
			(xy 180.938139 -306.178503) (xy 180.88992 -306.168659) (xy 180.843904 -306.151207) (xy 180.801283 -306.1266)
			(xy 180.763162 -306.095475) (xy 180.730527 -306.058638) (xy 180.704224 -306.017042) (xy 180.684933 -305.971766)
			(xy 180.673156 -305.923982) (xy 180.669196 -305.874928) (xy 180.330348 -305.874928) (xy 180.329853 -305.899535)
			(xy 180.321958 -305.948112) (xy 180.306374 -305.994793) (xy 180.283503 -306.03837) (xy 180.253938 -306.077714)
			(xy 180.218445 -306.111806) (xy 180.177942 -306.139762) (xy 180.13348 -306.16086) (xy 180.086209 -306.174552)
			(xy 180.037354 -306.180484) (xy 179.988179 -306.178503) (xy 179.93996 -306.168659) (xy 179.893944 -306.151207)
			(xy 179.851323 -306.1266) (xy 179.813202 -306.095475) (xy 179.780567 -306.058638) (xy 179.754264 -306.017042)
			(xy 179.734973 -305.971766) (xy 179.723196 -305.923982) (xy 179.719236 -305.874928) (xy 179.380388 -305.874928)
			(xy 179.379893 -305.899535) (xy 179.371998 -305.948112) (xy 179.356414 -305.994793) (xy 179.333543 -306.03837)
			(xy 179.303978 -306.077714) (xy 179.268485 -306.111806) (xy 179.227982 -306.139762) (xy 179.18352 -306.16086)
			(xy 179.136249 -306.174552) (xy 179.087394 -306.180484) (xy 179.038219 -306.178503) (xy 178.99 -306.168659)
			(xy 178.943984 -306.151207) (xy 178.901363 -306.1266) (xy 178.863242 -306.095475) (xy 178.830607 -306.058638)
			(xy 178.804304 -306.017042) (xy 178.785013 -305.971766) (xy 178.773236 -305.923982) (xy 178.769276 -305.874928)
			(xy 178.430174 -305.874928) (xy 178.429679 -305.899535) (xy 178.421784 -305.948112) (xy 178.4062 -305.994793)
			(xy 178.383329 -306.03837) (xy 178.353764 -306.077714) (xy 178.318271 -306.111806) (xy 178.277768 -306.139762)
			(xy 178.233306 -306.16086) (xy 178.186035 -306.174552) (xy 178.13718 -306.180484) (xy 178.088005 -306.178503)
			(xy 178.039786 -306.168659) (xy 177.99377 -306.151207) (xy 177.951149 -306.1266) (xy 177.913028 -306.095475)
			(xy 177.880393 -306.058638) (xy 177.85409 -306.017042) (xy 177.834799 -305.971766) (xy 177.823022 -305.923982)
			(xy 177.819062 -305.874928) (xy 177.480214 -305.874928) (xy 177.479719 -305.899535) (xy 177.471824 -305.948112)
			(xy 177.45624 -305.994793) (xy 177.433369 -306.03837) (xy 177.403804 -306.077714) (xy 177.368311 -306.111806)
			(xy 177.327808 -306.139762) (xy 177.283346 -306.16086) (xy 177.236075 -306.174552) (xy 177.18722 -306.180484)
			(xy 177.138045 -306.178503) (xy 177.089826 -306.168659) (xy 177.04381 -306.151207) (xy 177.001189 -306.1266)
			(xy 176.963068 -306.095475) (xy 176.930433 -306.058638) (xy 176.90413 -306.017042) (xy 176.884839 -305.971766)
			(xy 176.873062 -305.923982) (xy 176.869102 -305.874928) (xy 176.530254 -305.874928) (xy 176.529759 -305.899535)
			(xy 176.521864 -305.948112) (xy 176.50628 -305.994793) (xy 176.483409 -306.03837) (xy 176.453844 -306.077714)
			(xy 176.418351 -306.111806) (xy 176.377848 -306.139762) (xy 176.333386 -306.16086) (xy 176.286115 -306.174552)
			(xy 176.23726 -306.180484) (xy 176.188085 -306.178503) (xy 176.139866 -306.168659) (xy 176.09385 -306.151207)
			(xy 176.051229 -306.1266) (xy 176.013108 -306.095475) (xy 175.980473 -306.058638) (xy 175.95417 -306.017042)
			(xy 175.934879 -305.971766) (xy 175.923102 -305.923982) (xy 175.919142 -305.874928) (xy 174.630334 -305.874928)
			(xy 174.629839 -305.899535) (xy 174.621944 -305.948112) (xy 174.60636 -305.994793) (xy 174.583489 -306.03837)
			(xy 174.553924 -306.077714) (xy 174.518431 -306.111806) (xy 174.477928 -306.139762) (xy 174.433466 -306.16086)
			(xy 174.386195 -306.174552) (xy 174.33734 -306.180484) (xy 174.288165 -306.178503) (xy 174.239946 -306.168659)
			(xy 174.19393 -306.151207) (xy 174.151309 -306.1266) (xy 174.113188 -306.095475) (xy 174.080553 -306.058638)
			(xy 174.05425 -306.017042) (xy 174.034959 -305.971766) (xy 174.023182 -305.923982) (xy 174.019222 -305.874928)
			(xy 173.680374 -305.874928) (xy 173.679879 -305.899535) (xy 173.671984 -305.948112) (xy 173.6564 -305.994793)
			(xy 173.633529 -306.03837) (xy 173.603964 -306.077714) (xy 173.568471 -306.111806) (xy 173.527968 -306.139762)
			(xy 173.483506 -306.16086) (xy 173.436235 -306.174552) (xy 173.38738 -306.180484) (xy 173.338205 -306.178503)
			(xy 173.289986 -306.168659) (xy 173.24397 -306.151207) (xy 173.201349 -306.1266) (xy 173.163228 -306.095475)
			(xy 173.130593 -306.058638) (xy 173.10429 -306.017042) (xy 173.084999 -305.971766) (xy 173.073222 -305.923982)
			(xy 173.069262 -305.874928) (xy 172.73016 -305.874928) (xy 172.729665 -305.899535) (xy 172.72177 -305.948112)
			(xy 172.706186 -305.994793) (xy 172.683315 -306.03837) (xy 172.65375 -306.077714) (xy 172.618257 -306.111806)
			(xy 172.577754 -306.139762) (xy 172.533292 -306.16086) (xy 172.486021 -306.174552) (xy 172.437166 -306.180484)
			(xy 172.387991 -306.178503) (xy 172.339772 -306.168659) (xy 172.293756 -306.151207) (xy 172.251135 -306.1266)
			(xy 172.213014 -306.095475) (xy 172.180379 -306.058638) (xy 172.154076 -306.017042) (xy 172.134785 -305.971766)
			(xy 172.123008 -305.923982) (xy 172.119048 -305.874928) (xy 171.7802 -305.874928) (xy 171.779705 -305.899535)
			(xy 171.77181 -305.948112) (xy 171.756226 -305.994793) (xy 171.733355 -306.03837) (xy 171.70379 -306.077714)
			(xy 171.668297 -306.111806) (xy 171.627794 -306.139762) (xy 171.583332 -306.16086) (xy 171.536061 -306.174552)
			(xy 171.487206 -306.180484) (xy 171.438031 -306.178503) (xy 171.389812 -306.168659) (xy 171.343796 -306.151207)
			(xy 171.301175 -306.1266) (xy 171.263054 -306.095475) (xy 171.230419 -306.058638) (xy 171.204116 -306.017042)
			(xy 171.184825 -305.971766) (xy 171.173048 -305.923982) (xy 171.169088 -305.874928) (xy 170.83024 -305.874928)
			(xy 170.829745 -305.899535) (xy 170.82185 -305.948112) (xy 170.806266 -305.994793) (xy 170.783395 -306.03837)
			(xy 170.75383 -306.077714) (xy 170.718337 -306.111806) (xy 170.677834 -306.139762) (xy 170.633372 -306.16086)
			(xy 170.586101 -306.174552) (xy 170.537246 -306.180484) (xy 170.488071 -306.178503) (xy 170.439852 -306.168659)
			(xy 170.393836 -306.151207) (xy 170.351215 -306.1266) (xy 170.313094 -306.095475) (xy 170.280459 -306.058638)
			(xy 170.254156 -306.017042) (xy 170.234865 -305.971766) (xy 170.223088 -305.923982) (xy 170.219128 -305.874928)
			(xy 169.88028 -305.874928) (xy 169.879785 -305.899535) (xy 169.87189 -305.948112) (xy 169.856306 -305.994793)
			(xy 169.833435 -306.03837) (xy 169.80387 -306.077714) (xy 169.768377 -306.111806) (xy 169.727874 -306.139762)
			(xy 169.683412 -306.16086) (xy 169.636141 -306.174552) (xy 169.587286 -306.180484) (xy 169.538111 -306.178503)
			(xy 169.489892 -306.168659) (xy 169.443876 -306.151207) (xy 169.401255 -306.1266) (xy 169.363134 -306.095475)
			(xy 169.330499 -306.058638) (xy 169.304196 -306.017042) (xy 169.284905 -305.971766) (xy 169.273128 -305.923982)
			(xy 169.269168 -305.874928) (xy 168.93032 -305.874928) (xy 168.929825 -305.899535) (xy 168.92193 -305.948112)
			(xy 168.906346 -305.994793) (xy 168.883475 -306.03837) (xy 168.85391 -306.077714) (xy 168.818417 -306.111806)
			(xy 168.777914 -306.139762) (xy 168.733452 -306.16086) (xy 168.686181 -306.174552) (xy 168.637326 -306.180484)
			(xy 168.588151 -306.178503) (xy 168.539932 -306.168659) (xy 168.493916 -306.151207) (xy 168.451295 -306.1266)
			(xy 168.413174 -306.095475) (xy 168.380539 -306.058638) (xy 168.354236 -306.017042) (xy 168.334945 -305.971766)
			(xy 168.323168 -305.923982) (xy 168.319208 -305.874928) (xy 167.98036 -305.874928) (xy 167.979865 -305.899535)
			(xy 167.97197 -305.948112) (xy 167.956386 -305.994793) (xy 167.933515 -306.03837) (xy 167.90395 -306.077714)
			(xy 167.868457 -306.111806) (xy 167.827954 -306.139762) (xy 167.783492 -306.16086) (xy 167.736221 -306.174552)
			(xy 167.687366 -306.180484) (xy 167.638191 -306.178503) (xy 167.589972 -306.168659) (xy 167.543956 -306.151207)
			(xy 167.501335 -306.1266) (xy 167.463214 -306.095475) (xy 167.430579 -306.058638) (xy 167.404276 -306.017042)
			(xy 167.384985 -305.971766) (xy 167.373208 -305.923982) (xy 167.369248 -305.874928) (xy 167.0304 -305.874928)
			(xy 167.029905 -305.899535) (xy 167.02201 -305.948112) (xy 167.006426 -305.994793) (xy 166.983555 -306.03837)
			(xy 166.95399 -306.077714) (xy 166.918497 -306.111806) (xy 166.877994 -306.139762) (xy 166.833532 -306.16086)
			(xy 166.786261 -306.174552) (xy 166.737406 -306.180484) (xy 166.688231 -306.178503) (xy 166.640012 -306.168659)
			(xy 166.593996 -306.151207) (xy 166.551375 -306.1266) (xy 166.513254 -306.095475) (xy 166.480619 -306.058638)
			(xy 166.454316 -306.017042) (xy 166.435025 -305.971766) (xy 166.423248 -305.923982) (xy 166.419288 -305.874928)
			(xy 166.080186 -305.874928) (xy 166.079691 -305.899535) (xy 166.071796 -305.948112) (xy 166.056212 -305.994793)
			(xy 166.033341 -306.03837) (xy 166.003776 -306.077714) (xy 165.968283 -306.111806) (xy 165.92778 -306.139762)
			(xy 165.883318 -306.16086) (xy 165.836047 -306.174552) (xy 165.787192 -306.180484) (xy 165.738017 -306.178503)
			(xy 165.689798 -306.168659) (xy 165.643782 -306.151207) (xy 165.601161 -306.1266) (xy 165.56304 -306.095475)
			(xy 165.530405 -306.058638) (xy 165.504102 -306.017042) (xy 165.484811 -305.971766) (xy 165.473034 -305.923982)
			(xy 165.469074 -305.874928) (xy 165.130226 -305.874928) (xy 165.129731 -305.899535) (xy 165.121836 -305.948112)
			(xy 165.106252 -305.994793) (xy 165.083381 -306.03837) (xy 165.053816 -306.077714) (xy 165.018323 -306.111806)
			(xy 164.97782 -306.139762) (xy 164.933358 -306.16086) (xy 164.886087 -306.174552) (xy 164.837232 -306.180484)
			(xy 164.788057 -306.178503) (xy 164.739838 -306.168659) (xy 164.693822 -306.151207) (xy 164.651201 -306.1266)
			(xy 164.61308 -306.095475) (xy 164.580445 -306.058638) (xy 164.554142 -306.017042) (xy 164.534851 -305.971766)
			(xy 164.523074 -305.923982) (xy 164.519114 -305.874928) (xy 164.180266 -305.874928) (xy 164.179771 -305.899535)
			(xy 164.171876 -305.948112) (xy 164.156292 -305.994793) (xy 164.133421 -306.03837) (xy 164.103856 -306.077714)
			(xy 164.068363 -306.111806) (xy 164.02786 -306.139762) (xy 163.983398 -306.16086) (xy 163.936127 -306.174552)
			(xy 163.887272 -306.180484) (xy 163.838097 -306.178503) (xy 163.789878 -306.168659) (xy 163.743862 -306.151207)
			(xy 163.701241 -306.1266) (xy 163.66312 -306.095475) (xy 163.630485 -306.058638) (xy 163.604182 -306.017042)
			(xy 163.584891 -305.971766) (xy 163.573114 -305.923982) (xy 163.569154 -305.874928) (xy 163.230306 -305.874928)
			(xy 163.229811 -305.899535) (xy 163.221916 -305.948112) (xy 163.206332 -305.994793) (xy 163.183461 -306.03837)
			(xy 163.153896 -306.077714) (xy 163.118403 -306.111806) (xy 163.0779 -306.139762) (xy 163.033438 -306.16086)
			(xy 162.986167 -306.174552) (xy 162.937312 -306.180484) (xy 162.888137 -306.178503) (xy 162.839918 -306.168659)
			(xy 162.793902 -306.151207) (xy 162.751281 -306.1266) (xy 162.71316 -306.095475) (xy 162.680525 -306.058638)
			(xy 162.654222 -306.017042) (xy 162.634931 -305.971766) (xy 162.623154 -305.923982) (xy 162.619194 -305.874928)
			(xy 157.099 -305.874928) (xy 157.099 -306.349908) (xy 157.39416 -306.349908) (xy 157.39812 -306.300854)
			(xy 157.409897 -306.25307) (xy 157.429188 -306.207794) (xy 157.455491 -306.166198) (xy 157.488126 -306.129361)
			(xy 157.526247 -306.098236) (xy 157.568868 -306.073629) (xy 157.614884 -306.056177) (xy 157.663103 -306.046333)
			(xy 157.712278 -306.044352) (xy 157.761133 -306.050284) (xy 157.808404 -306.063976) (xy 157.852866 -306.085074)
			(xy 157.893369 -306.11303) (xy 157.928862 -306.147122) (xy 157.958427 -306.186466) (xy 157.981298 -306.230043)
			(xy 157.996882 -306.276724) (xy 158.004777 -306.325301) (xy 158.005272 -306.349908) (xy 158.34412 -306.349908)
			(xy 158.34808 -306.300854) (xy 158.359857 -306.25307) (xy 158.379148 -306.207794) (xy 158.405451 -306.166198)
			(xy 158.438086 -306.129361) (xy 158.476207 -306.098236) (xy 158.518828 -306.073629) (xy 158.564844 -306.056177)
			(xy 158.613063 -306.046333) (xy 158.662238 -306.044352) (xy 158.711093 -306.050284) (xy 158.758364 -306.063976)
			(xy 158.802826 -306.085074) (xy 158.843329 -306.11303) (xy 158.878822 -306.147122) (xy 158.908387 -306.186466)
			(xy 158.931258 -306.230043) (xy 158.946842 -306.276724) (xy 158.954737 -306.325301) (xy 158.955232 -306.349908)
			(xy 159.29408 -306.349908) (xy 159.29804 -306.300854) (xy 159.309817 -306.25307) (xy 159.329108 -306.207794)
			(xy 159.355411 -306.166198) (xy 159.388046 -306.129361) (xy 159.426167 -306.098236) (xy 159.468788 -306.073629)
			(xy 159.514804 -306.056177) (xy 159.563023 -306.046333) (xy 159.612198 -306.044352) (xy 159.661053 -306.050284)
			(xy 159.708324 -306.063976) (xy 159.752786 -306.085074) (xy 159.793289 -306.11303) (xy 159.828782 -306.147122)
			(xy 159.858347 -306.186466) (xy 159.881218 -306.230043) (xy 159.896802 -306.276724) (xy 159.904697 -306.325301)
			(xy 159.905192 -306.349908) (xy 160.24404 -306.349908) (xy 160.248 -306.300854) (xy 160.259777 -306.25307)
			(xy 160.279068 -306.207794) (xy 160.305371 -306.166198) (xy 160.338006 -306.129361) (xy 160.376127 -306.098236)
			(xy 160.418748 -306.073629) (xy 160.464764 -306.056177) (xy 160.512983 -306.046333) (xy 160.562158 -306.044352)
			(xy 160.611013 -306.050284) (xy 160.658284 -306.063976) (xy 160.702746 -306.085074) (xy 160.743249 -306.11303)
			(xy 160.778742 -306.147122) (xy 160.808307 -306.186466) (xy 160.831178 -306.230043) (xy 160.846762 -306.276724)
			(xy 160.854657 -306.325301) (xy 160.855152 -306.349908) (xy 161.194254 -306.349908) (xy 161.198214 -306.300854)
			(xy 161.209991 -306.25307) (xy 161.229282 -306.207794) (xy 161.255585 -306.166198) (xy 161.28822 -306.129361)
			(xy 161.326341 -306.098236) (xy 161.368962 -306.073629) (xy 161.414978 -306.056177) (xy 161.463197 -306.046333)
			(xy 161.512372 -306.044352) (xy 161.561227 -306.050284) (xy 161.608498 -306.063976) (xy 161.65296 -306.085074)
			(xy 161.693463 -306.11303) (xy 161.728956 -306.147122) (xy 161.758521 -306.186466) (xy 161.781392 -306.230043)
			(xy 161.796976 -306.276724) (xy 161.804871 -306.325301) (xy 161.805366 -306.349908) (xy 189.69407 -306.349908)
			(xy 189.69803 -306.300854) (xy 189.709807 -306.25307) (xy 189.729098 -306.207794) (xy 189.755401 -306.166198)
			(xy 189.788036 -306.129361) (xy 189.826157 -306.098236) (xy 189.868778 -306.073629) (xy 189.914794 -306.056177)
			(xy 189.963013 -306.046333) (xy 190.012188 -306.044352) (xy 190.061043 -306.050284) (xy 190.108314 -306.063976)
			(xy 190.152776 -306.085074) (xy 190.193279 -306.11303) (xy 190.228772 -306.147122) (xy 190.258337 -306.186466)
			(xy 190.281208 -306.230043) (xy 190.296792 -306.276724) (xy 190.304687 -306.325301) (xy 190.305182 -306.349908)
			(xy 190.304687 -306.374515) (xy 190.304508 -306.375616) (xy 190.62344 -306.375616) (xy 190.62344 -306.3242)
			(xy 190.631483 -306.273418) (xy 190.647371 -306.224519) (xy 190.670714 -306.178707) (xy 190.700935 -306.137111)
			(xy 190.737291 -306.100755) (xy 190.778887 -306.070534) (xy 190.824699 -306.047191) (xy 190.873598 -306.031303)
			(xy 190.92438 -306.02326) (xy 190.975796 -306.02326) (xy 191.026578 -306.031303) (xy 191.075477 -306.047191)
			(xy 191.121289 -306.070534) (xy 191.162885 -306.100755) (xy 191.199241 -306.137111) (xy 191.229462 -306.178707)
			(xy 191.252805 -306.224519) (xy 191.268693 -306.273418) (xy 191.276736 -306.3242) (xy 191.27724 -306.349908)
			(xy 191.276736 -306.375616) (xy 191.5734 -306.375616) (xy 191.5734 -306.3242) (xy 191.581443 -306.273418)
			(xy 191.597331 -306.224519) (xy 191.620674 -306.178707) (xy 191.650895 -306.137111) (xy 191.687251 -306.100755)
			(xy 191.728847 -306.070534) (xy 191.774659 -306.047191) (xy 191.823558 -306.031303) (xy 191.87434 -306.02326)
			(xy 191.925756 -306.02326) (xy 191.976538 -306.031303) (xy 192.025437 -306.047191) (xy 192.071249 -306.070534)
			(xy 192.112845 -306.100755) (xy 192.149201 -306.137111) (xy 192.179422 -306.178707) (xy 192.202765 -306.224519)
			(xy 192.218653 -306.273418) (xy 192.226696 -306.3242) (xy 192.2272 -306.349908) (xy 192.226696 -306.375616)
			(xy 192.218653 -306.426398) (xy 192.202765 -306.475297) (xy 192.179422 -306.521109) (xy 192.149201 -306.562705)
			(xy 192.112845 -306.599061) (xy 192.071249 -306.629282) (xy 192.025437 -306.652625) (xy 191.976538 -306.668513)
			(xy 191.925756 -306.676556) (xy 191.87434 -306.676556) (xy 191.823558 -306.668513) (xy 191.774659 -306.652625)
			(xy 191.728847 -306.629282) (xy 191.687251 -306.599061) (xy 191.650895 -306.562705) (xy 191.620674 -306.521109)
			(xy 191.597331 -306.475297) (xy 191.581443 -306.426398) (xy 191.5734 -306.375616) (xy 191.276736 -306.375616)
			(xy 191.268693 -306.426398) (xy 191.252805 -306.475297) (xy 191.229462 -306.521109) (xy 191.199241 -306.562705)
			(xy 191.162885 -306.599061) (xy 191.121289 -306.629282) (xy 191.075477 -306.652625) (xy 191.026578 -306.668513)
			(xy 190.975796 -306.676556) (xy 190.92438 -306.676556) (xy 190.873598 -306.668513) (xy 190.824699 -306.652625)
			(xy 190.778887 -306.629282) (xy 190.737291 -306.599061) (xy 190.700935 -306.562705) (xy 190.670714 -306.521109)
			(xy 190.647371 -306.475297) (xy 190.631483 -306.426398) (xy 190.62344 -306.375616) (xy 190.304508 -306.375616)
			(xy 190.296792 -306.423092) (xy 190.281208 -306.469773) (xy 190.258337 -306.51335) (xy 190.228772 -306.552694)
			(xy 190.193279 -306.586786) (xy 190.152776 -306.614742) (xy 190.108314 -306.63584) (xy 190.061043 -306.649532)
			(xy 190.012188 -306.655464) (xy 189.963013 -306.653483) (xy 189.914794 -306.643639) (xy 189.868778 -306.626187)
			(xy 189.826157 -306.60158) (xy 189.788036 -306.570455) (xy 189.755401 -306.533618) (xy 189.729098 -306.492022)
			(xy 189.709807 -306.446746) (xy 189.69803 -306.398962) (xy 189.69407 -306.349908) (xy 161.805366 -306.349908)
			(xy 161.804871 -306.374515) (xy 161.796976 -306.423092) (xy 161.781392 -306.469773) (xy 161.758521 -306.51335)
			(xy 161.728956 -306.552694) (xy 161.693463 -306.586786) (xy 161.65296 -306.614742) (xy 161.608498 -306.63584)
			(xy 161.561227 -306.649532) (xy 161.512372 -306.655464) (xy 161.463197 -306.653483) (xy 161.414978 -306.643639)
			(xy 161.368962 -306.626187) (xy 161.326341 -306.60158) (xy 161.28822 -306.570455) (xy 161.255585 -306.533618)
			(xy 161.229282 -306.492022) (xy 161.209991 -306.446746) (xy 161.198214 -306.398962) (xy 161.194254 -306.349908)
			(xy 160.855152 -306.349908) (xy 160.854657 -306.374515) (xy 160.846762 -306.423092) (xy 160.831178 -306.469773)
			(xy 160.808307 -306.51335) (xy 160.778742 -306.552694) (xy 160.743249 -306.586786) (xy 160.702746 -306.614742)
			(xy 160.658284 -306.63584) (xy 160.611013 -306.649532) (xy 160.562158 -306.655464) (xy 160.512983 -306.653483)
			(xy 160.464764 -306.643639) (xy 160.418748 -306.626187) (xy 160.376127 -306.60158) (xy 160.338006 -306.570455)
			(xy 160.305371 -306.533618) (xy 160.279068 -306.492022) (xy 160.259777 -306.446746) (xy 160.248 -306.398962)
			(xy 160.24404 -306.349908) (xy 159.905192 -306.349908) (xy 159.904697 -306.374515) (xy 159.896802 -306.423092)
			(xy 159.881218 -306.469773) (xy 159.858347 -306.51335) (xy 159.828782 -306.552694) (xy 159.793289 -306.586786)
			(xy 159.752786 -306.614742) (xy 159.708324 -306.63584) (xy 159.661053 -306.649532) (xy 159.612198 -306.655464)
			(xy 159.563023 -306.653483) (xy 159.514804 -306.643639) (xy 159.468788 -306.626187) (xy 159.426167 -306.60158)
			(xy 159.388046 -306.570455) (xy 159.355411 -306.533618) (xy 159.329108 -306.492022) (xy 159.309817 -306.446746)
			(xy 159.29804 -306.398962) (xy 159.29408 -306.349908) (xy 158.955232 -306.349908) (xy 158.954737 -306.374515)
			(xy 158.946842 -306.423092) (xy 158.931258 -306.469773) (xy 158.908387 -306.51335) (xy 158.878822 -306.552694)
			(xy 158.843329 -306.586786) (xy 158.802826 -306.614742) (xy 158.758364 -306.63584) (xy 158.711093 -306.649532)
			(xy 158.662238 -306.655464) (xy 158.613063 -306.653483) (xy 158.564844 -306.643639) (xy 158.518828 -306.626187)
			(xy 158.476207 -306.60158) (xy 158.438086 -306.570455) (xy 158.405451 -306.533618) (xy 158.379148 -306.492022)
			(xy 158.359857 -306.446746) (xy 158.34808 -306.398962) (xy 158.34412 -306.349908) (xy 158.005272 -306.349908)
			(xy 158.004777 -306.374515) (xy 157.996882 -306.423092) (xy 157.981298 -306.469773) (xy 157.958427 -306.51335)
			(xy 157.928862 -306.552694) (xy 157.893369 -306.586786) (xy 157.852866 -306.614742) (xy 157.808404 -306.63584)
			(xy 157.761133 -306.649532) (xy 157.712278 -306.655464) (xy 157.663103 -306.653483) (xy 157.614884 -306.643639)
			(xy 157.568868 -306.626187) (xy 157.526247 -306.60158) (xy 157.488126 -306.570455) (xy 157.455491 -306.533618)
			(xy 157.429188 -306.492022) (xy 157.409897 -306.446746) (xy 157.39812 -306.398962) (xy 157.39416 -306.349908)
			(xy 157.099 -306.349908) (xy 157.099 -306.824888) (xy 162.619194 -306.824888) (xy 162.623154 -306.775834)
			(xy 162.634931 -306.72805) (xy 162.654222 -306.682774) (xy 162.680525 -306.641178) (xy 162.71316 -306.604341)
			(xy 162.751281 -306.573216) (xy 162.793902 -306.548609) (xy 162.839918 -306.531157) (xy 162.888137 -306.521313)
			(xy 162.937312 -306.519332) (xy 162.986167 -306.525264) (xy 163.033438 -306.538956) (xy 163.0779 -306.560054)
			(xy 163.118403 -306.58801) (xy 163.153896 -306.622102) (xy 163.183461 -306.661446) (xy 163.206332 -306.705023)
			(xy 163.221916 -306.751704) (xy 163.229811 -306.800281) (xy 163.230306 -306.824888) (xy 163.569154 -306.824888)
			(xy 163.573114 -306.775834) (xy 163.584891 -306.72805) (xy 163.604182 -306.682774) (xy 163.630485 -306.641178)
			(xy 163.66312 -306.604341) (xy 163.701241 -306.573216) (xy 163.743862 -306.548609) (xy 163.789878 -306.531157)
			(xy 163.838097 -306.521313) (xy 163.887272 -306.519332) (xy 163.936127 -306.525264) (xy 163.983398 -306.538956)
			(xy 164.02786 -306.560054) (xy 164.068363 -306.58801) (xy 164.103856 -306.622102) (xy 164.133421 -306.661446)
			(xy 164.156292 -306.705023) (xy 164.171876 -306.751704) (xy 164.179771 -306.800281) (xy 164.180266 -306.824888)
			(xy 164.519114 -306.824888) (xy 164.523074 -306.775834) (xy 164.534851 -306.72805) (xy 164.554142 -306.682774)
			(xy 164.580445 -306.641178) (xy 164.61308 -306.604341) (xy 164.651201 -306.573216) (xy 164.693822 -306.548609)
			(xy 164.739838 -306.531157) (xy 164.788057 -306.521313) (xy 164.837232 -306.519332) (xy 164.886087 -306.525264)
			(xy 164.933358 -306.538956) (xy 164.97782 -306.560054) (xy 165.018323 -306.58801) (xy 165.053816 -306.622102)
			(xy 165.083381 -306.661446) (xy 165.106252 -306.705023) (xy 165.121836 -306.751704) (xy 165.129731 -306.800281)
			(xy 165.130226 -306.824888) (xy 165.469074 -306.824888) (xy 165.473034 -306.775834) (xy 165.484811 -306.72805)
			(xy 165.504102 -306.682774) (xy 165.530405 -306.641178) (xy 165.56304 -306.604341) (xy 165.601161 -306.573216)
			(xy 165.643782 -306.548609) (xy 165.689798 -306.531157) (xy 165.738017 -306.521313) (xy 165.787192 -306.519332)
			(xy 165.836047 -306.525264) (xy 165.883318 -306.538956) (xy 165.92778 -306.560054) (xy 165.968283 -306.58801)
			(xy 166.003776 -306.622102) (xy 166.033341 -306.661446) (xy 166.056212 -306.705023) (xy 166.071796 -306.751704)
			(xy 166.079691 -306.800281) (xy 166.080186 -306.824888) (xy 166.419288 -306.824888) (xy 166.423248 -306.775834)
			(xy 166.435025 -306.72805) (xy 166.454316 -306.682774) (xy 166.480619 -306.641178) (xy 166.513254 -306.604341)
			(xy 166.551375 -306.573216) (xy 166.593996 -306.548609) (xy 166.640012 -306.531157) (xy 166.688231 -306.521313)
			(xy 166.737406 -306.519332) (xy 166.786261 -306.525264) (xy 166.833532 -306.538956) (xy 166.877994 -306.560054)
			(xy 166.918497 -306.58801) (xy 166.95399 -306.622102) (xy 166.983555 -306.661446) (xy 167.006426 -306.705023)
			(xy 167.02201 -306.751704) (xy 167.029905 -306.800281) (xy 167.0304 -306.824888) (xy 167.369248 -306.824888)
			(xy 167.373208 -306.775834) (xy 167.384985 -306.72805) (xy 167.404276 -306.682774) (xy 167.430579 -306.641178)
			(xy 167.463214 -306.604341) (xy 167.501335 -306.573216) (xy 167.543956 -306.548609) (xy 167.589972 -306.531157)
			(xy 167.638191 -306.521313) (xy 167.687366 -306.519332) (xy 167.736221 -306.525264) (xy 167.783492 -306.538956)
			(xy 167.827954 -306.560054) (xy 167.868457 -306.58801) (xy 167.90395 -306.622102) (xy 167.933515 -306.661446)
			(xy 167.956386 -306.705023) (xy 167.97197 -306.751704) (xy 167.979865 -306.800281) (xy 167.98036 -306.824888)
			(xy 168.319208 -306.824888) (xy 168.323168 -306.775834) (xy 168.334945 -306.72805) (xy 168.354236 -306.682774)
			(xy 168.380539 -306.641178) (xy 168.413174 -306.604341) (xy 168.451295 -306.573216) (xy 168.493916 -306.548609)
			(xy 168.539932 -306.531157) (xy 168.588151 -306.521313) (xy 168.637326 -306.519332) (xy 168.686181 -306.525264)
			(xy 168.733452 -306.538956) (xy 168.777914 -306.560054) (xy 168.818417 -306.58801) (xy 168.85391 -306.622102)
			(xy 168.883475 -306.661446) (xy 168.906346 -306.705023) (xy 168.92193 -306.751704) (xy 168.929825 -306.800281)
			(xy 168.93032 -306.824888) (xy 169.269168 -306.824888) (xy 169.273128 -306.775834) (xy 169.284905 -306.72805)
			(xy 169.304196 -306.682774) (xy 169.330499 -306.641178) (xy 169.363134 -306.604341) (xy 169.401255 -306.573216)
			(xy 169.443876 -306.548609) (xy 169.489892 -306.531157) (xy 169.538111 -306.521313) (xy 169.587286 -306.519332)
			(xy 169.636141 -306.525264) (xy 169.683412 -306.538956) (xy 169.727874 -306.560054) (xy 169.768377 -306.58801)
			(xy 169.80387 -306.622102) (xy 169.833435 -306.661446) (xy 169.856306 -306.705023) (xy 169.87189 -306.751704)
			(xy 169.879785 -306.800281) (xy 169.88028 -306.824888) (xy 170.219128 -306.824888) (xy 170.223088 -306.775834)
			(xy 170.234865 -306.72805) (xy 170.254156 -306.682774) (xy 170.280459 -306.641178) (xy 170.313094 -306.604341)
			(xy 170.351215 -306.573216) (xy 170.393836 -306.548609) (xy 170.439852 -306.531157) (xy 170.488071 -306.521313)
			(xy 170.537246 -306.519332) (xy 170.586101 -306.525264) (xy 170.633372 -306.538956) (xy 170.677834 -306.560054)
			(xy 170.718337 -306.58801) (xy 170.75383 -306.622102) (xy 170.783395 -306.661446) (xy 170.806266 -306.705023)
			(xy 170.82185 -306.751704) (xy 170.829745 -306.800281) (xy 170.83024 -306.824888) (xy 171.169088 -306.824888)
			(xy 171.173048 -306.775834) (xy 171.184825 -306.72805) (xy 171.204116 -306.682774) (xy 171.230419 -306.641178)
			(xy 171.263054 -306.604341) (xy 171.301175 -306.573216) (xy 171.343796 -306.548609) (xy 171.389812 -306.531157)
			(xy 171.438031 -306.521313) (xy 171.487206 -306.519332) (xy 171.536061 -306.525264) (xy 171.583332 -306.538956)
			(xy 171.627794 -306.560054) (xy 171.668297 -306.58801) (xy 171.70379 -306.622102) (xy 171.733355 -306.661446)
			(xy 171.756226 -306.705023) (xy 171.77181 -306.751704) (xy 171.779705 -306.800281) (xy 171.7802 -306.824888)
			(xy 172.119048 -306.824888) (xy 172.123008 -306.775834) (xy 172.134785 -306.72805) (xy 172.154076 -306.682774)
			(xy 172.180379 -306.641178) (xy 172.213014 -306.604341) (xy 172.251135 -306.573216) (xy 172.293756 -306.548609)
			(xy 172.339772 -306.531157) (xy 172.387991 -306.521313) (xy 172.437166 -306.519332) (xy 172.486021 -306.525264)
			(xy 172.533292 -306.538956) (xy 172.577754 -306.560054) (xy 172.618257 -306.58801) (xy 172.65375 -306.622102)
			(xy 172.683315 -306.661446) (xy 172.706186 -306.705023) (xy 172.72177 -306.751704) (xy 172.729665 -306.800281)
			(xy 172.73016 -306.824888) (xy 173.069262 -306.824888) (xy 173.073222 -306.775834) (xy 173.084999 -306.72805)
			(xy 173.10429 -306.682774) (xy 173.130593 -306.641178) (xy 173.163228 -306.604341) (xy 173.201349 -306.573216)
			(xy 173.24397 -306.548609) (xy 173.289986 -306.531157) (xy 173.338205 -306.521313) (xy 173.38738 -306.519332)
			(xy 173.436235 -306.525264) (xy 173.483506 -306.538956) (xy 173.527968 -306.560054) (xy 173.568471 -306.58801)
			(xy 173.603964 -306.622102) (xy 173.633529 -306.661446) (xy 173.6564 -306.705023) (xy 173.671984 -306.751704)
			(xy 173.679879 -306.800281) (xy 173.680374 -306.824888) (xy 174.019222 -306.824888) (xy 174.023182 -306.775834)
			(xy 174.034959 -306.72805) (xy 174.05425 -306.682774) (xy 174.080553 -306.641178) (xy 174.113188 -306.604341)
			(xy 174.151309 -306.573216) (xy 174.19393 -306.548609) (xy 174.239946 -306.531157) (xy 174.288165 -306.521313)
			(xy 174.33734 -306.519332) (xy 174.386195 -306.525264) (xy 174.433466 -306.538956) (xy 174.477928 -306.560054)
			(xy 174.518431 -306.58801) (xy 174.553924 -306.622102) (xy 174.583489 -306.661446) (xy 174.60636 -306.705023)
			(xy 174.621944 -306.751704) (xy 174.629839 -306.800281) (xy 174.630334 -306.824888) (xy 175.919142 -306.824888)
			(xy 175.923102 -306.775834) (xy 175.934879 -306.72805) (xy 175.95417 -306.682774) (xy 175.980473 -306.641178)
			(xy 176.013108 -306.604341) (xy 176.051229 -306.573216) (xy 176.09385 -306.548609) (xy 176.139866 -306.531157)
			(xy 176.188085 -306.521313) (xy 176.23726 -306.519332) (xy 176.286115 -306.525264) (xy 176.333386 -306.538956)
			(xy 176.377848 -306.560054) (xy 176.418351 -306.58801) (xy 176.453844 -306.622102) (xy 176.483409 -306.661446)
			(xy 176.50628 -306.705023) (xy 176.521864 -306.751704) (xy 176.529759 -306.800281) (xy 176.530254 -306.824888)
			(xy 176.869102 -306.824888) (xy 176.873062 -306.775834) (xy 176.884839 -306.72805) (xy 176.90413 -306.682774)
			(xy 176.930433 -306.641178) (xy 176.963068 -306.604341) (xy 177.001189 -306.573216) (xy 177.04381 -306.548609)
			(xy 177.089826 -306.531157) (xy 177.138045 -306.521313) (xy 177.18722 -306.519332) (xy 177.236075 -306.525264)
			(xy 177.283346 -306.538956) (xy 177.327808 -306.560054) (xy 177.368311 -306.58801) (xy 177.403804 -306.622102)
			(xy 177.433369 -306.661446) (xy 177.45624 -306.705023) (xy 177.471824 -306.751704) (xy 177.479719 -306.800281)
			(xy 177.480214 -306.824888) (xy 177.819062 -306.824888) (xy 177.823022 -306.775834) (xy 177.834799 -306.72805)
			(xy 177.85409 -306.682774) (xy 177.880393 -306.641178) (xy 177.913028 -306.604341) (xy 177.951149 -306.573216)
			(xy 177.99377 -306.548609) (xy 178.039786 -306.531157) (xy 178.088005 -306.521313) (xy 178.13718 -306.519332)
			(xy 178.186035 -306.525264) (xy 178.233306 -306.538956) (xy 178.277768 -306.560054) (xy 178.318271 -306.58801)
			(xy 178.353764 -306.622102) (xy 178.383329 -306.661446) (xy 178.4062 -306.705023) (xy 178.421784 -306.751704)
			(xy 178.429679 -306.800281) (xy 178.430174 -306.824888) (xy 178.769276 -306.824888) (xy 178.773236 -306.775834)
			(xy 178.785013 -306.72805) (xy 178.804304 -306.682774) (xy 178.830607 -306.641178) (xy 178.863242 -306.604341)
			(xy 178.901363 -306.573216) (xy 178.943984 -306.548609) (xy 178.99 -306.531157) (xy 179.038219 -306.521313)
			(xy 179.087394 -306.519332) (xy 179.136249 -306.525264) (xy 179.18352 -306.538956) (xy 179.227982 -306.560054)
			(xy 179.268485 -306.58801) (xy 179.303978 -306.622102) (xy 179.333543 -306.661446) (xy 179.356414 -306.705023)
			(xy 179.371998 -306.751704) (xy 179.379893 -306.800281) (xy 179.380388 -306.824888) (xy 179.719236 -306.824888)
			(xy 179.723196 -306.775834) (xy 179.734973 -306.72805) (xy 179.754264 -306.682774) (xy 179.780567 -306.641178)
			(xy 179.813202 -306.604341) (xy 179.851323 -306.573216) (xy 179.893944 -306.548609) (xy 179.93996 -306.531157)
			(xy 179.988179 -306.521313) (xy 180.037354 -306.519332) (xy 180.086209 -306.525264) (xy 180.13348 -306.538956)
			(xy 180.177942 -306.560054) (xy 180.218445 -306.58801) (xy 180.253938 -306.622102) (xy 180.283503 -306.661446)
			(xy 180.306374 -306.705023) (xy 180.321958 -306.751704) (xy 180.329853 -306.800281) (xy 180.330348 -306.824888)
			(xy 180.669196 -306.824888) (xy 180.673156 -306.775834) (xy 180.684933 -306.72805) (xy 180.704224 -306.682774)
			(xy 180.730527 -306.641178) (xy 180.763162 -306.604341) (xy 180.801283 -306.573216) (xy 180.843904 -306.548609)
			(xy 180.88992 -306.531157) (xy 180.938139 -306.521313) (xy 180.987314 -306.519332) (xy 181.036169 -306.525264)
			(xy 181.08344 -306.538956) (xy 181.127902 -306.560054) (xy 181.168405 -306.58801) (xy 181.203898 -306.622102)
			(xy 181.233463 -306.661446) (xy 181.256334 -306.705023) (xy 181.271918 -306.751704) (xy 181.279813 -306.800281)
			(xy 181.280308 -306.824888) (xy 181.619156 -306.824888) (xy 181.623116 -306.775834) (xy 181.634893 -306.72805)
			(xy 181.654184 -306.682774) (xy 181.680487 -306.641178) (xy 181.713122 -306.604341) (xy 181.751243 -306.573216)
			(xy 181.793864 -306.548609) (xy 181.83988 -306.531157) (xy 181.888099 -306.521313) (xy 181.937274 -306.519332)
			(xy 181.986129 -306.525264) (xy 182.0334 -306.538956) (xy 182.077862 -306.560054) (xy 182.118365 -306.58801)
			(xy 182.153858 -306.622102) (xy 182.183423 -306.661446) (xy 182.206294 -306.705023) (xy 182.221878 -306.751704)
			(xy 182.229773 -306.800281) (xy 182.230268 -306.824888) (xy 182.569116 -306.824888) (xy 182.573076 -306.775834)
			(xy 182.584853 -306.72805) (xy 182.604144 -306.682774) (xy 182.630447 -306.641178) (xy 182.663082 -306.604341)
			(xy 182.701203 -306.573216) (xy 182.743824 -306.548609) (xy 182.78984 -306.531157) (xy 182.838059 -306.521313)
			(xy 182.887234 -306.519332) (xy 182.936089 -306.525264) (xy 182.98336 -306.538956) (xy 183.027822 -306.560054)
			(xy 183.068325 -306.58801) (xy 183.103818 -306.622102) (xy 183.133383 -306.661446) (xy 183.156254 -306.705023)
			(xy 183.171838 -306.751704) (xy 183.179733 -306.800281) (xy 183.180228 -306.824888) (xy 183.519076 -306.824888)
			(xy 183.523036 -306.775834) (xy 183.534813 -306.72805) (xy 183.554104 -306.682774) (xy 183.580407 -306.641178)
			(xy 183.613042 -306.604341) (xy 183.651163 -306.573216) (xy 183.693784 -306.548609) (xy 183.7398 -306.531157)
			(xy 183.788019 -306.521313) (xy 183.837194 -306.519332) (xy 183.886049 -306.525264) (xy 183.93332 -306.538956)
			(xy 183.977782 -306.560054) (xy 184.018285 -306.58801) (xy 184.053778 -306.622102) (xy 184.083343 -306.661446)
			(xy 184.106214 -306.705023) (xy 184.121798 -306.751704) (xy 184.129693 -306.800281) (xy 184.130188 -306.824888)
			(xy 184.469036 -306.824888) (xy 184.472996 -306.775834) (xy 184.484773 -306.72805) (xy 184.504064 -306.682774)
			(xy 184.530367 -306.641178) (xy 184.563002 -306.604341) (xy 184.601123 -306.573216) (xy 184.643744 -306.548609)
			(xy 184.68976 -306.531157) (xy 184.737979 -306.521313) (xy 184.787154 -306.519332) (xy 184.836009 -306.525264)
			(xy 184.88328 -306.538956) (xy 184.927742 -306.560054) (xy 184.968245 -306.58801) (xy 185.003738 -306.622102)
			(xy 185.033303 -306.661446) (xy 185.056174 -306.705023) (xy 185.071758 -306.751704) (xy 185.079653 -306.800281)
			(xy 185.080148 -306.824888) (xy 185.41925 -306.824888) (xy 185.42321 -306.775834) (xy 185.434987 -306.72805)
			(xy 185.454278 -306.682774) (xy 185.480581 -306.641178) (xy 185.513216 -306.604341) (xy 185.551337 -306.573216)
			(xy 185.593958 -306.548609) (xy 185.639974 -306.531157) (xy 185.688193 -306.521313) (xy 185.737368 -306.519332)
			(xy 185.786223 -306.525264) (xy 185.833494 -306.538956) (xy 185.877956 -306.560054) (xy 185.918459 -306.58801)
			(xy 185.953952 -306.622102) (xy 185.983517 -306.661446) (xy 186.006388 -306.705023) (xy 186.021972 -306.751704)
			(xy 186.029867 -306.800281) (xy 186.030362 -306.824888) (xy 186.36921 -306.824888) (xy 186.37317 -306.775834)
			(xy 186.384947 -306.72805) (xy 186.404238 -306.682774) (xy 186.430541 -306.641178) (xy 186.463176 -306.604341)
			(xy 186.501297 -306.573216) (xy 186.543918 -306.548609) (xy 186.589934 -306.531157) (xy 186.638153 -306.521313)
			(xy 186.687328 -306.519332) (xy 186.736183 -306.525264) (xy 186.783454 -306.538956) (xy 186.827916 -306.560054)
			(xy 186.868419 -306.58801) (xy 186.903912 -306.622102) (xy 186.933477 -306.661446) (xy 186.956348 -306.705023)
			(xy 186.971932 -306.751704) (xy 186.979827 -306.800281) (xy 186.980322 -306.824888) (xy 187.31917 -306.824888)
			(xy 187.32313 -306.775834) (xy 187.334907 -306.72805) (xy 187.354198 -306.682774) (xy 187.380501 -306.641178)
			(xy 187.413136 -306.604341) (xy 187.451257 -306.573216) (xy 187.493878 -306.548609) (xy 187.539894 -306.531157)
			(xy 187.588113 -306.521313) (xy 187.637288 -306.519332) (xy 187.686143 -306.525264) (xy 187.733414 -306.538956)
			(xy 187.777876 -306.560054) (xy 187.818379 -306.58801) (xy 187.853872 -306.622102) (xy 187.883437 -306.661446)
			(xy 187.906308 -306.705023) (xy 187.921892 -306.751704) (xy 187.929787 -306.800281) (xy 187.930282 -306.824888)
			(xy 188.26913 -306.824888) (xy 188.27309 -306.775834) (xy 188.284867 -306.72805) (xy 188.304158 -306.682774)
			(xy 188.330461 -306.641178) (xy 188.363096 -306.604341) (xy 188.401217 -306.573216) (xy 188.443838 -306.548609)
			(xy 188.489854 -306.531157) (xy 188.538073 -306.521313) (xy 188.587248 -306.519332) (xy 188.636103 -306.525264)
			(xy 188.683374 -306.538956) (xy 188.727836 -306.560054) (xy 188.768339 -306.58801) (xy 188.803832 -306.622102)
			(xy 188.833397 -306.661446) (xy 188.856268 -306.705023) (xy 188.871852 -306.751704) (xy 188.879747 -306.800281)
			(xy 188.880242 -306.824888) (xy 188.879747 -306.849495) (xy 188.871852 -306.898072) (xy 188.856268 -306.944753)
			(xy 188.833397 -306.98833) (xy 188.803832 -307.027674) (xy 188.768339 -307.061766) (xy 188.727836 -307.089722)
			(xy 188.683374 -307.11082) (xy 188.636103 -307.124512) (xy 188.587248 -307.130444) (xy 188.538073 -307.128463)
			(xy 188.489854 -307.118619) (xy 188.443838 -307.101167) (xy 188.401217 -307.07656) (xy 188.363096 -307.045435)
			(xy 188.330461 -307.008598) (xy 188.304158 -306.967002) (xy 188.284867 -306.921726) (xy 188.27309 -306.873942)
			(xy 188.26913 -306.824888) (xy 187.930282 -306.824888) (xy 187.929787 -306.849495) (xy 187.921892 -306.898072)
			(xy 187.906308 -306.944753) (xy 187.883437 -306.98833) (xy 187.853872 -307.027674) (xy 187.818379 -307.061766)
			(xy 187.777876 -307.089722) (xy 187.733414 -307.11082) (xy 187.686143 -307.124512) (xy 187.637288 -307.130444)
			(xy 187.588113 -307.128463) (xy 187.539894 -307.118619) (xy 187.493878 -307.101167) (xy 187.451257 -307.07656)
			(xy 187.413136 -307.045435) (xy 187.380501 -307.008598) (xy 187.354198 -306.967002) (xy 187.334907 -306.921726)
			(xy 187.32313 -306.873942) (xy 187.31917 -306.824888) (xy 186.980322 -306.824888) (xy 186.979827 -306.849495)
			(xy 186.971932 -306.898072) (xy 186.956348 -306.944753) (xy 186.933477 -306.98833) (xy 186.903912 -307.027674)
			(xy 186.868419 -307.061766) (xy 186.827916 -307.089722) (xy 186.783454 -307.11082) (xy 186.736183 -307.124512)
			(xy 186.687328 -307.130444) (xy 186.638153 -307.128463) (xy 186.589934 -307.118619) (xy 186.543918 -307.101167)
			(xy 186.501297 -307.07656) (xy 186.463176 -307.045435) (xy 186.430541 -307.008598) (xy 186.404238 -306.967002)
			(xy 186.384947 -306.921726) (xy 186.37317 -306.873942) (xy 186.36921 -306.824888) (xy 186.030362 -306.824888)
			(xy 186.029867 -306.849495) (xy 186.021972 -306.898072) (xy 186.006388 -306.944753) (xy 185.983517 -306.98833)
			(xy 185.953952 -307.027674) (xy 185.918459 -307.061766) (xy 185.877956 -307.089722) (xy 185.833494 -307.11082)
			(xy 185.786223 -307.124512) (xy 185.737368 -307.130444) (xy 185.688193 -307.128463) (xy 185.639974 -307.118619)
			(xy 185.593958 -307.101167) (xy 185.551337 -307.07656) (xy 185.513216 -307.045435) (xy 185.480581 -307.008598)
			(xy 185.454278 -306.967002) (xy 185.434987 -306.921726) (xy 185.42321 -306.873942) (xy 185.41925 -306.824888)
			(xy 185.080148 -306.824888) (xy 185.079653 -306.849495) (xy 185.071758 -306.898072) (xy 185.056174 -306.944753)
			(xy 185.033303 -306.98833) (xy 185.003738 -307.027674) (xy 184.968245 -307.061766) (xy 184.927742 -307.089722)
			(xy 184.88328 -307.11082) (xy 184.836009 -307.124512) (xy 184.787154 -307.130444) (xy 184.737979 -307.128463)
			(xy 184.68976 -307.118619) (xy 184.643744 -307.101167) (xy 184.601123 -307.07656) (xy 184.563002 -307.045435)
			(xy 184.530367 -307.008598) (xy 184.504064 -306.967002) (xy 184.484773 -306.921726) (xy 184.472996 -306.873942)
			(xy 184.469036 -306.824888) (xy 184.130188 -306.824888) (xy 184.129693 -306.849495) (xy 184.121798 -306.898072)
			(xy 184.106214 -306.944753) (xy 184.083343 -306.98833) (xy 184.053778 -307.027674) (xy 184.018285 -307.061766)
			(xy 183.977782 -307.089722) (xy 183.93332 -307.11082) (xy 183.886049 -307.124512) (xy 183.837194 -307.130444)
			(xy 183.788019 -307.128463) (xy 183.7398 -307.118619) (xy 183.693784 -307.101167) (xy 183.651163 -307.07656)
			(xy 183.613042 -307.045435) (xy 183.580407 -307.008598) (xy 183.554104 -306.967002) (xy 183.534813 -306.921726)
			(xy 183.523036 -306.873942) (xy 183.519076 -306.824888) (xy 183.180228 -306.824888) (xy 183.179733 -306.849495)
			(xy 183.171838 -306.898072) (xy 183.156254 -306.944753) (xy 183.133383 -306.98833) (xy 183.103818 -307.027674)
			(xy 183.068325 -307.061766) (xy 183.027822 -307.089722) (xy 182.98336 -307.11082) (xy 182.936089 -307.124512)
			(xy 182.887234 -307.130444) (xy 182.838059 -307.128463) (xy 182.78984 -307.118619) (xy 182.743824 -307.101167)
			(xy 182.701203 -307.07656) (xy 182.663082 -307.045435) (xy 182.630447 -307.008598) (xy 182.604144 -306.967002)
			(xy 182.584853 -306.921726) (xy 182.573076 -306.873942) (xy 182.569116 -306.824888) (xy 182.230268 -306.824888)
			(xy 182.229773 -306.849495) (xy 182.221878 -306.898072) (xy 182.206294 -306.944753) (xy 182.183423 -306.98833)
			(xy 182.153858 -307.027674) (xy 182.118365 -307.061766) (xy 182.077862 -307.089722) (xy 182.0334 -307.11082)
			(xy 181.986129 -307.124512) (xy 181.937274 -307.130444) (xy 181.888099 -307.128463) (xy 181.83988 -307.118619)
			(xy 181.793864 -307.101167) (xy 181.751243 -307.07656) (xy 181.713122 -307.045435) (xy 181.680487 -307.008598)
			(xy 181.654184 -306.967002) (xy 181.634893 -306.921726) (xy 181.623116 -306.873942) (xy 181.619156 -306.824888)
			(xy 181.280308 -306.824888) (xy 181.279813 -306.849495) (xy 181.271918 -306.898072) (xy 181.256334 -306.944753)
			(xy 181.233463 -306.98833) (xy 181.203898 -307.027674) (xy 181.168405 -307.061766) (xy 181.127902 -307.089722)
			(xy 181.08344 -307.11082) (xy 181.036169 -307.124512) (xy 180.987314 -307.130444) (xy 180.938139 -307.128463)
			(xy 180.88992 -307.118619) (xy 180.843904 -307.101167) (xy 180.801283 -307.07656) (xy 180.763162 -307.045435)
			(xy 180.730527 -307.008598) (xy 180.704224 -306.967002) (xy 180.684933 -306.921726) (xy 180.673156 -306.873942)
			(xy 180.669196 -306.824888) (xy 180.330348 -306.824888) (xy 180.329853 -306.849495) (xy 180.321958 -306.898072)
			(xy 180.306374 -306.944753) (xy 180.283503 -306.98833) (xy 180.253938 -307.027674) (xy 180.218445 -307.061766)
			(xy 180.177942 -307.089722) (xy 180.13348 -307.11082) (xy 180.086209 -307.124512) (xy 180.037354 -307.130444)
			(xy 179.988179 -307.128463) (xy 179.93996 -307.118619) (xy 179.893944 -307.101167) (xy 179.851323 -307.07656)
			(xy 179.813202 -307.045435) (xy 179.780567 -307.008598) (xy 179.754264 -306.967002) (xy 179.734973 -306.921726)
			(xy 179.723196 -306.873942) (xy 179.719236 -306.824888) (xy 179.380388 -306.824888) (xy 179.379893 -306.849495)
			(xy 179.371998 -306.898072) (xy 179.356414 -306.944753) (xy 179.333543 -306.98833) (xy 179.303978 -307.027674)
			(xy 179.268485 -307.061766) (xy 179.227982 -307.089722) (xy 179.18352 -307.11082) (xy 179.136249 -307.124512)
			(xy 179.087394 -307.130444) (xy 179.038219 -307.128463) (xy 178.99 -307.118619) (xy 178.943984 -307.101167)
			(xy 178.901363 -307.07656) (xy 178.863242 -307.045435) (xy 178.830607 -307.008598) (xy 178.804304 -306.967002)
			(xy 178.785013 -306.921726) (xy 178.773236 -306.873942) (xy 178.769276 -306.824888) (xy 178.430174 -306.824888)
			(xy 178.429679 -306.849495) (xy 178.421784 -306.898072) (xy 178.4062 -306.944753) (xy 178.383329 -306.98833)
			(xy 178.353764 -307.027674) (xy 178.318271 -307.061766) (xy 178.277768 -307.089722) (xy 178.233306 -307.11082)
			(xy 178.186035 -307.124512) (xy 178.13718 -307.130444) (xy 178.088005 -307.128463) (xy 178.039786 -307.118619)
			(xy 177.99377 -307.101167) (xy 177.951149 -307.07656) (xy 177.913028 -307.045435) (xy 177.880393 -307.008598)
			(xy 177.85409 -306.967002) (xy 177.834799 -306.921726) (xy 177.823022 -306.873942) (xy 177.819062 -306.824888)
			(xy 177.480214 -306.824888) (xy 177.479719 -306.849495) (xy 177.471824 -306.898072) (xy 177.45624 -306.944753)
			(xy 177.433369 -306.98833) (xy 177.403804 -307.027674) (xy 177.368311 -307.061766) (xy 177.327808 -307.089722)
			(xy 177.283346 -307.11082) (xy 177.236075 -307.124512) (xy 177.18722 -307.130444) (xy 177.138045 -307.128463)
			(xy 177.089826 -307.118619) (xy 177.04381 -307.101167) (xy 177.001189 -307.07656) (xy 176.963068 -307.045435)
			(xy 176.930433 -307.008598) (xy 176.90413 -306.967002) (xy 176.884839 -306.921726) (xy 176.873062 -306.873942)
			(xy 176.869102 -306.824888) (xy 176.530254 -306.824888) (xy 176.529759 -306.849495) (xy 176.521864 -306.898072)
			(xy 176.50628 -306.944753) (xy 176.483409 -306.98833) (xy 176.453844 -307.027674) (xy 176.418351 -307.061766)
			(xy 176.377848 -307.089722) (xy 176.333386 -307.11082) (xy 176.286115 -307.124512) (xy 176.23726 -307.130444)
			(xy 176.188085 -307.128463) (xy 176.139866 -307.118619) (xy 176.09385 -307.101167) (xy 176.051229 -307.07656)
			(xy 176.013108 -307.045435) (xy 175.980473 -307.008598) (xy 175.95417 -306.967002) (xy 175.934879 -306.921726)
			(xy 175.923102 -306.873942) (xy 175.919142 -306.824888) (xy 174.630334 -306.824888) (xy 174.629839 -306.849495)
			(xy 174.621944 -306.898072) (xy 174.60636 -306.944753) (xy 174.583489 -306.98833) (xy 174.553924 -307.027674)
			(xy 174.518431 -307.061766) (xy 174.477928 -307.089722) (xy 174.433466 -307.11082) (xy 174.386195 -307.124512)
			(xy 174.33734 -307.130444) (xy 174.288165 -307.128463) (xy 174.239946 -307.118619) (xy 174.19393 -307.101167)
			(xy 174.151309 -307.07656) (xy 174.113188 -307.045435) (xy 174.080553 -307.008598) (xy 174.05425 -306.967002)
			(xy 174.034959 -306.921726) (xy 174.023182 -306.873942) (xy 174.019222 -306.824888) (xy 173.680374 -306.824888)
			(xy 173.679879 -306.849495) (xy 173.671984 -306.898072) (xy 173.6564 -306.944753) (xy 173.633529 -306.98833)
			(xy 173.603964 -307.027674) (xy 173.568471 -307.061766) (xy 173.527968 -307.089722) (xy 173.483506 -307.11082)
			(xy 173.436235 -307.124512) (xy 173.38738 -307.130444) (xy 173.338205 -307.128463) (xy 173.289986 -307.118619)
			(xy 173.24397 -307.101167) (xy 173.201349 -307.07656) (xy 173.163228 -307.045435) (xy 173.130593 -307.008598)
			(xy 173.10429 -306.967002) (xy 173.084999 -306.921726) (xy 173.073222 -306.873942) (xy 173.069262 -306.824888)
			(xy 172.73016 -306.824888) (xy 172.729665 -306.849495) (xy 172.72177 -306.898072) (xy 172.706186 -306.944753)
			(xy 172.683315 -306.98833) (xy 172.65375 -307.027674) (xy 172.618257 -307.061766) (xy 172.577754 -307.089722)
			(xy 172.533292 -307.11082) (xy 172.486021 -307.124512) (xy 172.437166 -307.130444) (xy 172.387991 -307.128463)
			(xy 172.339772 -307.118619) (xy 172.293756 -307.101167) (xy 172.251135 -307.07656) (xy 172.213014 -307.045435)
			(xy 172.180379 -307.008598) (xy 172.154076 -306.967002) (xy 172.134785 -306.921726) (xy 172.123008 -306.873942)
			(xy 172.119048 -306.824888) (xy 171.7802 -306.824888) (xy 171.779705 -306.849495) (xy 171.77181 -306.898072)
			(xy 171.756226 -306.944753) (xy 171.733355 -306.98833) (xy 171.70379 -307.027674) (xy 171.668297 -307.061766)
			(xy 171.627794 -307.089722) (xy 171.583332 -307.11082) (xy 171.536061 -307.124512) (xy 171.487206 -307.130444)
			(xy 171.438031 -307.128463) (xy 171.389812 -307.118619) (xy 171.343796 -307.101167) (xy 171.301175 -307.07656)
			(xy 171.263054 -307.045435) (xy 171.230419 -307.008598) (xy 171.204116 -306.967002) (xy 171.184825 -306.921726)
			(xy 171.173048 -306.873942) (xy 171.169088 -306.824888) (xy 170.83024 -306.824888) (xy 170.829745 -306.849495)
			(xy 170.82185 -306.898072) (xy 170.806266 -306.944753) (xy 170.783395 -306.98833) (xy 170.75383 -307.027674)
			(xy 170.718337 -307.061766) (xy 170.677834 -307.089722) (xy 170.633372 -307.11082) (xy 170.586101 -307.124512)
			(xy 170.537246 -307.130444) (xy 170.488071 -307.128463) (xy 170.439852 -307.118619) (xy 170.393836 -307.101167)
			(xy 170.351215 -307.07656) (xy 170.313094 -307.045435) (xy 170.280459 -307.008598) (xy 170.254156 -306.967002)
			(xy 170.234865 -306.921726) (xy 170.223088 -306.873942) (xy 170.219128 -306.824888) (xy 169.88028 -306.824888)
			(xy 169.879785 -306.849495) (xy 169.87189 -306.898072) (xy 169.856306 -306.944753) (xy 169.833435 -306.98833)
			(xy 169.80387 -307.027674) (xy 169.768377 -307.061766) (xy 169.727874 -307.089722) (xy 169.683412 -307.11082)
			(xy 169.636141 -307.124512) (xy 169.587286 -307.130444) (xy 169.538111 -307.128463) (xy 169.489892 -307.118619)
			(xy 169.443876 -307.101167) (xy 169.401255 -307.07656) (xy 169.363134 -307.045435) (xy 169.330499 -307.008598)
			(xy 169.304196 -306.967002) (xy 169.284905 -306.921726) (xy 169.273128 -306.873942) (xy 169.269168 -306.824888)
			(xy 168.93032 -306.824888) (xy 168.929825 -306.849495) (xy 168.92193 -306.898072) (xy 168.906346 -306.944753)
			(xy 168.883475 -306.98833) (xy 168.85391 -307.027674) (xy 168.818417 -307.061766) (xy 168.777914 -307.089722)
			(xy 168.733452 -307.11082) (xy 168.686181 -307.124512) (xy 168.637326 -307.130444) (xy 168.588151 -307.128463)
			(xy 168.539932 -307.118619) (xy 168.493916 -307.101167) (xy 168.451295 -307.07656) (xy 168.413174 -307.045435)
			(xy 168.380539 -307.008598) (xy 168.354236 -306.967002) (xy 168.334945 -306.921726) (xy 168.323168 -306.873942)
			(xy 168.319208 -306.824888) (xy 167.98036 -306.824888) (xy 167.979865 -306.849495) (xy 167.97197 -306.898072)
			(xy 167.956386 -306.944753) (xy 167.933515 -306.98833) (xy 167.90395 -307.027674) (xy 167.868457 -307.061766)
			(xy 167.827954 -307.089722) (xy 167.783492 -307.11082) (xy 167.736221 -307.124512) (xy 167.687366 -307.130444)
			(xy 167.638191 -307.128463) (xy 167.589972 -307.118619) (xy 167.543956 -307.101167) (xy 167.501335 -307.07656)
			(xy 167.463214 -307.045435) (xy 167.430579 -307.008598) (xy 167.404276 -306.967002) (xy 167.384985 -306.921726)
			(xy 167.373208 -306.873942) (xy 167.369248 -306.824888) (xy 167.0304 -306.824888) (xy 167.029905 -306.849495)
			(xy 167.02201 -306.898072) (xy 167.006426 -306.944753) (xy 166.983555 -306.98833) (xy 166.95399 -307.027674)
			(xy 166.918497 -307.061766) (xy 166.877994 -307.089722) (xy 166.833532 -307.11082) (xy 166.786261 -307.124512)
			(xy 166.737406 -307.130444) (xy 166.688231 -307.128463) (xy 166.640012 -307.118619) (xy 166.593996 -307.101167)
			(xy 166.551375 -307.07656) (xy 166.513254 -307.045435) (xy 166.480619 -307.008598) (xy 166.454316 -306.967002)
			(xy 166.435025 -306.921726) (xy 166.423248 -306.873942) (xy 166.419288 -306.824888) (xy 166.080186 -306.824888)
			(xy 166.079691 -306.849495) (xy 166.071796 -306.898072) (xy 166.056212 -306.944753) (xy 166.033341 -306.98833)
			(xy 166.003776 -307.027674) (xy 165.968283 -307.061766) (xy 165.92778 -307.089722) (xy 165.883318 -307.11082)
			(xy 165.836047 -307.124512) (xy 165.787192 -307.130444) (xy 165.738017 -307.128463) (xy 165.689798 -307.118619)
			(xy 165.643782 -307.101167) (xy 165.601161 -307.07656) (xy 165.56304 -307.045435) (xy 165.530405 -307.008598)
			(xy 165.504102 -306.967002) (xy 165.484811 -306.921726) (xy 165.473034 -306.873942) (xy 165.469074 -306.824888)
			(xy 165.130226 -306.824888) (xy 165.129731 -306.849495) (xy 165.121836 -306.898072) (xy 165.106252 -306.944753)
			(xy 165.083381 -306.98833) (xy 165.053816 -307.027674) (xy 165.018323 -307.061766) (xy 164.97782 -307.089722)
			(xy 164.933358 -307.11082) (xy 164.886087 -307.124512) (xy 164.837232 -307.130444) (xy 164.788057 -307.128463)
			(xy 164.739838 -307.118619) (xy 164.693822 -307.101167) (xy 164.651201 -307.07656) (xy 164.61308 -307.045435)
			(xy 164.580445 -307.008598) (xy 164.554142 -306.967002) (xy 164.534851 -306.921726) (xy 164.523074 -306.873942)
			(xy 164.519114 -306.824888) (xy 164.180266 -306.824888) (xy 164.179771 -306.849495) (xy 164.171876 -306.898072)
			(xy 164.156292 -306.944753) (xy 164.133421 -306.98833) (xy 164.103856 -307.027674) (xy 164.068363 -307.061766)
			(xy 164.02786 -307.089722) (xy 163.983398 -307.11082) (xy 163.936127 -307.124512) (xy 163.887272 -307.130444)
			(xy 163.838097 -307.128463) (xy 163.789878 -307.118619) (xy 163.743862 -307.101167) (xy 163.701241 -307.07656)
			(xy 163.66312 -307.045435) (xy 163.630485 -307.008598) (xy 163.604182 -306.967002) (xy 163.584891 -306.921726)
			(xy 163.573114 -306.873942) (xy 163.569154 -306.824888) (xy 163.230306 -306.824888) (xy 163.229811 -306.849495)
			(xy 163.221916 -306.898072) (xy 163.206332 -306.944753) (xy 163.183461 -306.98833) (xy 163.153896 -307.027674)
			(xy 163.118403 -307.061766) (xy 163.0779 -307.089722) (xy 163.033438 -307.11082) (xy 162.986167 -307.124512)
			(xy 162.937312 -307.130444) (xy 162.888137 -307.128463) (xy 162.839918 -307.118619) (xy 162.793902 -307.101167)
			(xy 162.751281 -307.07656) (xy 162.71316 -307.045435) (xy 162.680525 -307.008598) (xy 162.654222 -306.967002)
			(xy 162.634931 -306.921726) (xy 162.623154 -306.873942) (xy 162.619194 -306.824888) (xy 157.099 -306.824888)
			(xy 157.099 -307.299868) (xy 157.39416 -307.299868) (xy 157.39812 -307.250814) (xy 157.409897 -307.20303)
			(xy 157.429188 -307.157754) (xy 157.455491 -307.116158) (xy 157.488126 -307.079321) (xy 157.526247 -307.048196)
			(xy 157.568868 -307.023589) (xy 157.614884 -307.006137) (xy 157.663103 -306.996293) (xy 157.712278 -306.994312)
			(xy 157.761133 -307.000244) (xy 157.808404 -307.013936) (xy 157.852866 -307.035034) (xy 157.893369 -307.06299)
			(xy 157.928862 -307.097082) (xy 157.958427 -307.136426) (xy 157.981298 -307.180003) (xy 157.996882 -307.226684)
			(xy 158.004777 -307.275261) (xy 158.005272 -307.299868) (xy 158.34412 -307.299868) (xy 158.34808 -307.250814)
			(xy 158.359857 -307.20303) (xy 158.379148 -307.157754) (xy 158.405451 -307.116158) (xy 158.438086 -307.079321)
			(xy 158.476207 -307.048196) (xy 158.518828 -307.023589) (xy 158.564844 -307.006137) (xy 158.613063 -306.996293)
			(xy 158.662238 -306.994312) (xy 158.711093 -307.000244) (xy 158.758364 -307.013936) (xy 158.802826 -307.035034)
			(xy 158.843329 -307.06299) (xy 158.878822 -307.097082) (xy 158.908387 -307.136426) (xy 158.931258 -307.180003)
			(xy 158.946842 -307.226684) (xy 158.954737 -307.275261) (xy 158.955232 -307.299868) (xy 159.29408 -307.299868)
			(xy 159.29804 -307.250814) (xy 159.309817 -307.20303) (xy 159.329108 -307.157754) (xy 159.355411 -307.116158)
			(xy 159.388046 -307.079321) (xy 159.426167 -307.048196) (xy 159.468788 -307.023589) (xy 159.514804 -307.006137)
			(xy 159.563023 -306.996293) (xy 159.612198 -306.994312) (xy 159.661053 -307.000244) (xy 159.708324 -307.013936)
			(xy 159.752786 -307.035034) (xy 159.793289 -307.06299) (xy 159.828782 -307.097082) (xy 159.858347 -307.136426)
			(xy 159.881218 -307.180003) (xy 159.896802 -307.226684) (xy 159.904697 -307.275261) (xy 159.905192 -307.299868)
			(xy 160.24404 -307.299868) (xy 160.248 -307.250814) (xy 160.259777 -307.20303) (xy 160.279068 -307.157754)
			(xy 160.305371 -307.116158) (xy 160.338006 -307.079321) (xy 160.376127 -307.048196) (xy 160.418748 -307.023589)
			(xy 160.464764 -307.006137) (xy 160.512983 -306.996293) (xy 160.562158 -306.994312) (xy 160.611013 -307.000244)
			(xy 160.658284 -307.013936) (xy 160.702746 -307.035034) (xy 160.743249 -307.06299) (xy 160.778742 -307.097082)
			(xy 160.808307 -307.136426) (xy 160.831178 -307.180003) (xy 160.846762 -307.226684) (xy 160.854657 -307.275261)
			(xy 160.855152 -307.299868) (xy 161.194254 -307.299868) (xy 161.198214 -307.250814) (xy 161.209991 -307.20303)
			(xy 161.229282 -307.157754) (xy 161.255585 -307.116158) (xy 161.28822 -307.079321) (xy 161.326341 -307.048196)
			(xy 161.368962 -307.023589) (xy 161.414978 -307.006137) (xy 161.463197 -306.996293) (xy 161.512372 -306.994312)
			(xy 161.561227 -307.000244) (xy 161.608498 -307.013936) (xy 161.65296 -307.035034) (xy 161.693463 -307.06299)
			(xy 161.728956 -307.097082) (xy 161.758521 -307.136426) (xy 161.781392 -307.180003) (xy 161.796976 -307.226684)
			(xy 161.804871 -307.275261) (xy 161.805366 -307.299868) (xy 189.69407 -307.299868) (xy 189.69803 -307.250814)
			(xy 189.709807 -307.20303) (xy 189.729098 -307.157754) (xy 189.755401 -307.116158) (xy 189.788036 -307.079321)
			(xy 189.826157 -307.048196) (xy 189.868778 -307.023589) (xy 189.914794 -307.006137) (xy 189.963013 -306.996293)
			(xy 190.012188 -306.994312) (xy 190.061043 -307.000244) (xy 190.108314 -307.013936) (xy 190.152776 -307.035034)
			(xy 190.193279 -307.06299) (xy 190.228772 -307.097082) (xy 190.258337 -307.136426) (xy 190.281208 -307.180003)
			(xy 190.296792 -307.226684) (xy 190.304687 -307.275261) (xy 190.305182 -307.299868) (xy 190.644284 -307.299868)
			(xy 190.648244 -307.250814) (xy 190.660021 -307.20303) (xy 190.679312 -307.157754) (xy 190.705615 -307.116158)
			(xy 190.73825 -307.079321) (xy 190.776371 -307.048196) (xy 190.818992 -307.023589) (xy 190.865008 -307.006137)
			(xy 190.913227 -306.996293) (xy 190.962402 -306.994312) (xy 191.011257 -307.000244) (xy 191.058528 -307.013936)
			(xy 191.10299 -307.035034) (xy 191.143493 -307.06299) (xy 191.178986 -307.097082) (xy 191.208551 -307.136426)
			(xy 191.231422 -307.180003) (xy 191.247006 -307.226684) (xy 191.254901 -307.275261) (xy 191.255396 -307.299868)
			(xy 191.594244 -307.299868) (xy 191.598204 -307.250814) (xy 191.609981 -307.20303) (xy 191.629272 -307.157754)
			(xy 191.655575 -307.116158) (xy 191.68821 -307.079321) (xy 191.726331 -307.048196) (xy 191.768952 -307.023589)
			(xy 191.814968 -307.006137) (xy 191.863187 -306.996293) (xy 191.912362 -306.994312) (xy 191.961217 -307.000244)
			(xy 192.008488 -307.013936) (xy 192.05295 -307.035034) (xy 192.093453 -307.06299) (xy 192.128946 -307.097082)
			(xy 192.158511 -307.136426) (xy 192.181382 -307.180003) (xy 192.196966 -307.226684) (xy 192.204861 -307.275261)
			(xy 192.205356 -307.299868) (xy 192.204861 -307.324475) (xy 192.196966 -307.373052) (xy 192.181382 -307.419733)
			(xy 192.158511 -307.46331) (xy 192.128946 -307.502654) (xy 192.093453 -307.536746) (xy 192.05295 -307.564702)
			(xy 192.008488 -307.5858) (xy 191.961217 -307.599492) (xy 191.912362 -307.605424) (xy 191.863187 -307.603443)
			(xy 191.814968 -307.593599) (xy 191.768952 -307.576147) (xy 191.726331 -307.55154) (xy 191.68821 -307.520415)
			(xy 191.655575 -307.483578) (xy 191.629272 -307.441982) (xy 191.609981 -307.396706) (xy 191.598204 -307.348922)
			(xy 191.594244 -307.299868) (xy 191.255396 -307.299868) (xy 191.254901 -307.324475) (xy 191.247006 -307.373052)
			(xy 191.231422 -307.419733) (xy 191.208551 -307.46331) (xy 191.178986 -307.502654) (xy 191.143493 -307.536746)
			(xy 191.10299 -307.564702) (xy 191.058528 -307.5858) (xy 191.011257 -307.599492) (xy 190.962402 -307.605424)
			(xy 190.913227 -307.603443) (xy 190.865008 -307.593599) (xy 190.818992 -307.576147) (xy 190.776371 -307.55154)
			(xy 190.73825 -307.520415) (xy 190.705615 -307.483578) (xy 190.679312 -307.441982) (xy 190.660021 -307.396706)
			(xy 190.648244 -307.348922) (xy 190.644284 -307.299868) (xy 190.305182 -307.299868) (xy 190.304687 -307.324475)
			(xy 190.296792 -307.373052) (xy 190.281208 -307.419733) (xy 190.258337 -307.46331) (xy 190.228772 -307.502654)
			(xy 190.193279 -307.536746) (xy 190.152776 -307.564702) (xy 190.108314 -307.5858) (xy 190.061043 -307.599492)
			(xy 190.012188 -307.605424) (xy 189.963013 -307.603443) (xy 189.914794 -307.593599) (xy 189.868778 -307.576147)
			(xy 189.826157 -307.55154) (xy 189.788036 -307.520415) (xy 189.755401 -307.483578) (xy 189.729098 -307.441982)
			(xy 189.709807 -307.396706) (xy 189.69803 -307.348922) (xy 189.69407 -307.299868) (xy 161.805366 -307.299868)
			(xy 161.804871 -307.324475) (xy 161.796976 -307.373052) (xy 161.781392 -307.419733) (xy 161.758521 -307.46331)
			(xy 161.728956 -307.502654) (xy 161.693463 -307.536746) (xy 161.65296 -307.564702) (xy 161.608498 -307.5858)
			(xy 161.561227 -307.599492) (xy 161.512372 -307.605424) (xy 161.463197 -307.603443) (xy 161.414978 -307.593599)
			(xy 161.368962 -307.576147) (xy 161.326341 -307.55154) (xy 161.28822 -307.520415) (xy 161.255585 -307.483578)
			(xy 161.229282 -307.441982) (xy 161.209991 -307.396706) (xy 161.198214 -307.348922) (xy 161.194254 -307.299868)
			(xy 160.855152 -307.299868) (xy 160.854657 -307.324475) (xy 160.846762 -307.373052) (xy 160.831178 -307.419733)
			(xy 160.808307 -307.46331) (xy 160.778742 -307.502654) (xy 160.743249 -307.536746) (xy 160.702746 -307.564702)
			(xy 160.658284 -307.5858) (xy 160.611013 -307.599492) (xy 160.562158 -307.605424) (xy 160.512983 -307.603443)
			(xy 160.464764 -307.593599) (xy 160.418748 -307.576147) (xy 160.376127 -307.55154) (xy 160.338006 -307.520415)
			(xy 160.305371 -307.483578) (xy 160.279068 -307.441982) (xy 160.259777 -307.396706) (xy 160.248 -307.348922)
			(xy 160.24404 -307.299868) (xy 159.905192 -307.299868) (xy 159.904697 -307.324475) (xy 159.896802 -307.373052)
			(xy 159.881218 -307.419733) (xy 159.858347 -307.46331) (xy 159.828782 -307.502654) (xy 159.793289 -307.536746)
			(xy 159.752786 -307.564702) (xy 159.708324 -307.5858) (xy 159.661053 -307.599492) (xy 159.612198 -307.605424)
			(xy 159.563023 -307.603443) (xy 159.514804 -307.593599) (xy 159.468788 -307.576147) (xy 159.426167 -307.55154)
			(xy 159.388046 -307.520415) (xy 159.355411 -307.483578) (xy 159.329108 -307.441982) (xy 159.309817 -307.396706)
			(xy 159.29804 -307.348922) (xy 159.29408 -307.299868) (xy 158.955232 -307.299868) (xy 158.954737 -307.324475)
			(xy 158.946842 -307.373052) (xy 158.931258 -307.419733) (xy 158.908387 -307.46331) (xy 158.878822 -307.502654)
			(xy 158.843329 -307.536746) (xy 158.802826 -307.564702) (xy 158.758364 -307.5858) (xy 158.711093 -307.599492)
			(xy 158.662238 -307.605424) (xy 158.613063 -307.603443) (xy 158.564844 -307.593599) (xy 158.518828 -307.576147)
			(xy 158.476207 -307.55154) (xy 158.438086 -307.520415) (xy 158.405451 -307.483578) (xy 158.379148 -307.441982)
			(xy 158.359857 -307.396706) (xy 158.34808 -307.348922) (xy 158.34412 -307.299868) (xy 158.005272 -307.299868)
			(xy 158.004777 -307.324475) (xy 157.996882 -307.373052) (xy 157.981298 -307.419733) (xy 157.958427 -307.46331)
			(xy 157.928862 -307.502654) (xy 157.893369 -307.536746) (xy 157.852866 -307.564702) (xy 157.808404 -307.5858)
			(xy 157.761133 -307.599492) (xy 157.712278 -307.605424) (xy 157.663103 -307.603443) (xy 157.614884 -307.593599)
			(xy 157.568868 -307.576147) (xy 157.526247 -307.55154) (xy 157.488126 -307.520415) (xy 157.455491 -307.483578)
			(xy 157.429188 -307.441982) (xy 157.409897 -307.396706) (xy 157.39812 -307.348922) (xy 157.39416 -307.299868)
			(xy 157.099 -307.299868) (xy 157.099 -307.774848) (xy 162.619194 -307.774848) (xy 162.623154 -307.725794)
			(xy 162.634931 -307.67801) (xy 162.654222 -307.632734) (xy 162.680525 -307.591138) (xy 162.71316 -307.554301)
			(xy 162.751281 -307.523176) (xy 162.793902 -307.498569) (xy 162.839918 -307.481117) (xy 162.888137 -307.471273)
			(xy 162.937312 -307.469292) (xy 162.986167 -307.475224) (xy 163.033438 -307.488916) (xy 163.0779 -307.510014)
			(xy 163.118403 -307.53797) (xy 163.153896 -307.572062) (xy 163.183461 -307.611406) (xy 163.206332 -307.654983)
			(xy 163.221916 -307.701664) (xy 163.229811 -307.750241) (xy 163.230306 -307.774848) (xy 163.569154 -307.774848)
			(xy 163.573114 -307.725794) (xy 163.584891 -307.67801) (xy 163.604182 -307.632734) (xy 163.630485 -307.591138)
			(xy 163.66312 -307.554301) (xy 163.701241 -307.523176) (xy 163.743862 -307.498569) (xy 163.789878 -307.481117)
			(xy 163.838097 -307.471273) (xy 163.887272 -307.469292) (xy 163.936127 -307.475224) (xy 163.983398 -307.488916)
			(xy 164.02786 -307.510014) (xy 164.068363 -307.53797) (xy 164.103856 -307.572062) (xy 164.133421 -307.611406)
			(xy 164.156292 -307.654983) (xy 164.171876 -307.701664) (xy 164.179771 -307.750241) (xy 164.180266 -307.774848)
			(xy 164.519114 -307.774848) (xy 164.523074 -307.725794) (xy 164.534851 -307.67801) (xy 164.554142 -307.632734)
			(xy 164.580445 -307.591138) (xy 164.61308 -307.554301) (xy 164.651201 -307.523176) (xy 164.693822 -307.498569)
			(xy 164.739838 -307.481117) (xy 164.788057 -307.471273) (xy 164.837232 -307.469292) (xy 164.886087 -307.475224)
			(xy 164.933358 -307.488916) (xy 164.97782 -307.510014) (xy 165.018323 -307.53797) (xy 165.053816 -307.572062)
			(xy 165.083381 -307.611406) (xy 165.106252 -307.654983) (xy 165.121836 -307.701664) (xy 165.129731 -307.750241)
			(xy 165.130226 -307.774848) (xy 165.469074 -307.774848) (xy 165.473034 -307.725794) (xy 165.484811 -307.67801)
			(xy 165.504102 -307.632734) (xy 165.530405 -307.591138) (xy 165.56304 -307.554301) (xy 165.601161 -307.523176)
			(xy 165.643782 -307.498569) (xy 165.689798 -307.481117) (xy 165.738017 -307.471273) (xy 165.787192 -307.469292)
			(xy 165.836047 -307.475224) (xy 165.883318 -307.488916) (xy 165.92778 -307.510014) (xy 165.968283 -307.53797)
			(xy 166.003776 -307.572062) (xy 166.033341 -307.611406) (xy 166.056212 -307.654983) (xy 166.071796 -307.701664)
			(xy 166.079691 -307.750241) (xy 166.080186 -307.774848) (xy 166.419288 -307.774848) (xy 166.423248 -307.725794)
			(xy 166.435025 -307.67801) (xy 166.454316 -307.632734) (xy 166.480619 -307.591138) (xy 166.513254 -307.554301)
			(xy 166.551375 -307.523176) (xy 166.593996 -307.498569) (xy 166.640012 -307.481117) (xy 166.688231 -307.471273)
			(xy 166.737406 -307.469292) (xy 166.786261 -307.475224) (xy 166.833532 -307.488916) (xy 166.877994 -307.510014)
			(xy 166.918497 -307.53797) (xy 166.95399 -307.572062) (xy 166.983555 -307.611406) (xy 167.006426 -307.654983)
			(xy 167.02201 -307.701664) (xy 167.029905 -307.750241) (xy 167.0304 -307.774848) (xy 167.369248 -307.774848)
			(xy 167.373208 -307.725794) (xy 167.384985 -307.67801) (xy 167.404276 -307.632734) (xy 167.430579 -307.591138)
			(xy 167.463214 -307.554301) (xy 167.501335 -307.523176) (xy 167.543956 -307.498569) (xy 167.589972 -307.481117)
			(xy 167.638191 -307.471273) (xy 167.687366 -307.469292) (xy 167.736221 -307.475224) (xy 167.783492 -307.488916)
			(xy 167.827954 -307.510014) (xy 167.868457 -307.53797) (xy 167.90395 -307.572062) (xy 167.933515 -307.611406)
			(xy 167.956386 -307.654983) (xy 167.97197 -307.701664) (xy 167.979865 -307.750241) (xy 167.98036 -307.774848)
			(xy 168.319208 -307.774848) (xy 168.323168 -307.725794) (xy 168.334945 -307.67801) (xy 168.354236 -307.632734)
			(xy 168.380539 -307.591138) (xy 168.413174 -307.554301) (xy 168.451295 -307.523176) (xy 168.493916 -307.498569)
			(xy 168.539932 -307.481117) (xy 168.588151 -307.471273) (xy 168.637326 -307.469292) (xy 168.686181 -307.475224)
			(xy 168.733452 -307.488916) (xy 168.777914 -307.510014) (xy 168.818417 -307.53797) (xy 168.85391 -307.572062)
			(xy 168.883475 -307.611406) (xy 168.906346 -307.654983) (xy 168.92193 -307.701664) (xy 168.929825 -307.750241)
			(xy 168.93032 -307.774848) (xy 169.269168 -307.774848) (xy 169.273128 -307.725794) (xy 169.284905 -307.67801)
			(xy 169.304196 -307.632734) (xy 169.330499 -307.591138) (xy 169.363134 -307.554301) (xy 169.401255 -307.523176)
			(xy 169.443876 -307.498569) (xy 169.489892 -307.481117) (xy 169.538111 -307.471273) (xy 169.587286 -307.469292)
			(xy 169.636141 -307.475224) (xy 169.683412 -307.488916) (xy 169.727874 -307.510014) (xy 169.768377 -307.53797)
			(xy 169.80387 -307.572062) (xy 169.833435 -307.611406) (xy 169.856306 -307.654983) (xy 169.87189 -307.701664)
			(xy 169.879785 -307.750241) (xy 169.88028 -307.774848) (xy 170.219128 -307.774848) (xy 170.223088 -307.725794)
			(xy 170.234865 -307.67801) (xy 170.254156 -307.632734) (xy 170.280459 -307.591138) (xy 170.313094 -307.554301)
			(xy 170.351215 -307.523176) (xy 170.393836 -307.498569) (xy 170.439852 -307.481117) (xy 170.488071 -307.471273)
			(xy 170.537246 -307.469292) (xy 170.586101 -307.475224) (xy 170.633372 -307.488916) (xy 170.677834 -307.510014)
			(xy 170.718337 -307.53797) (xy 170.75383 -307.572062) (xy 170.783395 -307.611406) (xy 170.806266 -307.654983)
			(xy 170.82185 -307.701664) (xy 170.829745 -307.750241) (xy 170.83024 -307.774848) (xy 171.169088 -307.774848)
			(xy 171.173048 -307.725794) (xy 171.184825 -307.67801) (xy 171.204116 -307.632734) (xy 171.230419 -307.591138)
			(xy 171.263054 -307.554301) (xy 171.301175 -307.523176) (xy 171.343796 -307.498569) (xy 171.389812 -307.481117)
			(xy 171.438031 -307.471273) (xy 171.487206 -307.469292) (xy 171.536061 -307.475224) (xy 171.583332 -307.488916)
			(xy 171.627794 -307.510014) (xy 171.668297 -307.53797) (xy 171.70379 -307.572062) (xy 171.733355 -307.611406)
			(xy 171.756226 -307.654983) (xy 171.77181 -307.701664) (xy 171.779705 -307.750241) (xy 171.7802 -307.774848)
			(xy 172.119302 -307.774848) (xy 172.123262 -307.725794) (xy 172.135039 -307.67801) (xy 172.15433 -307.632734)
			(xy 172.180633 -307.591138) (xy 172.213268 -307.554301) (xy 172.251389 -307.523176) (xy 172.29401 -307.498569)
			(xy 172.340026 -307.481117) (xy 172.388245 -307.471273) (xy 172.43742 -307.469292) (xy 172.486275 -307.475224)
			(xy 172.533546 -307.488916) (xy 172.578008 -307.510014) (xy 172.618511 -307.53797) (xy 172.654004 -307.572062)
			(xy 172.683569 -307.611406) (xy 172.70644 -307.654983) (xy 172.722024 -307.701664) (xy 172.729919 -307.750241)
			(xy 172.730414 -307.774848) (xy 173.069262 -307.774848) (xy 173.073222 -307.725794) (xy 173.084999 -307.67801)
			(xy 173.10429 -307.632734) (xy 173.130593 -307.591138) (xy 173.163228 -307.554301) (xy 173.201349 -307.523176)
			(xy 173.24397 -307.498569) (xy 173.289986 -307.481117) (xy 173.338205 -307.471273) (xy 173.38738 -307.469292)
			(xy 173.436235 -307.475224) (xy 173.483506 -307.488916) (xy 173.527968 -307.510014) (xy 173.568471 -307.53797)
			(xy 173.603964 -307.572062) (xy 173.633529 -307.611406) (xy 173.6564 -307.654983) (xy 173.671984 -307.701664)
			(xy 173.679879 -307.750241) (xy 173.680374 -307.774848) (xy 174.019222 -307.774848) (xy 174.023182 -307.725794)
			(xy 174.034959 -307.67801) (xy 174.05425 -307.632734) (xy 174.080553 -307.591138) (xy 174.113188 -307.554301)
			(xy 174.151309 -307.523176) (xy 174.19393 -307.498569) (xy 174.239946 -307.481117) (xy 174.288165 -307.471273)
			(xy 174.33734 -307.469292) (xy 174.386195 -307.475224) (xy 174.433466 -307.488916) (xy 174.477928 -307.510014)
			(xy 174.518431 -307.53797) (xy 174.553924 -307.572062) (xy 174.583489 -307.611406) (xy 174.60636 -307.654983)
			(xy 174.621944 -307.701664) (xy 174.629839 -307.750241) (xy 174.630334 -307.774848) (xy 175.919142 -307.774848)
			(xy 175.923102 -307.725794) (xy 175.934879 -307.67801) (xy 175.95417 -307.632734) (xy 175.980473 -307.591138)
			(xy 176.013108 -307.554301) (xy 176.051229 -307.523176) (xy 176.09385 -307.498569) (xy 176.139866 -307.481117)
			(xy 176.188085 -307.471273) (xy 176.23726 -307.469292) (xy 176.286115 -307.475224) (xy 176.333386 -307.488916)
			(xy 176.377848 -307.510014) (xy 176.418351 -307.53797) (xy 176.453844 -307.572062) (xy 176.483409 -307.611406)
			(xy 176.50628 -307.654983) (xy 176.521864 -307.701664) (xy 176.529759 -307.750241) (xy 176.530254 -307.774848)
			(xy 176.869102 -307.774848) (xy 176.873062 -307.725794) (xy 176.884839 -307.67801) (xy 176.90413 -307.632734)
			(xy 176.930433 -307.591138) (xy 176.963068 -307.554301) (xy 177.001189 -307.523176) (xy 177.04381 -307.498569)
			(xy 177.089826 -307.481117) (xy 177.138045 -307.471273) (xy 177.18722 -307.469292) (xy 177.236075 -307.475224)
			(xy 177.283346 -307.488916) (xy 177.327808 -307.510014) (xy 177.368311 -307.53797) (xy 177.403804 -307.572062)
			(xy 177.433369 -307.611406) (xy 177.45624 -307.654983) (xy 177.471824 -307.701664) (xy 177.479719 -307.750241)
			(xy 177.480214 -307.774848) (xy 177.819062 -307.774848) (xy 177.823022 -307.725794) (xy 177.834799 -307.67801)
			(xy 177.85409 -307.632734) (xy 177.880393 -307.591138) (xy 177.913028 -307.554301) (xy 177.951149 -307.523176)
			(xy 177.99377 -307.498569) (xy 178.039786 -307.481117) (xy 178.088005 -307.471273) (xy 178.13718 -307.469292)
			(xy 178.186035 -307.475224) (xy 178.233306 -307.488916) (xy 178.277768 -307.510014) (xy 178.318271 -307.53797)
			(xy 178.353764 -307.572062) (xy 178.383329 -307.611406) (xy 178.4062 -307.654983) (xy 178.421784 -307.701664)
			(xy 178.429679 -307.750241) (xy 178.430169 -307.774594) (xy 178.769022 -307.774594) (xy 178.772982 -307.72554)
			(xy 178.784759 -307.677756) (xy 178.80405 -307.63248) (xy 178.830353 -307.590884) (xy 178.862988 -307.554047)
			(xy 178.901109 -307.522922) (xy 178.94373 -307.498315) (xy 178.989746 -307.480863) (xy 179.037965 -307.471019)
			(xy 179.08714 -307.469038) (xy 179.135995 -307.47497) (xy 179.183266 -307.488662) (xy 179.227728 -307.50976)
			(xy 179.268231 -307.537716) (xy 179.303724 -307.571808) (xy 179.333289 -307.611152) (xy 179.35616 -307.654729)
			(xy 179.371744 -307.70141) (xy 179.379639 -307.749987) (xy 179.380134 -307.774594) (xy 179.719236 -307.774594)
			(xy 179.723196 -307.72554) (xy 179.734973 -307.677756) (xy 179.754264 -307.63248) (xy 179.780567 -307.590884)
			(xy 179.813202 -307.554047) (xy 179.851323 -307.522922) (xy 179.893944 -307.498315) (xy 179.93996 -307.480863)
			(xy 179.988179 -307.471019) (xy 180.037354 -307.469038) (xy 180.086209 -307.47497) (xy 180.13348 -307.488662)
			(xy 180.177942 -307.50976) (xy 180.218445 -307.537716) (xy 180.253938 -307.571808) (xy 180.283503 -307.611152)
			(xy 180.306374 -307.654729) (xy 180.321958 -307.70141) (xy 180.329853 -307.749987) (xy 180.330348 -307.774594)
			(xy 180.330343 -307.774848) (xy 180.669196 -307.774848) (xy 180.673156 -307.725794) (xy 180.684933 -307.67801)
			(xy 180.704224 -307.632734) (xy 180.730527 -307.591138) (xy 180.763162 -307.554301) (xy 180.801283 -307.523176)
			(xy 180.843904 -307.498569) (xy 180.88992 -307.481117) (xy 180.938139 -307.471273) (xy 180.987314 -307.469292)
			(xy 181.036169 -307.475224) (xy 181.08344 -307.488916) (xy 181.127902 -307.510014) (xy 181.168405 -307.53797)
			(xy 181.203898 -307.572062) (xy 181.233463 -307.611406) (xy 181.256334 -307.654983) (xy 181.271918 -307.701664)
			(xy 181.279813 -307.750241) (xy 181.280308 -307.774848) (xy 181.619156 -307.774848) (xy 181.623116 -307.725794)
			(xy 181.634893 -307.67801) (xy 181.654184 -307.632734) (xy 181.680487 -307.591138) (xy 181.713122 -307.554301)
			(xy 181.751243 -307.523176) (xy 181.793864 -307.498569) (xy 181.83988 -307.481117) (xy 181.888099 -307.471273)
			(xy 181.937274 -307.469292) (xy 181.986129 -307.475224) (xy 182.0334 -307.488916) (xy 182.077862 -307.510014)
			(xy 182.118365 -307.53797) (xy 182.153858 -307.572062) (xy 182.183423 -307.611406) (xy 182.206294 -307.654983)
			(xy 182.221878 -307.701664) (xy 182.229773 -307.750241) (xy 182.230268 -307.774848) (xy 182.569116 -307.774848)
			(xy 182.573076 -307.725794) (xy 182.584853 -307.67801) (xy 182.604144 -307.632734) (xy 182.630447 -307.591138)
			(xy 182.663082 -307.554301) (xy 182.701203 -307.523176) (xy 182.743824 -307.498569) (xy 182.78984 -307.481117)
			(xy 182.838059 -307.471273) (xy 182.887234 -307.469292) (xy 182.936089 -307.475224) (xy 182.98336 -307.488916)
			(xy 183.027822 -307.510014) (xy 183.068325 -307.53797) (xy 183.103818 -307.572062) (xy 183.133383 -307.611406)
			(xy 183.156254 -307.654983) (xy 183.171838 -307.701664) (xy 183.179733 -307.750241) (xy 183.180228 -307.774848)
			(xy 183.519076 -307.774848) (xy 183.523036 -307.725794) (xy 183.534813 -307.67801) (xy 183.554104 -307.632734)
			(xy 183.580407 -307.591138) (xy 183.613042 -307.554301) (xy 183.651163 -307.523176) (xy 183.693784 -307.498569)
			(xy 183.7398 -307.481117) (xy 183.788019 -307.471273) (xy 183.837194 -307.469292) (xy 183.886049 -307.475224)
			(xy 183.93332 -307.488916) (xy 183.977782 -307.510014) (xy 184.018285 -307.53797) (xy 184.053778 -307.572062)
			(xy 184.083343 -307.611406) (xy 184.106214 -307.654983) (xy 184.121798 -307.701664) (xy 184.129693 -307.750241)
			(xy 184.130188 -307.774848) (xy 184.469036 -307.774848) (xy 184.472996 -307.725794) (xy 184.484773 -307.67801)
			(xy 184.504064 -307.632734) (xy 184.530367 -307.591138) (xy 184.563002 -307.554301) (xy 184.601123 -307.523176)
			(xy 184.643744 -307.498569) (xy 184.68976 -307.481117) (xy 184.737979 -307.471273) (xy 184.787154 -307.469292)
			(xy 184.836009 -307.475224) (xy 184.88328 -307.488916) (xy 184.927742 -307.510014) (xy 184.968245 -307.53797)
			(xy 185.003738 -307.572062) (xy 185.033303 -307.611406) (xy 185.056174 -307.654983) (xy 185.071758 -307.701664)
			(xy 185.079653 -307.750241) (xy 185.080148 -307.774848) (xy 185.41925 -307.774848) (xy 185.42321 -307.725794)
			(xy 185.434987 -307.67801) (xy 185.454278 -307.632734) (xy 185.480581 -307.591138) (xy 185.513216 -307.554301)
			(xy 185.551337 -307.523176) (xy 185.593958 -307.498569) (xy 185.639974 -307.481117) (xy 185.688193 -307.471273)
			(xy 185.737368 -307.469292) (xy 185.786223 -307.475224) (xy 185.833494 -307.488916) (xy 185.877956 -307.510014)
			(xy 185.918459 -307.53797) (xy 185.953952 -307.572062) (xy 185.983517 -307.611406) (xy 186.006388 -307.654983)
			(xy 186.021972 -307.701664) (xy 186.029867 -307.750241) (xy 186.030362 -307.774848) (xy 186.36921 -307.774848)
			(xy 186.37317 -307.725794) (xy 186.384947 -307.67801) (xy 186.404238 -307.632734) (xy 186.430541 -307.591138)
			(xy 186.463176 -307.554301) (xy 186.501297 -307.523176) (xy 186.543918 -307.498569) (xy 186.589934 -307.481117)
			(xy 186.638153 -307.471273) (xy 186.687328 -307.469292) (xy 186.736183 -307.475224) (xy 186.783454 -307.488916)
			(xy 186.827916 -307.510014) (xy 186.868419 -307.53797) (xy 186.903912 -307.572062) (xy 186.933477 -307.611406)
			(xy 186.956348 -307.654983) (xy 186.971932 -307.701664) (xy 186.979827 -307.750241) (xy 186.980322 -307.774848)
			(xy 187.31917 -307.774848) (xy 187.32313 -307.725794) (xy 187.334907 -307.67801) (xy 187.354198 -307.632734)
			(xy 187.380501 -307.591138) (xy 187.413136 -307.554301) (xy 187.451257 -307.523176) (xy 187.493878 -307.498569)
			(xy 187.539894 -307.481117) (xy 187.588113 -307.471273) (xy 187.637288 -307.469292) (xy 187.686143 -307.475224)
			(xy 187.733414 -307.488916) (xy 187.777876 -307.510014) (xy 187.818379 -307.53797) (xy 187.853872 -307.572062)
			(xy 187.883437 -307.611406) (xy 187.906308 -307.654983) (xy 187.921892 -307.701664) (xy 187.929787 -307.750241)
			(xy 187.930282 -307.774848) (xy 188.26913 -307.774848) (xy 188.27309 -307.725794) (xy 188.284867 -307.67801)
			(xy 188.304158 -307.632734) (xy 188.330461 -307.591138) (xy 188.363096 -307.554301) (xy 188.401217 -307.523176)
			(xy 188.443838 -307.498569) (xy 188.489854 -307.481117) (xy 188.538073 -307.471273) (xy 188.587248 -307.469292)
			(xy 188.636103 -307.475224) (xy 188.683374 -307.488916) (xy 188.727836 -307.510014) (xy 188.768339 -307.53797)
			(xy 188.803832 -307.572062) (xy 188.833397 -307.611406) (xy 188.856268 -307.654983) (xy 188.871852 -307.701664)
			(xy 188.879747 -307.750241) (xy 188.880242 -307.774848) (xy 188.879747 -307.799455) (xy 188.871852 -307.848032)
			(xy 188.856268 -307.894713) (xy 188.833397 -307.93829) (xy 188.803832 -307.977634) (xy 188.768339 -308.011726)
			(xy 188.727836 -308.039682) (xy 188.683374 -308.06078) (xy 188.636103 -308.074472) (xy 188.587248 -308.080404)
			(xy 188.538073 -308.078423) (xy 188.489854 -308.068579) (xy 188.443838 -308.051127) (xy 188.401217 -308.02652)
			(xy 188.363096 -307.995395) (xy 188.330461 -307.958558) (xy 188.304158 -307.916962) (xy 188.284867 -307.871686)
			(xy 188.27309 -307.823902) (xy 188.26913 -307.774848) (xy 187.930282 -307.774848) (xy 187.929787 -307.799455)
			(xy 187.921892 -307.848032) (xy 187.906308 -307.894713) (xy 187.883437 -307.93829) (xy 187.853872 -307.977634)
			(xy 187.818379 -308.011726) (xy 187.777876 -308.039682) (xy 187.733414 -308.06078) (xy 187.686143 -308.074472)
			(xy 187.637288 -308.080404) (xy 187.588113 -308.078423) (xy 187.539894 -308.068579) (xy 187.493878 -308.051127)
			(xy 187.451257 -308.02652) (xy 187.413136 -307.995395) (xy 187.380501 -307.958558) (xy 187.354198 -307.916962)
			(xy 187.334907 -307.871686) (xy 187.32313 -307.823902) (xy 187.31917 -307.774848) (xy 186.980322 -307.774848)
			(xy 186.979827 -307.799455) (xy 186.971932 -307.848032) (xy 186.956348 -307.894713) (xy 186.933477 -307.93829)
			(xy 186.903912 -307.977634) (xy 186.868419 -308.011726) (xy 186.827916 -308.039682) (xy 186.783454 -308.06078)
			(xy 186.736183 -308.074472) (xy 186.687328 -308.080404) (xy 186.638153 -308.078423) (xy 186.589934 -308.068579)
			(xy 186.543918 -308.051127) (xy 186.501297 -308.02652) (xy 186.463176 -307.995395) (xy 186.430541 -307.958558)
			(xy 186.404238 -307.916962) (xy 186.384947 -307.871686) (xy 186.37317 -307.823902) (xy 186.36921 -307.774848)
			(xy 186.030362 -307.774848) (xy 186.029867 -307.799455) (xy 186.021972 -307.848032) (xy 186.006388 -307.894713)
			(xy 185.983517 -307.93829) (xy 185.953952 -307.977634) (xy 185.918459 -308.011726) (xy 185.877956 -308.039682)
			(xy 185.833494 -308.06078) (xy 185.786223 -308.074472) (xy 185.737368 -308.080404) (xy 185.688193 -308.078423)
			(xy 185.639974 -308.068579) (xy 185.593958 -308.051127) (xy 185.551337 -308.02652) (xy 185.513216 -307.995395)
			(xy 185.480581 -307.958558) (xy 185.454278 -307.916962) (xy 185.434987 -307.871686) (xy 185.42321 -307.823902)
			(xy 185.41925 -307.774848) (xy 185.080148 -307.774848) (xy 185.079653 -307.799455) (xy 185.071758 -307.848032)
			(xy 185.056174 -307.894713) (xy 185.033303 -307.93829) (xy 185.003738 -307.977634) (xy 184.968245 -308.011726)
			(xy 184.927742 -308.039682) (xy 184.88328 -308.06078) (xy 184.836009 -308.074472) (xy 184.787154 -308.080404)
			(xy 184.737979 -308.078423) (xy 184.68976 -308.068579) (xy 184.643744 -308.051127) (xy 184.601123 -308.02652)
			(xy 184.563002 -307.995395) (xy 184.530367 -307.958558) (xy 184.504064 -307.916962) (xy 184.484773 -307.871686)
			(xy 184.472996 -307.823902) (xy 184.469036 -307.774848) (xy 184.130188 -307.774848) (xy 184.129693 -307.799455)
			(xy 184.121798 -307.848032) (xy 184.106214 -307.894713) (xy 184.083343 -307.93829) (xy 184.053778 -307.977634)
			(xy 184.018285 -308.011726) (xy 183.977782 -308.039682) (xy 183.93332 -308.06078) (xy 183.886049 -308.074472)
			(xy 183.837194 -308.080404) (xy 183.788019 -308.078423) (xy 183.7398 -308.068579) (xy 183.693784 -308.051127)
			(xy 183.651163 -308.02652) (xy 183.613042 -307.995395) (xy 183.580407 -307.958558) (xy 183.554104 -307.916962)
			(xy 183.534813 -307.871686) (xy 183.523036 -307.823902) (xy 183.519076 -307.774848) (xy 183.180228 -307.774848)
			(xy 183.179733 -307.799455) (xy 183.171838 -307.848032) (xy 183.156254 -307.894713) (xy 183.133383 -307.93829)
			(xy 183.103818 -307.977634) (xy 183.068325 -308.011726) (xy 183.027822 -308.039682) (xy 182.98336 -308.06078)
			(xy 182.936089 -308.074472) (xy 182.887234 -308.080404) (xy 182.838059 -308.078423) (xy 182.78984 -308.068579)
			(xy 182.743824 -308.051127) (xy 182.701203 -308.02652) (xy 182.663082 -307.995395) (xy 182.630447 -307.958558)
			(xy 182.604144 -307.916962) (xy 182.584853 -307.871686) (xy 182.573076 -307.823902) (xy 182.569116 -307.774848)
			(xy 182.230268 -307.774848) (xy 182.229773 -307.799455) (xy 182.221878 -307.848032) (xy 182.206294 -307.894713)
			(xy 182.183423 -307.93829) (xy 182.153858 -307.977634) (xy 182.118365 -308.011726) (xy 182.077862 -308.039682)
			(xy 182.0334 -308.06078) (xy 181.986129 -308.074472) (xy 181.937274 -308.080404) (xy 181.888099 -308.078423)
			(xy 181.83988 -308.068579) (xy 181.793864 -308.051127) (xy 181.751243 -308.02652) (xy 181.713122 -307.995395)
			(xy 181.680487 -307.958558) (xy 181.654184 -307.916962) (xy 181.634893 -307.871686) (xy 181.623116 -307.823902)
			(xy 181.619156 -307.774848) (xy 181.280308 -307.774848) (xy 181.279813 -307.799455) (xy 181.271918 -307.848032)
			(xy 181.256334 -307.894713) (xy 181.233463 -307.93829) (xy 181.203898 -307.977634) (xy 181.168405 -308.011726)
			(xy 181.127902 -308.039682) (xy 181.08344 -308.06078) (xy 181.036169 -308.074472) (xy 180.987314 -308.080404)
			(xy 180.938139 -308.078423) (xy 180.88992 -308.068579) (xy 180.843904 -308.051127) (xy 180.801283 -308.02652)
			(xy 180.763162 -307.995395) (xy 180.730527 -307.958558) (xy 180.704224 -307.916962) (xy 180.684933 -307.871686)
			(xy 180.673156 -307.823902) (xy 180.669196 -307.774848) (xy 180.330343 -307.774848) (xy 180.329853 -307.799201)
			(xy 180.321958 -307.847778) (xy 180.306374 -307.894459) (xy 180.283503 -307.938036) (xy 180.253938 -307.97738)
			(xy 180.218445 -308.011472) (xy 180.177942 -308.039428) (xy 180.13348 -308.060526) (xy 180.086209 -308.074218)
			(xy 180.037354 -308.08015) (xy 179.988179 -308.078169) (xy 179.93996 -308.068325) (xy 179.893944 -308.050873)
			(xy 179.851323 -308.026266) (xy 179.813202 -307.995141) (xy 179.780567 -307.958304) (xy 179.754264 -307.916708)
			(xy 179.734973 -307.871432) (xy 179.723196 -307.823648) (xy 179.719236 -307.774594) (xy 179.380134 -307.774594)
			(xy 179.379639 -307.799201) (xy 179.371744 -307.847778) (xy 179.35616 -307.894459) (xy 179.333289 -307.938036)
			(xy 179.303724 -307.97738) (xy 179.268231 -308.011472) (xy 179.227728 -308.039428) (xy 179.183266 -308.060526)
			(xy 179.135995 -308.074218) (xy 179.08714 -308.08015) (xy 179.037965 -308.078169) (xy 178.989746 -308.068325)
			(xy 178.94373 -308.050873) (xy 178.901109 -308.026266) (xy 178.862988 -307.995141) (xy 178.830353 -307.958304)
			(xy 178.80405 -307.916708) (xy 178.784759 -307.871432) (xy 178.772982 -307.823648) (xy 178.769022 -307.774594)
			(xy 178.430169 -307.774594) (xy 178.430174 -307.774848) (xy 178.429679 -307.799455) (xy 178.421784 -307.848032)
			(xy 178.4062 -307.894713) (xy 178.383329 -307.93829) (xy 178.353764 -307.977634) (xy 178.318271 -308.011726)
			(xy 178.277768 -308.039682) (xy 178.233306 -308.06078) (xy 178.186035 -308.074472) (xy 178.13718 -308.080404)
			(xy 178.088005 -308.078423) (xy 178.039786 -308.068579) (xy 177.99377 -308.051127) (xy 177.951149 -308.02652)
			(xy 177.913028 -307.995395) (xy 177.880393 -307.958558) (xy 177.85409 -307.916962) (xy 177.834799 -307.871686)
			(xy 177.823022 -307.823902) (xy 177.819062 -307.774848) (xy 177.480214 -307.774848) (xy 177.479719 -307.799455)
			(xy 177.471824 -307.848032) (xy 177.45624 -307.894713) (xy 177.433369 -307.93829) (xy 177.403804 -307.977634)
			(xy 177.368311 -308.011726) (xy 177.327808 -308.039682) (xy 177.283346 -308.06078) (xy 177.236075 -308.074472)
			(xy 177.18722 -308.080404) (xy 177.138045 -308.078423) (xy 177.089826 -308.068579) (xy 177.04381 -308.051127)
			(xy 177.001189 -308.02652) (xy 176.963068 -307.995395) (xy 176.930433 -307.958558) (xy 176.90413 -307.916962)
			(xy 176.884839 -307.871686) (xy 176.873062 -307.823902) (xy 176.869102 -307.774848) (xy 176.530254 -307.774848)
			(xy 176.529759 -307.799455) (xy 176.521864 -307.848032) (xy 176.50628 -307.894713) (xy 176.483409 -307.93829)
			(xy 176.453844 -307.977634) (xy 176.418351 -308.011726) (xy 176.377848 -308.039682) (xy 176.333386 -308.06078)
			(xy 176.286115 -308.074472) (xy 176.23726 -308.080404) (xy 176.188085 -308.078423) (xy 176.139866 -308.068579)
			(xy 176.09385 -308.051127) (xy 176.051229 -308.02652) (xy 176.013108 -307.995395) (xy 175.980473 -307.958558)
			(xy 175.95417 -307.916962) (xy 175.934879 -307.871686) (xy 175.923102 -307.823902) (xy 175.919142 -307.774848)
			(xy 174.630334 -307.774848) (xy 174.629839 -307.799455) (xy 174.621944 -307.848032) (xy 174.60636 -307.894713)
			(xy 174.583489 -307.93829) (xy 174.553924 -307.977634) (xy 174.518431 -308.011726) (xy 174.477928 -308.039682)
			(xy 174.433466 -308.06078) (xy 174.386195 -308.074472) (xy 174.33734 -308.080404) (xy 174.288165 -308.078423)
			(xy 174.239946 -308.068579) (xy 174.19393 -308.051127) (xy 174.151309 -308.02652) (xy 174.113188 -307.995395)
			(xy 174.080553 -307.958558) (xy 174.05425 -307.916962) (xy 174.034959 -307.871686) (xy 174.023182 -307.823902)
			(xy 174.019222 -307.774848) (xy 173.680374 -307.774848) (xy 173.679879 -307.799455) (xy 173.671984 -307.848032)
			(xy 173.6564 -307.894713) (xy 173.633529 -307.93829) (xy 173.603964 -307.977634) (xy 173.568471 -308.011726)
			(xy 173.527968 -308.039682) (xy 173.483506 -308.06078) (xy 173.436235 -308.074472) (xy 173.38738 -308.080404)
			(xy 173.338205 -308.078423) (xy 173.289986 -308.068579) (xy 173.24397 -308.051127) (xy 173.201349 -308.02652)
			(xy 173.163228 -307.995395) (xy 173.130593 -307.958558) (xy 173.10429 -307.916962) (xy 173.084999 -307.871686)
			(xy 173.073222 -307.823902) (xy 173.069262 -307.774848) (xy 172.730414 -307.774848) (xy 172.729919 -307.799455)
			(xy 172.722024 -307.848032) (xy 172.70644 -307.894713) (xy 172.683569 -307.93829) (xy 172.654004 -307.977634)
			(xy 172.618511 -308.011726) (xy 172.578008 -308.039682) (xy 172.533546 -308.06078) (xy 172.486275 -308.074472)
			(xy 172.43742 -308.080404) (xy 172.388245 -308.078423) (xy 172.340026 -308.068579) (xy 172.29401 -308.051127)
			(xy 172.251389 -308.02652) (xy 172.213268 -307.995395) (xy 172.180633 -307.958558) (xy 172.15433 -307.916962)
			(xy 172.135039 -307.871686) (xy 172.123262 -307.823902) (xy 172.119302 -307.774848) (xy 171.7802 -307.774848)
			(xy 171.779705 -307.799455) (xy 171.77181 -307.848032) (xy 171.756226 -307.894713) (xy 171.733355 -307.93829)
			(xy 171.70379 -307.977634) (xy 171.668297 -308.011726) (xy 171.627794 -308.039682) (xy 171.583332 -308.06078)
			(xy 171.536061 -308.074472) (xy 171.487206 -308.080404) (xy 171.438031 -308.078423) (xy 171.389812 -308.068579)
			(xy 171.343796 -308.051127) (xy 171.301175 -308.02652) (xy 171.263054 -307.995395) (xy 171.230419 -307.958558)
			(xy 171.204116 -307.916962) (xy 171.184825 -307.871686) (xy 171.173048 -307.823902) (xy 171.169088 -307.774848)
			(xy 170.83024 -307.774848) (xy 170.829745 -307.799455) (xy 170.82185 -307.848032) (xy 170.806266 -307.894713)
			(xy 170.783395 -307.93829) (xy 170.75383 -307.977634) (xy 170.718337 -308.011726) (xy 170.677834 -308.039682)
			(xy 170.633372 -308.06078) (xy 170.586101 -308.074472) (xy 170.537246 -308.080404) (xy 170.488071 -308.078423)
			(xy 170.439852 -308.068579) (xy 170.393836 -308.051127) (xy 170.351215 -308.02652) (xy 170.313094 -307.995395)
			(xy 170.280459 -307.958558) (xy 170.254156 -307.916962) (xy 170.234865 -307.871686) (xy 170.223088 -307.823902)
			(xy 170.219128 -307.774848) (xy 169.88028 -307.774848) (xy 169.879785 -307.799455) (xy 169.87189 -307.848032)
			(xy 169.856306 -307.894713) (xy 169.833435 -307.93829) (xy 169.80387 -307.977634) (xy 169.768377 -308.011726)
			(xy 169.727874 -308.039682) (xy 169.683412 -308.06078) (xy 169.636141 -308.074472) (xy 169.587286 -308.080404)
			(xy 169.538111 -308.078423) (xy 169.489892 -308.068579) (xy 169.443876 -308.051127) (xy 169.401255 -308.02652)
			(xy 169.363134 -307.995395) (xy 169.330499 -307.958558) (xy 169.304196 -307.916962) (xy 169.284905 -307.871686)
			(xy 169.273128 -307.823902) (xy 169.269168 -307.774848) (xy 168.93032 -307.774848) (xy 168.929825 -307.799455)
			(xy 168.92193 -307.848032) (xy 168.906346 -307.894713) (xy 168.883475 -307.93829) (xy 168.85391 -307.977634)
			(xy 168.818417 -308.011726) (xy 168.777914 -308.039682) (xy 168.733452 -308.06078) (xy 168.686181 -308.074472)
			(xy 168.637326 -308.080404) (xy 168.588151 -308.078423) (xy 168.539932 -308.068579) (xy 168.493916 -308.051127)
			(xy 168.451295 -308.02652) (xy 168.413174 -307.995395) (xy 168.380539 -307.958558) (xy 168.354236 -307.916962)
			(xy 168.334945 -307.871686) (xy 168.323168 -307.823902) (xy 168.319208 -307.774848) (xy 167.98036 -307.774848)
			(xy 167.979865 -307.799455) (xy 167.97197 -307.848032) (xy 167.956386 -307.894713) (xy 167.933515 -307.93829)
			(xy 167.90395 -307.977634) (xy 167.868457 -308.011726) (xy 167.827954 -308.039682) (xy 167.783492 -308.06078)
			(xy 167.736221 -308.074472) (xy 167.687366 -308.080404) (xy 167.638191 -308.078423) (xy 167.589972 -308.068579)
			(xy 167.543956 -308.051127) (xy 167.501335 -308.02652) (xy 167.463214 -307.995395) (xy 167.430579 -307.958558)
			(xy 167.404276 -307.916962) (xy 167.384985 -307.871686) (xy 167.373208 -307.823902) (xy 167.369248 -307.774848)
			(xy 167.0304 -307.774848) (xy 167.029905 -307.799455) (xy 167.02201 -307.848032) (xy 167.006426 -307.894713)
			(xy 166.983555 -307.93829) (xy 166.95399 -307.977634) (xy 166.918497 -308.011726) (xy 166.877994 -308.039682)
			(xy 166.833532 -308.06078) (xy 166.786261 -308.074472) (xy 166.737406 -308.080404) (xy 166.688231 -308.078423)
			(xy 166.640012 -308.068579) (xy 166.593996 -308.051127) (xy 166.551375 -308.02652) (xy 166.513254 -307.995395)
			(xy 166.480619 -307.958558) (xy 166.454316 -307.916962) (xy 166.435025 -307.871686) (xy 166.423248 -307.823902)
			(xy 166.419288 -307.774848) (xy 166.080186 -307.774848) (xy 166.079691 -307.799455) (xy 166.071796 -307.848032)
			(xy 166.056212 -307.894713) (xy 166.033341 -307.93829) (xy 166.003776 -307.977634) (xy 165.968283 -308.011726)
			(xy 165.92778 -308.039682) (xy 165.883318 -308.06078) (xy 165.836047 -308.074472) (xy 165.787192 -308.080404)
			(xy 165.738017 -308.078423) (xy 165.689798 -308.068579) (xy 165.643782 -308.051127) (xy 165.601161 -308.02652)
			(xy 165.56304 -307.995395) (xy 165.530405 -307.958558) (xy 165.504102 -307.916962) (xy 165.484811 -307.871686)
			(xy 165.473034 -307.823902) (xy 165.469074 -307.774848) (xy 165.130226 -307.774848) (xy 165.129731 -307.799455)
			(xy 165.121836 -307.848032) (xy 165.106252 -307.894713) (xy 165.083381 -307.93829) (xy 165.053816 -307.977634)
			(xy 165.018323 -308.011726) (xy 164.97782 -308.039682) (xy 164.933358 -308.06078) (xy 164.886087 -308.074472)
			(xy 164.837232 -308.080404) (xy 164.788057 -308.078423) (xy 164.739838 -308.068579) (xy 164.693822 -308.051127)
			(xy 164.651201 -308.02652) (xy 164.61308 -307.995395) (xy 164.580445 -307.958558) (xy 164.554142 -307.916962)
			(xy 164.534851 -307.871686) (xy 164.523074 -307.823902) (xy 164.519114 -307.774848) (xy 164.180266 -307.774848)
			(xy 164.179771 -307.799455) (xy 164.171876 -307.848032) (xy 164.156292 -307.894713) (xy 164.133421 -307.93829)
			(xy 164.103856 -307.977634) (xy 164.068363 -308.011726) (xy 164.02786 -308.039682) (xy 163.983398 -308.06078)
			(xy 163.936127 -308.074472) (xy 163.887272 -308.080404) (xy 163.838097 -308.078423) (xy 163.789878 -308.068579)
			(xy 163.743862 -308.051127) (xy 163.701241 -308.02652) (xy 163.66312 -307.995395) (xy 163.630485 -307.958558)
			(xy 163.604182 -307.916962) (xy 163.584891 -307.871686) (xy 163.573114 -307.823902) (xy 163.569154 -307.774848)
			(xy 163.230306 -307.774848) (xy 163.229811 -307.799455) (xy 163.221916 -307.848032) (xy 163.206332 -307.894713)
			(xy 163.183461 -307.93829) (xy 163.153896 -307.977634) (xy 163.118403 -308.011726) (xy 163.0779 -308.039682)
			(xy 163.033438 -308.06078) (xy 162.986167 -308.074472) (xy 162.937312 -308.080404) (xy 162.888137 -308.078423)
			(xy 162.839918 -308.068579) (xy 162.793902 -308.051127) (xy 162.751281 -308.02652) (xy 162.71316 -307.995395)
			(xy 162.680525 -307.958558) (xy 162.654222 -307.916962) (xy 162.634931 -307.871686) (xy 162.623154 -307.823902)
			(xy 162.619194 -307.774848) (xy 157.099 -307.774848) (xy 157.099 -308.249828) (xy 157.39416 -308.249828)
			(xy 157.39812 -308.200774) (xy 157.409897 -308.15299) (xy 157.429188 -308.107714) (xy 157.455491 -308.066118)
			(xy 157.488126 -308.029281) (xy 157.526247 -307.998156) (xy 157.568868 -307.973549) (xy 157.614884 -307.956097)
			(xy 157.663103 -307.946253) (xy 157.712278 -307.944272) (xy 157.761133 -307.950204) (xy 157.808404 -307.963896)
			(xy 157.852866 -307.984994) (xy 157.893369 -308.01295) (xy 157.928862 -308.047042) (xy 157.958427 -308.086386)
			(xy 157.981298 -308.129963) (xy 157.996882 -308.176644) (xy 158.004777 -308.225221) (xy 158.005272 -308.249828)
			(xy 158.34412 -308.249828) (xy 158.34808 -308.200774) (xy 158.359857 -308.15299) (xy 158.379148 -308.107714)
			(xy 158.405451 -308.066118) (xy 158.438086 -308.029281) (xy 158.476207 -307.998156) (xy 158.518828 -307.973549)
			(xy 158.564844 -307.956097) (xy 158.613063 -307.946253) (xy 158.662238 -307.944272) (xy 158.711093 -307.950204)
			(xy 158.758364 -307.963896) (xy 158.802826 -307.984994) (xy 158.843329 -308.01295) (xy 158.878822 -308.047042)
			(xy 158.908387 -308.086386) (xy 158.931258 -308.129963) (xy 158.946842 -308.176644) (xy 158.954737 -308.225221)
			(xy 158.955232 -308.249828) (xy 159.29408 -308.249828) (xy 159.29804 -308.200774) (xy 159.309817 -308.15299)
			(xy 159.329108 -308.107714) (xy 159.355411 -308.066118) (xy 159.388046 -308.029281) (xy 159.426167 -307.998156)
			(xy 159.468788 -307.973549) (xy 159.514804 -307.956097) (xy 159.563023 -307.946253) (xy 159.612198 -307.944272)
			(xy 159.661053 -307.950204) (xy 159.708324 -307.963896) (xy 159.752786 -307.984994) (xy 159.793289 -308.01295)
			(xy 159.828782 -308.047042) (xy 159.858347 -308.086386) (xy 159.881218 -308.129963) (xy 159.896802 -308.176644)
			(xy 159.904697 -308.225221) (xy 159.905192 -308.249828) (xy 160.24404 -308.249828) (xy 160.248 -308.200774)
			(xy 160.259777 -308.15299) (xy 160.279068 -308.107714) (xy 160.305371 -308.066118) (xy 160.338006 -308.029281)
			(xy 160.376127 -307.998156) (xy 160.418748 -307.973549) (xy 160.464764 -307.956097) (xy 160.512983 -307.946253)
			(xy 160.562158 -307.944272) (xy 160.611013 -307.950204) (xy 160.658284 -307.963896) (xy 160.702746 -307.984994)
			(xy 160.743249 -308.01295) (xy 160.778742 -308.047042) (xy 160.808307 -308.086386) (xy 160.831178 -308.129963)
			(xy 160.846762 -308.176644) (xy 160.854657 -308.225221) (xy 160.855152 -308.249828) (xy 161.194254 -308.249828)
			(xy 161.198214 -308.200774) (xy 161.209991 -308.15299) (xy 161.229282 -308.107714) (xy 161.255585 -308.066118)
			(xy 161.28822 -308.029281) (xy 161.326341 -307.998156) (xy 161.368962 -307.973549) (xy 161.414978 -307.956097)
			(xy 161.463197 -307.946253) (xy 161.512372 -307.944272) (xy 161.561227 -307.950204) (xy 161.608498 -307.963896)
			(xy 161.65296 -307.984994) (xy 161.693463 -308.01295) (xy 161.728956 -308.047042) (xy 161.758521 -308.086386)
			(xy 161.781392 -308.129963) (xy 161.796976 -308.176644) (xy 161.804871 -308.225221) (xy 161.805366 -308.249828)
			(xy 189.69407 -308.249828) (xy 189.69803 -308.200774) (xy 189.709807 -308.15299) (xy 189.729098 -308.107714)
			(xy 189.755401 -308.066118) (xy 189.788036 -308.029281) (xy 189.826157 -307.998156) (xy 189.868778 -307.973549)
			(xy 189.914794 -307.956097) (xy 189.963013 -307.946253) (xy 190.012188 -307.944272) (xy 190.061043 -307.950204)
			(xy 190.108314 -307.963896) (xy 190.152776 -307.984994) (xy 190.193279 -308.01295) (xy 190.228772 -308.047042)
			(xy 190.258337 -308.086386) (xy 190.281208 -308.129963) (xy 190.296792 -308.176644) (xy 190.304687 -308.225221)
			(xy 190.305182 -308.249828) (xy 190.304687 -308.274435) (xy 190.304508 -308.275536) (xy 190.62344 -308.275536)
			(xy 190.62344 -308.22412) (xy 190.631483 -308.173338) (xy 190.647371 -308.124439) (xy 190.670714 -308.078627)
			(xy 190.700935 -308.037031) (xy 190.737291 -308.000675) (xy 190.778887 -307.970454) (xy 190.824699 -307.947111)
			(xy 190.873598 -307.931223) (xy 190.92438 -307.92318) (xy 190.975796 -307.92318) (xy 191.026578 -307.931223)
			(xy 191.075477 -307.947111) (xy 191.121289 -307.970454) (xy 191.162885 -308.000675) (xy 191.199241 -308.037031)
			(xy 191.229462 -308.078627) (xy 191.252805 -308.124439) (xy 191.268693 -308.173338) (xy 191.276736 -308.22412)
			(xy 191.27724 -308.249828) (xy 191.276736 -308.275536) (xy 191.5734 -308.275536) (xy 191.5734 -308.22412)
			(xy 191.581443 -308.173338) (xy 191.597331 -308.124439) (xy 191.620674 -308.078627) (xy 191.650895 -308.037031)
			(xy 191.687251 -308.000675) (xy 191.728847 -307.970454) (xy 191.774659 -307.947111) (xy 191.823558 -307.931223)
			(xy 191.87434 -307.92318) (xy 191.925756 -307.92318) (xy 191.976538 -307.931223) (xy 192.025437 -307.947111)
			(xy 192.071249 -307.970454) (xy 192.112845 -308.000675) (xy 192.149201 -308.037031) (xy 192.179422 -308.078627)
			(xy 192.202765 -308.124439) (xy 192.218653 -308.173338) (xy 192.226696 -308.22412) (xy 192.2272 -308.249828)
			(xy 192.226696 -308.275536) (xy 192.218653 -308.326318) (xy 192.202765 -308.375217) (xy 192.179422 -308.421029)
			(xy 192.149201 -308.462625) (xy 192.112845 -308.498981) (xy 192.071249 -308.529202) (xy 192.025437 -308.552545)
			(xy 191.976538 -308.568433) (xy 191.925756 -308.576476) (xy 191.87434 -308.576476) (xy 191.823558 -308.568433)
			(xy 191.774659 -308.552545) (xy 191.728847 -308.529202) (xy 191.687251 -308.498981) (xy 191.650895 -308.462625)
			(xy 191.620674 -308.421029) (xy 191.597331 -308.375217) (xy 191.581443 -308.326318) (xy 191.5734 -308.275536)
			(xy 191.276736 -308.275536) (xy 191.268693 -308.326318) (xy 191.252805 -308.375217) (xy 191.229462 -308.421029)
			(xy 191.199241 -308.462625) (xy 191.162885 -308.498981) (xy 191.121289 -308.529202) (xy 191.075477 -308.552545)
			(xy 191.026578 -308.568433) (xy 190.975796 -308.576476) (xy 190.92438 -308.576476) (xy 190.873598 -308.568433)
			(xy 190.824699 -308.552545) (xy 190.778887 -308.529202) (xy 190.737291 -308.498981) (xy 190.700935 -308.462625)
			(xy 190.670714 -308.421029) (xy 190.647371 -308.375217) (xy 190.631483 -308.326318) (xy 190.62344 -308.275536)
			(xy 190.304508 -308.275536) (xy 190.296792 -308.323012) (xy 190.281208 -308.369693) (xy 190.258337 -308.41327)
			(xy 190.228772 -308.452614) (xy 190.193279 -308.486706) (xy 190.152776 -308.514662) (xy 190.108314 -308.53576)
			(xy 190.061043 -308.549452) (xy 190.012188 -308.555384) (xy 189.963013 -308.553403) (xy 189.914794 -308.543559)
			(xy 189.868778 -308.526107) (xy 189.826157 -308.5015) (xy 189.788036 -308.470375) (xy 189.755401 -308.433538)
			(xy 189.729098 -308.391942) (xy 189.709807 -308.346666) (xy 189.69803 -308.298882) (xy 189.69407 -308.249828)
			(xy 161.805366 -308.249828) (xy 161.804871 -308.274435) (xy 161.796976 -308.323012) (xy 161.781392 -308.369693)
			(xy 161.758521 -308.41327) (xy 161.728956 -308.452614) (xy 161.693463 -308.486706) (xy 161.65296 -308.514662)
			(xy 161.608498 -308.53576) (xy 161.561227 -308.549452) (xy 161.512372 -308.555384) (xy 161.463197 -308.553403)
			(xy 161.414978 -308.543559) (xy 161.368962 -308.526107) (xy 161.326341 -308.5015) (xy 161.28822 -308.470375)
			(xy 161.255585 -308.433538) (xy 161.229282 -308.391942) (xy 161.209991 -308.346666) (xy 161.198214 -308.298882)
			(xy 161.194254 -308.249828) (xy 160.855152 -308.249828) (xy 160.854657 -308.274435) (xy 160.846762 -308.323012)
			(xy 160.831178 -308.369693) (xy 160.808307 -308.41327) (xy 160.778742 -308.452614) (xy 160.743249 -308.486706)
			(xy 160.702746 -308.514662) (xy 160.658284 -308.53576) (xy 160.611013 -308.549452) (xy 160.562158 -308.555384)
			(xy 160.512983 -308.553403) (xy 160.464764 -308.543559) (xy 160.418748 -308.526107) (xy 160.376127 -308.5015)
			(xy 160.338006 -308.470375) (xy 160.305371 -308.433538) (xy 160.279068 -308.391942) (xy 160.259777 -308.346666)
			(xy 160.248 -308.298882) (xy 160.24404 -308.249828) (xy 159.905192 -308.249828) (xy 159.904697 -308.274435)
			(xy 159.896802 -308.323012) (xy 159.881218 -308.369693) (xy 159.858347 -308.41327) (xy 159.828782 -308.452614)
			(xy 159.793289 -308.486706) (xy 159.752786 -308.514662) (xy 159.708324 -308.53576) (xy 159.661053 -308.549452)
			(xy 159.612198 -308.555384) (xy 159.563023 -308.553403) (xy 159.514804 -308.543559) (xy 159.468788 -308.526107)
			(xy 159.426167 -308.5015) (xy 159.388046 -308.470375) (xy 159.355411 -308.433538) (xy 159.329108 -308.391942)
			(xy 159.309817 -308.346666) (xy 159.29804 -308.298882) (xy 159.29408 -308.249828) (xy 158.955232 -308.249828)
			(xy 158.954737 -308.274435) (xy 158.946842 -308.323012) (xy 158.931258 -308.369693) (xy 158.908387 -308.41327)
			(xy 158.878822 -308.452614) (xy 158.843329 -308.486706) (xy 158.802826 -308.514662) (xy 158.758364 -308.53576)
			(xy 158.711093 -308.549452) (xy 158.662238 -308.555384) (xy 158.613063 -308.553403) (xy 158.564844 -308.543559)
			(xy 158.518828 -308.526107) (xy 158.476207 -308.5015) (xy 158.438086 -308.470375) (xy 158.405451 -308.433538)
			(xy 158.379148 -308.391942) (xy 158.359857 -308.346666) (xy 158.34808 -308.298882) (xy 158.34412 -308.249828)
			(xy 158.005272 -308.249828) (xy 158.004777 -308.274435) (xy 157.996882 -308.323012) (xy 157.981298 -308.369693)
			(xy 157.958427 -308.41327) (xy 157.928862 -308.452614) (xy 157.893369 -308.486706) (xy 157.852866 -308.514662)
			(xy 157.808404 -308.53576) (xy 157.761133 -308.549452) (xy 157.712278 -308.555384) (xy 157.663103 -308.553403)
			(xy 157.614884 -308.543559) (xy 157.568868 -308.526107) (xy 157.526247 -308.5015) (xy 157.488126 -308.470375)
			(xy 157.455491 -308.433538) (xy 157.429188 -308.391942) (xy 157.409897 -308.346666) (xy 157.39812 -308.298882)
			(xy 157.39416 -308.249828) (xy 157.099 -308.249828) (xy 157.099 -308.724808) (xy 162.619194 -308.724808)
			(xy 162.623154 -308.675754) (xy 162.634931 -308.62797) (xy 162.654222 -308.582694) (xy 162.680525 -308.541098)
			(xy 162.71316 -308.504261) (xy 162.751281 -308.473136) (xy 162.793902 -308.448529) (xy 162.839918 -308.431077)
			(xy 162.888137 -308.421233) (xy 162.937312 -308.419252) (xy 162.986167 -308.425184) (xy 163.033438 -308.438876)
			(xy 163.0779 -308.459974) (xy 163.118403 -308.48793) (xy 163.153896 -308.522022) (xy 163.183461 -308.561366)
			(xy 163.206332 -308.604943) (xy 163.221916 -308.651624) (xy 163.229811 -308.700201) (xy 163.230306 -308.724808)
			(xy 163.569154 -308.724808) (xy 163.573114 -308.675754) (xy 163.584891 -308.62797) (xy 163.604182 -308.582694)
			(xy 163.630485 -308.541098) (xy 163.66312 -308.504261) (xy 163.701241 -308.473136) (xy 163.743862 -308.448529)
			(xy 163.789878 -308.431077) (xy 163.838097 -308.421233) (xy 163.887272 -308.419252) (xy 163.936127 -308.425184)
			(xy 163.983398 -308.438876) (xy 164.02786 -308.459974) (xy 164.068363 -308.48793) (xy 164.103856 -308.522022)
			(xy 164.133421 -308.561366) (xy 164.156292 -308.604943) (xy 164.171876 -308.651624) (xy 164.179771 -308.700201)
			(xy 164.180266 -308.724808) (xy 164.519114 -308.724808) (xy 164.523074 -308.675754) (xy 164.534851 -308.62797)
			(xy 164.554142 -308.582694) (xy 164.580445 -308.541098) (xy 164.61308 -308.504261) (xy 164.651201 -308.473136)
			(xy 164.693822 -308.448529) (xy 164.739838 -308.431077) (xy 164.788057 -308.421233) (xy 164.837232 -308.419252)
			(xy 164.886087 -308.425184) (xy 164.933358 -308.438876) (xy 164.97782 -308.459974) (xy 165.018323 -308.48793)
			(xy 165.053816 -308.522022) (xy 165.083381 -308.561366) (xy 165.106252 -308.604943) (xy 165.121836 -308.651624)
			(xy 165.129731 -308.700201) (xy 165.130226 -308.724808) (xy 165.469074 -308.724808) (xy 165.473034 -308.675754)
			(xy 165.484811 -308.62797) (xy 165.504102 -308.582694) (xy 165.530405 -308.541098) (xy 165.56304 -308.504261)
			(xy 165.601161 -308.473136) (xy 165.643782 -308.448529) (xy 165.689798 -308.431077) (xy 165.738017 -308.421233)
			(xy 165.787192 -308.419252) (xy 165.836047 -308.425184) (xy 165.883318 -308.438876) (xy 165.92778 -308.459974)
			(xy 165.968283 -308.48793) (xy 166.003776 -308.522022) (xy 166.033341 -308.561366) (xy 166.056212 -308.604943)
			(xy 166.071796 -308.651624) (xy 166.079691 -308.700201) (xy 166.080186 -308.724808) (xy 166.419288 -308.724808)
			(xy 166.423248 -308.675754) (xy 166.435025 -308.62797) (xy 166.454316 -308.582694) (xy 166.480619 -308.541098)
			(xy 166.513254 -308.504261) (xy 166.551375 -308.473136) (xy 166.593996 -308.448529) (xy 166.640012 -308.431077)
			(xy 166.688231 -308.421233) (xy 166.737406 -308.419252) (xy 166.786261 -308.425184) (xy 166.833532 -308.438876)
			(xy 166.877994 -308.459974) (xy 166.918497 -308.48793) (xy 166.95399 -308.522022) (xy 166.983555 -308.561366)
			(xy 167.006426 -308.604943) (xy 167.02201 -308.651624) (xy 167.029905 -308.700201) (xy 167.0304 -308.724808)
			(xy 167.369248 -308.724808) (xy 167.373208 -308.675754) (xy 167.384985 -308.62797) (xy 167.404276 -308.582694)
			(xy 167.430579 -308.541098) (xy 167.463214 -308.504261) (xy 167.501335 -308.473136) (xy 167.543956 -308.448529)
			(xy 167.589972 -308.431077) (xy 167.638191 -308.421233) (xy 167.687366 -308.419252) (xy 167.736221 -308.425184)
			(xy 167.783492 -308.438876) (xy 167.827954 -308.459974) (xy 167.868457 -308.48793) (xy 167.90395 -308.522022)
			(xy 167.933515 -308.561366) (xy 167.956386 -308.604943) (xy 167.97197 -308.651624) (xy 167.979865 -308.700201)
			(xy 167.98036 -308.724808) (xy 168.319208 -308.724808) (xy 168.323168 -308.675754) (xy 168.334945 -308.62797)
			(xy 168.354236 -308.582694) (xy 168.380539 -308.541098) (xy 168.413174 -308.504261) (xy 168.451295 -308.473136)
			(xy 168.493916 -308.448529) (xy 168.539932 -308.431077) (xy 168.588151 -308.421233) (xy 168.637326 -308.419252)
			(xy 168.686181 -308.425184) (xy 168.733452 -308.438876) (xy 168.777914 -308.459974) (xy 168.818417 -308.48793)
			(xy 168.85391 -308.522022) (xy 168.883475 -308.561366) (xy 168.906346 -308.604943) (xy 168.92193 -308.651624)
			(xy 168.929825 -308.700201) (xy 168.93032 -308.724808) (xy 169.269168 -308.724808) (xy 169.273128 -308.675754)
			(xy 169.284905 -308.62797) (xy 169.304196 -308.582694) (xy 169.330499 -308.541098) (xy 169.363134 -308.504261)
			(xy 169.401255 -308.473136) (xy 169.443876 -308.448529) (xy 169.489892 -308.431077) (xy 169.538111 -308.421233)
			(xy 169.587286 -308.419252) (xy 169.636141 -308.425184) (xy 169.683412 -308.438876) (xy 169.727874 -308.459974)
			(xy 169.768377 -308.48793) (xy 169.80387 -308.522022) (xy 169.833435 -308.561366) (xy 169.856306 -308.604943)
			(xy 169.87189 -308.651624) (xy 169.879785 -308.700201) (xy 169.88028 -308.724808) (xy 170.219128 -308.724808)
			(xy 170.223088 -308.675754) (xy 170.234865 -308.62797) (xy 170.254156 -308.582694) (xy 170.280459 -308.541098)
			(xy 170.313094 -308.504261) (xy 170.351215 -308.473136) (xy 170.393836 -308.448529) (xy 170.439852 -308.431077)
			(xy 170.488071 -308.421233) (xy 170.537246 -308.419252) (xy 170.586101 -308.425184) (xy 170.633372 -308.438876)
			(xy 170.677834 -308.459974) (xy 170.718337 -308.48793) (xy 170.75383 -308.522022) (xy 170.783395 -308.561366)
			(xy 170.806266 -308.604943) (xy 170.82185 -308.651624) (xy 170.829745 -308.700201) (xy 170.83024 -308.724808)
			(xy 171.169088 -308.724808) (xy 171.173048 -308.675754) (xy 171.184825 -308.62797) (xy 171.204116 -308.582694)
			(xy 171.230419 -308.541098) (xy 171.263054 -308.504261) (xy 171.301175 -308.473136) (xy 171.343796 -308.448529)
			(xy 171.389812 -308.431077) (xy 171.438031 -308.421233) (xy 171.487206 -308.419252) (xy 171.536061 -308.425184)
			(xy 171.583332 -308.438876) (xy 171.627794 -308.459974) (xy 171.668297 -308.48793) (xy 171.70379 -308.522022)
			(xy 171.733355 -308.561366) (xy 171.756226 -308.604943) (xy 171.77181 -308.651624) (xy 171.779705 -308.700201)
			(xy 171.7802 -308.724808) (xy 172.119302 -308.724808) (xy 172.123262 -308.675754) (xy 172.135039 -308.62797)
			(xy 172.15433 -308.582694) (xy 172.180633 -308.541098) (xy 172.213268 -308.504261) (xy 172.251389 -308.473136)
			(xy 172.29401 -308.448529) (xy 172.340026 -308.431077) (xy 172.388245 -308.421233) (xy 172.43742 -308.419252)
			(xy 172.486275 -308.425184) (xy 172.533546 -308.438876) (xy 172.578008 -308.459974) (xy 172.618511 -308.48793)
			(xy 172.654004 -308.522022) (xy 172.683569 -308.561366) (xy 172.70644 -308.604943) (xy 172.722024 -308.651624)
			(xy 172.729919 -308.700201) (xy 172.730414 -308.724808) (xy 174.019222 -308.724808) (xy 174.023182 -308.675754)
			(xy 174.034959 -308.62797) (xy 174.05425 -308.582694) (xy 174.080553 -308.541098) (xy 174.113188 -308.504261)
			(xy 174.151309 -308.473136) (xy 174.19393 -308.448529) (xy 174.239946 -308.431077) (xy 174.288165 -308.421233)
			(xy 174.33734 -308.419252) (xy 174.386195 -308.425184) (xy 174.433466 -308.438876) (xy 174.477928 -308.459974)
			(xy 174.518431 -308.48793) (xy 174.553924 -308.522022) (xy 174.583489 -308.561366) (xy 174.60636 -308.604943)
			(xy 174.621944 -308.651624) (xy 174.629839 -308.700201) (xy 174.630334 -308.724808) (xy 174.630167 -308.733111)
			(xy 175.919135 -308.733111) (xy 175.921819 -308.683533) (xy 175.932489 -308.635042) (xy 175.950863 -308.588915)
			(xy 175.976458 -308.54637) (xy 176.008598 -308.508525) (xy 176.046439 -308.47638) (xy 176.088981 -308.45078)
			(xy 176.135105 -308.4324) (xy 176.183595 -308.421724) (xy 176.233173 -308.419034) (xy 176.282533 -308.424401)
			(xy 176.330375 -308.437683) (xy 176.375438 -308.45853) (xy 176.416534 -308.486394) (xy 176.45258 -308.520538)
			(xy 176.482628 -308.560065) (xy 176.505884 -308.603933) (xy 176.521737 -308.650985) (xy 176.529769 -308.699982)
			(xy 176.530254 -308.724808) (xy 176.530078 -308.738991) (xy 176.527405 -308.767231) (xy 176.52492 -308.781196)
			(xy 176.522634 -308.793642) (xy 176.53 -308.817264) (xy 176.60747 -308.894734) (xy 176.631092 -308.9021)
			(xy 176.643538 -308.899814) (xy 176.657504 -308.897336) (xy 176.685743 -308.894665) (xy 176.699926 -308.89448)
			(xy 176.714109 -308.894653) (xy 176.742349 -308.897328) (xy 176.756314 -308.899814) (xy 176.76876 -308.9021)
			(xy 176.792382 -308.894734) (xy 176.869852 -308.817264) (xy 176.877218 -308.793642) (xy 176.874932 -308.781196)
			(xy 176.872459 -308.76723) (xy 176.869785 -308.73899) (xy 176.869598 -308.724808) (xy 176.87012 -308.699553)
			(xy 176.878433 -308.649731) (xy 176.894834 -308.601957) (xy 176.918875 -308.557534) (xy 176.949899 -308.517674)
			(xy 176.987061 -308.483464) (xy 177.029347 -308.455838) (xy 177.075603 -308.435548) (xy 177.124568 -308.423148)
			(xy 177.174906 -308.418977) (xy 177.225244 -308.423148) (xy 177.274209 -308.435548) (xy 177.320465 -308.455838)
			(xy 177.362751 -308.483464) (xy 177.399913 -308.517674) (xy 177.430937 -308.557534) (xy 177.454978 -308.601957)
			(xy 177.471379 -308.649731) (xy 177.479692 -308.699553) (xy 177.480214 -308.724808) (xy 177.480038 -308.738991)
			(xy 177.477366 -308.767231) (xy 177.47488 -308.781196) (xy 177.472594 -308.793642) (xy 177.47996 -308.817264)
			(xy 177.55743 -308.894734) (xy 177.581052 -308.9021) (xy 177.593498 -308.899814) (xy 177.607465 -308.897342)
			(xy 177.635704 -308.894667) (xy 177.649886 -308.89448) (xy 177.664069 -308.894659) (xy 177.692309 -308.897329)
			(xy 177.706274 -308.899814) (xy 177.71872 -308.9021) (xy 177.742342 -308.894734) (xy 177.819812 -308.817264)
			(xy 177.827178 -308.793642) (xy 177.824892 -308.781196) (xy 177.822419 -308.76723) (xy 177.819745 -308.73899)
			(xy 177.819558 -308.724808) (xy 177.820069 -308.699986) (xy 177.8281 -308.650995) (xy 177.843951 -308.603949)
			(xy 177.867204 -308.560087) (xy 177.897247 -308.520566) (xy 177.933289 -308.486425) (xy 177.974379 -308.458565)
			(xy 178.019435 -308.43772) (xy 178.06727 -308.42444) (xy 178.116624 -308.419073) (xy 178.166195 -308.421762)
			(xy 178.214679 -308.432435) (xy 178.260797 -308.450812) (xy 178.303334 -308.476408) (xy 178.34117 -308.508548)
			(xy 178.373307 -308.546387) (xy 178.3989 -308.588926) (xy 178.417273 -308.635046) (xy 178.427942 -308.68353)
			(xy 178.430163 -308.724554) (xy 178.769022 -308.724554) (xy 178.772982 -308.6755) (xy 178.784759 -308.627716)
			(xy 178.80405 -308.58244) (xy 178.830353 -308.540844) (xy 178.862988 -308.504007) (xy 178.901109 -308.472882)
			(xy 178.94373 -308.448275) (xy 178.989746 -308.430823) (xy 179.037965 -308.420979) (xy 179.08714 -308.418998)
			(xy 179.135995 -308.42493) (xy 179.183266 -308.438622) (xy 179.227728 -308.45972) (xy 179.268231 -308.487676)
			(xy 179.303724 -308.521768) (xy 179.333289 -308.561112) (xy 179.35616 -308.604689) (xy 179.371744 -308.65137)
			(xy 179.379639 -308.699947) (xy 179.380134 -308.724554) (xy 179.380129 -308.724808) (xy 179.719236 -308.724808)
			(xy 179.723196 -308.675754) (xy 179.734973 -308.62797) (xy 179.754264 -308.582694) (xy 179.780567 -308.541098)
			(xy 179.813202 -308.504261) (xy 179.851323 -308.473136) (xy 179.893944 -308.448529) (xy 179.93996 -308.431077)
			(xy 179.988179 -308.421233) (xy 180.037354 -308.419252) (xy 180.086209 -308.425184) (xy 180.13348 -308.438876)
			(xy 180.177942 -308.459974) (xy 180.218445 -308.48793) (xy 180.253938 -308.522022) (xy 180.283503 -308.561366)
			(xy 180.306374 -308.604943) (xy 180.321958 -308.651624) (xy 180.329853 -308.700201) (xy 180.330348 -308.724808)
			(xy 180.669196 -308.724808) (xy 180.673156 -308.675754) (xy 180.684933 -308.62797) (xy 180.704224 -308.582694)
			(xy 180.730527 -308.541098) (xy 180.763162 -308.504261) (xy 180.801283 -308.473136) (xy 180.843904 -308.448529)
			(xy 180.88992 -308.431077) (xy 180.938139 -308.421233) (xy 180.987314 -308.419252) (xy 181.036169 -308.425184)
			(xy 181.08344 -308.438876) (xy 181.127902 -308.459974) (xy 181.168405 -308.48793) (xy 181.203898 -308.522022)
			(xy 181.233463 -308.561366) (xy 181.256334 -308.604943) (xy 181.271918 -308.651624) (xy 181.279813 -308.700201)
			(xy 181.280308 -308.724808) (xy 181.619156 -308.724808) (xy 181.623116 -308.675754) (xy 181.634893 -308.62797)
			(xy 181.654184 -308.582694) (xy 181.680487 -308.541098) (xy 181.713122 -308.504261) (xy 181.751243 -308.473136)
			(xy 181.793864 -308.448529) (xy 181.83988 -308.431077) (xy 181.888099 -308.421233) (xy 181.937274 -308.419252)
			(xy 181.986129 -308.425184) (xy 182.0334 -308.438876) (xy 182.077862 -308.459974) (xy 182.118365 -308.48793)
			(xy 182.153858 -308.522022) (xy 182.183423 -308.561366) (xy 182.206294 -308.604943) (xy 182.221878 -308.651624)
			(xy 182.229773 -308.700201) (xy 182.230268 -308.724808) (xy 182.569116 -308.724808) (xy 182.573076 -308.675754)
			(xy 182.584853 -308.62797) (xy 182.604144 -308.582694) (xy 182.630447 -308.541098) (xy 182.663082 -308.504261)
			(xy 182.701203 -308.473136) (xy 182.743824 -308.448529) (xy 182.78984 -308.431077) (xy 182.838059 -308.421233)
			(xy 182.887234 -308.419252) (xy 182.936089 -308.425184) (xy 182.98336 -308.438876) (xy 183.027822 -308.459974)
			(xy 183.068325 -308.48793) (xy 183.103818 -308.522022) (xy 183.133383 -308.561366) (xy 183.156254 -308.604943)
			(xy 183.171838 -308.651624) (xy 183.179733 -308.700201) (xy 183.180228 -308.724808) (xy 183.519076 -308.724808)
			(xy 183.523036 -308.675754) (xy 183.534813 -308.62797) (xy 183.554104 -308.582694) (xy 183.580407 -308.541098)
			(xy 183.613042 -308.504261) (xy 183.651163 -308.473136) (xy 183.693784 -308.448529) (xy 183.7398 -308.431077)
			(xy 183.788019 -308.421233) (xy 183.837194 -308.419252) (xy 183.886049 -308.425184) (xy 183.93332 -308.438876)
			(xy 183.977782 -308.459974) (xy 184.018285 -308.48793) (xy 184.053778 -308.522022) (xy 184.083343 -308.561366)
			(xy 184.106214 -308.604943) (xy 184.121798 -308.651624) (xy 184.129693 -308.700201) (xy 184.130188 -308.724808)
			(xy 184.46929 -308.724808) (xy 184.47325 -308.675754) (xy 184.485027 -308.62797) (xy 184.504318 -308.582694)
			(xy 184.530621 -308.541098) (xy 184.563256 -308.504261) (xy 184.601377 -308.473136) (xy 184.643998 -308.448529)
			(xy 184.690014 -308.431077) (xy 184.738233 -308.421233) (xy 184.787408 -308.419252) (xy 184.836263 -308.425184)
			(xy 184.883534 -308.438876) (xy 184.927996 -308.459974) (xy 184.968499 -308.48793) (xy 185.003992 -308.522022)
			(xy 185.033557 -308.561366) (xy 185.056428 -308.604943) (xy 185.072012 -308.651624) (xy 185.079907 -308.700201)
			(xy 185.080402 -308.724808) (xy 185.41925 -308.724808) (xy 185.42321 -308.675754) (xy 185.434987 -308.62797)
			(xy 185.454278 -308.582694) (xy 185.480581 -308.541098) (xy 185.513216 -308.504261) (xy 185.551337 -308.473136)
			(xy 185.593958 -308.448529) (xy 185.639974 -308.431077) (xy 185.688193 -308.421233) (xy 185.737368 -308.419252)
			(xy 185.786223 -308.425184) (xy 185.833494 -308.438876) (xy 185.877956 -308.459974) (xy 185.918459 -308.48793)
			(xy 185.953952 -308.522022) (xy 185.983517 -308.561366) (xy 186.006388 -308.604943) (xy 186.021972 -308.651624)
			(xy 186.029867 -308.700201) (xy 186.030362 -308.724808) (xy 186.36921 -308.724808) (xy 186.37317 -308.675754)
			(xy 186.384947 -308.62797) (xy 186.404238 -308.582694) (xy 186.430541 -308.541098) (xy 186.463176 -308.504261)
			(xy 186.501297 -308.473136) (xy 186.543918 -308.448529) (xy 186.589934 -308.431077) (xy 186.638153 -308.421233)
			(xy 186.687328 -308.419252) (xy 186.736183 -308.425184) (xy 186.783454 -308.438876) (xy 186.827916 -308.459974)
			(xy 186.868419 -308.48793) (xy 186.903912 -308.522022) (xy 186.933477 -308.561366) (xy 186.956348 -308.604943)
			(xy 186.971932 -308.651624) (xy 186.979827 -308.700201) (xy 186.980322 -308.724808) (xy 187.31917 -308.724808)
			(xy 187.32313 -308.675754) (xy 187.334907 -308.62797) (xy 187.354198 -308.582694) (xy 187.380501 -308.541098)
			(xy 187.413136 -308.504261) (xy 187.451257 -308.473136) (xy 187.493878 -308.448529) (xy 187.539894 -308.431077)
			(xy 187.588113 -308.421233) (xy 187.637288 -308.419252) (xy 187.686143 -308.425184) (xy 187.733414 -308.438876)
			(xy 187.777876 -308.459974) (xy 187.818379 -308.48793) (xy 187.853872 -308.522022) (xy 187.883437 -308.561366)
			(xy 187.906308 -308.604943) (xy 187.921892 -308.651624) (xy 187.929787 -308.700201) (xy 187.930282 -308.724808)
			(xy 188.26913 -308.724808) (xy 188.27309 -308.675754) (xy 188.284867 -308.62797) (xy 188.304158 -308.582694)
			(xy 188.330461 -308.541098) (xy 188.363096 -308.504261) (xy 188.401217 -308.473136) (xy 188.443838 -308.448529)
			(xy 188.489854 -308.431077) (xy 188.538073 -308.421233) (xy 188.587248 -308.419252) (xy 188.636103 -308.425184)
			(xy 188.683374 -308.438876) (xy 188.727836 -308.459974) (xy 188.768339 -308.48793) (xy 188.803832 -308.522022)
			(xy 188.833397 -308.561366) (xy 188.856268 -308.604943) (xy 188.871852 -308.651624) (xy 188.879747 -308.700201)
			(xy 188.880242 -308.724808) (xy 188.879747 -308.749415) (xy 188.871852 -308.797992) (xy 188.856268 -308.844673)
			(xy 188.833397 -308.88825) (xy 188.803832 -308.927594) (xy 188.768339 -308.961686) (xy 188.727836 -308.989642)
			(xy 188.683374 -309.01074) (xy 188.636103 -309.024432) (xy 188.587248 -309.030364) (xy 188.538073 -309.028383)
			(xy 188.489854 -309.018539) (xy 188.443838 -309.001087) (xy 188.401217 -308.97648) (xy 188.363096 -308.945355)
			(xy 188.330461 -308.908518) (xy 188.304158 -308.866922) (xy 188.284867 -308.821646) (xy 188.27309 -308.773862)
			(xy 188.26913 -308.724808) (xy 187.930282 -308.724808) (xy 187.929787 -308.749415) (xy 187.921892 -308.797992)
			(xy 187.906308 -308.844673) (xy 187.883437 -308.88825) (xy 187.853872 -308.927594) (xy 187.818379 -308.961686)
			(xy 187.777876 -308.989642) (xy 187.733414 -309.01074) (xy 187.686143 -309.024432) (xy 187.637288 -309.030364)
			(xy 187.588113 -309.028383) (xy 187.539894 -309.018539) (xy 187.493878 -309.001087) (xy 187.451257 -308.97648)
			(xy 187.413136 -308.945355) (xy 187.380501 -308.908518) (xy 187.354198 -308.866922) (xy 187.334907 -308.821646)
			(xy 187.32313 -308.773862) (xy 187.31917 -308.724808) (xy 186.980322 -308.724808) (xy 186.979827 -308.749415)
			(xy 186.971932 -308.797992) (xy 186.956348 -308.844673) (xy 186.933477 -308.88825) (xy 186.903912 -308.927594)
			(xy 186.868419 -308.961686) (xy 186.827916 -308.989642) (xy 186.783454 -309.01074) (xy 186.736183 -309.024432)
			(xy 186.687328 -309.030364) (xy 186.638153 -309.028383) (xy 186.589934 -309.018539) (xy 186.543918 -309.001087)
			(xy 186.501297 -308.97648) (xy 186.463176 -308.945355) (xy 186.430541 -308.908518) (xy 186.404238 -308.866922)
			(xy 186.384947 -308.821646) (xy 186.37317 -308.773862) (xy 186.36921 -308.724808) (xy 186.030362 -308.724808)
			(xy 186.029867 -308.749415) (xy 186.021972 -308.797992) (xy 186.006388 -308.844673) (xy 185.983517 -308.88825)
			(xy 185.953952 -308.927594) (xy 185.918459 -308.961686) (xy 185.877956 -308.989642) (xy 185.833494 -309.01074)
			(xy 185.786223 -309.024432) (xy 185.737368 -309.030364) (xy 185.688193 -309.028383) (xy 185.639974 -309.018539)
			(xy 185.593958 -309.001087) (xy 185.551337 -308.97648) (xy 185.513216 -308.945355) (xy 185.480581 -308.908518)
			(xy 185.454278 -308.866922) (xy 185.434987 -308.821646) (xy 185.42321 -308.773862) (xy 185.41925 -308.724808)
			(xy 185.080402 -308.724808) (xy 185.079907 -308.749415) (xy 185.072012 -308.797992) (xy 185.056428 -308.844673)
			(xy 185.033557 -308.88825) (xy 185.003992 -308.927594) (xy 184.968499 -308.961686) (xy 184.927996 -308.989642)
			(xy 184.883534 -309.01074) (xy 184.836263 -309.024432) (xy 184.787408 -309.030364) (xy 184.738233 -309.028383)
			(xy 184.690014 -309.018539) (xy 184.643998 -309.001087) (xy 184.601377 -308.97648) (xy 184.563256 -308.945355)
			(xy 184.530621 -308.908518) (xy 184.504318 -308.866922) (xy 184.485027 -308.821646) (xy 184.47325 -308.773862)
			(xy 184.46929 -308.724808) (xy 184.130188 -308.724808) (xy 184.129693 -308.749415) (xy 184.121798 -308.797992)
			(xy 184.106214 -308.844673) (xy 184.083343 -308.88825) (xy 184.053778 -308.927594) (xy 184.018285 -308.961686)
			(xy 183.977782 -308.989642) (xy 183.93332 -309.01074) (xy 183.886049 -309.024432) (xy 183.837194 -309.030364)
			(xy 183.788019 -309.028383) (xy 183.7398 -309.018539) (xy 183.693784 -309.001087) (xy 183.651163 -308.97648)
			(xy 183.613042 -308.945355) (xy 183.580407 -308.908518) (xy 183.554104 -308.866922) (xy 183.534813 -308.821646)
			(xy 183.523036 -308.773862) (xy 183.519076 -308.724808) (xy 183.180228 -308.724808) (xy 183.179733 -308.749415)
			(xy 183.171838 -308.797992) (xy 183.156254 -308.844673) (xy 183.133383 -308.88825) (xy 183.103818 -308.927594)
			(xy 183.068325 -308.961686) (xy 183.027822 -308.989642) (xy 182.98336 -309.01074) (xy 182.936089 -309.024432)
			(xy 182.887234 -309.030364) (xy 182.838059 -309.028383) (xy 182.78984 -309.018539) (xy 182.743824 -309.001087)
			(xy 182.701203 -308.97648) (xy 182.663082 -308.945355) (xy 182.630447 -308.908518) (xy 182.604144 -308.866922)
			(xy 182.584853 -308.821646) (xy 182.573076 -308.773862) (xy 182.569116 -308.724808) (xy 182.230268 -308.724808)
			(xy 182.229773 -308.749415) (xy 182.221878 -308.797992) (xy 182.206294 -308.844673) (xy 182.183423 -308.88825)
			(xy 182.153858 -308.927594) (xy 182.118365 -308.961686) (xy 182.077862 -308.989642) (xy 182.0334 -309.01074)
			(xy 181.986129 -309.024432) (xy 181.937274 -309.030364) (xy 181.888099 -309.028383) (xy 181.83988 -309.018539)
			(xy 181.793864 -309.001087) (xy 181.751243 -308.97648) (xy 181.713122 -308.945355) (xy 181.680487 -308.908518)
			(xy 181.654184 -308.866922) (xy 181.634893 -308.821646) (xy 181.623116 -308.773862) (xy 181.619156 -308.724808)
			(xy 181.280308 -308.724808) (xy 181.279813 -308.749415) (xy 181.271918 -308.797992) (xy 181.256334 -308.844673)
			(xy 181.233463 -308.88825) (xy 181.203898 -308.927594) (xy 181.168405 -308.961686) (xy 181.127902 -308.989642)
			(xy 181.08344 -309.01074) (xy 181.036169 -309.024432) (xy 180.987314 -309.030364) (xy 180.938139 -309.028383)
			(xy 180.88992 -309.018539) (xy 180.843904 -309.001087) (xy 180.801283 -308.97648) (xy 180.763162 -308.945355)
			(xy 180.730527 -308.908518) (xy 180.704224 -308.866922) (xy 180.684933 -308.821646) (xy 180.673156 -308.773862)
			(xy 180.669196 -308.724808) (xy 180.330348 -308.724808) (xy 180.329853 -308.749415) (xy 180.321958 -308.797992)
			(xy 180.306374 -308.844673) (xy 180.283503 -308.88825) (xy 180.253938 -308.927594) (xy 180.218445 -308.961686)
			(xy 180.177942 -308.989642) (xy 180.13348 -309.01074) (xy 180.086209 -309.024432) (xy 180.037354 -309.030364)
			(xy 179.988179 -309.028383) (xy 179.93996 -309.018539) (xy 179.893944 -309.001087) (xy 179.851323 -308.97648)
			(xy 179.813202 -308.945355) (xy 179.780567 -308.908518) (xy 179.754264 -308.866922) (xy 179.734973 -308.821646)
			(xy 179.723196 -308.773862) (xy 179.719236 -308.724808) (xy 179.380129 -308.724808) (xy 179.379639 -308.749161)
			(xy 179.371744 -308.797738) (xy 179.35616 -308.844419) (xy 179.333289 -308.887996) (xy 179.303724 -308.92734)
			(xy 179.268231 -308.961432) (xy 179.227728 -308.989388) (xy 179.183266 -309.010486) (xy 179.135995 -309.024178)
			(xy 179.08714 -309.03011) (xy 179.037965 -309.028129) (xy 178.989746 -309.018285) (xy 178.94373 -309.000833)
			(xy 178.901109 -308.976226) (xy 178.862988 -308.945101) (xy 178.830353 -308.908264) (xy 178.80405 -308.866668)
			(xy 178.784759 -308.821392) (xy 178.772982 -308.773608) (xy 178.769022 -308.724554) (xy 178.430163 -308.724554)
			(xy 178.430626 -308.733102) (xy 178.425255 -308.782455) (xy 178.411971 -308.830289) (xy 178.391122 -308.875344)
			(xy 178.363259 -308.916432) (xy 178.329115 -308.95247) (xy 178.289591 -308.98251) (xy 178.245727 -309.00576)
			(xy 178.19868 -309.021606) (xy 178.149688 -309.029633) (xy 178.124866 -309.030116) (xy 178.110683 -309.029944)
			(xy 178.082443 -309.027269) (xy 178.068478 -309.024782) (xy 178.056032 -309.022496) (xy 178.03241 -309.029862)
			(xy 177.95494 -309.107332) (xy 177.947574 -309.130954) (xy 177.94986 -309.1434) (xy 177.952332 -309.157367)
			(xy 177.955007 -309.185606) (xy 177.955194 -309.199788) (xy 189.69407 -309.199788) (xy 189.69803 -309.150734)
			(xy 189.709807 -309.10295) (xy 189.729098 -309.057674) (xy 189.755401 -309.016078) (xy 189.788036 -308.979241)
			(xy 189.826157 -308.948116) (xy 189.868778 -308.923509) (xy 189.914794 -308.906057) (xy 189.963013 -308.896213)
			(xy 190.012188 -308.894232) (xy 190.061043 -308.900164) (xy 190.108314 -308.913856) (xy 190.152776 -308.934954)
			(xy 190.193279 -308.96291) (xy 190.228772 -308.997002) (xy 190.258337 -309.036346) (xy 190.281208 -309.079923)
			(xy 190.296792 -309.126604) (xy 190.304687 -309.175181) (xy 190.305182 -309.199788) (xy 190.644284 -309.199788)
			(xy 190.648244 -309.150734) (xy 190.660021 -309.10295) (xy 190.679312 -309.057674) (xy 190.705615 -309.016078)
			(xy 190.73825 -308.979241) (xy 190.776371 -308.948116) (xy 190.818992 -308.923509) (xy 190.865008 -308.906057)
			(xy 190.913227 -308.896213) (xy 190.962402 -308.894232) (xy 191.011257 -308.900164) (xy 191.058528 -308.913856)
			(xy 191.10299 -308.934954) (xy 191.143493 -308.96291) (xy 191.178986 -308.997002) (xy 191.208551 -309.036346)
			(xy 191.231422 -309.079923) (xy 191.247006 -309.126604) (xy 191.254901 -309.175181) (xy 191.255396 -309.199788)
			(xy 191.594244 -309.199788) (xy 191.598204 -309.150734) (xy 191.609981 -309.10295) (xy 191.629272 -309.057674)
			(xy 191.655575 -309.016078) (xy 191.68821 -308.979241) (xy 191.726331 -308.948116) (xy 191.768952 -308.923509)
			(xy 191.814968 -308.906057) (xy 191.863187 -308.896213) (xy 191.912362 -308.894232) (xy 191.961217 -308.900164)
			(xy 192.008488 -308.913856) (xy 192.05295 -308.934954) (xy 192.093453 -308.96291) (xy 192.128946 -308.997002)
			(xy 192.158511 -309.036346) (xy 192.181382 -309.079923) (xy 192.196966 -309.126604) (xy 192.204861 -309.175181)
			(xy 192.205356 -309.199788) (xy 192.204861 -309.224395) (xy 192.196966 -309.272972) (xy 192.181382 -309.319653)
			(xy 192.158511 -309.36323) (xy 192.128946 -309.402574) (xy 192.093453 -309.436666) (xy 192.05295 -309.464622)
			(xy 192.008488 -309.48572) (xy 191.961217 -309.499412) (xy 191.912362 -309.505344) (xy 191.863187 -309.503363)
			(xy 191.814968 -309.493519) (xy 191.768952 -309.476067) (xy 191.726331 -309.45146) (xy 191.68821 -309.420335)
			(xy 191.655575 -309.383498) (xy 191.629272 -309.341902) (xy 191.609981 -309.296626) (xy 191.598204 -309.248842)
			(xy 191.594244 -309.199788) (xy 191.255396 -309.199788) (xy 191.254901 -309.224395) (xy 191.247006 -309.272972)
			(xy 191.231422 -309.319653) (xy 191.208551 -309.36323) (xy 191.178986 -309.402574) (xy 191.143493 -309.436666)
			(xy 191.10299 -309.464622) (xy 191.058528 -309.48572) (xy 191.011257 -309.499412) (xy 190.962402 -309.505344)
			(xy 190.913227 -309.503363) (xy 190.865008 -309.493519) (xy 190.818992 -309.476067) (xy 190.776371 -309.45146)
			(xy 190.73825 -309.420335) (xy 190.705615 -309.383498) (xy 190.679312 -309.341902) (xy 190.660021 -309.296626)
			(xy 190.648244 -309.248842) (xy 190.644284 -309.199788) (xy 190.305182 -309.199788) (xy 190.304687 -309.224395)
			(xy 190.296792 -309.272972) (xy 190.281208 -309.319653) (xy 190.258337 -309.36323) (xy 190.228772 -309.402574)
			(xy 190.193279 -309.436666) (xy 190.152776 -309.464622) (xy 190.108314 -309.48572) (xy 190.061043 -309.499412)
			(xy 190.012188 -309.505344) (xy 189.963013 -309.503363) (xy 189.914794 -309.493519) (xy 189.868778 -309.476067)
			(xy 189.826157 -309.45146) (xy 189.788036 -309.420335) (xy 189.755401 -309.383498) (xy 189.729098 -309.341902)
			(xy 189.709807 -309.296626) (xy 189.69803 -309.248842) (xy 189.69407 -309.199788) (xy 177.955194 -309.199788)
			(xy 177.954672 -309.225043) (xy 177.946359 -309.274865) (xy 177.929958 -309.322639) (xy 177.905917 -309.367062)
			(xy 177.874893 -309.406922) (xy 177.837731 -309.441132) (xy 177.795445 -309.468758) (xy 177.749189 -309.489048)
			(xy 177.700224 -309.501448) (xy 177.649886 -309.505619) (xy 177.599548 -309.501448) (xy 177.550583 -309.489048)
			(xy 177.504327 -309.468758) (xy 177.462041 -309.441132) (xy 177.424879 -309.406922) (xy 177.393855 -309.367062)
			(xy 177.369814 -309.322639) (xy 177.353413 -309.274865) (xy 177.3451 -309.225043) (xy 177.344578 -309.199788)
			(xy 177.344753 -309.185605) (xy 177.347426 -309.157365) (xy 177.349912 -309.1434) (xy 177.352198 -309.130954)
			(xy 177.344832 -309.107332) (xy 177.267362 -309.029862) (xy 177.24374 -309.022496) (xy 177.231294 -309.024782)
			(xy 177.217328 -309.027255) (xy 177.189088 -309.029929) (xy 177.174906 -309.030116) (xy 177.160723 -309.029938)
			(xy 177.132483 -309.027267) (xy 177.118518 -309.024782) (xy 177.106072 -309.022496) (xy 177.08245 -309.029862)
			(xy 177.00498 -309.107332) (xy 176.997614 -309.130954) (xy 176.9999 -309.1434) (xy 177.002373 -309.157367)
			(xy 177.005047 -309.185606) (xy 177.005234 -309.199788) (xy 177.004712 -309.225043) (xy 176.996399 -309.274865)
			(xy 176.979998 -309.322639) (xy 176.955957 -309.367062) (xy 176.924933 -309.406922) (xy 176.887771 -309.441132)
			(xy 176.845485 -309.468758) (xy 176.799229 -309.489048) (xy 176.750264 -309.501448) (xy 176.699926 -309.505619)
			(xy 176.649588 -309.501448) (xy 176.600623 -309.489048) (xy 176.554367 -309.468758) (xy 176.512081 -309.441132)
			(xy 176.474919 -309.406922) (xy 176.443895 -309.367062) (xy 176.419854 -309.322639) (xy 176.403453 -309.274865)
			(xy 176.39514 -309.225043) (xy 176.394618 -309.199788) (xy 176.394793 -309.185605) (xy 176.397466 -309.157365)
			(xy 176.399952 -309.1434) (xy 176.402238 -309.130954) (xy 176.394872 -309.107332) (xy 176.317402 -309.029862)
			(xy 176.29378 -309.022496) (xy 176.281334 -309.024782) (xy 176.267369 -309.027263) (xy 176.239129 -309.029932)
			(xy 176.224946 -309.030116) (xy 176.20012 -309.029672) (xy 176.151122 -309.021647) (xy 176.104068 -309.005799)
			(xy 176.060198 -308.982548) (xy 176.020667 -308.952506) (xy 175.986517 -308.916463) (xy 175.958649 -308.875371)
			(xy 175.937796 -308.830311) (xy 175.924508 -308.782471) (xy 175.919135 -308.733111) (xy 174.630167 -308.733111)
			(xy 174.629839 -308.749415) (xy 174.621944 -308.797992) (xy 174.60636 -308.844673) (xy 174.583489 -308.88825)
			(xy 174.553924 -308.927594) (xy 174.518431 -308.961686) (xy 174.477928 -308.989642) (xy 174.433466 -309.01074)
			(xy 174.386195 -309.024432) (xy 174.33734 -309.030364) (xy 174.288165 -309.028383) (xy 174.239946 -309.018539)
			(xy 174.19393 -309.001087) (xy 174.151309 -308.97648) (xy 174.113188 -308.945355) (xy 174.080553 -308.908518)
			(xy 174.05425 -308.866922) (xy 174.034959 -308.821646) (xy 174.023182 -308.773862) (xy 174.019222 -308.724808)
			(xy 172.730414 -308.724808) (xy 172.729919 -308.749415) (xy 172.722024 -308.797992) (xy 172.70644 -308.844673)
			(xy 172.683569 -308.88825) (xy 172.654004 -308.927594) (xy 172.618511 -308.961686) (xy 172.578008 -308.989642)
			(xy 172.533546 -309.01074) (xy 172.486275 -309.024432) (xy 172.43742 -309.030364) (xy 172.388245 -309.028383)
			(xy 172.340026 -309.018539) (xy 172.29401 -309.001087) (xy 172.251389 -308.97648) (xy 172.213268 -308.945355)
			(xy 172.180633 -308.908518) (xy 172.15433 -308.866922) (xy 172.135039 -308.821646) (xy 172.123262 -308.773862)
			(xy 172.119302 -308.724808) (xy 171.7802 -308.724808) (xy 171.779705 -308.749415) (xy 171.77181 -308.797992)
			(xy 171.756226 -308.844673) (xy 171.733355 -308.88825) (xy 171.70379 -308.927594) (xy 171.668297 -308.961686)
			(xy 171.627794 -308.989642) (xy 171.583332 -309.01074) (xy 171.536061 -309.024432) (xy 171.487206 -309.030364)
			(xy 171.438031 -309.028383) (xy 171.389812 -309.018539) (xy 171.343796 -309.001087) (xy 171.301175 -308.97648)
			(xy 171.263054 -308.945355) (xy 171.230419 -308.908518) (xy 171.204116 -308.866922) (xy 171.184825 -308.821646)
			(xy 171.173048 -308.773862) (xy 171.169088 -308.724808) (xy 170.83024 -308.724808) (xy 170.829745 -308.749415)
			(xy 170.82185 -308.797992) (xy 170.806266 -308.844673) (xy 170.783395 -308.88825) (xy 170.75383 -308.927594)
			(xy 170.718337 -308.961686) (xy 170.677834 -308.989642) (xy 170.633372 -309.01074) (xy 170.586101 -309.024432)
			(xy 170.537246 -309.030364) (xy 170.488071 -309.028383) (xy 170.439852 -309.018539) (xy 170.393836 -309.001087)
			(xy 170.351215 -308.97648) (xy 170.313094 -308.945355) (xy 170.280459 -308.908518) (xy 170.254156 -308.866922)
			(xy 170.234865 -308.821646) (xy 170.223088 -308.773862) (xy 170.219128 -308.724808) (xy 169.88028 -308.724808)
			(xy 169.879785 -308.749415) (xy 169.87189 -308.797992) (xy 169.856306 -308.844673) (xy 169.833435 -308.88825)
			(xy 169.80387 -308.927594) (xy 169.768377 -308.961686) (xy 169.727874 -308.989642) (xy 169.683412 -309.01074)
			(xy 169.636141 -309.024432) (xy 169.587286 -309.030364) (xy 169.538111 -309.028383) (xy 169.489892 -309.018539)
			(xy 169.443876 -309.001087) (xy 169.401255 -308.97648) (xy 169.363134 -308.945355) (xy 169.330499 -308.908518)
			(xy 169.304196 -308.866922) (xy 169.284905 -308.821646) (xy 169.273128 -308.773862) (xy 169.269168 -308.724808)
			(xy 168.93032 -308.724808) (xy 168.929825 -308.749415) (xy 168.92193 -308.797992) (xy 168.906346 -308.844673)
			(xy 168.883475 -308.88825) (xy 168.85391 -308.927594) (xy 168.818417 -308.961686) (xy 168.777914 -308.989642)
			(xy 168.733452 -309.01074) (xy 168.686181 -309.024432) (xy 168.637326 -309.030364) (xy 168.588151 -309.028383)
			(xy 168.539932 -309.018539) (xy 168.493916 -309.001087) (xy 168.451295 -308.97648) (xy 168.413174 -308.945355)
			(xy 168.380539 -308.908518) (xy 168.354236 -308.866922) (xy 168.334945 -308.821646) (xy 168.323168 -308.773862)
			(xy 168.319208 -308.724808) (xy 167.98036 -308.724808) (xy 167.979865 -308.749415) (xy 167.97197 -308.797992)
			(xy 167.956386 -308.844673) (xy 167.933515 -308.88825) (xy 167.90395 -308.927594) (xy 167.868457 -308.961686)
			(xy 167.827954 -308.989642) (xy 167.783492 -309.01074) (xy 167.736221 -309.024432) (xy 167.687366 -309.030364)
			(xy 167.638191 -309.028383) (xy 167.589972 -309.018539) (xy 167.543956 -309.001087) (xy 167.501335 -308.97648)
			(xy 167.463214 -308.945355) (xy 167.430579 -308.908518) (xy 167.404276 -308.866922) (xy 167.384985 -308.821646)
			(xy 167.373208 -308.773862) (xy 167.369248 -308.724808) (xy 167.0304 -308.724808) (xy 167.029905 -308.749415)
			(xy 167.02201 -308.797992) (xy 167.006426 -308.844673) (xy 166.983555 -308.88825) (xy 166.95399 -308.927594)
			(xy 166.918497 -308.961686) (xy 166.877994 -308.989642) (xy 166.833532 -309.01074) (xy 166.786261 -309.024432)
			(xy 166.737406 -309.030364) (xy 166.688231 -309.028383) (xy 166.640012 -309.018539) (xy 166.593996 -309.001087)
			(xy 166.551375 -308.97648) (xy 166.513254 -308.945355) (xy 166.480619 -308.908518) (xy 166.454316 -308.866922)
			(xy 166.435025 -308.821646) (xy 166.423248 -308.773862) (xy 166.419288 -308.724808) (xy 166.080186 -308.724808)
			(xy 166.079691 -308.749415) (xy 166.071796 -308.797992) (xy 166.056212 -308.844673) (xy 166.033341 -308.88825)
			(xy 166.003776 -308.927594) (xy 165.968283 -308.961686) (xy 165.92778 -308.989642) (xy 165.883318 -309.01074)
			(xy 165.836047 -309.024432) (xy 165.787192 -309.030364) (xy 165.738017 -309.028383) (xy 165.689798 -309.018539)
			(xy 165.643782 -309.001087) (xy 165.601161 -308.97648) (xy 165.56304 -308.945355) (xy 165.530405 -308.908518)
			(xy 165.504102 -308.866922) (xy 165.484811 -308.821646) (xy 165.473034 -308.773862) (xy 165.469074 -308.724808)
			(xy 165.130226 -308.724808) (xy 165.129731 -308.749415) (xy 165.121836 -308.797992) (xy 165.106252 -308.844673)
			(xy 165.083381 -308.88825) (xy 165.053816 -308.927594) (xy 165.018323 -308.961686) (xy 164.97782 -308.989642)
			(xy 164.933358 -309.01074) (xy 164.886087 -309.024432) (xy 164.837232 -309.030364) (xy 164.788057 -309.028383)
			(xy 164.739838 -309.018539) (xy 164.693822 -309.001087) (xy 164.651201 -308.97648) (xy 164.61308 -308.945355)
			(xy 164.580445 -308.908518) (xy 164.554142 -308.866922) (xy 164.534851 -308.821646) (xy 164.523074 -308.773862)
			(xy 164.519114 -308.724808) (xy 164.180266 -308.724808) (xy 164.179771 -308.749415) (xy 164.171876 -308.797992)
			(xy 164.156292 -308.844673) (xy 164.133421 -308.88825) (xy 164.103856 -308.927594) (xy 164.068363 -308.961686)
			(xy 164.02786 -308.989642) (xy 163.983398 -309.01074) (xy 163.936127 -309.024432) (xy 163.887272 -309.030364)
			(xy 163.838097 -309.028383) (xy 163.789878 -309.018539) (xy 163.743862 -309.001087) (xy 163.701241 -308.97648)
			(xy 163.66312 -308.945355) (xy 163.630485 -308.908518) (xy 163.604182 -308.866922) (xy 163.584891 -308.821646)
			(xy 163.573114 -308.773862) (xy 163.569154 -308.724808) (xy 163.230306 -308.724808) (xy 163.229811 -308.749415)
			(xy 163.221916 -308.797992) (xy 163.206332 -308.844673) (xy 163.183461 -308.88825) (xy 163.153896 -308.927594)
			(xy 163.118403 -308.961686) (xy 163.0779 -308.989642) (xy 163.033438 -309.01074) (xy 162.986167 -309.024432)
			(xy 162.937312 -309.030364) (xy 162.888137 -309.028383) (xy 162.839918 -309.018539) (xy 162.793902 -309.001087)
			(xy 162.751281 -308.97648) (xy 162.71316 -308.945355) (xy 162.680525 -308.908518) (xy 162.654222 -308.866922)
			(xy 162.634931 -308.821646) (xy 162.623154 -308.773862) (xy 162.619194 -308.724808) (xy 157.099 -308.724808)
			(xy 157.099 -309.199788) (xy 157.39416 -309.199788) (xy 157.39812 -309.150734) (xy 157.409897 -309.10295)
			(xy 157.429188 -309.057674) (xy 157.455491 -309.016078) (xy 157.488126 -308.979241) (xy 157.526247 -308.948116)
			(xy 157.568868 -308.923509) (xy 157.614884 -308.906057) (xy 157.663103 -308.896213) (xy 157.712278 -308.894232)
			(xy 157.761133 -308.900164) (xy 157.808404 -308.913856) (xy 157.852866 -308.934954) (xy 157.893369 -308.96291)
			(xy 157.928862 -308.997002) (xy 157.958427 -309.036346) (xy 157.981298 -309.079923) (xy 157.996882 -309.126604)
			(xy 158.004777 -309.175181) (xy 158.005272 -309.199788) (xy 158.34412 -309.199788) (xy 158.34808 -309.150734)
			(xy 158.359857 -309.10295) (xy 158.379148 -309.057674) (xy 158.405451 -309.016078) (xy 158.438086 -308.979241)
			(xy 158.476207 -308.948116) (xy 158.518828 -308.923509) (xy 158.564844 -308.906057) (xy 158.613063 -308.896213)
			(xy 158.662238 -308.894232) (xy 158.711093 -308.900164) (xy 158.758364 -308.913856) (xy 158.802826 -308.934954)
			(xy 158.843329 -308.96291) (xy 158.878822 -308.997002) (xy 158.908387 -309.036346) (xy 158.931258 -309.079923)
			(xy 158.946842 -309.126604) (xy 158.954737 -309.175181) (xy 158.955232 -309.199788) (xy 159.29408 -309.199788)
			(xy 159.29804 -309.150734) (xy 159.309817 -309.10295) (xy 159.329108 -309.057674) (xy 159.355411 -309.016078)
			(xy 159.388046 -308.979241) (xy 159.426167 -308.948116) (xy 159.468788 -308.923509) (xy 159.514804 -308.906057)
			(xy 159.563023 -308.896213) (xy 159.612198 -308.894232) (xy 159.661053 -308.900164) (xy 159.708324 -308.913856)
			(xy 159.752786 -308.934954) (xy 159.793289 -308.96291) (xy 159.828782 -308.997002) (xy 159.858347 -309.036346)
			(xy 159.881218 -309.079923) (xy 159.896802 -309.126604) (xy 159.904697 -309.175181) (xy 159.905192 -309.199788)
			(xy 160.24404 -309.199788) (xy 160.248 -309.150734) (xy 160.259777 -309.10295) (xy 160.279068 -309.057674)
			(xy 160.305371 -309.016078) (xy 160.338006 -308.979241) (xy 160.376127 -308.948116) (xy 160.418748 -308.923509)
			(xy 160.464764 -308.906057) (xy 160.512983 -308.896213) (xy 160.562158 -308.894232) (xy 160.611013 -308.900164)
			(xy 160.658284 -308.913856) (xy 160.702746 -308.934954) (xy 160.743249 -308.96291) (xy 160.778742 -308.997002)
			(xy 160.808307 -309.036346) (xy 160.831178 -309.079923) (xy 160.846762 -309.126604) (xy 160.854657 -309.175181)
			(xy 160.855152 -309.199788) (xy 161.194254 -309.199788) (xy 161.198214 -309.150734) (xy 161.209991 -309.10295)
			(xy 161.229282 -309.057674) (xy 161.255585 -309.016078) (xy 161.28822 -308.979241) (xy 161.326341 -308.948116)
			(xy 161.368962 -308.923509) (xy 161.414978 -308.906057) (xy 161.463197 -308.896213) (xy 161.512372 -308.894232)
			(xy 161.561227 -308.900164) (xy 161.608498 -308.913856) (xy 161.65296 -308.934954) (xy 161.693463 -308.96291)
			(xy 161.728956 -308.997002) (xy 161.758521 -309.036346) (xy 161.781392 -309.079923) (xy 161.796976 -309.126604)
			(xy 161.804871 -309.175181) (xy 161.805366 -309.199788) (xy 161.804871 -309.224395) (xy 161.796976 -309.272972)
			(xy 161.781392 -309.319653) (xy 161.758521 -309.36323) (xy 161.728956 -309.402574) (xy 161.693463 -309.436666)
			(xy 161.65296 -309.464622) (xy 161.608498 -309.48572) (xy 161.561227 -309.499412) (xy 161.512372 -309.505344)
			(xy 161.463197 -309.503363) (xy 161.414978 -309.493519) (xy 161.368962 -309.476067) (xy 161.326341 -309.45146)
			(xy 161.28822 -309.420335) (xy 161.255585 -309.383498) (xy 161.229282 -309.341902) (xy 161.209991 -309.296626)
			(xy 161.198214 -309.248842) (xy 161.194254 -309.199788) (xy 160.855152 -309.199788) (xy 160.854657 -309.224395)
			(xy 160.846762 -309.272972) (xy 160.831178 -309.319653) (xy 160.808307 -309.36323) (xy 160.778742 -309.402574)
			(xy 160.743249 -309.436666) (xy 160.702746 -309.464622) (xy 160.658284 -309.48572) (xy 160.611013 -309.499412)
			(xy 160.562158 -309.505344) (xy 160.512983 -309.503363) (xy 160.464764 -309.493519) (xy 160.418748 -309.476067)
			(xy 160.376127 -309.45146) (xy 160.338006 -309.420335) (xy 160.305371 -309.383498) (xy 160.279068 -309.341902)
			(xy 160.259777 -309.296626) (xy 160.248 -309.248842) (xy 160.24404 -309.199788) (xy 159.905192 -309.199788)
			(xy 159.904697 -309.224395) (xy 159.896802 -309.272972) (xy 159.881218 -309.319653) (xy 159.858347 -309.36323)
			(xy 159.828782 -309.402574) (xy 159.793289 -309.436666) (xy 159.752786 -309.464622) (xy 159.708324 -309.48572)
			(xy 159.661053 -309.499412) (xy 159.612198 -309.505344) (xy 159.563023 -309.503363) (xy 159.514804 -309.493519)
			(xy 159.468788 -309.476067) (xy 159.426167 -309.45146) (xy 159.388046 -309.420335) (xy 159.355411 -309.383498)
			(xy 159.329108 -309.341902) (xy 159.309817 -309.296626) (xy 159.29804 -309.248842) (xy 159.29408 -309.199788)
			(xy 158.955232 -309.199788) (xy 158.954737 -309.224395) (xy 158.946842 -309.272972) (xy 158.931258 -309.319653)
			(xy 158.908387 -309.36323) (xy 158.878822 -309.402574) (xy 158.843329 -309.436666) (xy 158.802826 -309.464622)
			(xy 158.758364 -309.48572) (xy 158.711093 -309.499412) (xy 158.662238 -309.505344) (xy 158.613063 -309.503363)
			(xy 158.564844 -309.493519) (xy 158.518828 -309.476067) (xy 158.476207 -309.45146) (xy 158.438086 -309.420335)
			(xy 158.405451 -309.383498) (xy 158.379148 -309.341902) (xy 158.359857 -309.296626) (xy 158.34808 -309.248842)
			(xy 158.34412 -309.199788) (xy 158.005272 -309.199788) (xy 158.004777 -309.224395) (xy 157.996882 -309.272972)
			(xy 157.981298 -309.319653) (xy 157.958427 -309.36323) (xy 157.928862 -309.402574) (xy 157.893369 -309.436666)
			(xy 157.852866 -309.464622) (xy 157.808404 -309.48572) (xy 157.761133 -309.499412) (xy 157.712278 -309.505344)
			(xy 157.663103 -309.503363) (xy 157.614884 -309.493519) (xy 157.568868 -309.476067) (xy 157.526247 -309.45146)
			(xy 157.488126 -309.420335) (xy 157.455491 -309.383498) (xy 157.429188 -309.341902) (xy 157.409897 -309.296626)
			(xy 157.39812 -309.248842) (xy 157.39416 -309.199788) (xy 157.099 -309.199788) (xy 157.099 -310.149748)
			(xy 157.39416 -310.149748) (xy 157.39812 -310.100694) (xy 157.409897 -310.05291) (xy 157.429188 -310.007634)
			(xy 157.455491 -309.966038) (xy 157.488126 -309.929201) (xy 157.526247 -309.898076) (xy 157.568868 -309.873469)
			(xy 157.614884 -309.856017) (xy 157.663103 -309.846173) (xy 157.712278 -309.844192) (xy 157.761133 -309.850124)
			(xy 157.808404 -309.863816) (xy 157.852866 -309.884914) (xy 157.893369 -309.91287) (xy 157.928862 -309.946962)
			(xy 157.958427 -309.986306) (xy 157.981298 -310.029883) (xy 157.996882 -310.076564) (xy 158.004777 -310.125141)
			(xy 158.005272 -310.149748) (xy 158.34412 -310.149748) (xy 158.34808 -310.100694) (xy 158.359857 -310.05291)
			(xy 158.379148 -310.007634) (xy 158.405451 -309.966038) (xy 158.438086 -309.929201) (xy 158.476207 -309.898076)
			(xy 158.518828 -309.873469) (xy 158.564844 -309.856017) (xy 158.613063 -309.846173) (xy 158.662238 -309.844192)
			(xy 158.711093 -309.850124) (xy 158.758364 -309.863816) (xy 158.802826 -309.884914) (xy 158.843329 -309.91287)
			(xy 158.878822 -309.946962) (xy 158.908387 -309.986306) (xy 158.931258 -310.029883) (xy 158.946842 -310.076564)
			(xy 158.954737 -310.125141) (xy 158.955232 -310.149748) (xy 159.29408 -310.149748) (xy 159.29804 -310.100694)
			(xy 159.309817 -310.05291) (xy 159.329108 -310.007634) (xy 159.355411 -309.966038) (xy 159.388046 -309.929201)
			(xy 159.426167 -309.898076) (xy 159.468788 -309.873469) (xy 159.514804 -309.856017) (xy 159.563023 -309.846173)
			(xy 159.612198 -309.844192) (xy 159.661053 -309.850124) (xy 159.708324 -309.863816) (xy 159.752786 -309.884914)
			(xy 159.793289 -309.91287) (xy 159.828782 -309.946962) (xy 159.858347 -309.986306) (xy 159.881218 -310.029883)
			(xy 159.896802 -310.076564) (xy 159.904697 -310.125141) (xy 159.905192 -310.149748) (xy 160.24404 -310.149748)
			(xy 160.248 -310.100694) (xy 160.259777 -310.05291) (xy 160.279068 -310.007634) (xy 160.305371 -309.966038)
			(xy 160.338006 -309.929201) (xy 160.376127 -309.898076) (xy 160.418748 -309.873469) (xy 160.464764 -309.856017)
			(xy 160.512983 -309.846173) (xy 160.562158 -309.844192) (xy 160.611013 -309.850124) (xy 160.658284 -309.863816)
			(xy 160.702746 -309.884914) (xy 160.743249 -309.91287) (xy 160.778742 -309.946962) (xy 160.808307 -309.986306)
			(xy 160.831178 -310.029883) (xy 160.846762 -310.076564) (xy 160.854657 -310.125141) (xy 160.855152 -310.149748)
			(xy 161.194254 -310.149748) (xy 161.198214 -310.100694) (xy 161.209991 -310.05291) (xy 161.229282 -310.007634)
			(xy 161.255585 -309.966038) (xy 161.28822 -309.929201) (xy 161.326341 -309.898076) (xy 161.368962 -309.873469)
			(xy 161.414978 -309.856017) (xy 161.463197 -309.846173) (xy 161.512372 -309.844192) (xy 161.561227 -309.850124)
			(xy 161.608498 -309.863816) (xy 161.65296 -309.884914) (xy 161.693463 -309.91287) (xy 161.728956 -309.946962)
			(xy 161.758521 -309.986306) (xy 161.781392 -310.029883) (xy 161.796976 -310.076564) (xy 161.804871 -310.125141)
			(xy 161.805198 -310.141392) (xy 162.14433 -310.141392) (xy 162.149701 -310.09205) (xy 162.162983 -310.044228)
			(xy 162.183827 -309.999184) (xy 162.211684 -309.958105) (xy 162.245819 -309.922075) (xy 162.285333 -309.892041)
			(xy 162.329186 -309.868796) (xy 162.376222 -309.852951) (xy 162.425202 -309.844924) (xy 162.450018 -309.84444)
			(xy 162.464201 -309.844613) (xy 162.492441 -309.847288) (xy 162.506406 -309.849774) (xy 162.518852 -309.85206)
			(xy 162.542474 -309.844694) (xy 162.619944 -309.767224) (xy 162.62731 -309.743602) (xy 162.625024 -309.731156)
			(xy 162.622546 -309.71719) (xy 162.619875 -309.688951) (xy 162.61969 -309.674768) (xy 162.620212 -309.649513)
			(xy 162.628525 -309.599691) (xy 162.644926 -309.551917) (xy 162.668967 -309.507494) (xy 162.699991 -309.467634)
			(xy 162.737153 -309.433424) (xy 162.779439 -309.405798) (xy 162.825695 -309.385508) (xy 162.87466 -309.373108)
			(xy 162.924998 -309.368937) (xy 162.975336 -309.373108) (xy 163.024301 -309.385508) (xy 163.070557 -309.405798)
			(xy 163.112843 -309.433424) (xy 163.150005 -309.467634) (xy 163.181029 -309.507494) (xy 163.20507 -309.551917)
			(xy 163.221471 -309.599691) (xy 163.229784 -309.649513) (xy 163.230306 -309.674768) (xy 163.230125 -309.688951)
			(xy 163.227456 -309.717191) (xy 163.224972 -309.731156) (xy 163.222686 -309.743602) (xy 163.230052 -309.767224)
			(xy 163.307522 -309.844694) (xy 163.331144 -309.85206) (xy 163.34359 -309.849774) (xy 163.357557 -309.847303)
			(xy 163.385796 -309.844627) (xy 163.399978 -309.84444) (xy 163.4248 -309.844854) (xy 163.473791 -309.852882)
			(xy 163.520838 -309.86873) (xy 163.564701 -309.89198) (xy 163.604225 -309.92202) (xy 163.638369 -309.958059)
			(xy 163.666232 -309.999147) (xy 163.687082 -310.044201) (xy 163.700368 -310.092034) (xy 163.705739 -310.141378)
			(xy 164.04423 -310.141378) (xy 164.049603 -310.092036) (xy 164.062888 -310.044214) (xy 164.083735 -309.99917)
			(xy 164.111594 -309.958093) (xy 164.145731 -309.922063) (xy 164.185248 -309.892032) (xy 164.229103 -309.868788)
			(xy 164.27614 -309.852946) (xy 164.325121 -309.844923) (xy 164.349938 -309.84444) (xy 164.364121 -309.844611)
			(xy 164.392361 -309.847287) (xy 164.406326 -309.849774) (xy 164.418772 -309.85206) (xy 164.442394 -309.844694)
			(xy 164.519864 -309.767224) (xy 164.52723 -309.743602) (xy 164.524944 -309.731156) (xy 164.522466 -309.71719)
			(xy 164.519795 -309.688951) (xy 164.51961 -309.674768) (xy 164.520132 -309.649513) (xy 164.528445 -309.599691)
			(xy 164.544846 -309.551917) (xy 164.568887 -309.507494) (xy 164.599911 -309.467634) (xy 164.637073 -309.433424)
			(xy 164.679359 -309.405798) (xy 164.725615 -309.385508) (xy 164.77458 -309.373108) (xy 164.824918 -309.368937)
			(xy 164.875256 -309.373108) (xy 164.924221 -309.385508) (xy 164.970477 -309.405798) (xy 165.012763 -309.433424)
			(xy 165.049925 -309.467634) (xy 165.080949 -309.507494) (xy 165.10499 -309.551917) (xy 165.121391 -309.599691)
			(xy 165.129704 -309.649513) (xy 165.130226 -309.674768) (xy 165.130045 -309.688951) (xy 165.127376 -309.717191)
			(xy 165.124892 -309.731156) (xy 165.122606 -309.743602) (xy 165.129972 -309.767224) (xy 165.207442 -309.844694)
			(xy 165.231064 -309.85206) (xy 165.24351 -309.849774) (xy 165.257476 -309.8473) (xy 165.285716 -309.844627)
			(xy 165.299898 -309.84444) (xy 165.314081 -309.844616) (xy 165.342321 -309.847288) (xy 165.356286 -309.849774)
			(xy 165.368732 -309.85206) (xy 165.392354 -309.844694) (xy 165.469824 -309.767224) (xy 165.47719 -309.743602)
			(xy 165.474904 -309.731156) (xy 165.472425 -309.71719) (xy 165.469755 -309.688951) (xy 165.46957 -309.674768)
			(xy 165.470092 -309.649513) (xy 165.478405 -309.599691) (xy 165.494806 -309.551917) (xy 165.518847 -309.507494)
			(xy 165.549871 -309.467634) (xy 165.587033 -309.433424) (xy 165.629319 -309.405798) (xy 165.675575 -309.385508)
			(xy 165.72454 -309.373108) (xy 165.774878 -309.368937) (xy 165.825216 -309.373108) (xy 165.874181 -309.385508)
			(xy 165.920437 -309.405798) (xy 165.962723 -309.433424) (xy 165.999885 -309.467634) (xy 166.030909 -309.507494)
			(xy 166.05495 -309.551917) (xy 166.071351 -309.599691) (xy 166.079664 -309.649513) (xy 166.080186 -309.674768)
			(xy 166.080005 -309.688951) (xy 166.077336 -309.717191) (xy 166.074852 -309.731156) (xy 166.072566 -309.743602)
			(xy 166.079932 -309.767224) (xy 166.157402 -309.844694) (xy 166.181024 -309.85206) (xy 166.19347 -309.849774)
			(xy 166.207435 -309.847292) (xy 166.235675 -309.844624) (xy 166.249858 -309.84444) (xy 166.274682 -309.844833)
			(xy 166.323678 -309.852858) (xy 166.370729 -309.868704) (xy 166.414597 -309.891954) (xy 166.454126 -309.921994)
			(xy 166.488274 -309.958034) (xy 166.516142 -309.999123) (xy 166.536995 -310.04418) (xy 166.550285 -310.092017)
			(xy 166.55566 -310.141373) (xy 166.555207 -310.149748) (xy 166.894268 -310.149748) (xy 166.898228 -310.100694)
			(xy 166.910005 -310.05291) (xy 166.929296 -310.007634) (xy 166.955599 -309.966038) (xy 166.988234 -309.929201)
			(xy 167.026355 -309.898076) (xy 167.068976 -309.873469) (xy 167.114992 -309.856017) (xy 167.163211 -309.846173)
			(xy 167.212386 -309.844192) (xy 167.261241 -309.850124) (xy 167.308512 -309.863816) (xy 167.352974 -309.884914)
			(xy 167.393477 -309.91287) (xy 167.42897 -309.946962) (xy 167.458535 -309.986306) (xy 167.481406 -310.029883)
			(xy 167.49699 -310.076564) (xy 167.504885 -310.125141) (xy 167.50538 -310.149748) (xy 167.844228 -310.149748)
			(xy 167.848188 -310.100694) (xy 167.859965 -310.05291) (xy 167.879256 -310.007634) (xy 167.905559 -309.966038)
			(xy 167.938194 -309.929201) (xy 167.976315 -309.898076) (xy 168.018936 -309.873469) (xy 168.064952 -309.856017)
			(xy 168.113171 -309.846173) (xy 168.162346 -309.844192) (xy 168.211201 -309.850124) (xy 168.258472 -309.863816)
			(xy 168.302934 -309.884914) (xy 168.343437 -309.91287) (xy 168.37893 -309.946962) (xy 168.408495 -309.986306)
			(xy 168.431366 -310.029883) (xy 168.44695 -310.076564) (xy 168.454845 -310.125141) (xy 168.45534 -310.149748)
			(xy 168.794188 -310.149748) (xy 168.798148 -310.100694) (xy 168.809925 -310.05291) (xy 168.829216 -310.007634)
			(xy 168.855519 -309.966038) (xy 168.888154 -309.929201) (xy 168.926275 -309.898076) (xy 168.968896 -309.873469)
			(xy 169.014912 -309.856017) (xy 169.063131 -309.846173) (xy 169.112306 -309.844192) (xy 169.161161 -309.850124)
			(xy 169.208432 -309.863816) (xy 169.252894 -309.884914) (xy 169.293397 -309.91287) (xy 169.32889 -309.946962)
			(xy 169.358455 -309.986306) (xy 169.381326 -310.029883) (xy 169.39691 -310.076564) (xy 169.404805 -310.125141)
			(xy 169.4053 -310.149748) (xy 169.744148 -310.149748) (xy 169.748108 -310.100694) (xy 169.759885 -310.05291)
			(xy 169.779176 -310.007634) (xy 169.805479 -309.966038) (xy 169.838114 -309.929201) (xy 169.876235 -309.898076)
			(xy 169.918856 -309.873469) (xy 169.964872 -309.856017) (xy 170.013091 -309.846173) (xy 170.062266 -309.844192)
			(xy 170.111121 -309.850124) (xy 170.158392 -309.863816) (xy 170.202854 -309.884914) (xy 170.243357 -309.91287)
			(xy 170.27885 -309.946962) (xy 170.308415 -309.986306) (xy 170.331286 -310.029883) (xy 170.34687 -310.076564)
			(xy 170.354765 -310.125141) (xy 170.35526 -310.149748) (xy 170.694108 -310.149748) (xy 170.698068 -310.100694)
			(xy 170.709845 -310.05291) (xy 170.729136 -310.007634) (xy 170.755439 -309.966038) (xy 170.788074 -309.929201)
			(xy 170.826195 -309.898076) (xy 170.868816 -309.873469) (xy 170.914832 -309.856017) (xy 170.963051 -309.846173)
			(xy 171.012226 -309.844192) (xy 171.061081 -309.850124) (xy 171.108352 -309.863816) (xy 171.152814 -309.884914)
			(xy 171.193317 -309.91287) (xy 171.22881 -309.946962) (xy 171.258375 -309.986306) (xy 171.281246 -310.029883)
			(xy 171.29683 -310.076564) (xy 171.304725 -310.125141) (xy 171.305053 -310.141423) (xy 171.644229 -310.141423)
			(xy 171.649594 -310.092082) (xy 171.662871 -310.04426) (xy 171.683709 -309.999215) (xy 171.71156 -309.958134)
			(xy 171.74569 -309.922101) (xy 171.785199 -309.892063) (xy 171.829047 -309.868812) (xy 171.87608 -309.852961)
			(xy 171.925056 -309.844928) (xy 171.949872 -309.84444) (xy 171.964055 -309.84462) (xy 171.992295 -309.84729)
			(xy 172.00626 -309.849774) (xy 172.018706 -309.85206) (xy 172.042328 -309.844694) (xy 172.119798 -309.767224)
			(xy 172.127164 -309.743602) (xy 172.124878 -309.731156) (xy 172.122399 -309.71719) (xy 172.119729 -309.688951)
			(xy 172.119544 -309.674768) (xy 172.120066 -309.649513) (xy 172.128379 -309.599691) (xy 172.14478 -309.551917)
			(xy 172.168821 -309.507494) (xy 172.199845 -309.467634) (xy 172.237007 -309.433424) (xy 172.279293 -309.405798)
			(xy 172.325549 -309.385508) (xy 172.374514 -309.373108) (xy 172.424852 -309.368937) (xy 172.47519 -309.373108)
			(xy 172.524155 -309.385508) (xy 172.570411 -309.405798) (xy 172.612697 -309.433424) (xy 172.649859 -309.467634)
			(xy 172.680883 -309.507494) (xy 172.704924 -309.551917) (xy 172.721325 -309.599691) (xy 172.729638 -309.649513)
			(xy 172.73016 -309.674768) (xy 172.72998 -309.688951) (xy 172.72731 -309.717191) (xy 172.724826 -309.731156)
			(xy 172.724826 -309.73141) (xy 172.72337 -309.743641) (xy 172.730654 -309.767127) (xy 172.738796 -309.776368)
			(xy 172.807376 -309.844694) (xy 172.830998 -309.85206) (xy 172.843444 -309.849774) (xy 172.857472 -309.847286)
			(xy 172.88584 -309.844616) (xy 172.900086 -309.84444) (xy 172.924907 -309.844863) (xy 172.973897 -309.852892)
			(xy 173.020942 -309.86874) (xy 173.064803 -309.891991) (xy 173.104325 -309.922031) (xy 173.138467 -309.958069)
			(xy 173.166329 -309.999156) (xy 173.187176 -310.044209) (xy 173.200461 -310.092041) (xy 173.205832 -310.141393)
			(xy 173.20538 -310.149748) (xy 173.544242 -310.149748) (xy 173.548202 -310.100694) (xy 173.559979 -310.05291)
			(xy 173.57927 -310.007634) (xy 173.605573 -309.966038) (xy 173.638208 -309.929201) (xy 173.676329 -309.898076)
			(xy 173.71895 -309.873469) (xy 173.764966 -309.856017) (xy 173.813185 -309.846173) (xy 173.86236 -309.844192)
			(xy 173.911215 -309.850124) (xy 173.958486 -309.863816) (xy 174.002948 -309.884914) (xy 174.043451 -309.91287)
			(xy 174.078944 -309.946962) (xy 174.108509 -309.986306) (xy 174.13138 -310.029883) (xy 174.146964 -310.076564)
			(xy 174.154859 -310.125141) (xy 174.155354 -310.149748) (xy 174.494202 -310.149748) (xy 174.498162 -310.100694)
			(xy 174.509939 -310.05291) (xy 174.52923 -310.007634) (xy 174.555533 -309.966038) (xy 174.588168 -309.929201)
			(xy 174.626289 -309.898076) (xy 174.66891 -309.873469) (xy 174.714926 -309.856017) (xy 174.763145 -309.846173)
			(xy 174.81232 -309.844192) (xy 174.861175 -309.850124) (xy 174.908446 -309.863816) (xy 174.952908 -309.884914)
			(xy 174.993411 -309.91287) (xy 175.028904 -309.946962) (xy 175.058469 -309.986306) (xy 175.08134 -310.029883)
			(xy 175.096924 -310.076564) (xy 175.104819 -310.125141) (xy 175.105314 -310.149748) (xy 175.444162 -310.149748)
			(xy 175.448122 -310.100694) (xy 175.459899 -310.05291) (xy 175.47919 -310.007634) (xy 175.505493 -309.966038)
			(xy 175.538128 -309.929201) (xy 175.576249 -309.898076) (xy 175.61887 -309.873469) (xy 175.664886 -309.856017)
			(xy 175.713105 -309.846173) (xy 175.76228 -309.844192) (xy 175.811135 -309.850124) (xy 175.858406 -309.863816)
			(xy 175.902868 -309.884914) (xy 175.943371 -309.91287) (xy 175.978864 -309.946962) (xy 176.008429 -309.986306)
			(xy 176.0313 -310.029883) (xy 176.046884 -310.076564) (xy 176.054779 -310.125141) (xy 176.055274 -310.149748)
			(xy 176.394122 -310.149748) (xy 176.398082 -310.100694) (xy 176.409859 -310.05291) (xy 176.42915 -310.007634)
			(xy 176.455453 -309.966038) (xy 176.488088 -309.929201) (xy 176.526209 -309.898076) (xy 176.56883 -309.873469)
			(xy 176.614846 -309.856017) (xy 176.663065 -309.846173) (xy 176.71224 -309.844192) (xy 176.761095 -309.850124)
			(xy 176.808366 -309.863816) (xy 176.852828 -309.884914) (xy 176.893331 -309.91287) (xy 176.928824 -309.946962)
			(xy 176.958389 -309.986306) (xy 176.98126 -310.029883) (xy 176.996844 -310.076564) (xy 177.004739 -310.125141)
			(xy 177.005234 -310.149748) (xy 177.344082 -310.149748) (xy 177.348042 -310.100694) (xy 177.359819 -310.05291)
			(xy 177.37911 -310.007634) (xy 177.405413 -309.966038) (xy 177.438048 -309.929201) (xy 177.476169 -309.898076)
			(xy 177.51879 -309.873469) (xy 177.564806 -309.856017) (xy 177.613025 -309.846173) (xy 177.6622 -309.844192)
			(xy 177.711055 -309.850124) (xy 177.758326 -309.863816) (xy 177.802788 -309.884914) (xy 177.843291 -309.91287)
			(xy 177.878784 -309.946962) (xy 177.908349 -309.986306) (xy 177.93122 -310.029883) (xy 177.946804 -310.076564)
			(xy 177.954699 -310.125141) (xy 177.955194 -310.149748) (xy 178.294042 -310.149748) (xy 178.298002 -310.100694)
			(xy 178.309779 -310.05291) (xy 178.32907 -310.007634) (xy 178.355373 -309.966038) (xy 178.388008 -309.929201)
			(xy 178.426129 -309.898076) (xy 178.46875 -309.873469) (xy 178.514766 -309.856017) (xy 178.562985 -309.846173)
			(xy 178.61216 -309.844192) (xy 178.661015 -309.850124) (xy 178.708286 -309.863816) (xy 178.752748 -309.884914)
			(xy 178.793251 -309.91287) (xy 178.828744 -309.946962) (xy 178.858309 -309.986306) (xy 178.88118 -310.029883)
			(xy 178.896764 -310.076564) (xy 178.904659 -310.125141) (xy 178.905154 -310.149748) (xy 179.244256 -310.149748)
			(xy 179.248216 -310.100694) (xy 179.259993 -310.05291) (xy 179.279284 -310.007634) (xy 179.305587 -309.966038)
			(xy 179.338222 -309.929201) (xy 179.376343 -309.898076) (xy 179.418964 -309.873469) (xy 179.46498 -309.856017)
			(xy 179.513199 -309.846173) (xy 179.562374 -309.844192) (xy 179.611229 -309.850124) (xy 179.6585 -309.863816)
			(xy 179.702962 -309.884914) (xy 179.743465 -309.91287) (xy 179.778958 -309.946962) (xy 179.808523 -309.986306)
			(xy 179.831394 -310.029883) (xy 179.846978 -310.076564) (xy 179.854873 -310.125141) (xy 179.855368 -310.149748)
			(xy 180.194216 -310.149748) (xy 180.198176 -310.100694) (xy 180.209953 -310.05291) (xy 180.229244 -310.007634)
			(xy 180.255547 -309.966038) (xy 180.288182 -309.929201) (xy 180.326303 -309.898076) (xy 180.368924 -309.873469)
			(xy 180.41494 -309.856017) (xy 180.463159 -309.846173) (xy 180.512334 -309.844192) (xy 180.561189 -309.850124)
			(xy 180.60846 -309.863816) (xy 180.652922 -309.884914) (xy 180.693425 -309.91287) (xy 180.728918 -309.946962)
			(xy 180.758483 -309.986306) (xy 180.781354 -310.029883) (xy 180.796938 -310.076564) (xy 180.804833 -310.125141)
			(xy 180.805328 -310.149748) (xy 181.144176 -310.149748) (xy 181.148136 -310.100694) (xy 181.159913 -310.05291)
			(xy 181.179204 -310.007634) (xy 181.205507 -309.966038) (xy 181.238142 -309.929201) (xy 181.276263 -309.898076)
			(xy 181.318884 -309.873469) (xy 181.3649 -309.856017) (xy 181.413119 -309.846173) (xy 181.462294 -309.844192)
			(xy 181.511149 -309.850124) (xy 181.55842 -309.863816) (xy 181.602882 -309.884914) (xy 181.643385 -309.91287)
			(xy 181.678878 -309.946962) (xy 181.708443 -309.986306) (xy 181.731314 -310.029883) (xy 181.746898 -310.076564)
			(xy 181.754793 -310.125141) (xy 181.755288 -310.149748) (xy 182.094136 -310.149748) (xy 182.098096 -310.100694)
			(xy 182.109873 -310.05291) (xy 182.129164 -310.007634) (xy 182.155467 -309.966038) (xy 182.188102 -309.929201)
			(xy 182.226223 -309.898076) (xy 182.268844 -309.873469) (xy 182.31486 -309.856017) (xy 182.363079 -309.846173)
			(xy 182.412254 -309.844192) (xy 182.461109 -309.850124) (xy 182.50838 -309.863816) (xy 182.552842 -309.884914)
			(xy 182.593345 -309.91287) (xy 182.628838 -309.946962) (xy 182.658403 -309.986306) (xy 182.681274 -310.029883)
			(xy 182.696858 -310.076564) (xy 182.704753 -310.125141) (xy 182.705248 -310.149748) (xy 183.044096 -310.149748)
			(xy 183.048056 -310.100694) (xy 183.059833 -310.05291) (xy 183.079124 -310.007634) (xy 183.105427 -309.966038)
			(xy 183.138062 -309.929201) (xy 183.176183 -309.898076) (xy 183.218804 -309.873469) (xy 183.26482 -309.856017)
			(xy 183.313039 -309.846173) (xy 183.362214 -309.844192) (xy 183.411069 -309.850124) (xy 183.45834 -309.863816)
			(xy 183.502802 -309.884914) (xy 183.543305 -309.91287) (xy 183.578798 -309.946962) (xy 183.608363 -309.986306)
			(xy 183.631234 -310.029883) (xy 183.646818 -310.076564) (xy 183.654713 -310.125141) (xy 183.655208 -310.149748)
			(xy 183.994056 -310.149748) (xy 183.998016 -310.100694) (xy 184.009793 -310.05291) (xy 184.029084 -310.007634)
			(xy 184.055387 -309.966038) (xy 184.088022 -309.929201) (xy 184.126143 -309.898076) (xy 184.168764 -309.873469)
			(xy 184.21478 -309.856017) (xy 184.262999 -309.846173) (xy 184.312174 -309.844192) (xy 184.361029 -309.850124)
			(xy 184.4083 -309.863816) (xy 184.452762 -309.884914) (xy 184.493265 -309.91287) (xy 184.528758 -309.946962)
			(xy 184.558323 -309.986306) (xy 184.581194 -310.029883) (xy 184.596778 -310.076564) (xy 184.604673 -310.125141)
			(xy 184.605168 -310.149748) (xy 184.94427 -310.149748) (xy 184.94823 -310.100694) (xy 184.960007 -310.05291)
			(xy 184.979298 -310.007634) (xy 185.005601 -309.966038) (xy 185.038236 -309.929201) (xy 185.076357 -309.898076)
			(xy 185.118978 -309.873469) (xy 185.164994 -309.856017) (xy 185.213213 -309.846173) (xy 185.262388 -309.844192)
			(xy 185.311243 -309.850124) (xy 185.358514 -309.863816) (xy 185.402976 -309.884914) (xy 185.443479 -309.91287)
			(xy 185.478972 -309.946962) (xy 185.508537 -309.986306) (xy 185.531408 -310.029883) (xy 185.546992 -310.076564)
			(xy 185.554887 -310.125141) (xy 185.555382 -310.149748) (xy 185.89423 -310.149748) (xy 185.89819 -310.100694)
			(xy 185.909967 -310.05291) (xy 185.929258 -310.007634) (xy 185.955561 -309.966038) (xy 185.988196 -309.929201)
			(xy 186.026317 -309.898076) (xy 186.068938 -309.873469) (xy 186.114954 -309.856017) (xy 186.163173 -309.846173)
			(xy 186.212348 -309.844192) (xy 186.261203 -309.850124) (xy 186.308474 -309.863816) (xy 186.352936 -309.884914)
			(xy 186.393439 -309.91287) (xy 186.428932 -309.946962) (xy 186.458497 -309.986306) (xy 186.481368 -310.029883)
			(xy 186.496952 -310.076564) (xy 186.504847 -310.125141) (xy 186.505342 -310.149748) (xy 186.84419 -310.149748)
			(xy 186.84815 -310.100694) (xy 186.859927 -310.05291) (xy 186.879218 -310.007634) (xy 186.905521 -309.966038)
			(xy 186.938156 -309.929201) (xy 186.976277 -309.898076) (xy 187.018898 -309.873469) (xy 187.064914 -309.856017)
			(xy 187.113133 -309.846173) (xy 187.162308 -309.844192) (xy 187.211163 -309.850124) (xy 187.258434 -309.863816)
			(xy 187.302896 -309.884914) (xy 187.343399 -309.91287) (xy 187.378892 -309.946962) (xy 187.408457 -309.986306)
			(xy 187.431328 -310.029883) (xy 187.446912 -310.076564) (xy 187.454807 -310.125141) (xy 187.455302 -310.149748)
			(xy 187.79415 -310.149748) (xy 187.79811 -310.100694) (xy 187.809887 -310.05291) (xy 187.829178 -310.007634)
			(xy 187.855481 -309.966038) (xy 187.888116 -309.929201) (xy 187.926237 -309.898076) (xy 187.968858 -309.873469)
			(xy 188.014874 -309.856017) (xy 188.063093 -309.846173) (xy 188.112268 -309.844192) (xy 188.161123 -309.850124)
			(xy 188.208394 -309.863816) (xy 188.252856 -309.884914) (xy 188.293359 -309.91287) (xy 188.328852 -309.946962)
			(xy 188.358417 -309.986306) (xy 188.381288 -310.029883) (xy 188.396872 -310.076564) (xy 188.404767 -310.125141)
			(xy 188.405262 -310.149748) (xy 188.74411 -310.149748) (xy 188.74807 -310.100694) (xy 188.759847 -310.05291)
			(xy 188.779138 -310.007634) (xy 188.805441 -309.966038) (xy 188.838076 -309.929201) (xy 188.876197 -309.898076)
			(xy 188.918818 -309.873469) (xy 188.964834 -309.856017) (xy 189.013053 -309.846173) (xy 189.062228 -309.844192)
			(xy 189.111083 -309.850124) (xy 189.158354 -309.863816) (xy 189.202816 -309.884914) (xy 189.243319 -309.91287)
			(xy 189.278812 -309.946962) (xy 189.308377 -309.986306) (xy 189.331248 -310.029883) (xy 189.346832 -310.076564)
			(xy 189.354727 -310.125141) (xy 189.355222 -310.149748) (xy 189.69407 -310.149748) (xy 189.69803 -310.100694)
			(xy 189.709807 -310.05291) (xy 189.729098 -310.007634) (xy 189.755401 -309.966038) (xy 189.788036 -309.929201)
			(xy 189.826157 -309.898076) (xy 189.868778 -309.873469) (xy 189.914794 -309.856017) (xy 189.963013 -309.846173)
			(xy 190.012188 -309.844192) (xy 190.061043 -309.850124) (xy 190.108314 -309.863816) (xy 190.152776 -309.884914)
			(xy 190.193279 -309.91287) (xy 190.228772 -309.946962) (xy 190.258337 -309.986306) (xy 190.281208 -310.029883)
			(xy 190.296792 -310.076564) (xy 190.304687 -310.125141) (xy 190.305182 -310.149748) (xy 190.644284 -310.149748)
			(xy 190.648244 -310.100694) (xy 190.660021 -310.05291) (xy 190.679312 -310.007634) (xy 190.705615 -309.966038)
			(xy 190.73825 -309.929201) (xy 190.776371 -309.898076) (xy 190.818992 -309.873469) (xy 190.865008 -309.856017)
			(xy 190.913227 -309.846173) (xy 190.962402 -309.844192) (xy 191.011257 -309.850124) (xy 191.058528 -309.863816)
			(xy 191.10299 -309.884914) (xy 191.143493 -309.91287) (xy 191.178986 -309.946962) (xy 191.208551 -309.986306)
			(xy 191.231422 -310.029883) (xy 191.247006 -310.076564) (xy 191.254901 -310.125141) (xy 191.255396 -310.149748)
			(xy 191.594244 -310.149748) (xy 191.598204 -310.100694) (xy 191.609981 -310.05291) (xy 191.629272 -310.007634)
			(xy 191.655575 -309.966038) (xy 191.68821 -309.929201) (xy 191.726331 -309.898076) (xy 191.768952 -309.873469)
			(xy 191.814968 -309.856017) (xy 191.863187 -309.846173) (xy 191.912362 -309.844192) (xy 191.961217 -309.850124)
			(xy 192.008488 -309.863816) (xy 192.05295 -309.884914) (xy 192.093453 -309.91287) (xy 192.128946 -309.946962)
			(xy 192.158511 -309.986306) (xy 192.181382 -310.029883) (xy 192.196966 -310.076564) (xy 192.204861 -310.125141)
			(xy 192.205356 -310.149748) (xy 192.204861 -310.174355) (xy 192.196966 -310.222932) (xy 192.181382 -310.269613)
			(xy 192.158511 -310.31319) (xy 192.128946 -310.352534) (xy 192.093453 -310.386626) (xy 192.05295 -310.414582)
			(xy 192.008488 -310.43568) (xy 191.961217 -310.449372) (xy 191.912362 -310.455304) (xy 191.863187 -310.453323)
			(xy 191.814968 -310.443479) (xy 191.768952 -310.426027) (xy 191.726331 -310.40142) (xy 191.68821 -310.370295)
			(xy 191.655575 -310.333458) (xy 191.629272 -310.291862) (xy 191.609981 -310.246586) (xy 191.598204 -310.198802)
			(xy 191.594244 -310.149748) (xy 191.255396 -310.149748) (xy 191.254901 -310.174355) (xy 191.247006 -310.222932)
			(xy 191.231422 -310.269613) (xy 191.208551 -310.31319) (xy 191.178986 -310.352534) (xy 191.143493 -310.386626)
			(xy 191.10299 -310.414582) (xy 191.058528 -310.43568) (xy 191.011257 -310.449372) (xy 190.962402 -310.455304)
			(xy 190.913227 -310.453323) (xy 190.865008 -310.443479) (xy 190.818992 -310.426027) (xy 190.776371 -310.40142)
			(xy 190.73825 -310.370295) (xy 190.705615 -310.333458) (xy 190.679312 -310.291862) (xy 190.660021 -310.246586)
			(xy 190.648244 -310.198802) (xy 190.644284 -310.149748) (xy 190.305182 -310.149748) (xy 190.304687 -310.174355)
			(xy 190.296792 -310.222932) (xy 190.281208 -310.269613) (xy 190.258337 -310.31319) (xy 190.228772 -310.352534)
			(xy 190.193279 -310.386626) (xy 190.152776 -310.414582) (xy 190.108314 -310.43568) (xy 190.061043 -310.449372)
			(xy 190.012188 -310.455304) (xy 189.963013 -310.453323) (xy 189.914794 -310.443479) (xy 189.868778 -310.426027)
			(xy 189.826157 -310.40142) (xy 189.788036 -310.370295) (xy 189.755401 -310.333458) (xy 189.729098 -310.291862)
			(xy 189.709807 -310.246586) (xy 189.69803 -310.198802) (xy 189.69407 -310.149748) (xy 189.355222 -310.149748)
			(xy 189.354727 -310.174355) (xy 189.346832 -310.222932) (xy 189.331248 -310.269613) (xy 189.308377 -310.31319)
			(xy 189.278812 -310.352534) (xy 189.243319 -310.386626) (xy 189.202816 -310.414582) (xy 189.158354 -310.43568)
			(xy 189.111083 -310.449372) (xy 189.062228 -310.455304) (xy 189.013053 -310.453323) (xy 188.964834 -310.443479)
			(xy 188.918818 -310.426027) (xy 188.876197 -310.40142) (xy 188.838076 -310.370295) (xy 188.805441 -310.333458)
			(xy 188.779138 -310.291862) (xy 188.759847 -310.246586) (xy 188.74807 -310.198802) (xy 188.74411 -310.149748)
			(xy 188.405262 -310.149748) (xy 188.404767 -310.174355) (xy 188.396872 -310.222932) (xy 188.381288 -310.269613)
			(xy 188.358417 -310.31319) (xy 188.328852 -310.352534) (xy 188.293359 -310.386626) (xy 188.252856 -310.414582)
			(xy 188.208394 -310.43568) (xy 188.161123 -310.449372) (xy 188.112268 -310.455304) (xy 188.063093 -310.453323)
			(xy 188.014874 -310.443479) (xy 187.968858 -310.426027) (xy 187.926237 -310.40142) (xy 187.888116 -310.370295)
			(xy 187.855481 -310.333458) (xy 187.829178 -310.291862) (xy 187.809887 -310.246586) (xy 187.79811 -310.198802)
			(xy 187.79415 -310.149748) (xy 187.455302 -310.149748) (xy 187.454807 -310.174355) (xy 187.446912 -310.222932)
			(xy 187.431328 -310.269613) (xy 187.408457 -310.31319) (xy 187.378892 -310.352534) (xy 187.343399 -310.386626)
			(xy 187.302896 -310.414582) (xy 187.258434 -310.43568) (xy 187.211163 -310.449372) (xy 187.162308 -310.455304)
			(xy 187.113133 -310.453323) (xy 187.064914 -310.443479) (xy 187.018898 -310.426027) (xy 186.976277 -310.40142)
			(xy 186.938156 -310.370295) (xy 186.905521 -310.333458) (xy 186.879218 -310.291862) (xy 186.859927 -310.246586)
			(xy 186.84815 -310.198802) (xy 186.84419 -310.149748) (xy 186.505342 -310.149748) (xy 186.504847 -310.174355)
			(xy 186.496952 -310.222932) (xy 186.481368 -310.269613) (xy 186.458497 -310.31319) (xy 186.428932 -310.352534)
			(xy 186.393439 -310.386626) (xy 186.352936 -310.414582) (xy 186.308474 -310.43568) (xy 186.261203 -310.449372)
			(xy 186.212348 -310.455304) (xy 186.163173 -310.453323) (xy 186.114954 -310.443479) (xy 186.068938 -310.426027)
			(xy 186.026317 -310.40142) (xy 185.988196 -310.370295) (xy 185.955561 -310.333458) (xy 185.929258 -310.291862)
			(xy 185.909967 -310.246586) (xy 185.89819 -310.198802) (xy 185.89423 -310.149748) (xy 185.555382 -310.149748)
			(xy 185.554887 -310.174355) (xy 185.546992 -310.222932) (xy 185.531408 -310.269613) (xy 185.508537 -310.31319)
			(xy 185.478972 -310.352534) (xy 185.443479 -310.386626) (xy 185.402976 -310.414582) (xy 185.358514 -310.43568)
			(xy 185.311243 -310.449372) (xy 185.262388 -310.455304) (xy 185.213213 -310.453323) (xy 185.164994 -310.443479)
			(xy 185.118978 -310.426027) (xy 185.076357 -310.40142) (xy 185.038236 -310.370295) (xy 185.005601 -310.333458)
			(xy 184.979298 -310.291862) (xy 184.960007 -310.246586) (xy 184.94823 -310.198802) (xy 184.94427 -310.149748)
			(xy 184.605168 -310.149748) (xy 184.604673 -310.174355) (xy 184.596778 -310.222932) (xy 184.581194 -310.269613)
			(xy 184.558323 -310.31319) (xy 184.528758 -310.352534) (xy 184.493265 -310.386626) (xy 184.452762 -310.414582)
			(xy 184.4083 -310.43568) (xy 184.361029 -310.449372) (xy 184.312174 -310.455304) (xy 184.262999 -310.453323)
			(xy 184.21478 -310.443479) (xy 184.168764 -310.426027) (xy 184.126143 -310.40142) (xy 184.088022 -310.370295)
			(xy 184.055387 -310.333458) (xy 184.029084 -310.291862) (xy 184.009793 -310.246586) (xy 183.998016 -310.198802)
			(xy 183.994056 -310.149748) (xy 183.655208 -310.149748) (xy 183.654713 -310.174355) (xy 183.646818 -310.222932)
			(xy 183.631234 -310.269613) (xy 183.608363 -310.31319) (xy 183.578798 -310.352534) (xy 183.543305 -310.386626)
			(xy 183.502802 -310.414582) (xy 183.45834 -310.43568) (xy 183.411069 -310.449372) (xy 183.362214 -310.455304)
			(xy 183.313039 -310.453323) (xy 183.26482 -310.443479) (xy 183.218804 -310.426027) (xy 183.176183 -310.40142)
			(xy 183.138062 -310.370295) (xy 183.105427 -310.333458) (xy 183.079124 -310.291862) (xy 183.059833 -310.246586)
			(xy 183.048056 -310.198802) (xy 183.044096 -310.149748) (xy 182.705248 -310.149748) (xy 182.704753 -310.174355)
			(xy 182.696858 -310.222932) (xy 182.681274 -310.269613) (xy 182.658403 -310.31319) (xy 182.628838 -310.352534)
			(xy 182.593345 -310.386626) (xy 182.552842 -310.414582) (xy 182.50838 -310.43568) (xy 182.461109 -310.449372)
			(xy 182.412254 -310.455304) (xy 182.363079 -310.453323) (xy 182.31486 -310.443479) (xy 182.268844 -310.426027)
			(xy 182.226223 -310.40142) (xy 182.188102 -310.370295) (xy 182.155467 -310.333458) (xy 182.129164 -310.291862)
			(xy 182.109873 -310.246586) (xy 182.098096 -310.198802) (xy 182.094136 -310.149748) (xy 181.755288 -310.149748)
			(xy 181.754793 -310.174355) (xy 181.746898 -310.222932) (xy 181.731314 -310.269613) (xy 181.708443 -310.31319)
			(xy 181.678878 -310.352534) (xy 181.643385 -310.386626) (xy 181.602882 -310.414582) (xy 181.55842 -310.43568)
			(xy 181.511149 -310.449372) (xy 181.462294 -310.455304) (xy 181.413119 -310.453323) (xy 181.3649 -310.443479)
			(xy 181.318884 -310.426027) (xy 181.276263 -310.40142) (xy 181.238142 -310.370295) (xy 181.205507 -310.333458)
			(xy 181.179204 -310.291862) (xy 181.159913 -310.246586) (xy 181.148136 -310.198802) (xy 181.144176 -310.149748)
			(xy 180.805328 -310.149748) (xy 180.804833 -310.174355) (xy 180.796938 -310.222932) (xy 180.781354 -310.269613)
			(xy 180.758483 -310.31319) (xy 180.728918 -310.352534) (xy 180.693425 -310.386626) (xy 180.652922 -310.414582)
			(xy 180.60846 -310.43568) (xy 180.561189 -310.449372) (xy 180.512334 -310.455304) (xy 180.463159 -310.453323)
			(xy 180.41494 -310.443479) (xy 180.368924 -310.426027) (xy 180.326303 -310.40142) (xy 180.288182 -310.370295)
			(xy 180.255547 -310.333458) (xy 180.229244 -310.291862) (xy 180.209953 -310.246586) (xy 180.198176 -310.198802)
			(xy 180.194216 -310.149748) (xy 179.855368 -310.149748) (xy 179.854873 -310.174355) (xy 179.846978 -310.222932)
			(xy 179.831394 -310.269613) (xy 179.808523 -310.31319) (xy 179.778958 -310.352534) (xy 179.743465 -310.386626)
			(xy 179.702962 -310.414582) (xy 179.6585 -310.43568) (xy 179.611229 -310.449372) (xy 179.562374 -310.455304)
			(xy 179.513199 -310.453323) (xy 179.46498 -310.443479) (xy 179.418964 -310.426027) (xy 179.376343 -310.40142)
			(xy 179.338222 -310.370295) (xy 179.305587 -310.333458) (xy 179.279284 -310.291862) (xy 179.259993 -310.246586)
			(xy 179.248216 -310.198802) (xy 179.244256 -310.149748) (xy 178.905154 -310.149748) (xy 178.904659 -310.174355)
			(xy 178.896764 -310.222932) (xy 178.88118 -310.269613) (xy 178.858309 -310.31319) (xy 178.828744 -310.352534)
			(xy 178.793251 -310.386626) (xy 178.752748 -310.414582) (xy 178.708286 -310.43568) (xy 178.661015 -310.449372)
			(xy 178.61216 -310.455304) (xy 178.562985 -310.453323) (xy 178.514766 -310.443479) (xy 178.46875 -310.426027)
			(xy 178.426129 -310.40142) (xy 178.388008 -310.370295) (xy 178.355373 -310.333458) (xy 178.32907 -310.291862)
			(xy 178.309779 -310.246586) (xy 178.298002 -310.198802) (xy 178.294042 -310.149748) (xy 177.955194 -310.149748)
			(xy 177.954699 -310.174355) (xy 177.946804 -310.222932) (xy 177.93122 -310.269613) (xy 177.908349 -310.31319)
			(xy 177.878784 -310.352534) (xy 177.843291 -310.386626) (xy 177.802788 -310.414582) (xy 177.758326 -310.43568)
			(xy 177.711055 -310.449372) (xy 177.6622 -310.455304) (xy 177.613025 -310.453323) (xy 177.564806 -310.443479)
			(xy 177.51879 -310.426027) (xy 177.476169 -310.40142) (xy 177.438048 -310.370295) (xy 177.405413 -310.333458)
			(xy 177.37911 -310.291862) (xy 177.359819 -310.246586) (xy 177.348042 -310.198802) (xy 177.344082 -310.149748)
			(xy 177.005234 -310.149748) (xy 177.004739 -310.174355) (xy 176.996844 -310.222932) (xy 176.98126 -310.269613)
			(xy 176.958389 -310.31319) (xy 176.928824 -310.352534) (xy 176.893331 -310.386626) (xy 176.852828 -310.414582)
			(xy 176.808366 -310.43568) (xy 176.761095 -310.449372) (xy 176.71224 -310.455304) (xy 176.663065 -310.453323)
			(xy 176.614846 -310.443479) (xy 176.56883 -310.426027) (xy 176.526209 -310.40142) (xy 176.488088 -310.370295)
			(xy 176.455453 -310.333458) (xy 176.42915 -310.291862) (xy 176.409859 -310.246586) (xy 176.398082 -310.198802)
			(xy 176.394122 -310.149748) (xy 176.055274 -310.149748) (xy 176.054779 -310.174355) (xy 176.046884 -310.222932)
			(xy 176.0313 -310.269613) (xy 176.008429 -310.31319) (xy 175.978864 -310.352534) (xy 175.943371 -310.386626)
			(xy 175.902868 -310.414582) (xy 175.858406 -310.43568) (xy 175.811135 -310.449372) (xy 175.76228 -310.455304)
			(xy 175.713105 -310.453323) (xy 175.664886 -310.443479) (xy 175.61887 -310.426027) (xy 175.576249 -310.40142)
			(xy 175.538128 -310.370295) (xy 175.505493 -310.333458) (xy 175.47919 -310.291862) (xy 175.459899 -310.246586)
			(xy 175.448122 -310.198802) (xy 175.444162 -310.149748) (xy 175.105314 -310.149748) (xy 175.104819 -310.174355)
			(xy 175.096924 -310.222932) (xy 175.08134 -310.269613) (xy 175.058469 -310.31319) (xy 175.028904 -310.352534)
			(xy 174.993411 -310.386626) (xy 174.952908 -310.414582) (xy 174.908446 -310.43568) (xy 174.861175 -310.449372)
			(xy 174.81232 -310.455304) (xy 174.763145 -310.453323) (xy 174.714926 -310.443479) (xy 174.66891 -310.426027)
			(xy 174.626289 -310.40142) (xy 174.588168 -310.370295) (xy 174.555533 -310.333458) (xy 174.52923 -310.291862)
			(xy 174.509939 -310.246586) (xy 174.498162 -310.198802) (xy 174.494202 -310.149748) (xy 174.155354 -310.149748)
			(xy 174.154859 -310.174355) (xy 174.146964 -310.222932) (xy 174.13138 -310.269613) (xy 174.108509 -310.31319)
			(xy 174.078944 -310.352534) (xy 174.043451 -310.386626) (xy 174.002948 -310.414582) (xy 173.958486 -310.43568)
			(xy 173.911215 -310.449372) (xy 173.86236 -310.455304) (xy 173.813185 -310.453323) (xy 173.764966 -310.443479)
			(xy 173.71895 -310.426027) (xy 173.676329 -310.40142) (xy 173.638208 -310.370295) (xy 173.605573 -310.333458)
			(xy 173.57927 -310.291862) (xy 173.559979 -310.246586) (xy 173.548202 -310.198802) (xy 173.544242 -310.149748)
			(xy 173.20538 -310.149748) (xy 173.203149 -310.190963) (xy 173.192481 -310.239446) (xy 173.174111 -310.285565)
			(xy 173.148521 -310.328104) (xy 173.116387 -310.365943) (xy 173.078554 -310.398085) (xy 173.03602 -310.423683)
			(xy 172.989905 -310.442063) (xy 172.941425 -310.45274) (xy 172.891855 -310.455434) (xy 172.842502 -310.450073)
			(xy 172.794667 -310.436798) (xy 172.74961 -310.415959) (xy 172.708517 -310.388106) (xy 172.672472 -310.353971)
			(xy 172.642424 -310.314455) (xy 172.619165 -310.270599) (xy 172.603307 -310.223557) (xy 172.595268 -310.174569)
			(xy 172.594778 -310.149748) (xy 172.594962 -310.135565) (xy 172.597629 -310.107325) (xy 172.600112 -310.09336)
			(xy 172.600112 -310.093106) (xy 172.601613 -310.080877) (xy 172.594296 -310.057387) (xy 172.586142 -310.048148)
			(xy 172.517562 -309.979822) (xy 172.49394 -309.972456) (xy 172.481494 -309.974742) (xy 172.467465 -309.977225)
			(xy 172.439098 -309.979898) (xy 172.424852 -309.980076) (xy 172.410669 -309.979893) (xy 172.382429 -309.977225)
			(xy 172.368464 -309.974742) (xy 172.356018 -309.972456) (xy 172.332396 -309.979822) (xy 172.254926 -310.057292)
			(xy 172.24756 -310.080914) (xy 172.249846 -310.09336) (xy 172.252326 -310.107325) (xy 172.254996 -310.135565)
			(xy 172.25518 -310.149748) (xy 172.25467 -310.174564) (xy 172.246634 -310.22354) (xy 172.23078 -310.270571)
			(xy 172.207526 -310.314418) (xy 172.177486 -310.353925) (xy 172.14145 -310.388052) (xy 172.100368 -310.415901)
			(xy 172.055321 -310.436736) (xy 172.007498 -310.450009) (xy 171.958157 -310.455371) (xy 171.908599 -310.452681)
			(xy 171.860129 -310.442009) (xy 171.814023 -310.423636) (xy 171.771498 -310.398046) (xy 171.733672 -310.365914)
			(xy 171.701542 -310.328086) (xy 171.675955 -310.285559) (xy 171.657585 -310.239452) (xy 171.646916 -310.190981)
			(xy 171.644229 -310.141423) (xy 171.305053 -310.141423) (xy 171.30522 -310.149748) (xy 171.304725 -310.174355)
			(xy 171.29683 -310.222932) (xy 171.281246 -310.269613) (xy 171.258375 -310.31319) (xy 171.22881 -310.352534)
			(xy 171.193317 -310.386626) (xy 171.152814 -310.414582) (xy 171.108352 -310.43568) (xy 171.061081 -310.449372)
			(xy 171.012226 -310.455304) (xy 170.963051 -310.453323) (xy 170.914832 -310.443479) (xy 170.868816 -310.426027)
			(xy 170.826195 -310.40142) (xy 170.788074 -310.370295) (xy 170.755439 -310.333458) (xy 170.729136 -310.291862)
			(xy 170.709845 -310.246586) (xy 170.698068 -310.198802) (xy 170.694108 -310.149748) (xy 170.35526 -310.149748)
			(xy 170.354765 -310.174355) (xy 170.34687 -310.222932) (xy 170.331286 -310.269613) (xy 170.308415 -310.31319)
			(xy 170.27885 -310.352534) (xy 170.243357 -310.386626) (xy 170.202854 -310.414582) (xy 170.158392 -310.43568)
			(xy 170.111121 -310.449372) (xy 170.062266 -310.455304) (xy 170.013091 -310.453323) (xy 169.964872 -310.443479)
			(xy 169.918856 -310.426027) (xy 169.876235 -310.40142) (xy 169.838114 -310.370295) (xy 169.805479 -310.333458)
			(xy 169.779176 -310.291862) (xy 169.759885 -310.246586) (xy 169.748108 -310.198802) (xy 169.744148 -310.149748)
			(xy 169.4053 -310.149748) (xy 169.404805 -310.174355) (xy 169.39691 -310.222932) (xy 169.381326 -310.269613)
			(xy 169.358455 -310.31319) (xy 169.32889 -310.352534) (xy 169.293397 -310.386626) (xy 169.252894 -310.414582)
			(xy 169.208432 -310.43568) (xy 169.161161 -310.449372) (xy 169.112306 -310.455304) (xy 169.063131 -310.453323)
			(xy 169.014912 -310.443479) (xy 168.968896 -310.426027) (xy 168.926275 -310.40142) (xy 168.888154 -310.370295)
			(xy 168.855519 -310.333458) (xy 168.829216 -310.291862) (xy 168.809925 -310.246586) (xy 168.798148 -310.198802)
			(xy 168.794188 -310.149748) (xy 168.45534 -310.149748) (xy 168.454845 -310.174355) (xy 168.44695 -310.222932)
			(xy 168.431366 -310.269613) (xy 168.408495 -310.31319) (xy 168.37893 -310.352534) (xy 168.343437 -310.386626)
			(xy 168.302934 -310.414582) (xy 168.258472 -310.43568) (xy 168.211201 -310.449372) (xy 168.162346 -310.455304)
			(xy 168.113171 -310.453323) (xy 168.064952 -310.443479) (xy 168.018936 -310.426027) (xy 167.976315 -310.40142)
			(xy 167.938194 -310.370295) (xy 167.905559 -310.333458) (xy 167.879256 -310.291862) (xy 167.859965 -310.246586)
			(xy 167.848188 -310.198802) (xy 167.844228 -310.149748) (xy 167.50538 -310.149748) (xy 167.504885 -310.174355)
			(xy 167.49699 -310.222932) (xy 167.481406 -310.269613) (xy 167.458535 -310.31319) (xy 167.42897 -310.352534)
			(xy 167.393477 -310.386626) (xy 167.352974 -310.414582) (xy 167.308512 -310.43568) (xy 167.261241 -310.449372)
			(xy 167.212386 -310.455304) (xy 167.163211 -310.453323) (xy 167.114992 -310.443479) (xy 167.068976 -310.426027)
			(xy 167.026355 -310.40142) (xy 166.988234 -310.370295) (xy 166.955599 -310.333458) (xy 166.929296 -310.291862)
			(xy 166.910005 -310.246586) (xy 166.898228 -310.198802) (xy 166.894268 -310.149748) (xy 166.555207 -310.149748)
			(xy 166.552979 -310.190949) (xy 166.542313 -310.239438) (xy 166.523943 -310.285563) (xy 166.498353 -310.328108)
			(xy 166.466217 -310.365953) (xy 166.428381 -310.3981) (xy 166.385844 -310.423703) (xy 166.339724 -310.442087)
			(xy 166.291238 -310.452767) (xy 166.241663 -310.455462) (xy 166.192305 -310.450102) (xy 166.144465 -310.436827)
			(xy 166.099402 -310.415987) (xy 166.058304 -310.388131) (xy 166.022254 -310.353993) (xy 165.992202 -310.314473)
			(xy 165.96894 -310.270612) (xy 165.95308 -310.223565) (xy 165.94504 -310.174572) (xy 165.94455 -310.149748)
			(xy 165.944734 -310.135565) (xy 165.947401 -310.107325) (xy 165.949884 -310.09336) (xy 165.95217 -310.080914)
			(xy 165.944804 -310.057292) (xy 165.867334 -309.979822) (xy 165.843712 -309.972456) (xy 165.831266 -309.974742)
			(xy 165.8173 -309.977219) (xy 165.789061 -309.97989) (xy 165.774878 -309.980076) (xy 165.760695 -309.979903)
			(xy 165.732455 -309.977229) (xy 165.71849 -309.974742) (xy 165.706044 -309.972456) (xy 165.682422 -309.979822)
			(xy 165.604952 -310.057292) (xy 165.597586 -310.080914) (xy 165.599872 -310.09336) (xy 165.602353 -310.107325)
			(xy 165.605022 -310.135565) (xy 165.605206 -310.149748) (xy 165.604684 -310.175003) (xy 165.596371 -310.224825)
			(xy 165.57997 -310.272599) (xy 165.555929 -310.317022) (xy 165.524905 -310.356882) (xy 165.487743 -310.391092)
			(xy 165.445457 -310.418718) (xy 165.399201 -310.439008) (xy 165.350236 -310.451408) (xy 165.299898 -310.455579)
			(xy 165.24956 -310.451408) (xy 165.200595 -310.439008) (xy 165.154339 -310.418718) (xy 165.112053 -310.391092)
			(xy 165.074891 -310.356882) (xy 165.043867 -310.317022) (xy 165.019826 -310.272599) (xy 165.003425 -310.224825)
			(xy 164.995112 -310.175003) (xy 164.99459 -310.149748) (xy 164.994773 -310.135565) (xy 164.997441 -310.107325)
			(xy 164.999924 -310.09336) (xy 165.00221 -310.080914) (xy 164.994844 -310.057292) (xy 164.917374 -309.979822)
			(xy 164.893752 -309.972456) (xy 164.881306 -309.974742) (xy 164.867339 -309.977213) (xy 164.8391 -309.979889)
			(xy 164.824918 -309.980076) (xy 164.810735 -309.979897) (xy 164.782495 -309.977227) (xy 164.76853 -309.974742)
			(xy 164.756084 -309.972456) (xy 164.732462 -309.979822) (xy 164.654992 -310.057292) (xy 164.647626 -310.080914)
			(xy 164.649912 -310.09336) (xy 164.652393 -310.107325) (xy 164.655062 -310.135565) (xy 164.655246 -310.149748)
			(xy 164.65467 -310.174565) (xy 164.646633 -310.223543) (xy 164.630778 -310.270576) (xy 164.607522 -310.314424)
			(xy 164.577479 -310.353933) (xy 164.54144 -310.38806) (xy 164.500355 -310.415908) (xy 164.455305 -310.436742)
			(xy 164.407479 -310.450013) (xy 164.358136 -310.455372) (xy 164.308575 -310.452678) (xy 164.260104 -310.442001)
			(xy 164.213998 -310.423623) (xy 164.171473 -310.398028) (xy 164.133648 -310.365891) (xy 164.101522 -310.328057)
			(xy 164.075939 -310.285525) (xy 164.057574 -310.239414) (xy 164.046911 -310.190939) (xy 164.04423 -310.141378)
			(xy 163.705739 -310.141378) (xy 163.70574 -310.141387) (xy 163.703057 -310.190959) (xy 163.69239 -310.239444)
			(xy 163.67402 -310.285564) (xy 163.64843 -310.328105) (xy 163.616296 -310.365946) (xy 163.578462 -310.398089)
			(xy 163.535927 -310.423689) (xy 163.489811 -310.44207) (xy 163.441328 -310.452748) (xy 163.391757 -310.455442)
			(xy 163.342403 -310.450081) (xy 163.294567 -310.436806) (xy 163.249508 -310.415967) (xy 163.208414 -310.388113)
			(xy 163.172367 -310.353978) (xy 163.142318 -310.31446) (xy 163.119058 -310.270603) (xy 163.103199 -310.223559)
			(xy 163.09516 -310.17457) (xy 163.09467 -310.149748) (xy 163.094854 -310.135565) (xy 163.097521 -310.107325)
			(xy 163.100004 -310.09336) (xy 163.10229 -310.080914) (xy 163.094924 -310.057292) (xy 163.017454 -309.979822)
			(xy 162.993832 -309.972456) (xy 162.981386 -309.974742) (xy 162.96742 -309.977216) (xy 162.93918 -309.97989)
			(xy 162.924998 -309.980076) (xy 162.910815 -309.9799) (xy 162.882575 -309.977228) (xy 162.86861 -309.974742)
			(xy 162.856164 -309.972456) (xy 162.832542 -309.979822) (xy 162.755072 -310.057292) (xy 162.747706 -310.080914)
			(xy 162.749992 -310.09336) (xy 162.752473 -310.107325) (xy 162.755142 -310.135565) (xy 162.755326 -310.149748)
			(xy 162.75477 -310.174564) (xy 162.746733 -310.223542) (xy 162.730878 -310.270575) (xy 162.707623 -310.314422)
			(xy 162.677581 -310.35393) (xy 162.641543 -310.388058) (xy 162.600459 -310.415906) (xy 162.55541 -310.43674)
			(xy 162.507585 -310.450012) (xy 162.458242 -310.455372) (xy 162.408682 -310.452679) (xy 162.360211 -310.442003)
			(xy 162.314106 -310.423627) (xy 162.27158 -310.398034) (xy 162.233755 -310.365898) (xy 162.201628 -310.328066)
			(xy 162.176044 -310.285535) (xy 162.157677 -310.239426) (xy 162.147012 -310.190952) (xy 162.14433 -310.141392)
			(xy 161.805198 -310.141392) (xy 161.805366 -310.149748) (xy 161.804871 -310.174355) (xy 161.796976 -310.222932)
			(xy 161.781392 -310.269613) (xy 161.758521 -310.31319) (xy 161.728956 -310.352534) (xy 161.693463 -310.386626)
			(xy 161.65296 -310.414582) (xy 161.608498 -310.43568) (xy 161.561227 -310.449372) (xy 161.512372 -310.455304)
			(xy 161.463197 -310.453323) (xy 161.414978 -310.443479) (xy 161.368962 -310.426027) (xy 161.326341 -310.40142)
			(xy 161.28822 -310.370295) (xy 161.255585 -310.333458) (xy 161.229282 -310.291862) (xy 161.209991 -310.246586)
			(xy 161.198214 -310.198802) (xy 161.194254 -310.149748) (xy 160.855152 -310.149748) (xy 160.854657 -310.174355)
			(xy 160.846762 -310.222932) (xy 160.831178 -310.269613) (xy 160.808307 -310.31319) (xy 160.778742 -310.352534)
			(xy 160.743249 -310.386626) (xy 160.702746 -310.414582) (xy 160.658284 -310.43568) (xy 160.611013 -310.449372)
			(xy 160.562158 -310.455304) (xy 160.512983 -310.453323) (xy 160.464764 -310.443479) (xy 160.418748 -310.426027)
			(xy 160.376127 -310.40142) (xy 160.338006 -310.370295) (xy 160.305371 -310.333458) (xy 160.279068 -310.291862)
			(xy 160.259777 -310.246586) (xy 160.248 -310.198802) (xy 160.24404 -310.149748) (xy 159.905192 -310.149748)
			(xy 159.904697 -310.174355) (xy 159.896802 -310.222932) (xy 159.881218 -310.269613) (xy 159.858347 -310.31319)
			(xy 159.828782 -310.352534) (xy 159.793289 -310.386626) (xy 159.752786 -310.414582) (xy 159.708324 -310.43568)
			(xy 159.661053 -310.449372) (xy 159.612198 -310.455304) (xy 159.563023 -310.453323) (xy 159.514804 -310.443479)
			(xy 159.468788 -310.426027) (xy 159.426167 -310.40142) (xy 159.388046 -310.370295) (xy 159.355411 -310.333458)
			(xy 159.329108 -310.291862) (xy 159.309817 -310.246586) (xy 159.29804 -310.198802) (xy 159.29408 -310.149748)
			(xy 158.955232 -310.149748) (xy 158.954737 -310.174355) (xy 158.946842 -310.222932) (xy 158.931258 -310.269613)
			(xy 158.908387 -310.31319) (xy 158.878822 -310.352534) (xy 158.843329 -310.386626) (xy 158.802826 -310.414582)
			(xy 158.758364 -310.43568) (xy 158.711093 -310.449372) (xy 158.662238 -310.455304) (xy 158.613063 -310.453323)
			(xy 158.564844 -310.443479) (xy 158.518828 -310.426027) (xy 158.476207 -310.40142) (xy 158.438086 -310.370295)
			(xy 158.405451 -310.333458) (xy 158.379148 -310.291862) (xy 158.359857 -310.246586) (xy 158.34808 -310.198802)
			(xy 158.34412 -310.149748) (xy 158.005272 -310.149748) (xy 158.004777 -310.174355) (xy 157.996882 -310.222932)
			(xy 157.981298 -310.269613) (xy 157.958427 -310.31319) (xy 157.928862 -310.352534) (xy 157.893369 -310.386626)
			(xy 157.852866 -310.414582) (xy 157.808404 -310.43568) (xy 157.761133 -310.449372) (xy 157.712278 -310.455304)
			(xy 157.663103 -310.453323) (xy 157.614884 -310.443479) (xy 157.568868 -310.426027) (xy 157.526247 -310.40142)
			(xy 157.488126 -310.370295) (xy 157.455491 -310.333458) (xy 157.429188 -310.291862) (xy 157.409897 -310.246586)
			(xy 157.39812 -310.198802) (xy 157.39416 -310.149748) (xy 157.099 -310.149748) (xy 157.099 -311.099962)
			(xy 157.39416 -311.099962) (xy 157.39812 -311.050908) (xy 157.409897 -311.003124) (xy 157.429188 -310.957848)
			(xy 157.455491 -310.916252) (xy 157.488126 -310.879415) (xy 157.526247 -310.84829) (xy 157.568868 -310.823683)
			(xy 157.614884 -310.806231) (xy 157.663103 -310.796387) (xy 157.712278 -310.794406) (xy 157.761133 -310.800338)
			(xy 157.808404 -310.81403) (xy 157.852866 -310.835128) (xy 157.893369 -310.863084) (xy 157.928862 -310.897176)
			(xy 157.958427 -310.93652) (xy 157.981298 -310.980097) (xy 157.996882 -311.026778) (xy 158.004777 -311.075355)
			(xy 158.005272 -311.099962) (xy 158.34412 -311.099962) (xy 158.34808 -311.050908) (xy 158.359857 -311.003124)
			(xy 158.379148 -310.957848) (xy 158.405451 -310.916252) (xy 158.438086 -310.879415) (xy 158.476207 -310.84829)
			(xy 158.518828 -310.823683) (xy 158.564844 -310.806231) (xy 158.613063 -310.796387) (xy 158.662238 -310.794406)
			(xy 158.711093 -310.800338) (xy 158.758364 -310.81403) (xy 158.802826 -310.835128) (xy 158.843329 -310.863084)
			(xy 158.878822 -310.897176) (xy 158.908387 -310.93652) (xy 158.931258 -310.980097) (xy 158.946842 -311.026778)
			(xy 158.954737 -311.075355) (xy 158.955232 -311.099962) (xy 159.29408 -311.099962) (xy 159.29804 -311.050908)
			(xy 159.309817 -311.003124) (xy 159.329108 -310.957848) (xy 159.355411 -310.916252) (xy 159.388046 -310.879415)
			(xy 159.426167 -310.84829) (xy 159.468788 -310.823683) (xy 159.514804 -310.806231) (xy 159.563023 -310.796387)
			(xy 159.612198 -310.794406) (xy 159.661053 -310.800338) (xy 159.708324 -310.81403) (xy 159.752786 -310.835128)
			(xy 159.793289 -310.863084) (xy 159.828782 -310.897176) (xy 159.858347 -310.93652) (xy 159.881218 -310.980097)
			(xy 159.896802 -311.026778) (xy 159.904697 -311.075355) (xy 159.905192 -311.099962) (xy 160.24404 -311.099962)
			(xy 160.248 -311.050908) (xy 160.259777 -311.003124) (xy 160.279068 -310.957848) (xy 160.305371 -310.916252)
			(xy 160.338006 -310.879415) (xy 160.376127 -310.84829) (xy 160.418748 -310.823683) (xy 160.464764 -310.806231)
			(xy 160.512983 -310.796387) (xy 160.562158 -310.794406) (xy 160.611013 -310.800338) (xy 160.658284 -310.81403)
			(xy 160.702746 -310.835128) (xy 160.743249 -310.863084) (xy 160.778742 -310.897176) (xy 160.808307 -310.93652)
			(xy 160.831178 -310.980097) (xy 160.846762 -311.026778) (xy 160.854657 -311.075355) (xy 160.855152 -311.099962)
			(xy 161.194254 -311.099962) (xy 161.198214 -311.050908) (xy 161.209991 -311.003124) (xy 161.229282 -310.957848)
			(xy 161.255585 -310.916252) (xy 161.28822 -310.879415) (xy 161.326341 -310.84829) (xy 161.368962 -310.823683)
			(xy 161.414978 -310.806231) (xy 161.463197 -310.796387) (xy 161.512372 -310.794406) (xy 161.561227 -310.800338)
			(xy 161.608498 -310.81403) (xy 161.65296 -310.835128) (xy 161.693463 -310.863084) (xy 161.728956 -310.897176)
			(xy 161.758521 -310.93652) (xy 161.781392 -310.980097) (xy 161.796976 -311.026778) (xy 161.804871 -311.075355)
			(xy 161.805366 -311.099962) (xy 162.144214 -311.099962) (xy 162.148174 -311.050908) (xy 162.159951 -311.003124)
			(xy 162.179242 -310.957848) (xy 162.205545 -310.916252) (xy 162.23818 -310.879415) (xy 162.276301 -310.84829)
			(xy 162.318922 -310.823683) (xy 162.364938 -310.806231) (xy 162.413157 -310.796387) (xy 162.462332 -310.794406)
			(xy 162.511187 -310.800338) (xy 162.558458 -310.81403) (xy 162.60292 -310.835128) (xy 162.643423 -310.863084)
			(xy 162.678916 -310.897176) (xy 162.708481 -310.93652) (xy 162.731352 -310.980097) (xy 162.746936 -311.026778)
			(xy 162.754831 -311.075355) (xy 162.755326 -311.099962) (xy 163.094174 -311.099962) (xy 163.098134 -311.050908)
			(xy 163.109911 -311.003124) (xy 163.129202 -310.957848) (xy 163.155505 -310.916252) (xy 163.18814 -310.879415)
			(xy 163.226261 -310.84829) (xy 163.268882 -310.823683) (xy 163.314898 -310.806231) (xy 163.363117 -310.796387)
			(xy 163.412292 -310.794406) (xy 163.461147 -310.800338) (xy 163.508418 -310.81403) (xy 163.55288 -310.835128)
			(xy 163.593383 -310.863084) (xy 163.628876 -310.897176) (xy 163.658441 -310.93652) (xy 163.681312 -310.980097)
			(xy 163.696896 -311.026778) (xy 163.704791 -311.075355) (xy 163.705286 -311.099962) (xy 164.044134 -311.099962)
			(xy 164.048094 -311.050908) (xy 164.059871 -311.003124) (xy 164.079162 -310.957848) (xy 164.105465 -310.916252)
			(xy 164.1381 -310.879415) (xy 164.176221 -310.84829) (xy 164.218842 -310.823683) (xy 164.264858 -310.806231)
			(xy 164.313077 -310.796387) (xy 164.362252 -310.794406) (xy 164.411107 -310.800338) (xy 164.458378 -310.81403)
			(xy 164.50284 -310.835128) (xy 164.543343 -310.863084) (xy 164.578836 -310.897176) (xy 164.608401 -310.93652)
			(xy 164.631272 -310.980097) (xy 164.646856 -311.026778) (xy 164.654751 -311.075355) (xy 164.655246 -311.099962)
			(xy 164.994094 -311.099962) (xy 164.998054 -311.050908) (xy 165.009831 -311.003124) (xy 165.029122 -310.957848)
			(xy 165.055425 -310.916252) (xy 165.08806 -310.879415) (xy 165.126181 -310.84829) (xy 165.168802 -310.823683)
			(xy 165.214818 -310.806231) (xy 165.263037 -310.796387) (xy 165.312212 -310.794406) (xy 165.361067 -310.800338)
			(xy 165.408338 -310.81403) (xy 165.4528 -310.835128) (xy 165.493303 -310.863084) (xy 165.528796 -310.897176)
			(xy 165.558361 -310.93652) (xy 165.581232 -310.980097) (xy 165.596816 -311.026778) (xy 165.604711 -311.075355)
			(xy 165.605206 -311.099962) (xy 165.944054 -311.099962) (xy 165.948014 -311.050908) (xy 165.959791 -311.003124)
			(xy 165.979082 -310.957848) (xy 166.005385 -310.916252) (xy 166.03802 -310.879415) (xy 166.076141 -310.84829)
			(xy 166.118762 -310.823683) (xy 166.164778 -310.806231) (xy 166.212997 -310.796387) (xy 166.262172 -310.794406)
			(xy 166.311027 -310.800338) (xy 166.358298 -310.81403) (xy 166.40276 -310.835128) (xy 166.443263 -310.863084)
			(xy 166.478756 -310.897176) (xy 166.508321 -310.93652) (xy 166.531192 -310.980097) (xy 166.546776 -311.026778)
			(xy 166.554671 -311.075355) (xy 166.555166 -311.099962) (xy 166.554671 -311.124569) (xy 166.554492 -311.12567)
			(xy 166.873424 -311.12567) (xy 166.873424 -311.074254) (xy 166.881467 -311.023472) (xy 166.897355 -310.974573)
			(xy 166.920698 -310.928761) (xy 166.950919 -310.887165) (xy 166.987275 -310.850809) (xy 167.028871 -310.820588)
			(xy 167.074683 -310.797245) (xy 167.123582 -310.781357) (xy 167.174364 -310.773314) (xy 167.22578 -310.773314)
			(xy 167.276562 -310.781357) (xy 167.325461 -310.797245) (xy 167.371273 -310.820588) (xy 167.412869 -310.850809)
			(xy 167.449225 -310.887165) (xy 167.479446 -310.928761) (xy 167.502789 -310.974573) (xy 167.518677 -311.023472)
			(xy 167.52672 -311.074254) (xy 167.527224 -311.099962) (xy 167.844228 -311.099962) (xy 167.848188 -311.050908)
			(xy 167.859965 -311.003124) (xy 167.879256 -310.957848) (xy 167.905559 -310.916252) (xy 167.938194 -310.879415)
			(xy 167.976315 -310.84829) (xy 168.018936 -310.823683) (xy 168.064952 -310.806231) (xy 168.113171 -310.796387)
			(xy 168.162346 -310.794406) (xy 168.211201 -310.800338) (xy 168.258472 -310.81403) (xy 168.302934 -310.835128)
			(xy 168.343437 -310.863084) (xy 168.37893 -310.897176) (xy 168.408495 -310.93652) (xy 168.431366 -310.980097)
			(xy 168.44695 -311.026778) (xy 168.454845 -311.075355) (xy 168.45534 -311.099962) (xy 168.454845 -311.124569)
			(xy 168.454666 -311.12567) (xy 168.773344 -311.12567) (xy 168.773344 -311.074254) (xy 168.781387 -311.023472)
			(xy 168.797275 -310.974573) (xy 168.820618 -310.928761) (xy 168.850839 -310.887165) (xy 168.887195 -310.850809)
			(xy 168.928791 -310.820588) (xy 168.974603 -310.797245) (xy 169.023502 -310.781357) (xy 169.074284 -310.773314)
			(xy 169.1257 -310.773314) (xy 169.176482 -310.781357) (xy 169.225381 -310.797245) (xy 169.271193 -310.820588)
			(xy 169.312789 -310.850809) (xy 169.349145 -310.887165) (xy 169.379366 -310.928761) (xy 169.402709 -310.974573)
			(xy 169.418597 -311.023472) (xy 169.42664 -311.074254) (xy 169.427144 -311.099962) (xy 169.744148 -311.099962)
			(xy 169.748108 -311.050908) (xy 169.759885 -311.003124) (xy 169.779176 -310.957848) (xy 169.805479 -310.916252)
			(xy 169.838114 -310.879415) (xy 169.876235 -310.84829) (xy 169.918856 -310.823683) (xy 169.964872 -310.806231)
			(xy 170.013091 -310.796387) (xy 170.062266 -310.794406) (xy 170.111121 -310.800338) (xy 170.158392 -310.81403)
			(xy 170.202854 -310.835128) (xy 170.243357 -310.863084) (xy 170.27885 -310.897176) (xy 170.308415 -310.93652)
			(xy 170.331286 -310.980097) (xy 170.34687 -311.026778) (xy 170.354765 -311.075355) (xy 170.35526 -311.099962)
			(xy 170.354765 -311.124569) (xy 170.354586 -311.12567) (xy 170.673264 -311.12567) (xy 170.673264 -311.074254)
			(xy 170.681307 -311.023472) (xy 170.697195 -310.974573) (xy 170.720538 -310.928761) (xy 170.750759 -310.887165)
			(xy 170.787115 -310.850809) (xy 170.828711 -310.820588) (xy 170.874523 -310.797245) (xy 170.923422 -310.781357)
			(xy 170.974204 -310.773314) (xy 171.02562 -310.773314) (xy 171.076402 -310.781357) (xy 171.125301 -310.797245)
			(xy 171.171113 -310.820588) (xy 171.212709 -310.850809) (xy 171.249065 -310.887165) (xy 171.279286 -310.928761)
			(xy 171.302629 -310.974573) (xy 171.318517 -311.023472) (xy 171.32656 -311.074254) (xy 171.327064 -311.099962)
			(xy 171.644068 -311.099962) (xy 171.648028 -311.050908) (xy 171.659805 -311.003124) (xy 171.679096 -310.957848)
			(xy 171.705399 -310.916252) (xy 171.738034 -310.879415) (xy 171.776155 -310.84829) (xy 171.818776 -310.823683)
			(xy 171.864792 -310.806231) (xy 171.913011 -310.796387) (xy 171.962186 -310.794406) (xy 172.011041 -310.800338)
			(xy 172.058312 -310.81403) (xy 172.102774 -310.835128) (xy 172.143277 -310.863084) (xy 172.17877 -310.897176)
			(xy 172.208335 -310.93652) (xy 172.231206 -310.980097) (xy 172.24679 -311.026778) (xy 172.254685 -311.075355)
			(xy 172.25518 -311.099962) (xy 172.254685 -311.124569) (xy 172.254506 -311.12567) (xy 172.573438 -311.12567)
			(xy 172.573438 -311.074254) (xy 172.581481 -311.023472) (xy 172.597369 -310.974573) (xy 172.620712 -310.928761)
			(xy 172.650933 -310.887165) (xy 172.687289 -310.850809) (xy 172.728885 -310.820588) (xy 172.774697 -310.797245)
			(xy 172.823596 -310.781357) (xy 172.874378 -310.773314) (xy 172.925794 -310.773314) (xy 172.976576 -310.781357)
			(xy 173.025475 -310.797245) (xy 173.071287 -310.820588) (xy 173.112883 -310.850809) (xy 173.149239 -310.887165)
			(xy 173.17946 -310.928761) (xy 173.202803 -310.974573) (xy 173.218691 -311.023472) (xy 173.226734 -311.074254)
			(xy 173.227238 -311.099962) (xy 173.544242 -311.099962) (xy 173.548202 -311.050908) (xy 173.559979 -311.003124)
			(xy 173.57927 -310.957848) (xy 173.605573 -310.916252) (xy 173.638208 -310.879415) (xy 173.676329 -310.84829)
			(xy 173.71895 -310.823683) (xy 173.764966 -310.806231) (xy 173.813185 -310.796387) (xy 173.86236 -310.794406)
			(xy 173.911215 -310.800338) (xy 173.958486 -310.81403) (xy 174.002948 -310.835128) (xy 174.043451 -310.863084)
			(xy 174.078944 -310.897176) (xy 174.108509 -310.93652) (xy 174.13138 -310.980097) (xy 174.146964 -311.026778)
			(xy 174.154859 -311.075355) (xy 174.155354 -311.099962) (xy 174.154859 -311.124569) (xy 174.15468 -311.12567)
			(xy 174.473358 -311.12567) (xy 174.473358 -311.074254) (xy 174.481401 -311.023472) (xy 174.497289 -310.974573)
			(xy 174.520632 -310.928761) (xy 174.550853 -310.887165) (xy 174.587209 -310.850809) (xy 174.628805 -310.820588)
			(xy 174.674617 -310.797245) (xy 174.723516 -310.781357) (xy 174.774298 -310.773314) (xy 174.825714 -310.773314)
			(xy 174.876496 -310.781357) (xy 174.925395 -310.797245) (xy 174.971207 -310.820588) (xy 175.012803 -310.850809)
			(xy 175.049159 -310.887165) (xy 175.07938 -310.928761) (xy 175.102723 -310.974573) (xy 175.118611 -311.023472)
			(xy 175.126654 -311.074254) (xy 175.127158 -311.099962) (xy 175.444162 -311.099962) (xy 175.448122 -311.050908)
			(xy 175.459899 -311.003124) (xy 175.47919 -310.957848) (xy 175.505493 -310.916252) (xy 175.538128 -310.879415)
			(xy 175.576249 -310.84829) (xy 175.61887 -310.823683) (xy 175.664886 -310.806231) (xy 175.713105 -310.796387)
			(xy 175.76228 -310.794406) (xy 175.811135 -310.800338) (xy 175.858406 -310.81403) (xy 175.902868 -310.835128)
			(xy 175.943371 -310.863084) (xy 175.978864 -310.897176) (xy 176.008429 -310.93652) (xy 176.0313 -310.980097)
			(xy 176.046884 -311.026778) (xy 176.054779 -311.075355) (xy 176.055274 -311.099962) (xy 176.054779 -311.124569)
			(xy 176.0546 -311.12567) (xy 176.373278 -311.12567) (xy 176.373278 -311.074254) (xy 176.381321 -311.023472)
			(xy 176.397209 -310.974573) (xy 176.420552 -310.928761) (xy 176.450773 -310.887165) (xy 176.487129 -310.850809)
			(xy 176.528725 -310.820588) (xy 176.574537 -310.797245) (xy 176.623436 -310.781357) (xy 176.674218 -310.773314)
			(xy 176.725634 -310.773314) (xy 176.776416 -310.781357) (xy 176.825315 -310.797245) (xy 176.871127 -310.820588)
			(xy 176.912723 -310.850809) (xy 176.949079 -310.887165) (xy 176.9793 -310.928761) (xy 177.002643 -310.974573)
			(xy 177.018531 -311.023472) (xy 177.026574 -311.074254) (xy 177.027078 -311.099962) (xy 177.344082 -311.099962)
			(xy 177.348042 -311.050908) (xy 177.359819 -311.003124) (xy 177.37911 -310.957848) (xy 177.405413 -310.916252)
			(xy 177.438048 -310.879415) (xy 177.476169 -310.84829) (xy 177.51879 -310.823683) (xy 177.564806 -310.806231)
			(xy 177.613025 -310.796387) (xy 177.6622 -310.794406) (xy 177.711055 -310.800338) (xy 177.758326 -310.81403)
			(xy 177.802788 -310.835128) (xy 177.843291 -310.863084) (xy 177.878784 -310.897176) (xy 177.908349 -310.93652)
			(xy 177.93122 -310.980097) (xy 177.946804 -311.026778) (xy 177.954699 -311.075355) (xy 177.955194 -311.099962)
			(xy 177.954699 -311.124569) (xy 177.95452 -311.12567) (xy 178.273198 -311.12567) (xy 178.273198 -311.074254)
			(xy 178.281241 -311.023472) (xy 178.297129 -310.974573) (xy 178.320472 -310.928761) (xy 178.350693 -310.887165)
			(xy 178.387049 -310.850809) (xy 178.428645 -310.820588) (xy 178.474457 -310.797245) (xy 178.523356 -310.781357)
			(xy 178.574138 -310.773314) (xy 178.625554 -310.773314) (xy 178.676336 -310.781357) (xy 178.725235 -310.797245)
			(xy 178.771047 -310.820588) (xy 178.812643 -310.850809) (xy 178.848999 -310.887165) (xy 178.87922 -310.928761)
			(xy 178.902563 -310.974573) (xy 178.918451 -311.023472) (xy 178.926494 -311.074254) (xy 178.926998 -311.099962)
			(xy 179.244256 -311.099962) (xy 179.248216 -311.050908) (xy 179.259993 -311.003124) (xy 179.279284 -310.957848)
			(xy 179.305587 -310.916252) (xy 179.338222 -310.879415) (xy 179.376343 -310.84829) (xy 179.418964 -310.823683)
			(xy 179.46498 -310.806231) (xy 179.513199 -310.796387) (xy 179.562374 -310.794406) (xy 179.611229 -310.800338)
			(xy 179.6585 -310.81403) (xy 179.702962 -310.835128) (xy 179.743465 -310.863084) (xy 179.778958 -310.897176)
			(xy 179.808523 -310.93652) (xy 179.831394 -310.980097) (xy 179.846978 -311.026778) (xy 179.854873 -311.075355)
			(xy 179.855368 -311.099962) (xy 179.854873 -311.124569) (xy 179.854694 -311.12567) (xy 180.173372 -311.12567)
			(xy 180.173372 -311.074254) (xy 180.181415 -311.023472) (xy 180.197303 -310.974573) (xy 180.220646 -310.928761)
			(xy 180.250867 -310.887165) (xy 180.287223 -310.850809) (xy 180.328819 -310.820588) (xy 180.374631 -310.797245)
			(xy 180.42353 -310.781357) (xy 180.474312 -310.773314) (xy 180.525728 -310.773314) (xy 180.57651 -310.781357)
			(xy 180.625409 -310.797245) (xy 180.671221 -310.820588) (xy 180.712817 -310.850809) (xy 180.749173 -310.887165)
			(xy 180.779394 -310.928761) (xy 180.802737 -310.974573) (xy 180.818625 -311.023472) (xy 180.826668 -311.074254)
			(xy 180.827172 -311.099962) (xy 181.144176 -311.099962) (xy 181.148136 -311.050908) (xy 181.159913 -311.003124)
			(xy 181.179204 -310.957848) (xy 181.205507 -310.916252) (xy 181.238142 -310.879415) (xy 181.276263 -310.84829)
			(xy 181.318884 -310.823683) (xy 181.3649 -310.806231) (xy 181.413119 -310.796387) (xy 181.462294 -310.794406)
			(xy 181.511149 -310.800338) (xy 181.55842 -310.81403) (xy 181.602882 -310.835128) (xy 181.643385 -310.863084)
			(xy 181.678878 -310.897176) (xy 181.708443 -310.93652) (xy 181.731314 -310.980097) (xy 181.746898 -311.026778)
			(xy 181.754793 -311.075355) (xy 181.755288 -311.099962) (xy 182.094136 -311.099962) (xy 182.098096 -311.050908)
			(xy 182.109873 -311.003124) (xy 182.129164 -310.957848) (xy 182.155467 -310.916252) (xy 182.188102 -310.879415)
			(xy 182.226223 -310.84829) (xy 182.268844 -310.823683) (xy 182.31486 -310.806231) (xy 182.363079 -310.796387)
			(xy 182.412254 -310.794406) (xy 182.461109 -310.800338) (xy 182.50838 -310.81403) (xy 182.552842 -310.835128)
			(xy 182.593345 -310.863084) (xy 182.628838 -310.897176) (xy 182.658403 -310.93652) (xy 182.681274 -310.980097)
			(xy 182.696858 -311.026778) (xy 182.704753 -311.075355) (xy 182.705248 -311.099962) (xy 183.044096 -311.099962)
			(xy 183.048056 -311.050908) (xy 183.059833 -311.003124) (xy 183.079124 -310.957848) (xy 183.105427 -310.916252)
			(xy 183.138062 -310.879415) (xy 183.176183 -310.84829) (xy 183.218804 -310.823683) (xy 183.26482 -310.806231)
			(xy 183.313039 -310.796387) (xy 183.362214 -310.794406) (xy 183.411069 -310.800338) (xy 183.45834 -310.81403)
			(xy 183.502802 -310.835128) (xy 183.543305 -310.863084) (xy 183.578798 -310.897176) (xy 183.608363 -310.93652)
			(xy 183.631234 -310.980097) (xy 183.646818 -311.026778) (xy 183.654713 -311.075355) (xy 183.655208 -311.099962)
			(xy 183.994056 -311.099962) (xy 183.998016 -311.050908) (xy 184.009793 -311.003124) (xy 184.029084 -310.957848)
			(xy 184.055387 -310.916252) (xy 184.088022 -310.879415) (xy 184.126143 -310.84829) (xy 184.168764 -310.823683)
			(xy 184.21478 -310.806231) (xy 184.262999 -310.796387) (xy 184.312174 -310.794406) (xy 184.361029 -310.800338)
			(xy 184.4083 -310.81403) (xy 184.452762 -310.835128) (xy 184.493265 -310.863084) (xy 184.528758 -310.897176)
			(xy 184.558323 -310.93652) (xy 184.581194 -310.980097) (xy 184.596778 -311.026778) (xy 184.604673 -311.075355)
			(xy 184.605168 -311.099962) (xy 184.94427 -311.099962) (xy 184.94823 -311.050908) (xy 184.960007 -311.003124)
			(xy 184.979298 -310.957848) (xy 185.005601 -310.916252) (xy 185.038236 -310.879415) (xy 185.076357 -310.84829)
			(xy 185.118978 -310.823683) (xy 185.164994 -310.806231) (xy 185.213213 -310.796387) (xy 185.262388 -310.794406)
			(xy 185.311243 -310.800338) (xy 185.358514 -310.81403) (xy 185.402976 -310.835128) (xy 185.443479 -310.863084)
			(xy 185.478972 -310.897176) (xy 185.508537 -310.93652) (xy 185.531408 -310.980097) (xy 185.546992 -311.026778)
			(xy 185.554887 -311.075355) (xy 185.555382 -311.099962) (xy 185.89423 -311.099962) (xy 185.89819 -311.050908)
			(xy 185.909967 -311.003124) (xy 185.929258 -310.957848) (xy 185.955561 -310.916252) (xy 185.988196 -310.879415)
			(xy 186.026317 -310.84829) (xy 186.068938 -310.823683) (xy 186.114954 -310.806231) (xy 186.163173 -310.796387)
			(xy 186.212348 -310.794406) (xy 186.261203 -310.800338) (xy 186.308474 -310.81403) (xy 186.352936 -310.835128)
			(xy 186.393439 -310.863084) (xy 186.428932 -310.897176) (xy 186.458497 -310.93652) (xy 186.481368 -310.980097)
			(xy 186.496952 -311.026778) (xy 186.504847 -311.075355) (xy 186.505342 -311.099962) (xy 186.84419 -311.099962)
			(xy 186.84815 -311.050908) (xy 186.859927 -311.003124) (xy 186.879218 -310.957848) (xy 186.905521 -310.916252)
			(xy 186.938156 -310.879415) (xy 186.976277 -310.84829) (xy 187.018898 -310.823683) (xy 187.064914 -310.806231)
			(xy 187.113133 -310.796387) (xy 187.162308 -310.794406) (xy 187.211163 -310.800338) (xy 187.258434 -310.81403)
			(xy 187.302896 -310.835128) (xy 187.343399 -310.863084) (xy 187.378892 -310.897176) (xy 187.408457 -310.93652)
			(xy 187.431328 -310.980097) (xy 187.446912 -311.026778) (xy 187.454807 -311.075355) (xy 187.455302 -311.099962)
			(xy 187.79415 -311.099962) (xy 187.79811 -311.050908) (xy 187.809887 -311.003124) (xy 187.829178 -310.957848)
			(xy 187.855481 -310.916252) (xy 187.888116 -310.879415) (xy 187.926237 -310.84829) (xy 187.968858 -310.823683)
			(xy 188.014874 -310.806231) (xy 188.063093 -310.796387) (xy 188.112268 -310.794406) (xy 188.161123 -310.800338)
			(xy 188.208394 -310.81403) (xy 188.252856 -310.835128) (xy 188.293359 -310.863084) (xy 188.328852 -310.897176)
			(xy 188.358417 -310.93652) (xy 188.381288 -310.980097) (xy 188.396872 -311.026778) (xy 188.404767 -311.075355)
			(xy 188.405262 -311.099962) (xy 188.74411 -311.099962) (xy 188.74807 -311.050908) (xy 188.759847 -311.003124)
			(xy 188.779138 -310.957848) (xy 188.805441 -310.916252) (xy 188.838076 -310.879415) (xy 188.876197 -310.84829)
			(xy 188.918818 -310.823683) (xy 188.964834 -310.806231) (xy 189.013053 -310.796387) (xy 189.062228 -310.794406)
			(xy 189.111083 -310.800338) (xy 189.158354 -310.81403) (xy 189.202816 -310.835128) (xy 189.243319 -310.863084)
			(xy 189.278812 -310.897176) (xy 189.308377 -310.93652) (xy 189.331248 -310.980097) (xy 189.346832 -311.026778)
			(xy 189.354727 -311.075355) (xy 189.355222 -311.099962) (xy 189.354727 -311.124569) (xy 189.354548 -311.12567)
			(xy 189.673226 -311.12567) (xy 189.673226 -311.074254) (xy 189.681269 -311.023472) (xy 189.697157 -310.974573)
			(xy 189.7205 -310.928761) (xy 189.750721 -310.887165) (xy 189.787077 -310.850809) (xy 189.828673 -310.820588)
			(xy 189.874485 -310.797245) (xy 189.923384 -310.781357) (xy 189.974166 -310.773314) (xy 190.025582 -310.773314)
			(xy 190.076364 -310.781357) (xy 190.125263 -310.797245) (xy 190.171075 -310.820588) (xy 190.212671 -310.850809)
			(xy 190.249027 -310.887165) (xy 190.279248 -310.928761) (xy 190.302591 -310.974573) (xy 190.318479 -311.023472)
			(xy 190.326522 -311.074254) (xy 190.327026 -311.099962) (xy 190.644284 -311.099962) (xy 190.648244 -311.050908)
			(xy 190.660021 -311.003124) (xy 190.679312 -310.957848) (xy 190.705615 -310.916252) (xy 190.73825 -310.879415)
			(xy 190.776371 -310.84829) (xy 190.818992 -310.823683) (xy 190.865008 -310.806231) (xy 190.913227 -310.796387)
			(xy 190.962402 -310.794406) (xy 191.011257 -310.800338) (xy 191.058528 -310.81403) (xy 191.10299 -310.835128)
			(xy 191.143493 -310.863084) (xy 191.178986 -310.897176) (xy 191.208551 -310.93652) (xy 191.231422 -310.980097)
			(xy 191.247006 -311.026778) (xy 191.254901 -311.075355) (xy 191.255396 -311.099962) (xy 191.254901 -311.124569)
			(xy 191.247006 -311.173146) (xy 191.231422 -311.219827) (xy 191.208551 -311.263404) (xy 191.178986 -311.302748)
			(xy 191.143493 -311.33684) (xy 191.10299 -311.364796) (xy 191.058528 -311.385894) (xy 191.011257 -311.399586)
			(xy 190.962402 -311.405518) (xy 190.913227 -311.403537) (xy 190.865008 -311.393693) (xy 190.818992 -311.376241)
			(xy 190.776371 -311.351634) (xy 190.73825 -311.320509) (xy 190.705615 -311.283672) (xy 190.679312 -311.242076)
			(xy 190.660021 -311.1968) (xy 190.648244 -311.149016) (xy 190.644284 -311.099962) (xy 190.327026 -311.099962)
			(xy 190.326522 -311.12567) (xy 190.318479 -311.176452) (xy 190.302591 -311.225351) (xy 190.279248 -311.271163)
			(xy 190.249027 -311.312759) (xy 190.212671 -311.349115) (xy 190.171075 -311.379336) (xy 190.125263 -311.402679)
			(xy 190.076364 -311.418567) (xy 190.025582 -311.42661) (xy 189.974166 -311.42661) (xy 189.923384 -311.418567)
			(xy 189.874485 -311.402679) (xy 189.828673 -311.379336) (xy 189.787077 -311.349115) (xy 189.750721 -311.312759)
			(xy 189.7205 -311.271163) (xy 189.697157 -311.225351) (xy 189.681269 -311.176452) (xy 189.673226 -311.12567)
			(xy 189.354548 -311.12567) (xy 189.346832 -311.173146) (xy 189.331248 -311.219827) (xy 189.308377 -311.263404)
			(xy 189.278812 -311.302748) (xy 189.243319 -311.33684) (xy 189.202816 -311.364796) (xy 189.158354 -311.385894)
			(xy 189.111083 -311.399586) (xy 189.062228 -311.405518) (xy 189.013053 -311.403537) (xy 188.964834 -311.393693)
			(xy 188.918818 -311.376241) (xy 188.876197 -311.351634) (xy 188.838076 -311.320509) (xy 188.805441 -311.283672)
			(xy 188.779138 -311.242076) (xy 188.759847 -311.1968) (xy 188.74807 -311.149016) (xy 188.74411 -311.099962)
			(xy 188.405262 -311.099962) (xy 188.404767 -311.124569) (xy 188.396872 -311.173146) (xy 188.381288 -311.219827)
			(xy 188.358417 -311.263404) (xy 188.328852 -311.302748) (xy 188.293359 -311.33684) (xy 188.252856 -311.364796)
			(xy 188.208394 -311.385894) (xy 188.161123 -311.399586) (xy 188.112268 -311.405518) (xy 188.063093 -311.403537)
			(xy 188.014874 -311.393693) (xy 187.968858 -311.376241) (xy 187.926237 -311.351634) (xy 187.888116 -311.320509)
			(xy 187.855481 -311.283672) (xy 187.829178 -311.242076) (xy 187.809887 -311.1968) (xy 187.79811 -311.149016)
			(xy 187.79415 -311.099962) (xy 187.455302 -311.099962) (xy 187.454807 -311.124569) (xy 187.446912 -311.173146)
			(xy 187.431328 -311.219827) (xy 187.408457 -311.263404) (xy 187.378892 -311.302748) (xy 187.343399 -311.33684)
			(xy 187.302896 -311.364796) (xy 187.258434 -311.385894) (xy 187.211163 -311.399586) (xy 187.162308 -311.405518)
			(xy 187.113133 -311.403537) (xy 187.064914 -311.393693) (xy 187.018898 -311.376241) (xy 186.976277 -311.351634)
			(xy 186.938156 -311.320509) (xy 186.905521 -311.283672) (xy 186.879218 -311.242076) (xy 186.859927 -311.1968)
			(xy 186.84815 -311.149016) (xy 186.84419 -311.099962) (xy 186.505342 -311.099962) (xy 186.504847 -311.124569)
			(xy 186.496952 -311.173146) (xy 186.481368 -311.219827) (xy 186.458497 -311.263404) (xy 186.428932 -311.302748)
			(xy 186.393439 -311.33684) (xy 186.352936 -311.364796) (xy 186.308474 -311.385894) (xy 186.261203 -311.399586)
			(xy 186.212348 -311.405518) (xy 186.163173 -311.403537) (xy 186.114954 -311.393693) (xy 186.068938 -311.376241)
			(xy 186.026317 -311.351634) (xy 185.988196 -311.320509) (xy 185.955561 -311.283672) (xy 185.929258 -311.242076)
			(xy 185.909967 -311.1968) (xy 185.89819 -311.149016) (xy 185.89423 -311.099962) (xy 185.555382 -311.099962)
			(xy 185.554887 -311.124569) (xy 185.546992 -311.173146) (xy 185.531408 -311.219827) (xy 185.508537 -311.263404)
			(xy 185.478972 -311.302748) (xy 185.443479 -311.33684) (xy 185.402976 -311.364796) (xy 185.358514 -311.385894)
			(xy 185.311243 -311.399586) (xy 185.262388 -311.405518) (xy 185.213213 -311.403537) (xy 185.164994 -311.393693)
			(xy 185.118978 -311.376241) (xy 185.076357 -311.351634) (xy 185.038236 -311.320509) (xy 185.005601 -311.283672)
			(xy 184.979298 -311.242076) (xy 184.960007 -311.1968) (xy 184.94823 -311.149016) (xy 184.94427 -311.099962)
			(xy 184.605168 -311.099962) (xy 184.604673 -311.124569) (xy 184.596778 -311.173146) (xy 184.581194 -311.219827)
			(xy 184.558323 -311.263404) (xy 184.528758 -311.302748) (xy 184.493265 -311.33684) (xy 184.452762 -311.364796)
			(xy 184.4083 -311.385894) (xy 184.361029 -311.399586) (xy 184.312174 -311.405518) (xy 184.262999 -311.403537)
			(xy 184.21478 -311.393693) (xy 184.168764 -311.376241) (xy 184.126143 -311.351634) (xy 184.088022 -311.320509)
			(xy 184.055387 -311.283672) (xy 184.029084 -311.242076) (xy 184.009793 -311.1968) (xy 183.998016 -311.149016)
			(xy 183.994056 -311.099962) (xy 183.655208 -311.099962) (xy 183.654713 -311.124569) (xy 183.646818 -311.173146)
			(xy 183.631234 -311.219827) (xy 183.608363 -311.263404) (xy 183.578798 -311.302748) (xy 183.543305 -311.33684)
			(xy 183.502802 -311.364796) (xy 183.45834 -311.385894) (xy 183.411069 -311.399586) (xy 183.362214 -311.405518)
			(xy 183.313039 -311.403537) (xy 183.26482 -311.393693) (xy 183.218804 -311.376241) (xy 183.176183 -311.351634)
			(xy 183.138062 -311.320509) (xy 183.105427 -311.283672) (xy 183.079124 -311.242076) (xy 183.059833 -311.1968)
			(xy 183.048056 -311.149016) (xy 183.044096 -311.099962) (xy 182.705248 -311.099962) (xy 182.704753 -311.124569)
			(xy 182.696858 -311.173146) (xy 182.681274 -311.219827) (xy 182.658403 -311.263404) (xy 182.628838 -311.302748)
			(xy 182.593345 -311.33684) (xy 182.552842 -311.364796) (xy 182.50838 -311.385894) (xy 182.461109 -311.399586)
			(xy 182.412254 -311.405518) (xy 182.363079 -311.403537) (xy 182.31486 -311.393693) (xy 182.268844 -311.376241)
			(xy 182.226223 -311.351634) (xy 182.188102 -311.320509) (xy 182.155467 -311.283672) (xy 182.129164 -311.242076)
			(xy 182.109873 -311.1968) (xy 182.098096 -311.149016) (xy 182.094136 -311.099962) (xy 181.755288 -311.099962)
			(xy 181.754793 -311.124569) (xy 181.746898 -311.173146) (xy 181.731314 -311.219827) (xy 181.708443 -311.263404)
			(xy 181.678878 -311.302748) (xy 181.643385 -311.33684) (xy 181.602882 -311.364796) (xy 181.55842 -311.385894)
			(xy 181.511149 -311.399586) (xy 181.462294 -311.405518) (xy 181.413119 -311.403537) (xy 181.3649 -311.393693)
			(xy 181.318884 -311.376241) (xy 181.276263 -311.351634) (xy 181.238142 -311.320509) (xy 181.205507 -311.283672)
			(xy 181.179204 -311.242076) (xy 181.159913 -311.1968) (xy 181.148136 -311.149016) (xy 181.144176 -311.099962)
			(xy 180.827172 -311.099962) (xy 180.826668 -311.12567) (xy 180.818625 -311.176452) (xy 180.802737 -311.225351)
			(xy 180.779394 -311.271163) (xy 180.749173 -311.312759) (xy 180.712817 -311.349115) (xy 180.671221 -311.379336)
			(xy 180.625409 -311.402679) (xy 180.57651 -311.418567) (xy 180.525728 -311.42661) (xy 180.474312 -311.42661)
			(xy 180.42353 -311.418567) (xy 180.374631 -311.402679) (xy 180.328819 -311.379336) (xy 180.287223 -311.349115)
			(xy 180.250867 -311.312759) (xy 180.220646 -311.271163) (xy 180.197303 -311.225351) (xy 180.181415 -311.176452)
			(xy 180.173372 -311.12567) (xy 179.854694 -311.12567) (xy 179.846978 -311.173146) (xy 179.831394 -311.219827)
			(xy 179.808523 -311.263404) (xy 179.778958 -311.302748) (xy 179.743465 -311.33684) (xy 179.702962 -311.364796)
			(xy 179.6585 -311.385894) (xy 179.611229 -311.399586) (xy 179.562374 -311.405518) (xy 179.513199 -311.403537)
			(xy 179.46498 -311.393693) (xy 179.418964 -311.376241) (xy 179.376343 -311.351634) (xy 179.338222 -311.320509)
			(xy 179.305587 -311.283672) (xy 179.279284 -311.242076) (xy 179.259993 -311.1968) (xy 179.248216 -311.149016)
			(xy 179.244256 -311.099962) (xy 178.926998 -311.099962) (xy 178.926494 -311.12567) (xy 178.918451 -311.176452)
			(xy 178.902563 -311.225351) (xy 178.87922 -311.271163) (xy 178.848999 -311.312759) (xy 178.812643 -311.349115)
			(xy 178.771047 -311.379336) (xy 178.725235 -311.402679) (xy 178.676336 -311.418567) (xy 178.625554 -311.42661)
			(xy 178.574138 -311.42661) (xy 178.523356 -311.418567) (xy 178.474457 -311.402679) (xy 178.428645 -311.379336)
			(xy 178.387049 -311.349115) (xy 178.350693 -311.312759) (xy 178.320472 -311.271163) (xy 178.297129 -311.225351)
			(xy 178.281241 -311.176452) (xy 178.273198 -311.12567) (xy 177.95452 -311.12567) (xy 177.946804 -311.173146)
			(xy 177.93122 -311.219827) (xy 177.908349 -311.263404) (xy 177.878784 -311.302748) (xy 177.843291 -311.33684)
			(xy 177.802788 -311.364796) (xy 177.758326 -311.385894) (xy 177.711055 -311.399586) (xy 177.6622 -311.405518)
			(xy 177.613025 -311.403537) (xy 177.564806 -311.393693) (xy 177.51879 -311.376241) (xy 177.476169 -311.351634)
			(xy 177.438048 -311.320509) (xy 177.405413 -311.283672) (xy 177.37911 -311.242076) (xy 177.359819 -311.1968)
			(xy 177.348042 -311.149016) (xy 177.344082 -311.099962) (xy 177.027078 -311.099962) (xy 177.026574 -311.12567)
			(xy 177.018531 -311.176452) (xy 177.002643 -311.225351) (xy 176.9793 -311.271163) (xy 176.949079 -311.312759)
			(xy 176.912723 -311.349115) (xy 176.871127 -311.379336) (xy 176.825315 -311.402679) (xy 176.776416 -311.418567)
			(xy 176.725634 -311.42661) (xy 176.674218 -311.42661) (xy 176.623436 -311.418567) (xy 176.574537 -311.402679)
			(xy 176.528725 -311.379336) (xy 176.487129 -311.349115) (xy 176.450773 -311.312759) (xy 176.420552 -311.271163)
			(xy 176.397209 -311.225351) (xy 176.381321 -311.176452) (xy 176.373278 -311.12567) (xy 176.0546 -311.12567)
			(xy 176.046884 -311.173146) (xy 176.0313 -311.219827) (xy 176.008429 -311.263404) (xy 175.978864 -311.302748)
			(xy 175.943371 -311.33684) (xy 175.902868 -311.364796) (xy 175.858406 -311.385894) (xy 175.811135 -311.399586)
			(xy 175.76228 -311.405518) (xy 175.713105 -311.403537) (xy 175.664886 -311.393693) (xy 175.61887 -311.376241)
			(xy 175.576249 -311.351634) (xy 175.538128 -311.320509) (xy 175.505493 -311.283672) (xy 175.47919 -311.242076)
			(xy 175.459899 -311.1968) (xy 175.448122 -311.149016) (xy 175.444162 -311.099962) (xy 175.127158 -311.099962)
			(xy 175.126654 -311.12567) (xy 175.118611 -311.176452) (xy 175.102723 -311.225351) (xy 175.07938 -311.271163)
			(xy 175.049159 -311.312759) (xy 175.012803 -311.349115) (xy 174.971207 -311.379336) (xy 174.925395 -311.402679)
			(xy 174.876496 -311.418567) (xy 174.825714 -311.42661) (xy 174.774298 -311.42661) (xy 174.723516 -311.418567)
			(xy 174.674617 -311.402679) (xy 174.628805 -311.379336) (xy 174.587209 -311.349115) (xy 174.550853 -311.312759)
			(xy 174.520632 -311.271163) (xy 174.497289 -311.225351) (xy 174.481401 -311.176452) (xy 174.473358 -311.12567)
			(xy 174.15468 -311.12567) (xy 174.146964 -311.173146) (xy 174.13138 -311.219827) (xy 174.108509 -311.263404)
			(xy 174.078944 -311.302748) (xy 174.043451 -311.33684) (xy 174.002948 -311.364796) (xy 173.958486 -311.385894)
			(xy 173.911215 -311.399586) (xy 173.86236 -311.405518) (xy 173.813185 -311.403537) (xy 173.764966 -311.393693)
			(xy 173.71895 -311.376241) (xy 173.676329 -311.351634) (xy 173.638208 -311.320509) (xy 173.605573 -311.283672)
			(xy 173.57927 -311.242076) (xy 173.559979 -311.1968) (xy 173.548202 -311.149016) (xy 173.544242 -311.099962)
			(xy 173.227238 -311.099962) (xy 173.226734 -311.12567) (xy 173.218691 -311.176452) (xy 173.202803 -311.225351)
			(xy 173.17946 -311.271163) (xy 173.149239 -311.312759) (xy 173.112883 -311.349115) (xy 173.071287 -311.379336)
			(xy 173.025475 -311.402679) (xy 172.976576 -311.418567) (xy 172.925794 -311.42661) (xy 172.874378 -311.42661)
			(xy 172.823596 -311.418567) (xy 172.774697 -311.402679) (xy 172.728885 -311.379336) (xy 172.687289 -311.349115)
			(xy 172.650933 -311.312759) (xy 172.620712 -311.271163) (xy 172.597369 -311.225351) (xy 172.581481 -311.176452)
			(xy 172.573438 -311.12567) (xy 172.254506 -311.12567) (xy 172.24679 -311.173146) (xy 172.231206 -311.219827)
			(xy 172.208335 -311.263404) (xy 172.17877 -311.302748) (xy 172.143277 -311.33684) (xy 172.102774 -311.364796)
			(xy 172.058312 -311.385894) (xy 172.011041 -311.399586) (xy 171.962186 -311.405518) (xy 171.913011 -311.403537)
			(xy 171.864792 -311.393693) (xy 171.818776 -311.376241) (xy 171.776155 -311.351634) (xy 171.738034 -311.320509)
			(xy 171.705399 -311.283672) (xy 171.679096 -311.242076) (xy 171.659805 -311.1968) (xy 171.648028 -311.149016)
			(xy 171.644068 -311.099962) (xy 171.327064 -311.099962) (xy 171.32656 -311.12567) (xy 171.318517 -311.176452)
			(xy 171.302629 -311.225351) (xy 171.279286 -311.271163) (xy 171.249065 -311.312759) (xy 171.212709 -311.349115)
			(xy 171.171113 -311.379336) (xy 171.125301 -311.402679) (xy 171.076402 -311.418567) (xy 171.02562 -311.42661)
			(xy 170.974204 -311.42661) (xy 170.923422 -311.418567) (xy 170.874523 -311.402679) (xy 170.828711 -311.379336)
			(xy 170.787115 -311.349115) (xy 170.750759 -311.312759) (xy 170.720538 -311.271163) (xy 170.697195 -311.225351)
			(xy 170.681307 -311.176452) (xy 170.673264 -311.12567) (xy 170.354586 -311.12567) (xy 170.34687 -311.173146)
			(xy 170.331286 -311.219827) (xy 170.308415 -311.263404) (xy 170.27885 -311.302748) (xy 170.243357 -311.33684)
			(xy 170.202854 -311.364796) (xy 170.158392 -311.385894) (xy 170.111121 -311.399586) (xy 170.062266 -311.405518)
			(xy 170.013091 -311.403537) (xy 169.964872 -311.393693) (xy 169.918856 -311.376241) (xy 169.876235 -311.351634)
			(xy 169.838114 -311.320509) (xy 169.805479 -311.283672) (xy 169.779176 -311.242076) (xy 169.759885 -311.1968)
			(xy 169.748108 -311.149016) (xy 169.744148 -311.099962) (xy 169.427144 -311.099962) (xy 169.42664 -311.12567)
			(xy 169.418597 -311.176452) (xy 169.402709 -311.225351) (xy 169.379366 -311.271163) (xy 169.349145 -311.312759)
			(xy 169.312789 -311.349115) (xy 169.271193 -311.379336) (xy 169.225381 -311.402679) (xy 169.176482 -311.418567)
			(xy 169.1257 -311.42661) (xy 169.074284 -311.42661) (xy 169.023502 -311.418567) (xy 168.974603 -311.402679)
			(xy 168.928791 -311.379336) (xy 168.887195 -311.349115) (xy 168.850839 -311.312759) (xy 168.820618 -311.271163)
			(xy 168.797275 -311.225351) (xy 168.781387 -311.176452) (xy 168.773344 -311.12567) (xy 168.454666 -311.12567)
			(xy 168.44695 -311.173146) (xy 168.431366 -311.219827) (xy 168.408495 -311.263404) (xy 168.37893 -311.302748)
			(xy 168.343437 -311.33684) (xy 168.302934 -311.364796) (xy 168.258472 -311.385894) (xy 168.211201 -311.399586)
			(xy 168.162346 -311.405518) (xy 168.113171 -311.403537) (xy 168.064952 -311.393693) (xy 168.018936 -311.376241)
			(xy 167.976315 -311.351634) (xy 167.938194 -311.320509) (xy 167.905559 -311.283672) (xy 167.879256 -311.242076)
			(xy 167.859965 -311.1968) (xy 167.848188 -311.149016) (xy 167.844228 -311.099962) (xy 167.527224 -311.099962)
			(xy 167.52672 -311.12567) (xy 167.518677 -311.176452) (xy 167.502789 -311.225351) (xy 167.479446 -311.271163)
			(xy 167.449225 -311.312759) (xy 167.412869 -311.349115) (xy 167.371273 -311.379336) (xy 167.325461 -311.402679)
			(xy 167.276562 -311.418567) (xy 167.22578 -311.42661) (xy 167.174364 -311.42661) (xy 167.123582 -311.418567)
			(xy 167.074683 -311.402679) (xy 167.028871 -311.379336) (xy 166.987275 -311.349115) (xy 166.950919 -311.312759)
			(xy 166.920698 -311.271163) (xy 166.897355 -311.225351) (xy 166.881467 -311.176452) (xy 166.873424 -311.12567)
			(xy 166.554492 -311.12567) (xy 166.546776 -311.173146) (xy 166.531192 -311.219827) (xy 166.508321 -311.263404)
			(xy 166.478756 -311.302748) (xy 166.443263 -311.33684) (xy 166.40276 -311.364796) (xy 166.358298 -311.385894)
			(xy 166.311027 -311.399586) (xy 166.262172 -311.405518) (xy 166.212997 -311.403537) (xy 166.164778 -311.393693)
			(xy 166.118762 -311.376241) (xy 166.076141 -311.351634) (xy 166.03802 -311.320509) (xy 166.005385 -311.283672)
			(xy 165.979082 -311.242076) (xy 165.959791 -311.1968) (xy 165.948014 -311.149016) (xy 165.944054 -311.099962)
			(xy 165.605206 -311.099962) (xy 165.604711 -311.124569) (xy 165.596816 -311.173146) (xy 165.581232 -311.219827)
			(xy 165.558361 -311.263404) (xy 165.528796 -311.302748) (xy 165.493303 -311.33684) (xy 165.4528 -311.364796)
			(xy 165.408338 -311.385894) (xy 165.361067 -311.399586) (xy 165.312212 -311.405518) (xy 165.263037 -311.403537)
			(xy 165.214818 -311.393693) (xy 165.168802 -311.376241) (xy 165.126181 -311.351634) (xy 165.08806 -311.320509)
			(xy 165.055425 -311.283672) (xy 165.029122 -311.242076) (xy 165.009831 -311.1968) (xy 164.998054 -311.149016)
			(xy 164.994094 -311.099962) (xy 164.655246 -311.099962) (xy 164.654751 -311.124569) (xy 164.646856 -311.173146)
			(xy 164.631272 -311.219827) (xy 164.608401 -311.263404) (xy 164.578836 -311.302748) (xy 164.543343 -311.33684)
			(xy 164.50284 -311.364796) (xy 164.458378 -311.385894) (xy 164.411107 -311.399586) (xy 164.362252 -311.405518)
			(xy 164.313077 -311.403537) (xy 164.264858 -311.393693) (xy 164.218842 -311.376241) (xy 164.176221 -311.351634)
			(xy 164.1381 -311.320509) (xy 164.105465 -311.283672) (xy 164.079162 -311.242076) (xy 164.059871 -311.1968)
			(xy 164.048094 -311.149016) (xy 164.044134 -311.099962) (xy 163.705286 -311.099962) (xy 163.704791 -311.124569)
			(xy 163.696896 -311.173146) (xy 163.681312 -311.219827) (xy 163.658441 -311.263404) (xy 163.628876 -311.302748)
			(xy 163.593383 -311.33684) (xy 163.55288 -311.364796) (xy 163.508418 -311.385894) (xy 163.461147 -311.399586)
			(xy 163.412292 -311.405518) (xy 163.363117 -311.403537) (xy 163.314898 -311.393693) (xy 163.268882 -311.376241)
			(xy 163.226261 -311.351634) (xy 163.18814 -311.320509) (xy 163.155505 -311.283672) (xy 163.129202 -311.242076)
			(xy 163.109911 -311.1968) (xy 163.098134 -311.149016) (xy 163.094174 -311.099962) (xy 162.755326 -311.099962)
			(xy 162.754831 -311.124569) (xy 162.746936 -311.173146) (xy 162.731352 -311.219827) (xy 162.708481 -311.263404)
			(xy 162.678916 -311.302748) (xy 162.643423 -311.33684) (xy 162.60292 -311.364796) (xy 162.558458 -311.385894)
			(xy 162.511187 -311.399586) (xy 162.462332 -311.405518) (xy 162.413157 -311.403537) (xy 162.364938 -311.393693)
			(xy 162.318922 -311.376241) (xy 162.276301 -311.351634) (xy 162.23818 -311.320509) (xy 162.205545 -311.283672)
			(xy 162.179242 -311.242076) (xy 162.159951 -311.1968) (xy 162.148174 -311.149016) (xy 162.144214 -311.099962)
			(xy 161.805366 -311.099962) (xy 161.804871 -311.124569) (xy 161.796976 -311.173146) (xy 161.781392 -311.219827)
			(xy 161.758521 -311.263404) (xy 161.728956 -311.302748) (xy 161.693463 -311.33684) (xy 161.65296 -311.364796)
			(xy 161.608498 -311.385894) (xy 161.561227 -311.399586) (xy 161.512372 -311.405518) (xy 161.463197 -311.403537)
			(xy 161.414978 -311.393693) (xy 161.368962 -311.376241) (xy 161.326341 -311.351634) (xy 161.28822 -311.320509)
			(xy 161.255585 -311.283672) (xy 161.229282 -311.242076) (xy 161.209991 -311.1968) (xy 161.198214 -311.149016)
			(xy 161.194254 -311.099962) (xy 160.855152 -311.099962) (xy 160.854657 -311.124569) (xy 160.846762 -311.173146)
			(xy 160.831178 -311.219827) (xy 160.808307 -311.263404) (xy 160.778742 -311.302748) (xy 160.743249 -311.33684)
			(xy 160.702746 -311.364796) (xy 160.658284 -311.385894) (xy 160.611013 -311.399586) (xy 160.562158 -311.405518)
			(xy 160.512983 -311.403537) (xy 160.464764 -311.393693) (xy 160.418748 -311.376241) (xy 160.376127 -311.351634)
			(xy 160.338006 -311.320509) (xy 160.305371 -311.283672) (xy 160.279068 -311.242076) (xy 160.259777 -311.1968)
			(xy 160.248 -311.149016) (xy 160.24404 -311.099962) (xy 159.905192 -311.099962) (xy 159.904697 -311.124569)
			(xy 159.896802 -311.173146) (xy 159.881218 -311.219827) (xy 159.858347 -311.263404) (xy 159.828782 -311.302748)
			(xy 159.793289 -311.33684) (xy 159.752786 -311.364796) (xy 159.708324 -311.385894) (xy 159.661053 -311.399586)
			(xy 159.612198 -311.405518) (xy 159.563023 -311.403537) (xy 159.514804 -311.393693) (xy 159.468788 -311.376241)
			(xy 159.426167 -311.351634) (xy 159.388046 -311.320509) (xy 159.355411 -311.283672) (xy 159.329108 -311.242076)
			(xy 159.309817 -311.1968) (xy 159.29804 -311.149016) (xy 159.29408 -311.099962) (xy 158.955232 -311.099962)
			(xy 158.954737 -311.124569) (xy 158.946842 -311.173146) (xy 158.931258 -311.219827) (xy 158.908387 -311.263404)
			(xy 158.878822 -311.302748) (xy 158.843329 -311.33684) (xy 158.802826 -311.364796) (xy 158.758364 -311.385894)
			(xy 158.711093 -311.399586) (xy 158.662238 -311.405518) (xy 158.613063 -311.403537) (xy 158.564844 -311.393693)
			(xy 158.518828 -311.376241) (xy 158.476207 -311.351634) (xy 158.438086 -311.320509) (xy 158.405451 -311.283672)
			(xy 158.379148 -311.242076) (xy 158.359857 -311.1968) (xy 158.34808 -311.149016) (xy 158.34412 -311.099962)
			(xy 158.005272 -311.099962) (xy 158.004777 -311.124569) (xy 157.996882 -311.173146) (xy 157.981298 -311.219827)
			(xy 157.958427 -311.263404) (xy 157.928862 -311.302748) (xy 157.893369 -311.33684) (xy 157.852866 -311.364796)
			(xy 157.808404 -311.385894) (xy 157.761133 -311.399586) (xy 157.712278 -311.405518) (xy 157.663103 -311.403537)
			(xy 157.614884 -311.393693) (xy 157.568868 -311.376241) (xy 157.526247 -311.351634) (xy 157.488126 -311.320509)
			(xy 157.455491 -311.283672) (xy 157.429188 -311.242076) (xy 157.409897 -311.1968) (xy 157.39812 -311.149016)
			(xy 157.39416 -311.099962) (xy 157.099 -311.099962) (xy 157.099 -311.408318) (xy 157.099427 -311.418387)
			(xy 157.107146 -311.436986) (xy 157.113986 -311.444386) (xy 157.312614 -311.643014) (xy 157.320009 -311.649868)
			(xy 157.338608 -311.65761) (xy 157.348682 -311.658)
		)
		(stroke
			(width 0)
			(type solid)
		)
		(fill yes)
		(layer "In9.Cu")
		(net "P1V8_VDDA_PEX1")
	)
)
